(kicad_pcb
	(version 20260206)
	(generator "pcbnew")
	(generator_version "10.0")
	(general
		(thickness 1.6)
		(legacy_teardrops no)
	)
	(paper "A4")
	(layers
		(0 "F.Cu" signal "TOP")
		(4 "In1.Cu" signal "GND")
		(6 "In2.Cu" signal "IN1")
		(8 "In3.Cu" signal "GND1")
		(10 "In4.Cu" signal "IN2")
		(12 "In5.Cu" signal "VCC")
		(14 "In6.Cu" signal "VCC1")
		(16 "In7.Cu" signal "IN3")
		(18 "In8.Cu" signal "GND2")
		(20 "In9.Cu" signal "IN4")
		(22 "In10.Cu" signal "GND3")
		(2 "B.Cu" signal "BOTTOM")
		(9 "F.Adhes" user "F.Adhesive")
		(11 "B.Adhes" user "B.Adhesive")
		(13 "F.Paste" user "Package Geometry/Pastemask Top")
		(15 "B.Paste" user "Package Geometry/Pastemask Bottom")
		(5 "F.SilkS" user "Ref Des/Silkscreen Top")
		(7 "B.SilkS" user "Ref Des/Silkscreen Bottom")
		(1 "F.Mask" user "Board Geometry/Soldermask Top")
		(3 "B.Mask" user "Board Geometry/Soldermask Bottom")
		(17 "Dwgs.User" user "User.Drawings")
		(19 "Cmts.User" user "User.Comments")
		(21 "Eco1.User" user "User.Eco1")
		(23 "Eco2.User" user "User.Eco2")
		(25 "Edge.Cuts" user "Board Geometry/Outline")
		(27 "Margin" user)
		(31 "F.CrtYd" user "Package Geometry/Place Bound Top")
		(29 "B.CrtYd" user "Package Geometry/Place Bound Bottom")
		(35 "F.Fab" user "Ref Des/Assembly Top")
		(33 "B.Fab" user "Ref Des/Assembly Bottom")
	)
	(setup
		(pad_to_mask_clearance 0)
		(allow_soldermask_bridges_in_footprints no)
		(tenting
			(front yes)
			(back yes)
		)
		(covering
			(front no)
			(back no)
		)
		(plugging
			(front no)
			(back no)
		)
		(capping no)
		(filling no)
		(pcbplotparams
			(layerselection 0x00000000_00000000_55555555_5755f5ff)
			(plot_on_all_layers_selection 0x00000000_00000000_00000000_00000000)
			(disableapertmacros no)
			(usegerberextensions no)
			(usegerberattributes yes)
			(usegerberadvancedattributes yes)
			(creategerberjobfile yes)
			(dashed_line_dash_ratio 12)
			(dashed_line_gap_ratio 3)
			(svgprecision 4)
			(plotframeref no)
			(mode 1)
			(useauxorigin no)
			(pdf_front_fp_property_popups yes)
			(pdf_back_fp_property_popups yes)
			(pdf_metadata yes)
			(pdf_single_document no)
			(dxfpolygonmode yes)
			(dxfimperialunits yes)
			(dxfusepcbnewfont yes)
			(psnegative no)
			(psa4output no)
			(plot_black_and_white yes)
			(sketchpadsonfab no)
			(plotpadnumbers no)
			(hidednponfab no)
			(sketchdnponfab yes)
			(crossoutdnponfab yes)
			(subtractmaskfromsilk no)
			(outputformat 1)
			(mirror no)
			(drillshape 1)
			(scaleselection 1)
			(outputdirectory "")
		)
	)
	(footprint ""
		(layer "F.Cu")
		(at 12.319 -93.472 180)
		(property "Reference" "R531"
			(at 0 0 180)
			(layer "F.SilkS")
			(hide yes)
			(effects
				(font
					(size 1.27 1.27)
				)
			)
		)
		(property "Value" ""
			(at 0 0 180)
			(layer "F.Fab")
			(effects
				(font
					(size 1.27 1.27)
				)
			)
		)
		(duplicate_pad_numbers_are_jumpers no)
		(fp_line
			(start 0.7874 0.4064)
			(end -0.7874 0.4064)
			(stroke
				(width 0.1524)
				(type default)
			)
			(layer "F.SilkS")
		)
		(fp_line
			(start 0.7874 -0.4064)
			(end 0.7874 0.4064)
			(stroke
				(width 0.1524)
				(type default)
			)
			(layer "F.SilkS")
		)
		(fp_line
			(start -0.7874 0.4064)
			(end -0.7874 -0.4064)
			(stroke
				(width 0.1524)
				(type default)
			)
			(layer "F.SilkS")
		)
		(fp_line
			(start -0.7874 -0.4064)
			(end 0.7874 -0.4064)
			(stroke
				(width 0.1524)
				(type default)
			)
			(layer "F.SilkS")
		)
		(fp_line
			(start 0.67945 0.3048)
			(end 0.120396 0.3048)
			(stroke
				(width 0.1)
				(type default)
			)
			(layer "F.Fab")
		)
		(fp_line
			(start 0.67945 -0.3048)
			(end 0.67945 0.3048)
			(stroke
				(width 0.1)
				(type default)
			)
			(layer "F.Fab")
		)
		(fp_line
			(start 0.12065 -0.2794)
			(end 0.12065 -0.3048)
			(stroke
				(width 0.1)
				(type default)
			)
			(layer "F.Fab")
		)
		(fp_line
			(start 0.12065 -0.3048)
			(end 0.67945 -0.3048)
			(stroke
				(width 0.1)
				(type default)
			)
			(layer "F.Fab")
		)
		(fp_line
			(start 0.120396 0.3048)
			(end 0.120396 0.2794)
			(stroke
				(width 0.1)
				(type default)
			)
			(layer "F.Fab")
		)
		(fp_line
			(start 0.120396 0.2794)
			(end -0.12065 0.2794)
			(stroke
				(width 0.1)
				(type default)
			)
			(layer "F.Fab")
		)
		(fp_line
			(start -0.12065 0.3048)
			(end -0.67945 0.3048)
			(stroke
				(width 0.1)
				(type default)
			)
			(layer "F.Fab")
		)
		(fp_line
			(start -0.12065 0.2794)
			(end -0.12065 0.3048)
			(stroke
				(width 0.1)
				(type default)
			)
			(layer "F.Fab")
		)
		(fp_line
			(start -0.12065 -0.2794)
			(end 0.12065 -0.2794)
			(stroke
				(width 0.1)
				(type default)
			)
			(layer "F.Fab")
		)
		(fp_line
			(start -0.12065 -0.305054)
			(end -0.12065 -0.2794)
			(stroke
				(width 0.1)
				(type default)
			)
			(layer "F.Fab")
		)
		(fp_line
			(start -0.67945 0.3048)
			(end -0.67945 -0.305054)
			(stroke
				(width 0.1)
				(type default)
			)
			(layer "F.Fab")
		)
		(fp_line
			(start -0.67945 -0.305054)
			(end -0.12065 -0.305054)
			(stroke
				(width 0.1)
				(type default)
			)
			(layer "F.Fab")
		)
		(pad "1" smd circle
			(at -0.40005 0 180)
			(size 0 0)
			(layers "F.Cu" "F.Mask" "F.Paste")
			(net "BMC_CPLD_GPIO_8_R2")
		)
		(pad "2" smd circle
			(at 0.40005 0 180)
			(size 0 0)
			(layers "F.Cu" "F.Mask" "F.Paste")
			(net "BMC_CPLD_GPIO_8")
		)
	)
	(footprint ""
		(layer "F.Cu")
		(at 13.31976 -64.54394 90)
		(property "Reference" "PR534"
			(at 0 0 90)
			(layer "F.SilkS")
			(hide yes)
			(effects
				(font
					(size 1.27 1.27)
				)
			)
		)
		(property "Value" ""
			(at 0 0 90)
			(layer "F.Fab")
			(effects
				(font
					(size 1.27 1.27)
				)
			)
		)
		(duplicate_pad_numbers_are_jumpers no)
		(fp_line
			(start 0.7874 -0.4064)
			(end 0.7874 0.4064)
			(stroke
				(width 0.1524)
				(type default)
			)
			(layer "F.SilkS")
		)
		(fp_line
			(start -0.7874 -0.4064)
			(end 0.7874 -0.4064)
			(stroke
				(width 0.1524)
				(type default)
			)
			(layer "F.SilkS")
		)
		(fp_line
			(start 0.7874 0.4064)
			(end -0.7874 0.4064)
			(stroke
				(width 0.1524)
				(type default)
			)
			(layer "F.SilkS")
		)
		(fp_line
			(start -0.7874 0.4064)
			(end -0.7874 -0.4064)
			(stroke
				(width 0.1524)
				(type default)
			)
			(layer "F.SilkS")
		)
		(fp_line
			(start -0.12065 -0.305054)
			(end -0.12065 -0.2794)
			(stroke
				(width 0.1)
				(type default)
			)
			(layer "F.Fab")
		)
		(fp_line
			(start -0.67945 -0.305054)
			(end -0.12065 -0.305054)
			(stroke
				(width 0.1)
				(type default)
			)
			(layer "F.Fab")
		)
		(fp_line
			(start 0.67945 -0.3048)
			(end 0.67945 0.3048)
			(stroke
				(width 0.1)
				(type default)
			)
			(layer "F.Fab")
		)
		(fp_line
			(start 0.12065 -0.3048)
			(end 0.67945 -0.3048)
			(stroke
				(width 0.1)
				(type default)
			)
			(layer "F.Fab")
		)
		(fp_line
			(start 0.12065 -0.2794)
			(end 0.12065 -0.3048)
			(stroke
				(width 0.1)
				(type default)
			)
			(layer "F.Fab")
		)
		(fp_line
			(start -0.12065 -0.2794)
			(end 0.12065 -0.2794)
			(stroke
				(width 0.1)
				(type default)
			)
			(layer "F.Fab")
		)
		(fp_line
			(start 0.120396 0.2794)
			(end -0.12065 0.2794)
			(stroke
				(width 0.1)
				(type default)
			)
			(layer "F.Fab")
		)
		(fp_line
			(start -0.12065 0.2794)
			(end -0.12065 0.3048)
			(stroke
				(width 0.1)
				(type default)
			)
			(layer "F.Fab")
		)
		(fp_line
			(start 0.67945 0.3048)
			(end 0.120396 0.3048)
			(stroke
				(width 0.1)
				(type default)
			)
			(layer "F.Fab")
		)
		(fp_line
			(start 0.120396 0.3048)
			(end 0.120396 0.2794)
			(stroke
				(width 0.1)
				(type default)
			)
			(layer "F.Fab")
		)
		(fp_line
			(start -0.12065 0.3048)
			(end -0.67945 0.3048)
			(stroke
				(width 0.1)
				(type default)
			)
			(layer "F.Fab")
		)
		(fp_line
			(start -0.67945 0.3048)
			(end -0.67945 -0.305054)
			(stroke
				(width 0.1)
				(type default)
			)
			(layer "F.Fab")
		)
		(pad "1" smd circle
			(at -0.40005 0 90)
			(size 0 0)
			(layers "F.Cu" "F.Mask" "F.Paste")
			(net "P3V3_AUX_FB_RC")
		)
		(pad "2" smd circle
			(at 0.40005 0 90)
			(size 0 0)
			(layers "F.Cu" "F.Mask" "F.Paste")
			(net "P3V3_AUX")
		)
	)
	(footprint ""
		(layer "F.Cu")
		(at 46.5709 -66.23812 90)
		(property "Reference" "R26"
			(at 0 0 90)
			(layer "F.SilkS")
			(hide yes)
			(effects
				(font
					(size 1.27 1.27)
				)
			)
		)
		(property "Value" ""
			(at 0 0 90)
			(layer "F.Fab")
			(effects
				(font
					(size 1.27 1.27)
				)
			)
		)
		(duplicate_pad_numbers_are_jumpers no)
		(fp_line
			(start 0.7874 -0.4064)
			(end 0.7874 0.4064)
			(stroke
				(width 0.1524)
				(type default)
			)
			(layer "F.SilkS")
		)
		(fp_line
			(start -0.7874 -0.4064)
			(end 0.7874 -0.4064)
			(stroke
				(width 0.1524)
				(type default)
			)
			(layer "F.SilkS")
		)
		(fp_line
			(start 0.7874 0.4064)
			(end -0.7874 0.4064)
			(stroke
				(width 0.1524)
				(type default)
			)
			(layer "F.SilkS")
		)
		(fp_line
			(start -0.7874 0.4064)
			(end -0.7874 -0.4064)
			(stroke
				(width 0.1524)
				(type default)
			)
			(layer "F.SilkS")
		)
		(fp_line
			(start -0.12065 -0.305054)
			(end -0.12065 -0.2794)
			(stroke
				(width 0.1)
				(type default)
			)
			(layer "F.Fab")
		)
		(fp_line
			(start -0.67945 -0.305054)
			(end -0.12065 -0.305054)
			(stroke
				(width 0.1)
				(type default)
			)
			(layer "F.Fab")
		)
		(fp_line
			(start 0.67945 -0.3048)
			(end 0.67945 0.3048)
			(stroke
				(width 0.1)
				(type default)
			)
			(layer "F.Fab")
		)
		(fp_line
			(start 0.12065 -0.3048)
			(end 0.67945 -0.3048)
			(stroke
				(width 0.1)
				(type default)
			)
			(layer "F.Fab")
		)
		(fp_line
			(start 0.12065 -0.2794)
			(end 0.12065 -0.3048)
			(stroke
				(width 0.1)
				(type default)
			)
			(layer "F.Fab")
		)
		(fp_line
			(start -0.12065 -0.2794)
			(end 0.12065 -0.2794)
			(stroke
				(width 0.1)
				(type default)
			)
			(layer "F.Fab")
		)
		(fp_line
			(start 0.120396 0.2794)
			(end -0.12065 0.2794)
			(stroke
				(width 0.1)
				(type default)
			)
			(layer "F.Fab")
		)
		(fp_line
			(start -0.12065 0.2794)
			(end -0.12065 0.3048)
			(stroke
				(width 0.1)
				(type default)
			)
			(layer "F.Fab")
		)
		(fp_line
			(start 0.67945 0.3048)
			(end 0.120396 0.3048)
			(stroke
				(width 0.1)
				(type default)
			)
			(layer "F.Fab")
		)
		(fp_line
			(start 0.120396 0.3048)
			(end 0.120396 0.2794)
			(stroke
				(width 0.1)
				(type default)
			)
			(layer "F.Fab")
		)
		(fp_line
			(start -0.12065 0.3048)
			(end -0.67945 0.3048)
			(stroke
				(width 0.1)
				(type default)
			)
			(layer "F.Fab")
		)
		(fp_line
			(start -0.67945 0.3048)
			(end -0.67945 -0.305054)
			(stroke
				(width 0.1)
				(type default)
			)
			(layer "F.Fab")
		)
		(pad "1" smd circle
			(at -0.40005 0 90)
			(size 0 0)
			(layers "F.Cu" "F.Mask" "F.Paste")
			(net "V_DACR_R")
		)
		(pad "2" smd circle
			(at 0.40005 0 90)
			(size 0 0)
			(layers "F.Cu" "F.Mask" "F.Paste")
			(net "V_DACR")
		)
	)
	(footprint ""
		(layer "F.Cu")
		(at 63.960502 -68.174362)
		(property "Reference" "C224"
			(at 0 0 0)
			(layer "F.SilkS")
			(hide yes)
			(effects
				(font
					(size 1.27 1.27)
				)
			)
		)
		(property "Value" ""
			(at 0 0 0)
			(layer "F.Fab")
			(effects
				(font
					(size 1.27 1.27)
				)
			)
		)
		(duplicate_pad_numbers_are_jumpers no)
		(fp_line
			(start -0.7874 -0.4064)
			(end 0.7874 -0.4064)
			(stroke
				(width 0.1524)
				(type default)
			)
			(layer "F.SilkS")
		)
		(fp_line
			(start -0.7874 0.4064)
			(end -0.7874 -0.4064)
			(stroke
				(width 0.1524)
				(type default)
			)
			(layer "F.SilkS")
		)
		(fp_line
			(start 0.7874 -0.4064)
			(end 0.7874 0.4064)
			(stroke
				(width 0.1524)
				(type default)
			)
			(layer "F.SilkS")
		)
		(fp_line
			(start 0.7874 0.4064)
			(end -0.7874 0.4064)
			(stroke
				(width 0.1524)
				(type default)
			)
			(layer "F.SilkS")
		)
		(fp_line
			(start -0.67945 -0.305054)
			(end -0.12065 -0.305054)
			(stroke
				(width 0.1)
				(type default)
			)
			(layer "F.Fab")
		)
		(fp_line
			(start -0.67945 0.3048)
			(end -0.67945 -0.305054)
			(stroke
				(width 0.1)
				(type default)
			)
			(layer "F.Fab")
		)
		(fp_line
			(start -0.12065 -0.305054)
			(end -0.12065 -0.2794)
			(stroke
				(width 0.1)
				(type default)
			)
			(layer "F.Fab")
		)
		(fp_line
			(start -0.12065 -0.2794)
			(end 0.12065 -0.2794)
			(stroke
				(width 0.1)
				(type default)
			)
			(layer "F.Fab")
		)
		(fp_line
			(start -0.12065 0.2794)
			(end -0.12065 0.3048)
			(stroke
				(width 0.1)
				(type default)
			)
			(layer "F.Fab")
		)
		(fp_line
			(start -0.12065 0.3048)
			(end -0.67945 0.3048)
			(stroke
				(width 0.1)
				(type default)
			)
			(layer "F.Fab")
		)
		(fp_line
			(start 0.120396 0.2794)
			(end -0.12065 0.2794)
			(stroke
				(width 0.1)
				(type default)
			)
			(layer "F.Fab")
		)
		(fp_line
			(start 0.120396 0.3048)
			(end 0.120396 0.2794)
			(stroke
				(width 0.1)
				(type default)
			)
			(layer "F.Fab")
		)
		(fp_line
			(start 0.12065 -0.3048)
			(end 0.67945 -0.3048)
			(stroke
				(width 0.1)
				(type default)
			)
			(layer "F.Fab")
		)
		(fp_line
			(start 0.12065 -0.2794)
			(end 0.12065 -0.3048)
			(stroke
				(width 0.1)
				(type default)
			)
			(layer "F.Fab")
		)
		(fp_line
			(start 0.67945 -0.3048)
			(end 0.67945 0.3048)
			(stroke
				(width 0.1)
				(type default)
			)
			(layer "F.Fab")
		)
		(fp_line
			(start 0.67945 0.3048)
			(end 0.120396 0.3048)
			(stroke
				(width 0.1)
				(type default)
			)
			(layer "F.Fab")
		)
		(pad "1" smd circle
			(at -0.40005 0)
			(size 0 0)
			(layers "F.Cu" "F.Mask" "F.Paste")
			(net "PGPPA_BMC_AUX")
		)
		(pad "2" smd circle
			(at 0.40005 0)
			(size 0 0)
			(layers "F.Cu" "F.Mask" "F.Paste")
			(net "GND")
		)
	)
	(footprint ""
		(layer "F.Cu")
		(at 42.932604 -87.679784 90)
		(property "Reference" "R490"
			(at 0 0 90)
			(layer "F.SilkS")
			(hide yes)
			(effects
				(font
					(size 1.27 1.27)
				)
			)
		)
		(property "Value" ""
			(at 0 0 90)
			(layer "F.Fab")
			(effects
				(font
					(size 1.27 1.27)
				)
			)
		)
		(duplicate_pad_numbers_are_jumpers no)
		(fp_line
			(start 0.7874 -0.4064)
			(end 0.7874 0.4064)
			(stroke
				(width 0.1524)
				(type default)
			)
			(layer "F.SilkS")
		)
		(fp_line
			(start -0.7874 -0.4064)
			(end 0.7874 -0.4064)
			(stroke
				(width 0.1524)
				(type default)
			)
			(layer "F.SilkS")
		)
		(fp_line
			(start 0.7874 0.4064)
			(end -0.7874 0.4064)
			(stroke
				(width 0.1524)
				(type default)
			)
			(layer "F.SilkS")
		)
		(fp_line
			(start -0.7874 0.4064)
			(end -0.7874 -0.4064)
			(stroke
				(width 0.1524)
				(type default)
			)
			(layer "F.SilkS")
		)
		(fp_line
			(start -0.12065 -0.305054)
			(end -0.12065 -0.2794)
			(stroke
				(width 0.1)
				(type default)
			)
			(layer "F.Fab")
		)
		(fp_line
			(start -0.67945 -0.305054)
			(end -0.12065 -0.305054)
			(stroke
				(width 0.1)
				(type default)
			)
			(layer "F.Fab")
		)
		(fp_line
			(start 0.67945 -0.3048)
			(end 0.67945 0.3048)
			(stroke
				(width 0.1)
				(type default)
			)
			(layer "F.Fab")
		)
		(fp_line
			(start 0.12065 -0.3048)
			(end 0.67945 -0.3048)
			(stroke
				(width 0.1)
				(type default)
			)
			(layer "F.Fab")
		)
		(fp_line
			(start 0.12065 -0.2794)
			(end 0.12065 -0.3048)
			(stroke
				(width 0.1)
				(type default)
			)
			(layer "F.Fab")
		)
		(fp_line
			(start -0.12065 -0.2794)
			(end 0.12065 -0.2794)
			(stroke
				(width 0.1)
				(type default)
			)
			(layer "F.Fab")
		)
		(fp_line
			(start 0.120396 0.2794)
			(end -0.12065 0.2794)
			(stroke
				(width 0.1)
				(type default)
			)
			(layer "F.Fab")
		)
		(fp_line
			(start -0.12065 0.2794)
			(end -0.12065 0.3048)
			(stroke
				(width 0.1)
				(type default)
			)
			(layer "F.Fab")
		)
		(fp_line
			(start 0.67945 0.3048)
			(end 0.120396 0.3048)
			(stroke
				(width 0.1)
				(type default)
			)
			(layer "F.Fab")
		)
		(fp_line
			(start 0.120396 0.3048)
			(end 0.120396 0.2794)
			(stroke
				(width 0.1)
				(type default)
			)
			(layer "F.Fab")
		)
		(fp_line
			(start -0.12065 0.3048)
			(end -0.67945 0.3048)
			(stroke
				(width 0.1)
				(type default)
			)
			(layer "F.Fab")
		)
		(fp_line
			(start -0.67945 0.3048)
			(end -0.67945 -0.305054)
			(stroke
				(width 0.1)
				(type default)
			)
			(layer "F.Fab")
		)
		(pad "1" smd circle
			(at -0.40005 0 90)
			(size 0 0)
			(layers "F.Cu" "F.Mask" "F.Paste")
			(net "P3V3_AUX")
		)
		(pad "2" smd circle
			(at 0.40005 0 90)
			(size 0 0)
			(layers "F.Cu" "F.Mask" "F.Paste")
			(net "SPI_PCH_CS0_FLASH_R1_N")
		)
	)
	(footprint ""
		(layer "F.Cu")
		(at 39.8272 -75.438)
		(property "Reference" "R552"
			(at 0 0 0)
			(layer "F.SilkS")
			(hide yes)
			(effects
				(font
					(size 1.27 1.27)
				)
			)
		)
		(property "Value" ""
			(at 0 0 0)
			(layer "F.Fab")
			(effects
				(font
					(size 1.27 1.27)
				)
			)
		)
		(duplicate_pad_numbers_are_jumpers no)
		(fp_line
			(start -0.7874 -0.4064)
			(end 0.7874 -0.4064)
			(stroke
				(width 0.1524)
				(type default)
			)
			(layer "F.SilkS")
		)
		(fp_line
			(start -0.7874 0.4064)
			(end -0.7874 -0.4064)
			(stroke
				(width 0.1524)
				(type default)
			)
			(layer "F.SilkS")
		)
		(fp_line
			(start 0.7874 -0.4064)
			(end 0.7874 0.4064)
			(stroke
				(width 0.1524)
				(type default)
			)
			(layer "F.SilkS")
		)
		(fp_line
			(start 0.7874 0.4064)
			(end -0.7874 0.4064)
			(stroke
				(width 0.1524)
				(type default)
			)
			(layer "F.SilkS")
		)
		(fp_line
			(start -0.67945 -0.305054)
			(end -0.12065 -0.305054)
			(stroke
				(width 0.1)
				(type default)
			)
			(layer "F.Fab")
		)
		(fp_line
			(start -0.67945 0.3048)
			(end -0.67945 -0.305054)
			(stroke
				(width 0.1)
				(type default)
			)
			(layer "F.Fab")
		)
		(fp_line
			(start -0.12065 -0.305054)
			(end -0.12065 -0.2794)
			(stroke
				(width 0.1)
				(type default)
			)
			(layer "F.Fab")
		)
		(fp_line
			(start -0.12065 -0.2794)
			(end 0.12065 -0.2794)
			(stroke
				(width 0.1)
				(type default)
			)
			(layer "F.Fab")
		)
		(fp_line
			(start -0.12065 0.2794)
			(end -0.12065 0.3048)
			(stroke
				(width 0.1)
				(type default)
			)
			(layer "F.Fab")
		)
		(fp_line
			(start -0.12065 0.3048)
			(end -0.67945 0.3048)
			(stroke
				(width 0.1)
				(type default)
			)
			(layer "F.Fab")
		)
		(fp_line
			(start 0.120396 0.2794)
			(end -0.12065 0.2794)
			(stroke
				(width 0.1)
				(type default)
			)
			(layer "F.Fab")
		)
		(fp_line
			(start 0.120396 0.3048)
			(end 0.120396 0.2794)
			(stroke
				(width 0.1)
				(type default)
			)
			(layer "F.Fab")
		)
		(fp_line
			(start 0.12065 -0.3048)
			(end 0.67945 -0.3048)
			(stroke
				(width 0.1)
				(type default)
			)
			(layer "F.Fab")
		)
		(fp_line
			(start 0.12065 -0.2794)
			(end 0.12065 -0.3048)
			(stroke
				(width 0.1)
				(type default)
			)
			(layer "F.Fab")
		)
		(fp_line
			(start 0.67945 -0.3048)
			(end 0.67945 0.3048)
			(stroke
				(width 0.1)
				(type default)
			)
			(layer "F.Fab")
		)
		(fp_line
			(start 0.67945 0.3048)
			(end 0.120396 0.3048)
			(stroke
				(width 0.1)
				(type default)
			)
			(layer "F.Fab")
		)
		(pad "1" smd circle
			(at -0.40005 0)
			(size 0 0)
			(layers "F.Cu" "F.Mask" "F.Paste")
			(net "SPI_BMC_IO1_FLASH_R")
		)
		(pad "2" smd circle
			(at 0.40005 0)
			(size 0 0)
			(layers "F.Cu" "F.Mask" "F.Paste")
			(net "SPI_BMC_BOOT_MISO")
		)
	)
	(footprint ""
		(layer "F.Cu")
		(at 36.8808 -109.4613 -90)
		(property "Reference" "R74"
			(at 0 0 270)
			(layer "F.SilkS")
			(hide yes)
			(effects
				(font
					(size 1.27 1.27)
				)
			)
		)
		(property "Value" ""
			(at 0 0 270)
			(layer "F.Fab")
			(effects
				(font
					(size 1.27 1.27)
				)
			)
		)
		(duplicate_pad_numbers_are_jumpers no)
		(fp_line
			(start -0.7874 0.4064)
			(end -0.7874 -0.4064)
			(stroke
				(width 0.1524)
				(type default)
			)
			(layer "F.SilkS")
		)
		(fp_line
			(start 0.7874 0.4064)
			(end -0.7874 0.4064)
			(stroke
				(width 0.1524)
				(type default)
			)
			(layer "F.SilkS")
		)
		(fp_line
			(start -0.7874 -0.4064)
			(end 0.7874 -0.4064)
			(stroke
				(width 0.1524)
				(type default)
			)
			(layer "F.SilkS")
		)
		(fp_line
			(start 0.7874 -0.4064)
			(end 0.7874 0.4064)
			(stroke
				(width 0.1524)
				(type default)
			)
			(layer "F.SilkS")
		)
		(fp_line
			(start -0.67945 0.3048)
			(end -0.67945 -0.305054)
			(stroke
				(width 0.1)
				(type default)
			)
			(layer "F.Fab")
		)
		(fp_line
			(start -0.12065 0.3048)
			(end -0.67945 0.3048)
			(stroke
				(width 0.1)
				(type default)
			)
			(layer "F.Fab")
		)
		(fp_line
			(start 0.120396 0.3048)
			(end 0.120396 0.2794)
			(stroke
				(width 0.1)
				(type default)
			)
			(layer "F.Fab")
		)
		(fp_line
			(start 0.67945 0.3048)
			(end 0.120396 0.3048)
			(stroke
				(width 0.1)
				(type default)
			)
			(layer "F.Fab")
		)
		(fp_line
			(start -0.12065 0.2794)
			(end -0.12065 0.3048)
			(stroke
				(width 0.1)
				(type default)
			)
			(layer "F.Fab")
		)
		(fp_line
			(start 0.120396 0.2794)
			(end -0.12065 0.2794)
			(stroke
				(width 0.1)
				(type default)
			)
			(layer "F.Fab")
		)
		(fp_line
			(start -0.12065 -0.2794)
			(end 0.12065 -0.2794)
			(stroke
				(width 0.1)
				(type default)
			)
			(layer "F.Fab")
		)
		(fp_line
			(start 0.12065 -0.2794)
			(end 0.12065 -0.3048)
			(stroke
				(width 0.1)
				(type default)
			)
			(layer "F.Fab")
		)
		(fp_line
			(start 0.12065 -0.3048)
			(end 0.67945 -0.3048)
			(stroke
				(width 0.1)
				(type default)
			)
			(layer "F.Fab")
		)
		(fp_line
			(start 0.67945 -0.3048)
			(end 0.67945 0.3048)
			(stroke
				(width 0.1)
				(type default)
			)
			(layer "F.Fab")
		)
		(fp_line
			(start -0.67945 -0.305054)
			(end -0.12065 -0.305054)
			(stroke
				(width 0.1)
				(type default)
			)
			(layer "F.Fab")
		)
		(fp_line
			(start -0.12065 -0.305054)
			(end -0.12065 -0.2794)
			(stroke
				(width 0.1)
				(type default)
			)
			(layer "F.Fab")
		)
		(pad "1" smd circle
			(at -0.40005 0 270)
			(size 0 0)
			(layers "F.Cu" "F.Mask" "F.Paste")
			(net "P3V3_AUX")
		)
		(pad "2" smd circle
			(at 0.40005 0 270)
			(size 0 0)
			(layers "F.Cu" "F.Mask" "F.Paste")
			(net "SGPIO_DI_1")
		)
	)
	(footprint ""
		(layer "F.Cu")
		(at 7.4422 -67.183 180)
		(property "Reference" "PC224"
			(at 0 0 180)
			(layer "F.SilkS")
			(hide yes)
			(effects
				(font
					(size 1.27 1.27)
				)
			)
		)
		(property "Value" ""
			(at 0 0 180)
			(layer "F.Fab")
			(effects
				(font
					(size 1.27 1.27)
				)
			)
		)
		(duplicate_pad_numbers_are_jumpers no)
		(fp_line
			(start 0.7874 0.4064)
			(end -0.7874 0.4064)
			(stroke
				(width 0.1524)
				(type default)
			)
			(layer "F.SilkS")
		)
		(fp_line
			(start 0.7874 -0.4064)
			(end 0.7874 0.4064)
			(stroke
				(width 0.1524)
				(type default)
			)
			(layer "F.SilkS")
		)
		(fp_line
			(start -0.7874 0.4064)
			(end -0.7874 -0.4064)
			(stroke
				(width 0.1524)
				(type default)
			)
			(layer "F.SilkS")
		)
		(fp_line
			(start -0.7874 -0.4064)
			(end 0.7874 -0.4064)
			(stroke
				(width 0.1524)
				(type default)
			)
			(layer "F.SilkS")
		)
		(fp_line
			(start 0.67945 0.3048)
			(end 0.120396 0.3048)
			(stroke
				(width 0.1)
				(type default)
			)
			(layer "F.Fab")
		)
		(fp_line
			(start 0.67945 -0.3048)
			(end 0.67945 0.3048)
			(stroke
				(width 0.1)
				(type default)
			)
			(layer "F.Fab")
		)
		(fp_line
			(start 0.12065 -0.2794)
			(end 0.12065 -0.3048)
			(stroke
				(width 0.1)
				(type default)
			)
			(layer "F.Fab")
		)
		(fp_line
			(start 0.12065 -0.3048)
			(end 0.67945 -0.3048)
			(stroke
				(width 0.1)
				(type default)
			)
			(layer "F.Fab")
		)
		(fp_line
			(start 0.120396 0.3048)
			(end 0.120396 0.2794)
			(stroke
				(width 0.1)
				(type default)
			)
			(layer "F.Fab")
		)
		(fp_line
			(start 0.120396 0.2794)
			(end -0.12065 0.2794)
			(stroke
				(width 0.1)
				(type default)
			)
			(layer "F.Fab")
		)
		(fp_line
			(start -0.12065 0.3048)
			(end -0.67945 0.3048)
			(stroke
				(width 0.1)
				(type default)
			)
			(layer "F.Fab")
		)
		(fp_line
			(start -0.12065 0.2794)
			(end -0.12065 0.3048)
			(stroke
				(width 0.1)
				(type default)
			)
			(layer "F.Fab")
		)
		(fp_line
			(start -0.12065 -0.2794)
			(end 0.12065 -0.2794)
			(stroke
				(width 0.1)
				(type default)
			)
			(layer "F.Fab")
		)
		(fp_line
			(start -0.12065 -0.305054)
			(end -0.12065 -0.2794)
			(stroke
				(width 0.1)
				(type default)
			)
			(layer "F.Fab")
		)
		(fp_line
			(start -0.67945 0.3048)
			(end -0.67945 -0.305054)
			(stroke
				(width 0.1)
				(type default)
			)
			(layer "F.Fab")
		)
		(fp_line
			(start -0.67945 -0.305054)
			(end -0.12065 -0.305054)
			(stroke
				(width 0.1)
				(type default)
			)
			(layer "F.Fab")
		)
		(pad "1" smd circle
			(at -0.40005 0 180)
			(size 0 0)
			(layers "F.Cu" "F.Mask" "F.Paste")
			(net "SW_P3V3_AUX_BST")
		)
		(pad "2" smd circle
			(at 0.40005 0 180)
			(size 0 0)
			(layers "F.Cu" "F.Mask" "F.Paste")
			(net "SW_P3V3_AUX_SW")
		)
	)
	(footprint ""
		(layer "F.Cu")
		(at 69.90588 -25.2349 180)
		(property "Reference" "R513"
			(at 0 0 180)
			(layer "F.SilkS")
			(hide yes)
			(effects
				(font
					(size 1.27 1.27)
				)
			)
		)
		(property "Value" ""
			(at 0 0 180)
			(layer "F.Fab")
			(effects
				(font
					(size 1.27 1.27)
				)
			)
		)
		(duplicate_pad_numbers_are_jumpers no)
		(fp_line
			(start 0.7874 0.4064)
			(end -0.7874 0.4064)
			(stroke
				(width 0.1524)
				(type default)
			)
			(layer "F.SilkS")
		)
		(fp_line
			(start 0.7874 -0.4064)
			(end 0.7874 0.4064)
			(stroke
				(width 0.1524)
				(type default)
			)
			(layer "F.SilkS")
		)
		(fp_line
			(start -0.7874 0.4064)
			(end -0.7874 -0.4064)
			(stroke
				(width 0.1524)
				(type default)
			)
			(layer "F.SilkS")
		)
		(fp_line
			(start -0.7874 -0.4064)
			(end 0.7874 -0.4064)
			(stroke
				(width 0.1524)
				(type default)
			)
			(layer "F.SilkS")
		)
		(fp_line
			(start 0.67945 0.3048)
			(end 0.120396 0.3048)
			(stroke
				(width 0.1)
				(type default)
			)
			(layer "F.Fab")
		)
		(fp_line
			(start 0.67945 -0.3048)
			(end 0.67945 0.3048)
			(stroke
				(width 0.1)
				(type default)
			)
			(layer "F.Fab")
		)
		(fp_line
			(start 0.12065 -0.2794)
			(end 0.12065 -0.3048)
			(stroke
				(width 0.1)
				(type default)
			)
			(layer "F.Fab")
		)
		(fp_line
			(start 0.12065 -0.3048)
			(end 0.67945 -0.3048)
			(stroke
				(width 0.1)
				(type default)
			)
			(layer "F.Fab")
		)
		(fp_line
			(start 0.120396 0.3048)
			(end 0.120396 0.2794)
			(stroke
				(width 0.1)
				(type default)
			)
			(layer "F.Fab")
		)
		(fp_line
			(start 0.120396 0.2794)
			(end -0.12065 0.2794)
			(stroke
				(width 0.1)
				(type default)
			)
			(layer "F.Fab")
		)
		(fp_line
			(start -0.12065 0.3048)
			(end -0.67945 0.3048)
			(stroke
				(width 0.1)
				(type default)
			)
			(layer "F.Fab")
		)
		(fp_line
			(start -0.12065 0.2794)
			(end -0.12065 0.3048)
			(stroke
				(width 0.1)
				(type default)
			)
			(layer "F.Fab")
		)
		(fp_line
			(start -0.12065 -0.2794)
			(end 0.12065 -0.2794)
			(stroke
				(width 0.1)
				(type default)
			)
			(layer "F.Fab")
		)
		(fp_line
			(start -0.12065 -0.305054)
			(end -0.12065 -0.2794)
			(stroke
				(width 0.1)
				(type default)
			)
			(layer "F.Fab")
		)
		(fp_line
			(start -0.67945 0.3048)
			(end -0.67945 -0.305054)
			(stroke
				(width 0.1)
				(type default)
			)
			(layer "F.Fab")
		)
		(fp_line
			(start -0.67945 -0.305054)
			(end -0.12065 -0.305054)
			(stroke
				(width 0.1)
				(type default)
			)
			(layer "F.Fab")
		)
		(pad "1" smd circle
			(at -0.40005 0 180)
			(size 0 0)
			(layers "F.Cu" "F.Mask" "F.Paste")
			(net "JTAG_SCM_TDO")
		)
		(pad "2" smd circle
			(at 0.40005 0 180)
			(size 0 0)
			(layers "F.Cu" "F.Mask" "F.Paste")
			(net "JTAG_SCM_PLD_TDO")
		)
	)
	(footprint ""
		(layer "F.Cu")
		(at 73.941686 -37.523674 180)
		(property "Reference" "L8"
			(at 0 0 180)
			(layer "F.SilkS")
			(hide yes)
			(effects
				(font
					(size 1.27 1.27)
				)
			)
		)
		(property "Value" ""
			(at 0 0 180)
			(layer "F.Fab")
			(effects
				(font
					(size 1.27 1.27)
				)
			)
		)
		(duplicate_pad_numbers_are_jumpers no)
		(fp_line
			(start 1.27 0.5842)
			(end 1.27 -0.5842)
			(stroke
				(width 0.1524)
				(type default)
			)
			(layer "F.SilkS")
		)
		(fp_line
			(start 1.27 0.5842)
			(end -1.27 0.5842)
			(stroke
				(width 0.1524)
				(type default)
			)
			(layer "F.SilkS")
		)
		(fp_line
			(start 0.127 0.5842)
			(end 0.127 -0.5842)
			(stroke
				(width 0.1524)
				(type default)
			)
			(layer "F.SilkS")
		)
		(fp_line
			(start -0.127 0.5842)
			(end -0.127 -0.5842)
			(stroke
				(width 0.1524)
				(type default)
			)
			(layer "F.SilkS")
		)
		(fp_line
			(start -1.27 0.5842)
			(end -1.27 -0.5842)
			(stroke
				(width 0.1524)
				(type default)
			)
			(layer "F.SilkS")
		)
		(fp_line
			(start -1.27 -0.5588)
			(end -1.27 -0.5842)
			(stroke
				(width 0.1524)
				(type default)
			)
			(layer "F.SilkS")
		)
		(fp_line
			(start -1.27 -0.5842)
			(end 1.27 -0.5842)
			(stroke
				(width 0.1524)
				(type default)
			)
			(layer "F.SilkS")
		)
		(fp_line
			(start 1.1938 0.4064)
			(end 0.9144 0.4064)
			(stroke
				(width 0.1)
				(type default)
			)
			(layer "F.Fab")
		)
		(fp_line
			(start 1.1938 -0.406654)
			(end 1.1938 0.4064)
			(stroke
				(width 0.1)
				(type default)
			)
			(layer "F.Fab")
		)
		(fp_line
			(start 0.9144 0.508)
			(end -0.9144 0.508)
			(stroke
				(width 0.1)
				(type default)
			)
			(layer "F.Fab")
		)
		(fp_line
			(start 0.9144 0.4064)
			(end 0.9144 0.508)
			(stroke
				(width 0.1)
				(type default)
			)
			(layer "F.Fab")
		)
		(fp_line
			(start 0.9144 -0.406654)
			(end 1.1938 -0.406654)
			(stroke
				(width 0.1)
				(type default)
			)
			(layer "F.Fab")
		)
		(fp_line
			(start 0.9144 -0.508)
			(end 0.9144 -0.406654)
			(stroke
				(width 0.1)
				(type default)
			)
			(layer "F.Fab")
		)
		(fp_line
			(start -0.9144 0.508)
			(end -0.9144 0.406654)
			(stroke
				(width 0.1)
				(type default)
			)
			(layer "F.Fab")
		)
		(fp_line
			(start -0.9144 0.406654)
			(end -1.194308 0.406654)
			(stroke
				(width 0.1)
				(type default)
			)
			(layer "F.Fab")
		)
		(fp_line
			(start -0.9144 -0.406654)
			(end -0.9144 -0.508)
			(stroke
				(width 0.1)
				(type default)
			)
			(layer "F.Fab")
		)
		(fp_line
			(start -0.9144 -0.508)
			(end 0.9144 -0.508)
			(stroke
				(width 0.1)
				(type default)
			)
			(layer "F.Fab")
		)
		(fp_line
			(start -1.194308 0.406654)
			(end -1.194308 -0.406654)
			(stroke
				(width 0.1)
				(type default)
			)
			(layer "F.Fab")
		)
		(fp_line
			(start -1.194308 -0.406654)
			(end -0.9144 -0.406654)
			(stroke
				(width 0.1)
				(type default)
			)
			(layer "F.Fab")
		)
		(pad "1" smd rect
			(at -0.7366 0 90)
			(size 0.7112 0.8128)
			(layers "F.Cu" "F.Mask" "F.Paste")
			(net "P1V0_AUX")
		)
		(pad "2" smd rect
			(at 0.7366 0 90)
			(size 0.7112 0.8128)
			(layers "F.Cu" "F.Mask" "F.Paste")
			(net "P1V0_STBY_PLAVDD")
		)
	)
	(footprint ""
		(layer "F.Cu")
		(at 18.6436 -56.1848 90)
		(property "Reference" "R900"
			(at 0 0 90)
			(layer "F.SilkS")
			(hide yes)
			(effects
				(font
					(size 1.27 1.27)
				)
			)
		)
		(property "Value" ""
			(at 0 0 90)
			(layer "F.Fab")
			(effects
				(font
					(size 1.27 1.27)
				)
			)
		)
		(duplicate_pad_numbers_are_jumpers no)
		(fp_line
			(start 0.7874 -0.4064)
			(end 0.7874 0.4064)
			(stroke
				(width 0.1524)
				(type default)
			)
			(layer "F.SilkS")
		)
		(fp_line
			(start -0.7874 -0.4064)
			(end 0.7874 -0.4064)
			(stroke
				(width 0.1524)
				(type default)
			)
			(layer "F.SilkS")
		)
		(fp_line
			(start 0.7874 0.4064)
			(end -0.7874 0.4064)
			(stroke
				(width 0.1524)
				(type default)
			)
			(layer "F.SilkS")
		)
		(fp_line
			(start -0.7874 0.4064)
			(end -0.7874 -0.4064)
			(stroke
				(width 0.1524)
				(type default)
			)
			(layer "F.SilkS")
		)
		(fp_line
			(start -0.12065 -0.305054)
			(end -0.12065 -0.2794)
			(stroke
				(width 0.1)
				(type default)
			)
			(layer "F.Fab")
		)
		(fp_line
			(start -0.67945 -0.305054)
			(end -0.12065 -0.305054)
			(stroke
				(width 0.1)
				(type default)
			)
			(layer "F.Fab")
		)
		(fp_line
			(start 0.67945 -0.3048)
			(end 0.67945 0.3048)
			(stroke
				(width 0.1)
				(type default)
			)
			(layer "F.Fab")
		)
		(fp_line
			(start 0.12065 -0.3048)
			(end 0.67945 -0.3048)
			(stroke
				(width 0.1)
				(type default)
			)
			(layer "F.Fab")
		)
		(fp_line
			(start 0.12065 -0.2794)
			(end 0.12065 -0.3048)
			(stroke
				(width 0.1)
				(type default)
			)
			(layer "F.Fab")
		)
		(fp_line
			(start -0.12065 -0.2794)
			(end 0.12065 -0.2794)
			(stroke
				(width 0.1)
				(type default)
			)
			(layer "F.Fab")
		)
		(fp_line
			(start 0.120396 0.2794)
			(end -0.12065 0.2794)
			(stroke
				(width 0.1)
				(type default)
			)
			(layer "F.Fab")
		)
		(fp_line
			(start -0.12065 0.2794)
			(end -0.12065 0.3048)
			(stroke
				(width 0.1)
				(type default)
			)
			(layer "F.Fab")
		)
		(fp_line
			(start 0.67945 0.3048)
			(end 0.120396 0.3048)
			(stroke
				(width 0.1)
				(type default)
			)
			(layer "F.Fab")
		)
		(fp_line
			(start 0.120396 0.3048)
			(end 0.120396 0.2794)
			(stroke
				(width 0.1)
				(type default)
			)
			(layer "F.Fab")
		)
		(fp_line
			(start -0.12065 0.3048)
			(end -0.67945 0.3048)
			(stroke
				(width 0.1)
				(type default)
			)
			(layer "F.Fab")
		)
		(fp_line
			(start -0.67945 0.3048)
			(end -0.67945 -0.305054)
			(stroke
				(width 0.1)
				(type default)
			)
			(layer "F.Fab")
		)
		(pad "1" smd circle
			(at -0.40005 0 90)
			(size 0 0)
			(layers "F.Cu" "F.Mask" "F.Paste")
			(net "UART_BIC_DBG_TX")
		)
		(pad "2" smd circle
			(at 0.40005 0 90)
			(size 0 0)
			(layers "F.Cu" "F.Mask" "F.Paste")
			(net "UART_BIC_DBG_TX_R")
		)
	)
	(footprint ""
		(layer "F.Cu")
		(at 63.553848 -34.870898 -90)
		(property "Reference" "R528"
			(at 0 0 270)
			(layer "F.SilkS")
			(hide yes)
			(effects
				(font
					(size 1.27 1.27)
				)
			)
		)
		(property "Value" ""
			(at 0 0 270)
			(layer "F.Fab")
			(effects
				(font
					(size 1.27 1.27)
				)
			)
		)
		(duplicate_pad_numbers_are_jumpers no)
		(fp_line
			(start 0.420878 0.4064)
			(end -0.122682 0.4064)
			(stroke
				(width 0.1524)
				(type default)
			)
			(layer "F.SilkS")
		)
		(fp_line
			(start -0.7874 0.036068)
			(end -0.7874 -0.4064)
			(stroke
				(width 0.1524)
				(type default)
			)
			(layer "F.SilkS")
		)
		(fp_line
			(start -0.7874 -0.4064)
			(end 0.7874 -0.4064)
			(stroke
				(width 0.1524)
				(type default)
			)
			(layer "F.SilkS")
		)
		(fp_line
			(start 0.7874 -0.4064)
			(end 0.7874 0.084328)
			(stroke
				(width 0.1524)
				(type default)
			)
			(layer "F.SilkS")
		)
		(fp_line
			(start -0.67945 0.3048)
			(end -0.67945 -0.305054)
			(stroke
				(width 0.1)
				(type default)
			)
			(layer "F.Fab")
		)
		(fp_line
			(start -0.12065 0.3048)
			(end -0.67945 0.3048)
			(stroke
				(width 0.1)
				(type default)
			)
			(layer "F.Fab")
		)
		(fp_line
			(start 0.120396 0.3048)
			(end 0.120396 0.2794)
			(stroke
				(width 0.1)
				(type default)
			)
			(layer "F.Fab")
		)
		(fp_line
			(start 0.67945 0.3048)
			(end 0.120396 0.3048)
			(stroke
				(width 0.1)
				(type default)
			)
			(layer "F.Fab")
		)
		(fp_line
			(start -0.12065 0.2794)
			(end -0.12065 0.3048)
			(stroke
				(width 0.1)
				(type default)
			)
			(layer "F.Fab")
		)
		(fp_line
			(start 0.120396 0.2794)
			(end -0.12065 0.2794)
			(stroke
				(width 0.1)
				(type default)
			)
			(layer "F.Fab")
		)
		(fp_line
			(start -0.12065 -0.2794)
			(end 0.12065 -0.2794)
			(stroke
				(width 0.1)
				(type default)
			)
			(layer "F.Fab")
		)
		(fp_line
			(start 0.12065 -0.2794)
			(end 0.12065 -0.3048)
			(stroke
				(width 0.1)
				(type default)
			)
			(layer "F.Fab")
		)
		(fp_line
			(start 0.12065 -0.3048)
			(end 0.67945 -0.3048)
			(stroke
				(width 0.1)
				(type default)
			)
			(layer "F.Fab")
		)
		(fp_line
			(start 0.67945 -0.3048)
			(end 0.67945 0.3048)
			(stroke
				(width 0.1)
				(type default)
			)
			(layer "F.Fab")
		)
		(fp_line
			(start -0.67945 -0.305054)
			(end -0.12065 -0.305054)
			(stroke
				(width 0.1)
				(type default)
			)
			(layer "F.Fab")
		)
		(fp_line
			(start -0.12065 -0.305054)
			(end -0.12065 -0.2794)
			(stroke
				(width 0.1)
				(type default)
			)
			(layer "F.Fab")
		)
		(pad "1" smd circle
			(at -0.40005 0 270)
			(size 0 0)
			(layers "F.Cu" "F.Mask" "F.Paste")
			(net "USB_HOST_BMC_B_R_DN")
		)
		(pad "2" smd circle
			(at 0.40005 0 270)
			(size 0 0)
			(layers "F.Cu" "F.Mask" "F.Paste")
			(net "USB_HOST_BMC_B_DN")
		)
	)
	(footprint ""
		(layer "F.Cu")
		(at 68.961 -101.473)
		(property "Reference" "R126"
			(at 0 0 0)
			(layer "F.SilkS")
			(hide yes)
			(effects
				(font
					(size 1.27 1.27)
				)
			)
		)
		(property "Value" ""
			(at 0 0 0)
			(layer "F.Fab")
			(effects
				(font
					(size 1.27 1.27)
				)
			)
		)
		(duplicate_pad_numbers_are_jumpers no)
		(fp_line
			(start -0.7874 -0.4064)
			(end 0.7874 -0.4064)
			(stroke
				(width 0.1524)
				(type default)
			)
			(layer "F.SilkS")
		)
		(fp_line
			(start -0.7874 0.4064)
			(end -0.7874 -0.4064)
			(stroke
				(width 0.1524)
				(type default)
			)
			(layer "F.SilkS")
		)
		(fp_line
			(start 0.7874 -0.4064)
			(end 0.7874 0.4064)
			(stroke
				(width 0.1524)
				(type default)
			)
			(layer "F.SilkS")
		)
		(fp_line
			(start 0.7874 0.4064)
			(end -0.7874 0.4064)
			(stroke
				(width 0.1524)
				(type default)
			)
			(layer "F.SilkS")
		)
		(fp_line
			(start -0.67945 -0.305054)
			(end -0.12065 -0.305054)
			(stroke
				(width 0.1)
				(type default)
			)
			(layer "F.Fab")
		)
		(fp_line
			(start -0.67945 0.3048)
			(end -0.67945 -0.305054)
			(stroke
				(width 0.1)
				(type default)
			)
			(layer "F.Fab")
		)
		(fp_line
			(start -0.12065 -0.305054)
			(end -0.12065 -0.2794)
			(stroke
				(width 0.1)
				(type default)
			)
			(layer "F.Fab")
		)
		(fp_line
			(start -0.12065 -0.2794)
			(end 0.12065 -0.2794)
			(stroke
				(width 0.1)
				(type default)
			)
			(layer "F.Fab")
		)
		(fp_line
			(start -0.12065 0.2794)
			(end -0.12065 0.3048)
			(stroke
				(width 0.1)
				(type default)
			)
			(layer "F.Fab")
		)
		(fp_line
			(start -0.12065 0.3048)
			(end -0.67945 0.3048)
			(stroke
				(width 0.1)
				(type default)
			)
			(layer "F.Fab")
		)
		(fp_line
			(start 0.120396 0.2794)
			(end -0.12065 0.2794)
			(stroke
				(width 0.1)
				(type default)
			)
			(layer "F.Fab")
		)
		(fp_line
			(start 0.120396 0.3048)
			(end 0.120396 0.2794)
			(stroke
				(width 0.1)
				(type default)
			)
			(layer "F.Fab")
		)
		(fp_line
			(start 0.12065 -0.3048)
			(end 0.67945 -0.3048)
			(stroke
				(width 0.1)
				(type default)
			)
			(layer "F.Fab")
		)
		(fp_line
			(start 0.12065 -0.2794)
			(end 0.12065 -0.3048)
			(stroke
				(width 0.1)
				(type default)
			)
			(layer "F.Fab")
		)
		(fp_line
			(start 0.67945 -0.3048)
			(end 0.67945 0.3048)
			(stroke
				(width 0.1)
				(type default)
			)
			(layer "F.Fab")
		)
		(fp_line
			(start 0.67945 0.3048)
			(end 0.120396 0.3048)
			(stroke
				(width 0.1)
				(type default)
			)
			(layer "F.Fab")
		)
		(pad "1" smd circle
			(at -0.40005 0)
			(size 0 0)
			(layers "F.Cu" "F.Mask" "F.Paste")
			(net "SMB_PCH_TPM_SDA")
		)
		(pad "2" smd circle
			(at 0.40005 0)
			(size 0 0)
			(layers "F.Cu" "F.Mask" "F.Paste")
			(net "P3V3_AUX")
		)
	)
	(footprint ""
		(layer "F.Cu")
		(at 8.9662 -54.5338 180)
		(property "Reference" "R868"
			(at 0 0 180)
			(layer "F.SilkS")
			(hide yes)
			(effects
				(font
					(size 1.27 1.27)
				)
			)
		)
		(property "Value" ""
			(at 0 0 180)
			(layer "F.Fab")
			(effects
				(font
					(size 1.27 1.27)
				)
			)
		)
		(duplicate_pad_numbers_are_jumpers no)
		(fp_line
			(start 0.7874 0.4064)
			(end -0.7874 0.4064)
			(stroke
				(width 0.1524)
				(type default)
			)
			(layer "F.SilkS")
		)
		(fp_line
			(start 0.7874 -0.4064)
			(end 0.7874 0.4064)
			(stroke
				(width 0.1524)
				(type default)
			)
			(layer "F.SilkS")
		)
		(fp_line
			(start -0.7874 0.4064)
			(end -0.7874 -0.4064)
			(stroke
				(width 0.1524)
				(type default)
			)
			(layer "F.SilkS")
		)
		(fp_line
			(start -0.7874 -0.4064)
			(end 0.7874 -0.4064)
			(stroke
				(width 0.1524)
				(type default)
			)
			(layer "F.SilkS")
		)
		(fp_line
			(start 0.67945 0.3048)
			(end 0.120396 0.3048)
			(stroke
				(width 0.1)
				(type default)
			)
			(layer "F.Fab")
		)
		(fp_line
			(start 0.67945 -0.3048)
			(end 0.67945 0.3048)
			(stroke
				(width 0.1)
				(type default)
			)
			(layer "F.Fab")
		)
		(fp_line
			(start 0.12065 -0.2794)
			(end 0.12065 -0.3048)
			(stroke
				(width 0.1)
				(type default)
			)
			(layer "F.Fab")
		)
		(fp_line
			(start 0.12065 -0.3048)
			(end 0.67945 -0.3048)
			(stroke
				(width 0.1)
				(type default)
			)
			(layer "F.Fab")
		)
		(fp_line
			(start 0.120396 0.3048)
			(end 0.120396 0.2794)
			(stroke
				(width 0.1)
				(type default)
			)
			(layer "F.Fab")
		)
		(fp_line
			(start 0.120396 0.2794)
			(end -0.12065 0.2794)
			(stroke
				(width 0.1)
				(type default)
			)
			(layer "F.Fab")
		)
		(fp_line
			(start -0.12065 0.3048)
			(end -0.67945 0.3048)
			(stroke
				(width 0.1)
				(type default)
			)
			(layer "F.Fab")
		)
		(fp_line
			(start -0.12065 0.2794)
			(end -0.12065 0.3048)
			(stroke
				(width 0.1)
				(type default)
			)
			(layer "F.Fab")
		)
		(fp_line
			(start -0.12065 -0.2794)
			(end 0.12065 -0.2794)
			(stroke
				(width 0.1)
				(type default)
			)
			(layer "F.Fab")
		)
		(fp_line
			(start -0.12065 -0.305054)
			(end -0.12065 -0.2794)
			(stroke
				(width 0.1)
				(type default)
			)
			(layer "F.Fab")
		)
		(fp_line
			(start -0.67945 0.3048)
			(end -0.67945 -0.305054)
			(stroke
				(width 0.1)
				(type default)
			)
			(layer "F.Fab")
		)
		(fp_line
			(start -0.67945 -0.305054)
			(end -0.12065 -0.305054)
			(stroke
				(width 0.1)
				(type default)
			)
			(layer "F.Fab")
		)
		(pad "1" smd circle
			(at -0.40005 0 180)
			(size 0 0)
			(layers "F.Cu" "F.Mask" "F.Paste")
			(net "PWRGD_P5V_AUX_R")
		)
		(pad "2" smd circle
			(at 0.40005 0 180)
			(size 0 0)
			(layers "F.Cu" "F.Mask" "F.Paste")
			(net "EN_P3V3_R1")
		)
	)
	(footprint ""
		(layer "F.Cu")
		(at 15.3416 -47.8536 -90)
		(property "Reference" "C296"
			(at 0 0 270)
			(layer "F.SilkS")
			(hide yes)
			(effects
				(font
					(size 1.27 1.27)
				)
			)
		)
		(property "Value" ""
			(at 0 0 270)
			(layer "F.Fab")
			(effects
				(font
					(size 1.27 1.27)
				)
			)
		)
		(duplicate_pad_numbers_are_jumpers no)
		(fp_line
			(start -0.7874 0.4064)
			(end -0.7874 -0.4064)
			(stroke
				(width 0.1524)
				(type default)
			)
			(layer "F.SilkS")
		)
		(fp_line
			(start 0.7874 0.4064)
			(end -0.7874 0.4064)
			(stroke
				(width 0.1524)
				(type default)
			)
			(layer "F.SilkS")
		)
		(fp_line
			(start -0.7874 -0.4064)
			(end 0.7874 -0.4064)
			(stroke
				(width 0.1524)
				(type default)
			)
			(layer "F.SilkS")
		)
		(fp_line
			(start 0.7874 -0.4064)
			(end 0.7874 0.4064)
			(stroke
				(width 0.1524)
				(type default)
			)
			(layer "F.SilkS")
		)
		(fp_line
			(start -0.67945 0.3048)
			(end -0.67945 -0.305054)
			(stroke
				(width 0.1)
				(type default)
			)
			(layer "F.Fab")
		)
		(fp_line
			(start -0.12065 0.3048)
			(end -0.67945 0.3048)
			(stroke
				(width 0.1)
				(type default)
			)
			(layer "F.Fab")
		)
		(fp_line
			(start 0.120396 0.3048)
			(end 0.120396 0.2794)
			(stroke
				(width 0.1)
				(type default)
			)
			(layer "F.Fab")
		)
		(fp_line
			(start 0.67945 0.3048)
			(end 0.120396 0.3048)
			(stroke
				(width 0.1)
				(type default)
			)
			(layer "F.Fab")
		)
		(fp_line
			(start -0.12065 0.2794)
			(end -0.12065 0.3048)
			(stroke
				(width 0.1)
				(type default)
			)
			(layer "F.Fab")
		)
		(fp_line
			(start 0.120396 0.2794)
			(end -0.12065 0.2794)
			(stroke
				(width 0.1)
				(type default)
			)
			(layer "F.Fab")
		)
		(fp_line
			(start -0.12065 -0.2794)
			(end 0.12065 -0.2794)
			(stroke
				(width 0.1)
				(type default)
			)
			(layer "F.Fab")
		)
		(fp_line
			(start 0.12065 -0.2794)
			(end 0.12065 -0.3048)
			(stroke
				(width 0.1)
				(type default)
			)
			(layer "F.Fab")
		)
		(fp_line
			(start 0.12065 -0.3048)
			(end 0.67945 -0.3048)
			(stroke
				(width 0.1)
				(type default)
			)
			(layer "F.Fab")
		)
		(fp_line
			(start 0.67945 -0.3048)
			(end 0.67945 0.3048)
			(stroke
				(width 0.1)
				(type default)
			)
			(layer "F.Fab")
		)
		(fp_line
			(start -0.67945 -0.305054)
			(end -0.12065 -0.305054)
			(stroke
				(width 0.1)
				(type default)
			)
			(layer "F.Fab")
		)
		(fp_line
			(start -0.12065 -0.305054)
			(end -0.12065 -0.2794)
			(stroke
				(width 0.1)
				(type default)
			)
			(layer "F.Fab")
		)
		(pad "1" smd circle
			(at -0.40005 0 270)
			(size 0 0)
			(layers "F.Cu" "F.Mask" "F.Paste")
			(net "P3V3_LDO")
		)
		(pad "2" smd circle
			(at 0.40005 0 270)
			(size 0 0)
			(layers "F.Cu" "F.Mask" "F.Paste")
			(net "GND")
		)
	)
	(footprint ""
		(layer "F.Cu")
		(at 70.8025 -31.3055)
		(property "Reference" "R709"
			(at 0 0 0)
			(layer "F.SilkS")
			(hide yes)
			(effects
				(font
					(size 1.27 1.27)
				)
			)
		)
		(property "Value" ""
			(at 0 0 0)
			(layer "F.Fab")
			(effects
				(font
					(size 1.27 1.27)
				)
			)
		)
		(duplicate_pad_numbers_are_jumpers no)
		(fp_line
			(start -0.7874 -0.4064)
			(end 0.7874 -0.4064)
			(stroke
				(width 0.1524)
				(type default)
			)
			(layer "F.SilkS")
		)
		(fp_line
			(start -0.7874 0.4064)
			(end -0.7874 -0.4064)
			(stroke
				(width 0.1524)
				(type default)
			)
			(layer "F.SilkS")
		)
		(fp_line
			(start 0.7874 -0.4064)
			(end 0.7874 0.4064)
			(stroke
				(width 0.1524)
				(type default)
			)
			(layer "F.SilkS")
		)
		(fp_line
			(start 0.7874 0.4064)
			(end -0.7874 0.4064)
			(stroke
				(width 0.1524)
				(type default)
			)
			(layer "F.SilkS")
		)
		(fp_line
			(start -0.67945 -0.305054)
			(end -0.12065 -0.305054)
			(stroke
				(width 0.1)
				(type default)
			)
			(layer "F.Fab")
		)
		(fp_line
			(start -0.67945 0.3048)
			(end -0.67945 -0.305054)
			(stroke
				(width 0.1)
				(type default)
			)
			(layer "F.Fab")
		)
		(fp_line
			(start -0.12065 -0.305054)
			(end -0.12065 -0.2794)
			(stroke
				(width 0.1)
				(type default)
			)
			(layer "F.Fab")
		)
		(fp_line
			(start -0.12065 -0.2794)
			(end 0.12065 -0.2794)
			(stroke
				(width 0.1)
				(type default)
			)
			(layer "F.Fab")
		)
		(fp_line
			(start -0.12065 0.2794)
			(end -0.12065 0.3048)
			(stroke
				(width 0.1)
				(type default)
			)
			(layer "F.Fab")
		)
		(fp_line
			(start -0.12065 0.3048)
			(end -0.67945 0.3048)
			(stroke
				(width 0.1)
				(type default)
			)
			(layer "F.Fab")
		)
		(fp_line
			(start 0.120396 0.2794)
			(end -0.12065 0.2794)
			(stroke
				(width 0.1)
				(type default)
			)
			(layer "F.Fab")
		)
		(fp_line
			(start 0.120396 0.3048)
			(end 0.120396 0.2794)
			(stroke
				(width 0.1)
				(type default)
			)
			(layer "F.Fab")
		)
		(fp_line
			(start 0.12065 -0.3048)
			(end 0.67945 -0.3048)
			(stroke
				(width 0.1)
				(type default)
			)
			(layer "F.Fab")
		)
		(fp_line
			(start 0.12065 -0.2794)
			(end 0.12065 -0.3048)
			(stroke
				(width 0.1)
				(type default)
			)
			(layer "F.Fab")
		)
		(fp_line
			(start 0.67945 -0.3048)
			(end 0.67945 0.3048)
			(stroke
				(width 0.1)
				(type default)
			)
			(layer "F.Fab")
		)
		(fp_line
			(start 0.67945 0.3048)
			(end 0.120396 0.3048)
			(stroke
				(width 0.1)
				(type default)
			)
			(layer "F.Fab")
		)
		(pad "1" smd circle
			(at -0.40005 0)
			(size 0 0)
			(layers "F.Cu" "F.Mask" "F.Paste")
			(net "P3V3_RGM")
		)
		(pad "2" smd circle
			(at 0.40005 0)
			(size 0 0)
			(layers "F.Cu" "F.Mask" "F.Paste")
			(net "PWRGD_P3V3_RGM_R")
		)
	)
	(footprint ""
		(layer "F.Cu")
		(at 30.1752 -90.3478 90)
		(property "Reference" "R748"
			(at 0 0 90)
			(layer "F.SilkS")
			(hide yes)
			(effects
				(font
					(size 1.27 1.27)
				)
			)
		)
		(property "Value" ""
			(at 0 0 90)
			(layer "F.Fab")
			(effects
				(font
					(size 1.27 1.27)
				)
			)
		)
		(duplicate_pad_numbers_are_jumpers no)
		(fp_line
			(start 0.7874 -0.4064)
			(end 0.7874 0.4064)
			(stroke
				(width 0.1524)
				(type default)
			)
			(layer "F.SilkS")
		)
		(fp_line
			(start -0.7874 -0.4064)
			(end 0.7874 -0.4064)
			(stroke
				(width 0.1524)
				(type default)
			)
			(layer "F.SilkS")
		)
		(fp_line
			(start 0.7874 0.4064)
			(end -0.7874 0.4064)
			(stroke
				(width 0.1524)
				(type default)
			)
			(layer "F.SilkS")
		)
		(fp_line
			(start -0.7874 0.4064)
			(end -0.7874 -0.4064)
			(stroke
				(width 0.1524)
				(type default)
			)
			(layer "F.SilkS")
		)
		(fp_line
			(start -0.12065 -0.305054)
			(end -0.12065 -0.2794)
			(stroke
				(width 0.1)
				(type default)
			)
			(layer "F.Fab")
		)
		(fp_line
			(start -0.67945 -0.305054)
			(end -0.12065 -0.305054)
			(stroke
				(width 0.1)
				(type default)
			)
			(layer "F.Fab")
		)
		(fp_line
			(start 0.67945 -0.3048)
			(end 0.67945 0.3048)
			(stroke
				(width 0.1)
				(type default)
			)
			(layer "F.Fab")
		)
		(fp_line
			(start 0.12065 -0.3048)
			(end 0.67945 -0.3048)
			(stroke
				(width 0.1)
				(type default)
			)
			(layer "F.Fab")
		)
		(fp_line
			(start 0.12065 -0.2794)
			(end 0.12065 -0.3048)
			(stroke
				(width 0.1)
				(type default)
			)
			(layer "F.Fab")
		)
		(fp_line
			(start -0.12065 -0.2794)
			(end 0.12065 -0.2794)
			(stroke
				(width 0.1)
				(type default)
			)
			(layer "F.Fab")
		)
		(fp_line
			(start 0.120396 0.2794)
			(end -0.12065 0.2794)
			(stroke
				(width 0.1)
				(type default)
			)
			(layer "F.Fab")
		)
		(fp_line
			(start -0.12065 0.2794)
			(end -0.12065 0.3048)
			(stroke
				(width 0.1)
				(type default)
			)
			(layer "F.Fab")
		)
		(fp_line
			(start 0.67945 0.3048)
			(end 0.120396 0.3048)
			(stroke
				(width 0.1)
				(type default)
			)
			(layer "F.Fab")
		)
		(fp_line
			(start 0.120396 0.3048)
			(end 0.120396 0.2794)
			(stroke
				(width 0.1)
				(type default)
			)
			(layer "F.Fab")
		)
		(fp_line
			(start -0.12065 0.3048)
			(end -0.67945 0.3048)
			(stroke
				(width 0.1)
				(type default)
			)
			(layer "F.Fab")
		)
		(fp_line
			(start -0.67945 0.3048)
			(end -0.67945 -0.305054)
			(stroke
				(width 0.1)
				(type default)
			)
			(layer "F.Fab")
		)
		(pad "1" smd circle
			(at -0.40005 0 90)
			(size 0 0)
			(layers "F.Cu" "F.Mask" "F.Paste")
			(net "PU_FPGA_NCONFIG")
		)
		(pad "2" smd circle
			(at 0.40005 0 90)
			(size 0 0)
			(layers "F.Cu" "F.Mask" "F.Paste")
			(net "RST_ROT_CPU_N")
		)
	)
	(footprint ""
		(layer "F.Cu")
		(at 40.132 -56.896 180)
		(property "Reference" "R406"
			(at 0 0 180)
			(layer "F.SilkS")
			(hide yes)
			(effects
				(font
					(size 1.27 1.27)
				)
			)
		)
		(property "Value" ""
			(at 0 0 180)
			(layer "F.Fab")
			(effects
				(font
					(size 1.27 1.27)
				)
			)
		)
		(duplicate_pad_numbers_are_jumpers no)
		(fp_line
			(start 0.7874 0.4064)
			(end -0.7874 0.4064)
			(stroke
				(width 0.1524)
				(type default)
			)
			(layer "F.SilkS")
		)
		(fp_line
			(start 0.7874 -0.4064)
			(end 0.7874 0.4064)
			(stroke
				(width 0.1524)
				(type default)
			)
			(layer "F.SilkS")
		)
		(fp_line
			(start -0.7874 0.4064)
			(end -0.7874 -0.4064)
			(stroke
				(width 0.1524)
				(type default)
			)
			(layer "F.SilkS")
		)
		(fp_line
			(start -0.7874 -0.4064)
			(end 0.7874 -0.4064)
			(stroke
				(width 0.1524)
				(type default)
			)
			(layer "F.SilkS")
		)
		(fp_line
			(start 0.67945 0.3048)
			(end 0.120396 0.3048)
			(stroke
				(width 0.1)
				(type default)
			)
			(layer "F.Fab")
		)
		(fp_line
			(start 0.67945 -0.3048)
			(end 0.67945 0.3048)
			(stroke
				(width 0.1)
				(type default)
			)
			(layer "F.Fab")
		)
		(fp_line
			(start 0.12065 -0.2794)
			(end 0.12065 -0.3048)
			(stroke
				(width 0.1)
				(type default)
			)
			(layer "F.Fab")
		)
		(fp_line
			(start 0.12065 -0.3048)
			(end 0.67945 -0.3048)
			(stroke
				(width 0.1)
				(type default)
			)
			(layer "F.Fab")
		)
		(fp_line
			(start 0.120396 0.3048)
			(end 0.120396 0.2794)
			(stroke
				(width 0.1)
				(type default)
			)
			(layer "F.Fab")
		)
		(fp_line
			(start 0.120396 0.2794)
			(end -0.12065 0.2794)
			(stroke
				(width 0.1)
				(type default)
			)
			(layer "F.Fab")
		)
		(fp_line
			(start -0.12065 0.3048)
			(end -0.67945 0.3048)
			(stroke
				(width 0.1)
				(type default)
			)
			(layer "F.Fab")
		)
		(fp_line
			(start -0.12065 0.2794)
			(end -0.12065 0.3048)
			(stroke
				(width 0.1)
				(type default)
			)
			(layer "F.Fab")
		)
		(fp_line
			(start -0.12065 -0.2794)
			(end 0.12065 -0.2794)
			(stroke
				(width 0.1)
				(type default)
			)
			(layer "F.Fab")
		)
		(fp_line
			(start -0.12065 -0.305054)
			(end -0.12065 -0.2794)
			(stroke
				(width 0.1)
				(type default)
			)
			(layer "F.Fab")
		)
		(fp_line
			(start -0.67945 0.3048)
			(end -0.67945 -0.305054)
			(stroke
				(width 0.1)
				(type default)
			)
			(layer "F.Fab")
		)
		(fp_line
			(start -0.67945 -0.305054)
			(end -0.12065 -0.305054)
			(stroke
				(width 0.1)
				(type default)
			)
			(layer "F.Fab")
		)
		(pad "1" smd circle
			(at -0.40005 0 180)
			(size 0 0)
			(layers "F.Cu" "F.Mask" "F.Paste")
			(net "P3V3_AUX")
		)
		(pad "2" smd circle
			(at 0.40005 0 180)
			(size 0 0)
			(layers "F.Cu" "F.Mask" "F.Paste")
			(net "PWRGD_P1V8_AUX_R")
		)
	)
	(footprint ""
		(layer "F.Cu")
		(at 47.2694 -74.803 180)
		(property "Reference" "C312"
			(at 0 0 180)
			(layer "F.SilkS")
			(hide yes)
			(effects
				(font
					(size 1.27 1.27)
				)
			)
		)
		(property "Value" ""
			(at 0 0 180)
			(layer "F.Fab")
			(effects
				(font
					(size 1.27 1.27)
				)
			)
		)
		(duplicate_pad_numbers_are_jumpers no)
		(fp_line
			(start 0.7874 0.4064)
			(end -0.7874 0.4064)
			(stroke
				(width 0.1524)
				(type default)
			)
			(layer "F.SilkS")
		)
		(fp_line
			(start 0.7874 -0.4064)
			(end 0.7874 0.4064)
			(stroke
				(width 0.1524)
				(type default)
			)
			(layer "F.SilkS")
		)
		(fp_line
			(start -0.7874 0.4064)
			(end -0.7874 -0.4064)
			(stroke
				(width 0.1524)
				(type default)
			)
			(layer "F.SilkS")
		)
		(fp_line
			(start -0.7874 -0.4064)
			(end 0.7874 -0.4064)
			(stroke
				(width 0.1524)
				(type default)
			)
			(layer "F.SilkS")
		)
		(fp_line
			(start 0.67945 0.3048)
			(end 0.120396 0.3048)
			(stroke
				(width 0.1)
				(type default)
			)
			(layer "F.Fab")
		)
		(fp_line
			(start 0.67945 -0.3048)
			(end 0.67945 0.3048)
			(stroke
				(width 0.1)
				(type default)
			)
			(layer "F.Fab")
		)
		(fp_line
			(start 0.12065 -0.2794)
			(end 0.12065 -0.3048)
			(stroke
				(width 0.1)
				(type default)
			)
			(layer "F.Fab")
		)
		(fp_line
			(start 0.12065 -0.3048)
			(end 0.67945 -0.3048)
			(stroke
				(width 0.1)
				(type default)
			)
			(layer "F.Fab")
		)
		(fp_line
			(start 0.120396 0.3048)
			(end 0.120396 0.2794)
			(stroke
				(width 0.1)
				(type default)
			)
			(layer "F.Fab")
		)
		(fp_line
			(start 0.120396 0.2794)
			(end -0.12065 0.2794)
			(stroke
				(width 0.1)
				(type default)
			)
			(layer "F.Fab")
		)
		(fp_line
			(start -0.12065 0.3048)
			(end -0.67945 0.3048)
			(stroke
				(width 0.1)
				(type default)
			)
			(layer "F.Fab")
		)
		(fp_line
			(start -0.12065 0.2794)
			(end -0.12065 0.3048)
			(stroke
				(width 0.1)
				(type default)
			)
			(layer "F.Fab")
		)
		(fp_line
			(start -0.12065 -0.2794)
			(end 0.12065 -0.2794)
			(stroke
				(width 0.1)
				(type default)
			)
			(layer "F.Fab")
		)
		(fp_line
			(start -0.12065 -0.305054)
			(end -0.12065 -0.2794)
			(stroke
				(width 0.1)
				(type default)
			)
			(layer "F.Fab")
		)
		(fp_line
			(start -0.67945 0.3048)
			(end -0.67945 -0.305054)
			(stroke
				(width 0.1)
				(type default)
			)
			(layer "F.Fab")
		)
		(fp_line
			(start -0.67945 -0.305054)
			(end -0.12065 -0.305054)
			(stroke
				(width 0.1)
				(type default)
			)
			(layer "F.Fab")
		)
		(pad "1" smd circle
			(at -0.40005 0 180)
			(size 0 0)
			(layers "F.Cu" "F.Mask" "F.Paste")
			(net "P3V3_AUX")
		)
		(pad "2" smd circle
			(at 0.40005 0 180)
			(size 0 0)
			(layers "F.Cu" "F.Mask" "F.Paste")
			(net "GND")
		)
	)
	(footprint ""
		(layer "F.Cu")
		(at 45.085 -82.6008)
		(property "Reference" "R556"
			(at 0 0 0)
			(layer "F.SilkS")
			(hide yes)
			(effects
				(font
					(size 1.27 1.27)
				)
			)
		)
		(property "Value" ""
			(at 0 0 0)
			(layer "F.Fab")
			(effects
				(font
					(size 1.27 1.27)
				)
			)
		)
		(duplicate_pad_numbers_are_jumpers no)
		(fp_line
			(start -0.7874 -0.4064)
			(end 0.7874 -0.4064)
			(stroke
				(width 0.1524)
				(type default)
			)
			(layer "F.SilkS")
		)
		(fp_line
			(start -0.7874 0.4064)
			(end -0.7874 -0.4064)
			(stroke
				(width 0.1524)
				(type default)
			)
			(layer "F.SilkS")
		)
		(fp_line
			(start 0.7874 -0.4064)
			(end 0.7874 0.4064)
			(stroke
				(width 0.1524)
				(type default)
			)
			(layer "F.SilkS")
		)
		(fp_line
			(start 0.7874 0.4064)
			(end -0.7874 0.4064)
			(stroke
				(width 0.1524)
				(type default)
			)
			(layer "F.SilkS")
		)
		(fp_line
			(start -0.67945 -0.305054)
			(end -0.12065 -0.305054)
			(stroke
				(width 0.1)
				(type default)
			)
			(layer "F.Fab")
		)
		(fp_line
			(start -0.67945 0.3048)
			(end -0.67945 -0.305054)
			(stroke
				(width 0.1)
				(type default)
			)
			(layer "F.Fab")
		)
		(fp_line
			(start -0.12065 -0.305054)
			(end -0.12065 -0.2794)
			(stroke
				(width 0.1)
				(type default)
			)
			(layer "F.Fab")
		)
		(fp_line
			(start -0.12065 -0.2794)
			(end 0.12065 -0.2794)
			(stroke
				(width 0.1)
				(type default)
			)
			(layer "F.Fab")
		)
		(fp_line
			(start -0.12065 0.2794)
			(end -0.12065 0.3048)
			(stroke
				(width 0.1)
				(type default)
			)
			(layer "F.Fab")
		)
		(fp_line
			(start -0.12065 0.3048)
			(end -0.67945 0.3048)
			(stroke
				(width 0.1)
				(type default)
			)
			(layer "F.Fab")
		)
		(fp_line
			(start 0.120396 0.2794)
			(end -0.12065 0.2794)
			(stroke
				(width 0.1)
				(type default)
			)
			(layer "F.Fab")
		)
		(fp_line
			(start 0.120396 0.3048)
			(end 0.120396 0.2794)
			(stroke
				(width 0.1)
				(type default)
			)
			(layer "F.Fab")
		)
		(fp_line
			(start 0.12065 -0.3048)
			(end 0.67945 -0.3048)
			(stroke
				(width 0.1)
				(type default)
			)
			(layer "F.Fab")
		)
		(fp_line
			(start 0.12065 -0.2794)
			(end 0.12065 -0.3048)
			(stroke
				(width 0.1)
				(type default)
			)
			(layer "F.Fab")
		)
		(fp_line
			(start 0.67945 -0.3048)
			(end 0.67945 0.3048)
			(stroke
				(width 0.1)
				(type default)
			)
			(layer "F.Fab")
		)
		(fp_line
			(start 0.67945 0.3048)
			(end 0.120396 0.3048)
			(stroke
				(width 0.1)
				(type default)
			)
			(layer "F.Fab")
		)
		(pad "1" smd circle
			(at -0.40005 0)
			(size 0 0)
			(layers "F.Cu" "F.Mask" "F.Paste")
			(net "SPI_BMC_BT_WP1_N_R")
		)
		(pad "2" smd circle
			(at 0.40005 0)
			(size 0 0)
			(layers "F.Cu" "F.Mask" "F.Paste")
			(net "FLASH_LATCH_Q_N_R2")
		)
	)
	(footprint ""
		(layer "F.Cu")
		(at 13.335 -18.161 -90)
		(property "Reference" "R839"
			(at 0 0 270)
			(layer "F.SilkS")
			(hide yes)
			(effects
				(font
					(size 1.27 1.27)
				)
			)
		)
		(property "Value" ""
			(at 0 0 270)
			(layer "F.Fab")
			(effects
				(font
					(size 1.27 1.27)
				)
			)
		)
		(duplicate_pad_numbers_are_jumpers no)
		(fp_line
			(start -0.7874 0.4064)
			(end -0.7874 -0.4064)
			(stroke
				(width 0.1524)
				(type default)
			)
			(layer "F.SilkS")
		)
		(fp_line
			(start 0.7874 0.4064)
			(end -0.7874 0.4064)
			(stroke
				(width 0.1524)
				(type default)
			)
			(layer "F.SilkS")
		)
		(fp_line
			(start -0.7874 -0.4064)
			(end 0.7874 -0.4064)
			(stroke
				(width 0.1524)
				(type default)
			)
			(layer "F.SilkS")
		)
		(fp_line
			(start 0.7874 -0.4064)
			(end 0.7874 0.4064)
			(stroke
				(width 0.1524)
				(type default)
			)
			(layer "F.SilkS")
		)
		(fp_line
			(start -0.67945 0.3048)
			(end -0.67945 -0.305054)
			(stroke
				(width 0.1)
				(type default)
			)
			(layer "F.Fab")
		)
		(fp_line
			(start -0.12065 0.3048)
			(end -0.67945 0.3048)
			(stroke
				(width 0.1)
				(type default)
			)
			(layer "F.Fab")
		)
		(fp_line
			(start 0.120396 0.3048)
			(end 0.120396 0.2794)
			(stroke
				(width 0.1)
				(type default)
			)
			(layer "F.Fab")
		)
		(fp_line
			(start 0.67945 0.3048)
			(end 0.120396 0.3048)
			(stroke
				(width 0.1)
				(type default)
			)
			(layer "F.Fab")
		)
		(fp_line
			(start -0.12065 0.2794)
			(end -0.12065 0.3048)
			(stroke
				(width 0.1)
				(type default)
			)
			(layer "F.Fab")
		)
		(fp_line
			(start 0.120396 0.2794)
			(end -0.12065 0.2794)
			(stroke
				(width 0.1)
				(type default)
			)
			(layer "F.Fab")
		)
		(fp_line
			(start -0.12065 -0.2794)
			(end 0.12065 -0.2794)
			(stroke
				(width 0.1)
				(type default)
			)
			(layer "F.Fab")
		)
		(fp_line
			(start 0.12065 -0.2794)
			(end 0.12065 -0.3048)
			(stroke
				(width 0.1)
				(type default)
			)
			(layer "F.Fab")
		)
		(fp_line
			(start 0.12065 -0.3048)
			(end 0.67945 -0.3048)
			(stroke
				(width 0.1)
				(type default)
			)
			(layer "F.Fab")
		)
		(fp_line
			(start 0.67945 -0.3048)
			(end 0.67945 0.3048)
			(stroke
				(width 0.1)
				(type default)
			)
			(layer "F.Fab")
		)
		(fp_line
			(start -0.67945 -0.305054)
			(end -0.12065 -0.305054)
			(stroke
				(width 0.1)
				(type default)
			)
			(layer "F.Fab")
		)
		(fp_line
			(start -0.12065 -0.305054)
			(end -0.12065 -0.2794)
			(stroke
				(width 0.1)
				(type default)
			)
			(layer "F.Fab")
		)
		(pad "1" smd circle
			(at -0.40005 0 270)
			(size 0 0)
			(layers "F.Cu" "F.Mask" "F.Paste")
			(net "PWR_LED")
		)
		(pad "2" smd circle
			(at 0.40005 0 270)
			(size 0 0)
			(layers "F.Cu" "F.Mask" "F.Paste")
			(net "GND")
		)
	)
	(footprint ""
		(layer "F.Cu")
		(at 17.47774 -42.72534 90)
		(property "Reference" "U44"
			(at -0.94234 -1.70307 90)
			(unlocked yes)
			(layer "F.SilkS")
			(effects
				(font
					(size 0.7874 0.5842)
					(thickness 0.1524)
				)
				(justify left)
			)
		)
		(property "Value" ""
			(at 0 0 90)
			(layer "F.Fab")
			(effects
				(font
					(size 1.27 1.27)
				)
			)
		)
		(duplicate_pad_numbers_are_jumpers no)
		(fp_line
			(start 1.684274 -1.074928)
			(end 1.684274 1.074928)
			(stroke
				(width 0.1524)
				(type default)
			)
			(layer "F.SilkS")
		)
		(fp_line
			(start 0.381 -1.074928)
			(end 1.684274 -1.074928)
			(stroke
				(width 0.1524)
				(type default)
			)
			(layer "F.SilkS")
		)
		(fp_line
			(start -0.381 -1.074928)
			(end 0 -0.625094)
			(stroke
				(width 0.1524)
				(type default)
			)
			(layer "F.SilkS")
		)
		(fp_line
			(start -1.684274 -1.074928)
			(end -0.381 -1.074928)
			(stroke
				(width 0.1524)
				(type default)
			)
			(layer "F.SilkS")
		)
		(fp_line
			(start 0 -0.625094)
			(end 0.381 -1.074928)
			(stroke
				(width 0.1524)
				(type default)
			)
			(layer "F.SilkS")
		)
		(fp_line
			(start 1.684274 1.074928)
			(end -1.684274 1.074928)
			(stroke
				(width 0.1524)
				(type default)
			)
			(layer "F.SilkS")
		)
		(fp_line
			(start -1.684274 1.074928)
			(end -1.684274 -1.074928)
			(stroke
				(width 0.1524)
				(type default)
			)
			(layer "F.SilkS")
		)
		(fp_poly
			(pts
				(xy -2.637282 -0.903986) (xy -2.637282 -0.395986) (xy -1.875282 -0.649986)
			)
			(stroke
				(width 0)
				(type default)
			)
			(fill yes)
			(layer "F.SilkS")
		)
		(fp_line
			(start 0.700024 -1.074928)
			(end -0.700024 -1.074928)
			(stroke
				(width 0.1)
				(type default)
			)
			(layer "F.Fab")
		)
		(fp_line
			(start -0.700024 -1.074928)
			(end -0.700024 1.074928)
			(stroke
				(width 0.1)
				(type default)
			)
			(layer "F.Fab")
		)
		(fp_line
			(start 0.700024 1.074928)
			(end 0.700024 -1.074928)
			(stroke
				(width 0.1)
				(type default)
			)
			(layer "F.Fab")
		)
		(fp_line
			(start -0.700024 1.074928)
			(end 0.700024 1.074928)
			(stroke
				(width 0.1)
				(type default)
			)
			(layer "F.Fab")
		)
		(fp_poly
			(pts
				(xy -2.637282 -0.903986) (xy -2.637282 -0.395986) (xy -1.875282 -0.649986)
			)
			(stroke
				(width 0)
				(type default)
			)
			(fill yes)
			(layer "F.Fab")
		)
		(pad "1" smd rect
			(at -1.100074 -0.649986)
			(size 0.4064 0.9144)
			(layers "F.Cu" "F.Mask" "F.Paste")
			(net "Net_1197")
		)
		(pad "2" smd rect
			(at -1.100074 0)
			(size 0.4064 0.9144)
			(layers "F.Cu" "F.Mask" "F.Paste")
			(net "RST_SPI_FLASH_R_N")
		)
		(pad "3" smd rect
			(at -1.100074 0.649986)
			(size 0.4064 0.9144)
			(layers "F.Cu" "F.Mask" "F.Paste")
			(net "GND")
		)
		(pad "4" smd rect
			(at 1.100074 0.649986)
			(size 0.4064 0.9144)
			(layers "F.Cu" "F.Mask" "F.Paste")
			(net "RST_SPI_FLASH_BUF_R3_N")
		)
		(pad "5" smd rect
			(at 1.100074 -0.649986)
			(size 0.4064 0.9144)
			(layers "F.Cu" "F.Mask" "F.Paste")
			(net "P3V3_AUX")
		)
	)
	(footprint ""
		(layer "F.Cu")
		(at 59.5884 -27.813 -90)
		(property "Reference" "R215"
			(at 0 0 270)
			(layer "F.SilkS")
			(hide yes)
			(effects
				(font
					(size 1.27 1.27)
				)
			)
		)
		(property "Value" ""
			(at 0 0 270)
			(layer "F.Fab")
			(effects
				(font
					(size 1.27 1.27)
				)
			)
		)
		(duplicate_pad_numbers_are_jumpers no)
		(fp_line
			(start -0.7874 0.4064)
			(end -0.7874 -0.4064)
			(stroke
				(width 0.1524)
				(type default)
			)
			(layer "F.SilkS")
		)
		(fp_line
			(start 0.7874 0.4064)
			(end -0.7874 0.4064)
			(stroke
				(width 0.1524)
				(type default)
			)
			(layer "F.SilkS")
		)
		(fp_line
			(start -0.7874 -0.4064)
			(end 0.7874 -0.4064)
			(stroke
				(width 0.1524)
				(type default)
			)
			(layer "F.SilkS")
		)
		(fp_line
			(start 0.7874 -0.4064)
			(end 0.7874 0.4064)
			(stroke
				(width 0.1524)
				(type default)
			)
			(layer "F.SilkS")
		)
		(fp_line
			(start -0.67945 0.3048)
			(end -0.67945 -0.305054)
			(stroke
				(width 0.1)
				(type default)
			)
			(layer "F.Fab")
		)
		(fp_line
			(start -0.12065 0.3048)
			(end -0.67945 0.3048)
			(stroke
				(width 0.1)
				(type default)
			)
			(layer "F.Fab")
		)
		(fp_line
			(start 0.120396 0.3048)
			(end 0.120396 0.2794)
			(stroke
				(width 0.1)
				(type default)
			)
			(layer "F.Fab")
		)
		(fp_line
			(start 0.67945 0.3048)
			(end 0.120396 0.3048)
			(stroke
				(width 0.1)
				(type default)
			)
			(layer "F.Fab")
		)
		(fp_line
			(start -0.12065 0.2794)
			(end -0.12065 0.3048)
			(stroke
				(width 0.1)
				(type default)
			)
			(layer "F.Fab")
		)
		(fp_line
			(start 0.120396 0.2794)
			(end -0.12065 0.2794)
			(stroke
				(width 0.1)
				(type default)
			)
			(layer "F.Fab")
		)
		(fp_line
			(start -0.12065 -0.2794)
			(end 0.12065 -0.2794)
			(stroke
				(width 0.1)
				(type default)
			)
			(layer "F.Fab")
		)
		(fp_line
			(start 0.12065 -0.2794)
			(end 0.12065 -0.3048)
			(stroke
				(width 0.1)
				(type default)
			)
			(layer "F.Fab")
		)
		(fp_line
			(start 0.12065 -0.3048)
			(end 0.67945 -0.3048)
			(stroke
				(width 0.1)
				(type default)
			)
			(layer "F.Fab")
		)
		(fp_line
			(start 0.67945 -0.3048)
			(end 0.67945 0.3048)
			(stroke
				(width 0.1)
				(type default)
			)
			(layer "F.Fab")
		)
		(fp_line
			(start -0.67945 -0.305054)
			(end -0.12065 -0.305054)
			(stroke
				(width 0.1)
				(type default)
			)
			(layer "F.Fab")
		)
		(fp_line
			(start -0.12065 -0.305054)
			(end -0.12065 -0.2794)
			(stroke
				(width 0.1)
				(type default)
			)
			(layer "F.Fab")
		)
		(pad "1" smd circle
			(at -0.40005 0 270)
			(size 0 0)
			(layers "F.Cu" "F.Mask" "F.Paste")
			(net "BMC_CLK_25M_R")
		)
		(pad "2" smd circle
			(at 0.40005 0 270)
			(size 0 0)
			(layers "F.Cu" "F.Mask" "F.Paste")
			(net "BMC_CLK_25M")
		)
	)
	(footprint ""
		(layer "F.Cu")
		(at 33.909 -40.2082 90)
		(property "Reference" "U43"
			(at -0.8128 -2.31013 90)
			(unlocked yes)
			(layer "F.SilkS")
			(effects
				(font
					(size 0.7874 0.5842)
					(thickness 0.1524)
				)
			)
		)
		(property "Value" ""
			(at 0 0 90)
			(layer "F.Fab")
			(effects
				(font
					(size 1.27 1.27)
				)
			)
		)
		(duplicate_pad_numbers_are_jumpers no)
		(fp_line
			(start 2.032 -1.525016)
			(end 2.032 1.525016)
			(stroke
				(width 0.1524)
				(type default)
			)
			(layer "F.SilkS")
		)
		(fp_line
			(start 0.635 -1.525016)
			(end 2.032 -1.525016)
			(stroke
				(width 0.1524)
				(type default)
			)
			(layer "F.SilkS")
		)
		(fp_line
			(start -0.635 -1.525016)
			(end 0 -0.889)
			(stroke
				(width 0.1524)
				(type default)
			)
			(layer "F.SilkS")
		)
		(fp_line
			(start -2.032 -1.525016)
			(end -0.635 -1.525016)
			(stroke
				(width 0.1524)
				(type default)
			)
			(layer "F.SilkS")
		)
		(fp_line
			(start 0 -0.889)
			(end 0.635 -1.525016)
			(stroke
				(width 0.1524)
				(type default)
			)
			(layer "F.SilkS")
		)
		(fp_line
			(start 2.032 1.525016)
			(end -2.032 1.525016)
			(stroke
				(width 0.1524)
				(type default)
			)
			(layer "F.SilkS")
		)
		(fp_line
			(start -2.032 1.525016)
			(end -2.032 -1.525016)
			(stroke
				(width 0.1524)
				(type default)
			)
			(layer "F.SilkS")
		)
		(fp_poly
			(pts
				(xy -2.9718 -1.33096) (xy -2.9718 -0.56896) (xy -2.2098 -0.94996)
			)
			(stroke
				(width 0)
				(type default)
			)
			(fill yes)
			(layer "F.SilkS")
		)
		(fp_line
			(start 0.87503 -1.525016)
			(end 0.87503 1.525016)
			(stroke
				(width 0.1)
				(type default)
			)
			(layer "F.Fab")
		)
		(fp_line
			(start -0.87503 -1.525016)
			(end 0.87503 -1.525016)
			(stroke
				(width 0.1)
				(type default)
			)
			(layer "F.Fab")
		)
		(fp_line
			(start 0.87503 1.525016)
			(end -0.87503 1.525016)
			(stroke
				(width 0.1)
				(type default)
			)
			(layer "F.Fab")
		)
		(fp_line
			(start -0.87503 1.525016)
			(end -0.87503 -1.525016)
			(stroke
				(width 0.1)
				(type default)
			)
			(layer "F.Fab")
		)
		(fp_poly
			(pts
				(xy -2.9718 -1.33096) (xy -2.9718 -0.56896) (xy -2.2098 -0.94996)
			)
			(stroke
				(width 0)
				(type default)
			)
			(fill yes)
			(layer "F.Fab")
		)
		(pad "1" smd rect
			(at -1.35001 -0.94996)
			(size 0.6096 1.0668)
			(layers "F.Cu" "F.Mask" "F.Paste")
			(net "PWRGD_P1V0_AUX_DELAY_R1")
		)
		(pad "2" smd rect
			(at -1.35001 0)
			(size 0.6096 1.0668)
			(layers "F.Cu" "F.Mask" "F.Paste")
			(net "GND")
		)
		(pad "3" smd rect
			(at -1.35001 0.94996)
			(size 0.6096 1.0668)
			(layers "F.Cu" "F.Mask" "F.Paste")
			(net "PWRGD_P1V0_AUX_R2")
		)
		(pad "4" smd rect
			(at 1.35001 0.94996)
			(size 0.6096 1.0668)
			(layers "F.Cu" "F.Mask" "F.Paste")
			(net "U43_CT")
		)
		(pad "5" smd rect
			(at 1.35001 0)
			(size 0.6096 1.0668)
			(layers "F.Cu" "F.Mask" "F.Paste")
			(net "P1V0_AUX")
		)
		(pad "6" smd rect
			(at 1.35001 -0.94996)
			(size 0.6096 1.0668)
			(layers "F.Cu" "F.Mask" "F.Paste")
			(net "P3V3_AUX")
		)
	)
	(footprint ""
		(layer "F.Cu")
		(at 49.2125 -93.9165 -90)
		(property "Reference" "R291"
			(at 0 0 270)
			(layer "F.SilkS")
			(hide yes)
			(effects
				(font
					(size 1.27 1.27)
				)
			)
		)
		(property "Value" ""
			(at 0 0 270)
			(layer "F.Fab")
			(effects
				(font
					(size 1.27 1.27)
				)
			)
		)
		(duplicate_pad_numbers_are_jumpers no)
		(fp_line
			(start -0.7874 0.4064)
			(end -0.7874 -0.4064)
			(stroke
				(width 0.1524)
				(type default)
			)
			(layer "F.SilkS")
		)
		(fp_line
			(start 0.7874 0.4064)
			(end -0.7874 0.4064)
			(stroke
				(width 0.1524)
				(type default)
			)
			(layer "F.SilkS")
		)
		(fp_line
			(start -0.7874 -0.4064)
			(end 0.7874 -0.4064)
			(stroke
				(width 0.1524)
				(type default)
			)
			(layer "F.SilkS")
		)
		(fp_line
			(start 0.7874 -0.4064)
			(end 0.7874 0.4064)
			(stroke
				(width 0.1524)
				(type default)
			)
			(layer "F.SilkS")
		)
		(fp_line
			(start -0.67945 0.3048)
			(end -0.67945 -0.305054)
			(stroke
				(width 0.1)
				(type default)
			)
			(layer "F.Fab")
		)
		(fp_line
			(start -0.12065 0.3048)
			(end -0.67945 0.3048)
			(stroke
				(width 0.1)
				(type default)
			)
			(layer "F.Fab")
		)
		(fp_line
			(start 0.120396 0.3048)
			(end 0.120396 0.2794)
			(stroke
				(width 0.1)
				(type default)
			)
			(layer "F.Fab")
		)
		(fp_line
			(start 0.67945 0.3048)
			(end 0.120396 0.3048)
			(stroke
				(width 0.1)
				(type default)
			)
			(layer "F.Fab")
		)
		(fp_line
			(start -0.12065 0.2794)
			(end -0.12065 0.3048)
			(stroke
				(width 0.1)
				(type default)
			)
			(layer "F.Fab")
		)
		(fp_line
			(start 0.120396 0.2794)
			(end -0.12065 0.2794)
			(stroke
				(width 0.1)
				(type default)
			)
			(layer "F.Fab")
		)
		(fp_line
			(start -0.12065 -0.2794)
			(end 0.12065 -0.2794)
			(stroke
				(width 0.1)
				(type default)
			)
			(layer "F.Fab")
		)
		(fp_line
			(start 0.12065 -0.2794)
			(end 0.12065 -0.3048)
			(stroke
				(width 0.1)
				(type default)
			)
			(layer "F.Fab")
		)
		(fp_line
			(start 0.12065 -0.3048)
			(end 0.67945 -0.3048)
			(stroke
				(width 0.1)
				(type default)
			)
			(layer "F.Fab")
		)
		(fp_line
			(start 0.67945 -0.3048)
			(end 0.67945 0.3048)
			(stroke
				(width 0.1)
				(type default)
			)
			(layer "F.Fab")
		)
		(fp_line
			(start -0.67945 -0.305054)
			(end -0.12065 -0.305054)
			(stroke
				(width 0.1)
				(type default)
			)
			(layer "F.Fab")
		)
		(fp_line
			(start -0.12065 -0.305054)
			(end -0.12065 -0.2794)
			(stroke
				(width 0.1)
				(type default)
			)
			(layer "F.Fab")
		)
		(pad "1" smd circle
			(at -0.40005 0 270)
			(size 0 0)
			(layers "F.Cu" "F.Mask" "F.Paste")
			(net "P3V3_RGM")
		)
		(pad "2" smd circle
			(at 0.40005 0 270)
			(size 0 0)
			(layers "F.Cu" "F.Mask" "F.Paste")
			(net "RST_BMC_EXTRST_R1_N")
		)
	)
	(footprint ""
		(layer "F.Cu")
		(at 39.9034 -41.5036)
		(property "Reference" "R442"
			(at 0 0 0)
			(layer "F.SilkS")
			(hide yes)
			(effects
				(font
					(size 1.27 1.27)
				)
			)
		)
		(property "Value" ""
			(at 0 0 0)
			(layer "F.Fab")
			(effects
				(font
					(size 1.27 1.27)
				)
			)
		)
		(duplicate_pad_numbers_are_jumpers no)
		(fp_line
			(start -0.7874 -0.4064)
			(end 0.7874 -0.4064)
			(stroke
				(width 0.1524)
				(type default)
			)
			(layer "F.SilkS")
		)
		(fp_line
			(start -0.7874 0.4064)
			(end -0.7874 -0.4064)
			(stroke
				(width 0.1524)
				(type default)
			)
			(layer "F.SilkS")
		)
		(fp_line
			(start 0.7874 -0.4064)
			(end 0.7874 0.4064)
			(stroke
				(width 0.1524)
				(type default)
			)
			(layer "F.SilkS")
		)
		(fp_line
			(start 0.7874 0.4064)
			(end -0.7874 0.4064)
			(stroke
				(width 0.1524)
				(type default)
			)
			(layer "F.SilkS")
		)
		(fp_line
			(start -0.67945 -0.305054)
			(end -0.12065 -0.305054)
			(stroke
				(width 0.1)
				(type default)
			)
			(layer "F.Fab")
		)
		(fp_line
			(start -0.67945 0.3048)
			(end -0.67945 -0.305054)
			(stroke
				(width 0.1)
				(type default)
			)
			(layer "F.Fab")
		)
		(fp_line
			(start -0.12065 -0.305054)
			(end -0.12065 -0.2794)
			(stroke
				(width 0.1)
				(type default)
			)
			(layer "F.Fab")
		)
		(fp_line
			(start -0.12065 -0.2794)
			(end 0.12065 -0.2794)
			(stroke
				(width 0.1)
				(type default)
			)
			(layer "F.Fab")
		)
		(fp_line
			(start -0.12065 0.2794)
			(end -0.12065 0.3048)
			(stroke
				(width 0.1)
				(type default)
			)
			(layer "F.Fab")
		)
		(fp_line
			(start -0.12065 0.3048)
			(end -0.67945 0.3048)
			(stroke
				(width 0.1)
				(type default)
			)
			(layer "F.Fab")
		)
		(fp_line
			(start 0.120396 0.2794)
			(end -0.12065 0.2794)
			(stroke
				(width 0.1)
				(type default)
			)
			(layer "F.Fab")
		)
		(fp_line
			(start 0.120396 0.3048)
			(end 0.120396 0.2794)
			(stroke
				(width 0.1)
				(type default)
			)
			(layer "F.Fab")
		)
		(fp_line
			(start 0.12065 -0.3048)
			(end 0.67945 -0.3048)
			(stroke
				(width 0.1)
				(type default)
			)
			(layer "F.Fab")
		)
		(fp_line
			(start 0.12065 -0.2794)
			(end 0.12065 -0.3048)
			(stroke
				(width 0.1)
				(type default)
			)
			(layer "F.Fab")
		)
		(fp_line
			(start 0.67945 -0.3048)
			(end 0.67945 0.3048)
			(stroke
				(width 0.1)
				(type default)
			)
			(layer "F.Fab")
		)
		(fp_line
			(start 0.67945 0.3048)
			(end 0.120396 0.3048)
			(stroke
				(width 0.1)
				(type default)
			)
			(layer "F.Fab")
		)
		(pad "1" smd circle
			(at -0.40005 0)
			(size 0 0)
			(layers "F.Cu" "F.Mask" "F.Paste")
			(net "SMB_BMC_ALERT3_N")
		)
		(pad "2" smd circle
			(at 0.40005 0)
			(size 0 0)
			(layers "F.Cu" "F.Mask" "F.Paste")
			(net "SMB_BMC_ALERT3_R_N")
		)
	)
	(footprint ""
		(layer "F.Cu")
		(at 56.5912 -95.95485 -90)
		(property "Reference" "R497"
			(at 0 0 270)
			(layer "F.SilkS")
			(hide yes)
			(effects
				(font
					(size 1.27 1.27)
				)
			)
		)
		(property "Value" ""
			(at 0 0 270)
			(layer "F.Fab")
			(effects
				(font
					(size 1.27 1.27)
				)
			)
		)
		(duplicate_pad_numbers_are_jumpers no)
		(fp_line
			(start -0.7874 0.4064)
			(end -0.7874 -0.4064)
			(stroke
				(width 0.1524)
				(type default)
			)
			(layer "F.SilkS")
		)
		(fp_line
			(start 0.7874 0.4064)
			(end -0.7874 0.4064)
			(stroke
				(width 0.1524)
				(type default)
			)
			(layer "F.SilkS")
		)
		(fp_line
			(start -0.7874 -0.4064)
			(end 0.7874 -0.4064)
			(stroke
				(width 0.1524)
				(type default)
			)
			(layer "F.SilkS")
		)
		(fp_line
			(start 0.7874 -0.4064)
			(end 0.7874 0.4064)
			(stroke
				(width 0.1524)
				(type default)
			)
			(layer "F.SilkS")
		)
		(fp_line
			(start -0.67945 0.3048)
			(end -0.67945 -0.305054)
			(stroke
				(width 0.1)
				(type default)
			)
			(layer "F.Fab")
		)
		(fp_line
			(start -0.12065 0.3048)
			(end -0.67945 0.3048)
			(stroke
				(width 0.1)
				(type default)
			)
			(layer "F.Fab")
		)
		(fp_line
			(start 0.120396 0.3048)
			(end 0.120396 0.2794)
			(stroke
				(width 0.1)
				(type default)
			)
			(layer "F.Fab")
		)
		(fp_line
			(start 0.67945 0.3048)
			(end 0.120396 0.3048)
			(stroke
				(width 0.1)
				(type default)
			)
			(layer "F.Fab")
		)
		(fp_line
			(start -0.12065 0.2794)
			(end -0.12065 0.3048)
			(stroke
				(width 0.1)
				(type default)
			)
			(layer "F.Fab")
		)
		(fp_line
			(start 0.120396 0.2794)
			(end -0.12065 0.2794)
			(stroke
				(width 0.1)
				(type default)
			)
			(layer "F.Fab")
		)
		(fp_line
			(start -0.12065 -0.2794)
			(end 0.12065 -0.2794)
			(stroke
				(width 0.1)
				(type default)
			)
			(layer "F.Fab")
		)
		(fp_line
			(start 0.12065 -0.2794)
			(end 0.12065 -0.3048)
			(stroke
				(width 0.1)
				(type default)
			)
			(layer "F.Fab")
		)
		(fp_line
			(start 0.12065 -0.3048)
			(end 0.67945 -0.3048)
			(stroke
				(width 0.1)
				(type default)
			)
			(layer "F.Fab")
		)
		(fp_line
			(start 0.67945 -0.3048)
			(end 0.67945 0.3048)
			(stroke
				(width 0.1)
				(type default)
			)
			(layer "F.Fab")
		)
		(fp_line
			(start -0.67945 -0.305054)
			(end -0.12065 -0.305054)
			(stroke
				(width 0.1)
				(type default)
			)
			(layer "F.Fab")
		)
		(fp_line
			(start -0.12065 -0.305054)
			(end -0.12065 -0.2794)
			(stroke
				(width 0.1)
				(type default)
			)
			(layer "F.Fab")
		)
		(pad "1" smd circle
			(at -0.40005 0 270)
			(size 0 0)
			(layers "F.Cu" "F.Mask" "F.Paste")
			(net "P3V3_AUX")
		)
		(pad "2" smd circle
			(at 0.40005 0 270)
			(size 0 0)
			(layers "F.Cu" "F.Mask" "F.Paste")
			(net "IRQ_PCH_TPM_SPI_N")
		)
	)
	(footprint ""
		(layer "F.Cu")
		(at 41.9608 -81.026 90)
		(property "Reference" "R553"
			(at 0 0 90)
			(layer "F.SilkS")
			(hide yes)
			(effects
				(font
					(size 1.27 1.27)
				)
			)
		)
		(property "Value" ""
			(at 0 0 90)
			(layer "F.Fab")
			(effects
				(font
					(size 1.27 1.27)
				)
			)
		)
		(duplicate_pad_numbers_are_jumpers no)
		(fp_line
			(start 0.7874 -0.4064)
			(end 0.7874 0.4064)
			(stroke
				(width 0.1524)
				(type default)
			)
			(layer "F.SilkS")
		)
		(fp_line
			(start -0.7874 -0.4064)
			(end 0.7874 -0.4064)
			(stroke
				(width 0.1524)
				(type default)
			)
			(layer "F.SilkS")
		)
		(fp_line
			(start 0.7874 0.4064)
			(end -0.7874 0.4064)
			(stroke
				(width 0.1524)
				(type default)
			)
			(layer "F.SilkS")
		)
		(fp_line
			(start -0.7874 0.4064)
			(end -0.7874 -0.4064)
			(stroke
				(width 0.1524)
				(type default)
			)
			(layer "F.SilkS")
		)
		(fp_line
			(start -0.12065 -0.305054)
			(end -0.12065 -0.2794)
			(stroke
				(width 0.1)
				(type default)
			)
			(layer "F.Fab")
		)
		(fp_line
			(start -0.67945 -0.305054)
			(end -0.12065 -0.305054)
			(stroke
				(width 0.1)
				(type default)
			)
			(layer "F.Fab")
		)
		(fp_line
			(start 0.67945 -0.3048)
			(end 0.67945 0.3048)
			(stroke
				(width 0.1)
				(type default)
			)
			(layer "F.Fab")
		)
		(fp_line
			(start 0.12065 -0.3048)
			(end 0.67945 -0.3048)
			(stroke
				(width 0.1)
				(type default)
			)
			(layer "F.Fab")
		)
		(fp_line
			(start 0.12065 -0.2794)
			(end 0.12065 -0.3048)
			(stroke
				(width 0.1)
				(type default)
			)
			(layer "F.Fab")
		)
		(fp_line
			(start -0.12065 -0.2794)
			(end 0.12065 -0.2794)
			(stroke
				(width 0.1)
				(type default)
			)
			(layer "F.Fab")
		)
		(fp_line
			(start 0.120396 0.2794)
			(end -0.12065 0.2794)
			(stroke
				(width 0.1)
				(type default)
			)
			(layer "F.Fab")
		)
		(fp_line
			(start -0.12065 0.2794)
			(end -0.12065 0.3048)
			(stroke
				(width 0.1)
				(type default)
			)
			(layer "F.Fab")
		)
		(fp_line
			(start 0.67945 0.3048)
			(end 0.120396 0.3048)
			(stroke
				(width 0.1)
				(type default)
			)
			(layer "F.Fab")
		)
		(fp_line
			(start 0.120396 0.3048)
			(end 0.120396 0.2794)
			(stroke
				(width 0.1)
				(type default)
			)
			(layer "F.Fab")
		)
		(fp_line
			(start -0.12065 0.3048)
			(end -0.67945 0.3048)
			(stroke
				(width 0.1)
				(type default)
			)
			(layer "F.Fab")
		)
		(fp_line
			(start -0.67945 0.3048)
			(end -0.67945 -0.305054)
			(stroke
				(width 0.1)
				(type default)
			)
			(layer "F.Fab")
		)
		(pad "1" smd circle
			(at -0.40005 0 90)
			(size 0 0)
			(layers "F.Cu" "F.Mask" "F.Paste")
			(net "SPI_BMC_CS0_FLASH_R_N")
		)
		(pad "2" smd circle
			(at 0.40005 0 90)
			(size 0 0)
			(layers "F.Cu" "F.Mask" "F.Paste")
			(net "SPI_BMC_BOOT_CS0_R_N")
		)
	)
	(footprint ""
		(layer "F.Cu")
		(at 10.287 -94.615 90)
		(property "Reference" "R515"
			(at 0 0 90)
			(layer "F.SilkS")
			(hide yes)
			(effects
				(font
					(size 1.27 1.27)
				)
			)
		)
		(property "Value" ""
			(at 0 0 90)
			(layer "F.Fab")
			(effects
				(font
					(size 1.27 1.27)
				)
			)
		)
		(duplicate_pad_numbers_are_jumpers no)
		(fp_line
			(start 0.7874 -0.4064)
			(end 0.7874 0.4064)
			(stroke
				(width 0.1524)
				(type default)
			)
			(layer "F.SilkS")
		)
		(fp_line
			(start -0.7874 -0.4064)
			(end 0.7874 -0.4064)
			(stroke
				(width 0.1524)
				(type default)
			)
			(layer "F.SilkS")
		)
		(fp_line
			(start 0.7874 0.4064)
			(end -0.7874 0.4064)
			(stroke
				(width 0.1524)
				(type default)
			)
			(layer "F.SilkS")
		)
		(fp_line
			(start -0.7874 0.4064)
			(end -0.7874 -0.4064)
			(stroke
				(width 0.1524)
				(type default)
			)
			(layer "F.SilkS")
		)
		(fp_line
			(start -0.12065 -0.305054)
			(end -0.12065 -0.2794)
			(stroke
				(width 0.1)
				(type default)
			)
			(layer "F.Fab")
		)
		(fp_line
			(start -0.67945 -0.305054)
			(end -0.12065 -0.305054)
			(stroke
				(width 0.1)
				(type default)
			)
			(layer "F.Fab")
		)
		(fp_line
			(start 0.67945 -0.3048)
			(end 0.67945 0.3048)
			(stroke
				(width 0.1)
				(type default)
			)
			(layer "F.Fab")
		)
		(fp_line
			(start 0.12065 -0.3048)
			(end 0.67945 -0.3048)
			(stroke
				(width 0.1)
				(type default)
			)
			(layer "F.Fab")
		)
		(fp_line
			(start 0.12065 -0.2794)
			(end 0.12065 -0.3048)
			(stroke
				(width 0.1)
				(type default)
			)
			(layer "F.Fab")
		)
		(fp_line
			(start -0.12065 -0.2794)
			(end 0.12065 -0.2794)
			(stroke
				(width 0.1)
				(type default)
			)
			(layer "F.Fab")
		)
		(fp_line
			(start 0.120396 0.2794)
			(end -0.12065 0.2794)
			(stroke
				(width 0.1)
				(type default)
			)
			(layer "F.Fab")
		)
		(fp_line
			(start -0.12065 0.2794)
			(end -0.12065 0.3048)
			(stroke
				(width 0.1)
				(type default)
			)
			(layer "F.Fab")
		)
		(fp_line
			(start 0.67945 0.3048)
			(end 0.120396 0.3048)
			(stroke
				(width 0.1)
				(type default)
			)
			(layer "F.Fab")
		)
		(fp_line
			(start 0.120396 0.3048)
			(end 0.120396 0.2794)
			(stroke
				(width 0.1)
				(type default)
			)
			(layer "F.Fab")
		)
		(fp_line
			(start -0.12065 0.3048)
			(end -0.67945 0.3048)
			(stroke
				(width 0.1)
				(type default)
			)
			(layer "F.Fab")
		)
		(fp_line
			(start -0.67945 0.3048)
			(end -0.67945 -0.305054)
			(stroke
				(width 0.1)
				(type default)
			)
			(layer "F.Fab")
		)
		(pad "1" smd circle
			(at -0.40005 0 90)
			(size 0 0)
			(layers "F.Cu" "F.Mask" "F.Paste")
			(net "JTAG_SCM_PLD_TMS")
		)
		(pad "2" smd circle
			(at 0.40005 0 90)
			(size 0 0)
			(layers "F.Cu" "F.Mask" "F.Paste")
			(net "JTAG_SCM_CONN_TMS")
		)
	)
	(footprint ""
		(layer "F.Cu")
		(at 21.209 -68.834 -90)
		(property "Reference" "R561"
			(at 0 0 270)
			(layer "F.SilkS")
			(hide yes)
			(effects
				(font
					(size 1.27 1.27)
				)
			)
		)
		(property "Value" ""
			(at 0 0 270)
			(layer "F.Fab")
			(effects
				(font
					(size 1.27 1.27)
				)
			)
		)
		(duplicate_pad_numbers_are_jumpers no)
		(fp_line
			(start -0.7874 0.4064)
			(end -0.7874 -0.4064)
			(stroke
				(width 0.1524)
				(type default)
			)
			(layer "F.SilkS")
		)
		(fp_line
			(start 0.7874 0.4064)
			(end -0.7874 0.4064)
			(stroke
				(width 0.1524)
				(type default)
			)
			(layer "F.SilkS")
		)
		(fp_line
			(start -0.7874 -0.4064)
			(end 0.7874 -0.4064)
			(stroke
				(width 0.1524)
				(type default)
			)
			(layer "F.SilkS")
		)
		(fp_line
			(start 0.7874 -0.4064)
			(end 0.7874 0.4064)
			(stroke
				(width 0.1524)
				(type default)
			)
			(layer "F.SilkS")
		)
		(fp_line
			(start -0.67945 0.3048)
			(end -0.67945 -0.305054)
			(stroke
				(width 0.1)
				(type default)
			)
			(layer "F.Fab")
		)
		(fp_line
			(start -0.12065 0.3048)
			(end -0.67945 0.3048)
			(stroke
				(width 0.1)
				(type default)
			)
			(layer "F.Fab")
		)
		(fp_line
			(start 0.120396 0.3048)
			(end 0.120396 0.2794)
			(stroke
				(width 0.1)
				(type default)
			)
			(layer "F.Fab")
		)
		(fp_line
			(start 0.67945 0.3048)
			(end 0.120396 0.3048)
			(stroke
				(width 0.1)
				(type default)
			)
			(layer "F.Fab")
		)
		(fp_line
			(start -0.12065 0.2794)
			(end -0.12065 0.3048)
			(stroke
				(width 0.1)
				(type default)
			)
			(layer "F.Fab")
		)
		(fp_line
			(start 0.120396 0.2794)
			(end -0.12065 0.2794)
			(stroke
				(width 0.1)
				(type default)
			)
			(layer "F.Fab")
		)
		(fp_line
			(start -0.12065 -0.2794)
			(end 0.12065 -0.2794)
			(stroke
				(width 0.1)
				(type default)
			)
			(layer "F.Fab")
		)
		(fp_line
			(start 0.12065 -0.2794)
			(end 0.12065 -0.3048)
			(stroke
				(width 0.1)
				(type default)
			)
			(layer "F.Fab")
		)
		(fp_line
			(start 0.12065 -0.3048)
			(end 0.67945 -0.3048)
			(stroke
				(width 0.1)
				(type default)
			)
			(layer "F.Fab")
		)
		(fp_line
			(start 0.67945 -0.3048)
			(end 0.67945 0.3048)
			(stroke
				(width 0.1)
				(type default)
			)
			(layer "F.Fab")
		)
		(fp_line
			(start -0.67945 -0.305054)
			(end -0.12065 -0.305054)
			(stroke
				(width 0.1)
				(type default)
			)
			(layer "F.Fab")
		)
		(fp_line
			(start -0.12065 -0.305054)
			(end -0.12065 -0.2794)
			(stroke
				(width 0.1)
				(type default)
			)
			(layer "F.Fab")
		)
		(pad "1" smd circle
			(at -0.40005 0 270)
			(size 0 0)
			(layers "F.Cu" "F.Mask" "F.Paste")
			(net "RST_SPI_BMC_FLASH_R2_N")
		)
		(pad "2" smd circle
			(at 0.40005 0 270)
			(size 0 0)
			(layers "F.Cu" "F.Mask" "F.Paste")
			(net "RST_SPI_FLASH_BUF_N")
		)
	)
	(footprint ""
		(layer "F.Cu")
		(at 34.93135 -36.151058 90)
		(property "Reference" "R49"
			(at 0 0 90)
			(layer "F.SilkS")
			(hide yes)
			(effects
				(font
					(size 1.27 1.27)
				)
			)
		)
		(property "Value" ""
			(at 0 0 90)
			(layer "F.Fab")
			(effects
				(font
					(size 1.27 1.27)
				)
			)
		)
		(duplicate_pad_numbers_are_jumpers no)
		(fp_line
			(start 0.7874 -0.4064)
			(end 0.7874 0.4064)
			(stroke
				(width 0.1524)
				(type default)
			)
			(layer "F.SilkS")
		)
		(fp_line
			(start -0.7874 -0.4064)
			(end 0.7874 -0.4064)
			(stroke
				(width 0.1524)
				(type default)
			)
			(layer "F.SilkS")
		)
		(fp_line
			(start 0.7874 0.4064)
			(end -0.7874 0.4064)
			(stroke
				(width 0.1524)
				(type default)
			)
			(layer "F.SilkS")
		)
		(fp_line
			(start -0.7874 0.4064)
			(end -0.7874 -0.4064)
			(stroke
				(width 0.1524)
				(type default)
			)
			(layer "F.SilkS")
		)
		(fp_line
			(start -0.12065 -0.305054)
			(end -0.12065 -0.2794)
			(stroke
				(width 0.1)
				(type default)
			)
			(layer "F.Fab")
		)
		(fp_line
			(start -0.67945 -0.305054)
			(end -0.12065 -0.305054)
			(stroke
				(width 0.1)
				(type default)
			)
			(layer "F.Fab")
		)
		(fp_line
			(start 0.67945 -0.3048)
			(end 0.67945 0.3048)
			(stroke
				(width 0.1)
				(type default)
			)
			(layer "F.Fab")
		)
		(fp_line
			(start 0.12065 -0.3048)
			(end 0.67945 -0.3048)
			(stroke
				(width 0.1)
				(type default)
			)
			(layer "F.Fab")
		)
		(fp_line
			(start 0.12065 -0.2794)
			(end 0.12065 -0.3048)
			(stroke
				(width 0.1)
				(type default)
			)
			(layer "F.Fab")
		)
		(fp_line
			(start -0.12065 -0.2794)
			(end 0.12065 -0.2794)
			(stroke
				(width 0.1)
				(type default)
			)
			(layer "F.Fab")
		)
		(fp_line
			(start 0.120396 0.2794)
			(end -0.12065 0.2794)
			(stroke
				(width 0.1)
				(type default)
			)
			(layer "F.Fab")
		)
		(fp_line
			(start -0.12065 0.2794)
			(end -0.12065 0.3048)
			(stroke
				(width 0.1)
				(type default)
			)
			(layer "F.Fab")
		)
		(fp_line
			(start 0.67945 0.3048)
			(end 0.120396 0.3048)
			(stroke
				(width 0.1)
				(type default)
			)
			(layer "F.Fab")
		)
		(fp_line
			(start 0.120396 0.3048)
			(end 0.120396 0.2794)
			(stroke
				(width 0.1)
				(type default)
			)
			(layer "F.Fab")
		)
		(fp_line
			(start -0.12065 0.3048)
			(end -0.67945 0.3048)
			(stroke
				(width 0.1)
				(type default)
			)
			(layer "F.Fab")
		)
		(fp_line
			(start -0.67945 0.3048)
			(end -0.67945 -0.305054)
			(stroke
				(width 0.1)
				(type default)
			)
			(layer "F.Fab")
		)
		(pad "1" smd circle
			(at -0.40005 0 90)
			(size 0 0)
			(layers "F.Cu" "F.Mask" "F.Paste")
			(net "PWRGD_P1V0_AUX")
		)
		(pad "2" smd circle
			(at 0.40005 0 90)
			(size 0 0)
			(layers "F.Cu" "F.Mask" "F.Paste")
			(net "PWRGD_P1V0_AUX_R2")
		)
	)
	(footprint ""
		(layer "F.Cu")
		(at 70.600062 -3.3401)
		(property "Reference" "SW8"
			(at -5.516626 -6.306566 0)
			(unlocked yes)
			(layer "F.SilkS")
			(effects
				(font
					(size 0.7874 0.5842)
					(thickness 0.1524)
				)
				(justify left)
			)
		)
		(property "Value" ""
			(at 0 0 0)
			(layer "F.Fab")
			(effects
				(font
					(size 1.27 1.27)
				)
			)
		)
		(duplicate_pad_numbers_are_jumpers no)
		(fp_line
			(start -3.700018 -4.549902)
			(end -3.700018 -2.51206)
			(stroke
				(width 0.1524)
				(type default)
			)
			(layer "F.SilkS")
		)
		(fp_line
			(start -3.700018 -0.98806)
			(end -3.700018 -0.88646)
			(stroke
				(width 0.1524)
				(type default)
			)
			(layer "F.SilkS")
		)
		(fp_line
			(start -3.700018 1.39954)
			(end -3.700018 1.549908)
			(stroke
				(width 0.1524)
				(type default)
			)
			(layer "F.SilkS")
		)
		(fp_line
			(start -3.700018 1.549908)
			(end -1.75006 1.549908)
			(stroke
				(width 0.1524)
				(type default)
			)
			(layer "F.SilkS")
		)
		(fp_line
			(start -3.1496 -4.549902)
			(end -3.700018 -4.549902)
			(stroke
				(width 0.1524)
				(type default)
			)
			(layer "F.SilkS")
		)
		(fp_line
			(start -1.75006 1.549908)
			(end -1.75006 4.549902)
			(stroke
				(width 0.1524)
				(type default)
			)
			(layer "F.SilkS")
		)
		(fp_line
			(start -1.75006 4.549902)
			(end 1.75006 4.549902)
			(stroke
				(width 0.1524)
				(type default)
			)
			(layer "F.SilkS")
		)
		(fp_line
			(start 1.3716 -4.549902)
			(end -1.3716 -4.549902)
			(stroke
				(width 0.1524)
				(type default)
			)
			(layer "F.SilkS")
		)
		(fp_line
			(start 1.75006 1.549908)
			(end 3.700018 1.549908)
			(stroke
				(width 0.1524)
				(type default)
			)
			(layer "F.SilkS")
		)
		(fp_line
			(start 1.75006 4.549902)
			(end 1.75006 1.549908)
			(stroke
				(width 0.1524)
				(type default)
			)
			(layer "F.SilkS")
		)
		(fp_line
			(start 3.700018 -4.549902)
			(end 3.1496 -4.549902)
			(stroke
				(width 0.1524)
				(type default)
			)
			(layer "F.SilkS")
		)
		(fp_line
			(start 3.700018 -2.51206)
			(end 3.700018 -4.549902)
			(stroke
				(width 0.1524)
				(type default)
			)
			(layer "F.SilkS")
		)
		(fp_line
			(start 3.700018 -0.88646)
			(end 3.700018 -0.98806)
			(stroke
				(width 0.1524)
				(type default)
			)
			(layer "F.SilkS")
		)
		(fp_line
			(start 3.700018 1.549908)
			(end 3.700018 1.39954)
			(stroke
				(width 0.1524)
				(type default)
			)
			(layer "F.SilkS")
		)
		(fp_poly
			(pts
				(xy -2.249932 -5.286502) (xy -2.963418 -6.713474) (xy -1.536446 -6.713474)
			)
			(stroke
				(width 0)
				(type default)
			)
			(fill yes)
			(layer "F.SilkS")
		)
		(fp_line
			(start -3.700018 -4.549902)
			(end -3.700018 1.549908)
			(stroke
				(width 0.1)
				(type default)
			)
			(layer "F.Fab")
		)
		(fp_line
			(start -3.700018 1.549908)
			(end -1.75006 1.549908)
			(stroke
				(width 0.1)
				(type default)
			)
			(layer "F.Fab")
		)
		(fp_line
			(start -1.75006 1.549908)
			(end -1.75006 4.549902)
			(stroke
				(width 0.1)
				(type default)
			)
			(layer "F.Fab")
		)
		(fp_line
			(start -1.75006 4.549902)
			(end 1.75006 4.549902)
			(stroke
				(width 0.1)
				(type default)
			)
			(layer "F.Fab")
		)
		(fp_line
			(start 1.75006 1.549908)
			(end 3.700018 1.549908)
			(stroke
				(width 0.1)
				(type default)
			)
			(layer "F.Fab")
		)
		(fp_line
			(start 1.75006 4.549902)
			(end 1.75006 1.549908)
			(stroke
				(width 0.1)
				(type default)
			)
			(layer "F.Fab")
		)
		(fp_line
			(start 3.700018 -4.549902)
			(end -3.700018 -4.549902)
			(stroke
				(width 0.1)
				(type default)
			)
			(layer "F.Fab")
		)
		(fp_line
			(start 3.700018 1.549908)
			(end 3.700018 -4.549902)
			(stroke
				(width 0.1)
				(type default)
			)
			(layer "F.Fab")
		)
		(fp_poly
			(pts
				(xy -3.883914 -4.043934) (xy -5.310886 -3.330448) (xy -5.310886 -4.75742)
			)
			(stroke
				(width 0)
				(type default)
			)
			(fill yes)
			(layer "F.Fab")
		)
		(pad "" np_thru_hole circle
			(at -3.50012 -1.75006)
			(size 0.9144 0.9144)
			(drill 0.9144)
			(layers "*.Cu" "*.Mask")
			(clearance 0.381)
			(thermal_gap 0.381)
		)
		(pad "" np_thru_hole circle
			(at 3.50012 -1.75006)
			(size 0.9144 0.9144)
			(drill 0.9144)
			(layers "*.Cu" "*.Mask")
			(clearance 0.381)
			(thermal_gap 0.381)
		)
		(pad "1" smd rect
			(at -2.249932 -4.05003)
			(size 1.4986 2.0066)
			(layers "F.Cu" "F.Mask" "F.Paste")
			(net "GND")
		)
		(pad "2" smd rect
			(at 2.249932 -4.05003)
			(size 1.4986 2.0066)
			(layers "F.Cu" "F.Mask" "F.Paste")
			(net "REAR_AC_PWR_BTN")
		)
		(pad "3" smd rect
			(at -4.19989 0.249936)
			(size 2.0066 2.0066)
			(layers "F.Cu" "F.Mask" "F.Paste")
			(net "GND")
		)
		(pad "4" smd rect
			(at 4.19989 0.249936)
			(size 2.0066 2.0066)
			(layers "F.Cu" "F.Mask" "F.Paste")
			(net "GND")
		)
		(zone
			(layers "F.Cu" "B.Cu" "In1.Cu" "In2.Cu" "In3.Cu" "In4.Cu" "In5.Cu" "In6.Cu"
				"In7.Cu" "In8.Cu" "In9.Cu" "In10.Cu"
			)
			(hatch none 0.5)
			(connect_pads
				(clearance 0)
			)
			(min_thickness 0.25)
			(keepout
				(tracks not_allowed)
				(vias allowed)
				(pads allowed)
				(copperpour not_allowed)
				(footprints allowed)
			)
			(placement
				(enabled no)
				(sheetname "")
			)
			(fill
				(thermal_gap 0.5)
				(thermal_bridge_width 0.5)
				(island_removal_mode 0)
			)
			(polygon
				(pts
					(arc
						(start 67.963796 -5.09016)
						(mid 66.236088 -5.09016)
						(end 67.963796 -5.09016)
					)
				)
			)
		)
		(zone
			(layers "F.Cu" "B.Cu" "In1.Cu" "In2.Cu" "In3.Cu" "In4.Cu" "In5.Cu" "In6.Cu"
				"In7.Cu" "In8.Cu" "In9.Cu" "In10.Cu"
			)
			(hatch none 0.5)
			(connect_pads
				(clearance 0)
			)
			(min_thickness 0.25)
			(keepout
				(tracks not_allowed)
				(vias allowed)
				(pads allowed)
				(copperpour not_allowed)
				(footprints allowed)
			)
			(placement
				(enabled no)
				(sheetname "")
			)
			(fill
				(thermal_gap 0.5)
				(thermal_bridge_width 0.5)
				(island_removal_mode 0)
			)
			(polygon
				(pts
					(arc
						(start 74.963782 -5.09016)
						(mid 73.236582 -5.09016)
						(end 74.963782 -5.09016)
					)
				)
			)
		)
	)
	(footprint ""
		(layer "F.Cu")
		(at 10.287 -92.837 90)
		(property "Reference" "R285"
			(at 0 0 90)
			(layer "F.SilkS")
			(hide yes)
			(effects
				(font
					(size 1.27 1.27)
				)
			)
		)
		(property "Value" ""
			(at 0 0 90)
			(layer "F.Fab")
			(effects
				(font
					(size 1.27 1.27)
				)
			)
		)
		(duplicate_pad_numbers_are_jumpers no)
		(fp_line
			(start 0.7874 -0.4064)
			(end 0.7874 0.4064)
			(stroke
				(width 0.1524)
				(type default)
			)
			(layer "F.SilkS")
		)
		(fp_line
			(start -0.7874 -0.4064)
			(end 0.7874 -0.4064)
			(stroke
				(width 0.1524)
				(type default)
			)
			(layer "F.SilkS")
		)
		(fp_line
			(start 0.7874 0.4064)
			(end -0.7874 0.4064)
			(stroke
				(width 0.1524)
				(type default)
			)
			(layer "F.SilkS")
		)
		(fp_line
			(start -0.7874 0.4064)
			(end -0.7874 -0.4064)
			(stroke
				(width 0.1524)
				(type default)
			)
			(layer "F.SilkS")
		)
		(fp_line
			(start -0.12065 -0.305054)
			(end -0.12065 -0.2794)
			(stroke
				(width 0.1)
				(type default)
			)
			(layer "F.Fab")
		)
		(fp_line
			(start -0.67945 -0.305054)
			(end -0.12065 -0.305054)
			(stroke
				(width 0.1)
				(type default)
			)
			(layer "F.Fab")
		)
		(fp_line
			(start 0.67945 -0.3048)
			(end 0.67945 0.3048)
			(stroke
				(width 0.1)
				(type default)
			)
			(layer "F.Fab")
		)
		(fp_line
			(start 0.12065 -0.3048)
			(end 0.67945 -0.3048)
			(stroke
				(width 0.1)
				(type default)
			)
			(layer "F.Fab")
		)
		(fp_line
			(start 0.12065 -0.2794)
			(end 0.12065 -0.3048)
			(stroke
				(width 0.1)
				(type default)
			)
			(layer "F.Fab")
		)
		(fp_line
			(start -0.12065 -0.2794)
			(end 0.12065 -0.2794)
			(stroke
				(width 0.1)
				(type default)
			)
			(layer "F.Fab")
		)
		(fp_line
			(start 0.120396 0.2794)
			(end -0.12065 0.2794)
			(stroke
				(width 0.1)
				(type default)
			)
			(layer "F.Fab")
		)
		(fp_line
			(start -0.12065 0.2794)
			(end -0.12065 0.3048)
			(stroke
				(width 0.1)
				(type default)
			)
			(layer "F.Fab")
		)
		(fp_line
			(start 0.67945 0.3048)
			(end 0.120396 0.3048)
			(stroke
				(width 0.1)
				(type default)
			)
			(layer "F.Fab")
		)
		(fp_line
			(start 0.120396 0.3048)
			(end 0.120396 0.2794)
			(stroke
				(width 0.1)
				(type default)
			)
			(layer "F.Fab")
		)
		(fp_line
			(start -0.12065 0.3048)
			(end -0.67945 0.3048)
			(stroke
				(width 0.1)
				(type default)
			)
			(layer "F.Fab")
		)
		(fp_line
			(start -0.67945 0.3048)
			(end -0.67945 -0.305054)
			(stroke
				(width 0.1)
				(type default)
			)
			(layer "F.Fab")
		)
		(pad "1" smd circle
			(at -0.40005 0 90)
			(size 0 0)
			(layers "F.Cu" "F.Mask" "F.Paste")
			(net "JTAG_SCM_PLD_TCK")
		)
		(pad "2" smd circle
			(at 0.40005 0 90)
			(size 0 0)
			(layers "F.Cu" "F.Mask" "F.Paste")
			(net "GND")
		)
	)
	(footprint ""
		(layer "F.Cu")
		(at 61.5188 -30.861 90)
		(property "Reference" "R202"
			(at 0 0 90)
			(layer "F.SilkS")
			(hide yes)
			(effects
				(font
					(size 1.27 1.27)
				)
			)
		)
		(property "Value" ""
			(at 0 0 90)
			(layer "F.Fab")
			(effects
				(font
					(size 1.27 1.27)
				)
			)
		)
		(duplicate_pad_numbers_are_jumpers no)
		(fp_line
			(start 0.7874 -0.4064)
			(end 0.7874 0.4064)
			(stroke
				(width 0.1524)
				(type default)
			)
			(layer "F.SilkS")
		)
		(fp_line
			(start -0.7874 -0.4064)
			(end 0.7874 -0.4064)
			(stroke
				(width 0.1524)
				(type default)
			)
			(layer "F.SilkS")
		)
		(fp_line
			(start 0.7874 0.4064)
			(end -0.7874 0.4064)
			(stroke
				(width 0.1524)
				(type default)
			)
			(layer "F.SilkS")
		)
		(fp_line
			(start -0.7874 0.4064)
			(end -0.7874 -0.4064)
			(stroke
				(width 0.1524)
				(type default)
			)
			(layer "F.SilkS")
		)
		(fp_line
			(start -0.12065 -0.305054)
			(end -0.12065 -0.2794)
			(stroke
				(width 0.1)
				(type default)
			)
			(layer "F.Fab")
		)
		(fp_line
			(start -0.67945 -0.305054)
			(end -0.12065 -0.305054)
			(stroke
				(width 0.1)
				(type default)
			)
			(layer "F.Fab")
		)
		(fp_line
			(start 0.67945 -0.3048)
			(end 0.67945 0.3048)
			(stroke
				(width 0.1)
				(type default)
			)
			(layer "F.Fab")
		)
		(fp_line
			(start 0.12065 -0.3048)
			(end 0.67945 -0.3048)
			(stroke
				(width 0.1)
				(type default)
			)
			(layer "F.Fab")
		)
		(fp_line
			(start 0.12065 -0.2794)
			(end 0.12065 -0.3048)
			(stroke
				(width 0.1)
				(type default)
			)
			(layer "F.Fab")
		)
		(fp_line
			(start -0.12065 -0.2794)
			(end 0.12065 -0.2794)
			(stroke
				(width 0.1)
				(type default)
			)
			(layer "F.Fab")
		)
		(fp_line
			(start 0.120396 0.2794)
			(end -0.12065 0.2794)
			(stroke
				(width 0.1)
				(type default)
			)
			(layer "F.Fab")
		)
		(fp_line
			(start -0.12065 0.2794)
			(end -0.12065 0.3048)
			(stroke
				(width 0.1)
				(type default)
			)
			(layer "F.Fab")
		)
		(fp_line
			(start 0.67945 0.3048)
			(end 0.120396 0.3048)
			(stroke
				(width 0.1)
				(type default)
			)
			(layer "F.Fab")
		)
		(fp_line
			(start 0.120396 0.3048)
			(end 0.120396 0.2794)
			(stroke
				(width 0.1)
				(type default)
			)
			(layer "F.Fab")
		)
		(fp_line
			(start -0.12065 0.3048)
			(end -0.67945 0.3048)
			(stroke
				(width 0.1)
				(type default)
			)
			(layer "F.Fab")
		)
		(fp_line
			(start -0.67945 0.3048)
			(end -0.67945 -0.305054)
			(stroke
				(width 0.1)
				(type default)
			)
			(layer "F.Fab")
		)
		(pad "1" smd circle
			(at -0.40005 0 90)
			(size 0 0)
			(layers "F.Cu" "F.Mask" "F.Paste")
			(net "GND")
		)
		(pad "2" smd circle
			(at 0.40005 0 90)
			(size 0 0)
			(layers "F.Cu" "F.Mask" "F.Paste")
			(net "JTAG_SCM_TCK")
		)
	)
	(footprint ""
		(layer "F.Cu")
		(at 51.562 -20.32)
		(property "Reference" "C177"
			(at 0 0 0)
			(layer "F.SilkS")
			(hide yes)
			(effects
				(font
					(size 1.27 1.27)
				)
			)
		)
		(property "Value" ""
			(at 0 0 0)
			(layer "F.Fab")
			(effects
				(font
					(size 1.27 1.27)
				)
			)
		)
		(duplicate_pad_numbers_are_jumpers no)
		(fp_line
			(start -2.2098 -0.9398)
			(end 2.2098 -0.9398)
			(stroke
				(width 0.1524)
				(type default)
			)
			(layer "F.SilkS")
		)
		(fp_line
			(start -2.2098 0.9398)
			(end -2.2098 -0.9398)
			(stroke
				(width 0.1524)
				(type default)
			)
			(layer "F.SilkS")
		)
		(fp_line
			(start 2.2098 -0.9398)
			(end 2.2098 0.9398)
			(stroke
				(width 0.1524)
				(type default)
			)
			(layer "F.SilkS")
		)
		(fp_line
			(start 2.2098 0.9398)
			(end -2.2098 0.9398)
			(stroke
				(width 0.1524)
				(type default)
			)
			(layer "F.SilkS")
		)
		(fp_line
			(start -1.700022 -0.899922)
			(end 1.700022 -0.899922)
			(stroke
				(width 0.1)
				(type default)
			)
			(layer "F.Fab")
		)
		(fp_line
			(start -1.700022 0.899922)
			(end -1.700022 -0.899922)
			(stroke
				(width 0.1)
				(type default)
			)
			(layer "F.Fab")
		)
		(fp_line
			(start 1.700022 -0.899922)
			(end 1.700022 0.899922)
			(stroke
				(width 0.1)
				(type default)
			)
			(layer "F.Fab")
		)
		(fp_line
			(start 1.700022 0.899922)
			(end -1.700022 0.899922)
			(stroke
				(width 0.1)
				(type default)
			)
			(layer "F.Fab")
		)
		(pad "1" smd rect
			(at -1.4732 0 180)
			(size 1.1684 1.5748)
			(layers "F.Cu" "F.Mask" "F.Paste")
			(net "P5V_USB_REAR")
		)
		(pad "2" smd rect
			(at 1.4732 0 180)
			(size 1.1684 1.5748)
			(layers "F.Cu" "F.Mask" "F.Paste")
			(net "GND")
		)
	)
	(footprint ""
		(layer "F.Cu")
		(at 76.499974 -107.700064)
		(property "Reference" "H3"
			(at 1.279652 -3.484118 0)
			(unlocked yes)
			(layer "F.SilkS")
			(effects
				(font
					(size 0.7874 0.5842)
					(thickness 0.1524)
				)
				(justify left)
			)
		)
		(property "Value" ""
			(at 0 0 0)
			(layer "F.Fab")
			(effects
				(font
					(size 1.27 1.27)
				)
			)
		)
		(duplicate_pad_numbers_are_jumpers no)
		(pad "1" thru_hole circle
			(at 0 0)
			(size 6.0198 6.0198)
			(drill 3.4036)
			(layers "*.Cu" "*.Mask")
			(remove_unused_layers no)
			(net "GND")
			(clearance -1.0541)
		)
	)
	(footprint ""
		(layer "F.Cu")
		(at 75.25004 -36.298378 180)
		(property "Reference" "C17"
			(at 0 0 180)
			(layer "F.SilkS")
			(hide yes)
			(effects
				(font
					(size 1.27 1.27)
				)
			)
		)
		(property "Value" ""
			(at 0 0 180)
			(layer "F.Fab")
			(effects
				(font
					(size 1.27 1.27)
				)
			)
		)
		(duplicate_pad_numbers_are_jumpers no)
		(fp_line
			(start 0.7874 0.4064)
			(end -0.7874 0.4064)
			(stroke
				(width 0.1524)
				(type default)
			)
			(layer "F.SilkS")
		)
		(fp_line
			(start 0.7874 -0.4064)
			(end 0.7874 0.4064)
			(stroke
				(width 0.1524)
				(type default)
			)
			(layer "F.SilkS")
		)
		(fp_line
			(start -0.7874 0.4064)
			(end -0.7874 -0.4064)
			(stroke
				(width 0.1524)
				(type default)
			)
			(layer "F.SilkS")
		)
		(fp_line
			(start -0.7874 -0.4064)
			(end 0.7874 -0.4064)
			(stroke
				(width 0.1524)
				(type default)
			)
			(layer "F.SilkS")
		)
		(fp_line
			(start 0.67945 0.3048)
			(end 0.120396 0.3048)
			(stroke
				(width 0.1)
				(type default)
			)
			(layer "F.Fab")
		)
		(fp_line
			(start 0.67945 -0.3048)
			(end 0.67945 0.3048)
			(stroke
				(width 0.1)
				(type default)
			)
			(layer "F.Fab")
		)
		(fp_line
			(start 0.12065 -0.2794)
			(end 0.12065 -0.3048)
			(stroke
				(width 0.1)
				(type default)
			)
			(layer "F.Fab")
		)
		(fp_line
			(start 0.12065 -0.3048)
			(end 0.67945 -0.3048)
			(stroke
				(width 0.1)
				(type default)
			)
			(layer "F.Fab")
		)
		(fp_line
			(start 0.120396 0.3048)
			(end 0.120396 0.2794)
			(stroke
				(width 0.1)
				(type default)
			)
			(layer "F.Fab")
		)
		(fp_line
			(start 0.120396 0.2794)
			(end -0.12065 0.2794)
			(stroke
				(width 0.1)
				(type default)
			)
			(layer "F.Fab")
		)
		(fp_line
			(start -0.12065 0.3048)
			(end -0.67945 0.3048)
			(stroke
				(width 0.1)
				(type default)
			)
			(layer "F.Fab")
		)
		(fp_line
			(start -0.12065 0.2794)
			(end -0.12065 0.3048)
			(stroke
				(width 0.1)
				(type default)
			)
			(layer "F.Fab")
		)
		(fp_line
			(start -0.12065 -0.2794)
			(end 0.12065 -0.2794)
			(stroke
				(width 0.1)
				(type default)
			)
			(layer "F.Fab")
		)
		(fp_line
			(start -0.12065 -0.305054)
			(end -0.12065 -0.2794)
			(stroke
				(width 0.1)
				(type default)
			)
			(layer "F.Fab")
		)
		(fp_line
			(start -0.67945 0.3048)
			(end -0.67945 -0.305054)
			(stroke
				(width 0.1)
				(type default)
			)
			(layer "F.Fab")
		)
		(fp_line
			(start -0.67945 -0.305054)
			(end -0.12065 -0.305054)
			(stroke
				(width 0.1)
				(type default)
			)
			(layer "F.Fab")
		)
		(pad "1" smd circle
			(at -0.40005 0 180)
			(size 0 0)
			(layers "F.Cu" "F.Mask" "F.Paste")
			(net "P1V2_AUX")
		)
		(pad "2" smd circle
			(at 0.40005 0 180)
			(size 0 0)
			(layers "F.Cu" "F.Mask" "F.Paste")
			(net "GND")
		)
	)
	(footprint ""
		(layer "F.Cu")
		(at 29.6164 -27.3304 180)
		(property "Reference" "R17"
			(at 0 0 180)
			(layer "F.SilkS")
			(hide yes)
			(effects
				(font
					(size 1.27 1.27)
				)
			)
		)
		(property "Value" ""
			(at 0 0 180)
			(layer "F.Fab")
			(effects
				(font
					(size 1.27 1.27)
				)
			)
		)
		(duplicate_pad_numbers_are_jumpers no)
		(fp_line
			(start 0.7874 0.4064)
			(end -0.7874 0.4064)
			(stroke
				(width 0.1524)
				(type default)
			)
			(layer "F.SilkS")
		)
		(fp_line
			(start 0.7874 -0.4064)
			(end 0.7874 0.4064)
			(stroke
				(width 0.1524)
				(type default)
			)
			(layer "F.SilkS")
		)
		(fp_line
			(start -0.7874 0.4064)
			(end -0.7874 -0.4064)
			(stroke
				(width 0.1524)
				(type default)
			)
			(layer "F.SilkS")
		)
		(fp_line
			(start -0.7874 -0.4064)
			(end 0.7874 -0.4064)
			(stroke
				(width 0.1524)
				(type default)
			)
			(layer "F.SilkS")
		)
		(fp_line
			(start 0.67945 0.3048)
			(end 0.120396 0.3048)
			(stroke
				(width 0.1)
				(type default)
			)
			(layer "F.Fab")
		)
		(fp_line
			(start 0.67945 -0.3048)
			(end 0.67945 0.3048)
			(stroke
				(width 0.1)
				(type default)
			)
			(layer "F.Fab")
		)
		(fp_line
			(start 0.12065 -0.2794)
			(end 0.12065 -0.3048)
			(stroke
				(width 0.1)
				(type default)
			)
			(layer "F.Fab")
		)
		(fp_line
			(start 0.12065 -0.3048)
			(end 0.67945 -0.3048)
			(stroke
				(width 0.1)
				(type default)
			)
			(layer "F.Fab")
		)
		(fp_line
			(start 0.120396 0.3048)
			(end 0.120396 0.2794)
			(stroke
				(width 0.1)
				(type default)
			)
			(layer "F.Fab")
		)
		(fp_line
			(start 0.120396 0.2794)
			(end -0.12065 0.2794)
			(stroke
				(width 0.1)
				(type default)
			)
			(layer "F.Fab")
		)
		(fp_line
			(start -0.12065 0.3048)
			(end -0.67945 0.3048)
			(stroke
				(width 0.1)
				(type default)
			)
			(layer "F.Fab")
		)
		(fp_line
			(start -0.12065 0.2794)
			(end -0.12065 0.3048)
			(stroke
				(width 0.1)
				(type default)
			)
			(layer "F.Fab")
		)
		(fp_line
			(start -0.12065 -0.2794)
			(end 0.12065 -0.2794)
			(stroke
				(width 0.1)
				(type default)
			)
			(layer "F.Fab")
		)
		(fp_line
			(start -0.12065 -0.305054)
			(end -0.12065 -0.2794)
			(stroke
				(width 0.1)
				(type default)
			)
			(layer "F.Fab")
		)
		(fp_line
			(start -0.67945 0.3048)
			(end -0.67945 -0.305054)
			(stroke
				(width 0.1)
				(type default)
			)
			(layer "F.Fab")
		)
		(fp_line
			(start -0.67945 -0.305054)
			(end -0.12065 -0.305054)
			(stroke
				(width 0.1)
				(type default)
			)
			(layer "F.Fab")
		)
		(pad "1" smd circle
			(at -0.40005 0 180)
			(size 0 0)
			(layers "F.Cu" "F.Mask" "F.Paste")
			(net "V_BMC_LS_DDC_SDA_R")
		)
		(pad "2" smd circle
			(at 0.40005 0 180)
			(size 0 0)
			(layers "F.Cu" "F.Mask" "F.Paste")
			(net "CRT_VCC5")
		)
	)
	(footprint ""
		(layer "F.Cu")
		(at 61.8998 -27.3304 -90)
		(property "Reference" "R273"
			(at 0 0 270)
			(layer "F.SilkS")
			(hide yes)
			(effects
				(font
					(size 1.27 1.27)
				)
			)
		)
		(property "Value" ""
			(at 0 0 270)
			(layer "F.Fab")
			(effects
				(font
					(size 1.27 1.27)
				)
			)
		)
		(duplicate_pad_numbers_are_jumpers no)
		(fp_line
			(start -0.7874 0.4064)
			(end -0.7874 -0.4064)
			(stroke
				(width 0.1524)
				(type default)
			)
			(layer "F.SilkS")
		)
		(fp_line
			(start 0.7874 0.4064)
			(end -0.7874 0.4064)
			(stroke
				(width 0.1524)
				(type default)
			)
			(layer "F.SilkS")
		)
		(fp_line
			(start -0.7874 -0.4064)
			(end 0.7874 -0.4064)
			(stroke
				(width 0.1524)
				(type default)
			)
			(layer "F.SilkS")
		)
		(fp_line
			(start 0.7874 -0.4064)
			(end 0.7874 0.4064)
			(stroke
				(width 0.1524)
				(type default)
			)
			(layer "F.SilkS")
		)
		(fp_line
			(start -0.67945 0.3048)
			(end -0.67945 -0.305054)
			(stroke
				(width 0.1)
				(type default)
			)
			(layer "F.Fab")
		)
		(fp_line
			(start -0.12065 0.3048)
			(end -0.67945 0.3048)
			(stroke
				(width 0.1)
				(type default)
			)
			(layer "F.Fab")
		)
		(fp_line
			(start 0.120396 0.3048)
			(end 0.120396 0.2794)
			(stroke
				(width 0.1)
				(type default)
			)
			(layer "F.Fab")
		)
		(fp_line
			(start 0.67945 0.3048)
			(end 0.120396 0.3048)
			(stroke
				(width 0.1)
				(type default)
			)
			(layer "F.Fab")
		)
		(fp_line
			(start -0.12065 0.2794)
			(end -0.12065 0.3048)
			(stroke
				(width 0.1)
				(type default)
			)
			(layer "F.Fab")
		)
		(fp_line
			(start 0.120396 0.2794)
			(end -0.12065 0.2794)
			(stroke
				(width 0.1)
				(type default)
			)
			(layer "F.Fab")
		)
		(fp_line
			(start -0.12065 -0.2794)
			(end 0.12065 -0.2794)
			(stroke
				(width 0.1)
				(type default)
			)
			(layer "F.Fab")
		)
		(fp_line
			(start 0.12065 -0.2794)
			(end 0.12065 -0.3048)
			(stroke
				(width 0.1)
				(type default)
			)
			(layer "F.Fab")
		)
		(fp_line
			(start 0.12065 -0.3048)
			(end 0.67945 -0.3048)
			(stroke
				(width 0.1)
				(type default)
			)
			(layer "F.Fab")
		)
		(fp_line
			(start 0.67945 -0.3048)
			(end 0.67945 0.3048)
			(stroke
				(width 0.1)
				(type default)
			)
			(layer "F.Fab")
		)
		(fp_line
			(start -0.67945 -0.305054)
			(end -0.12065 -0.305054)
			(stroke
				(width 0.1)
				(type default)
			)
			(layer "F.Fab")
		)
		(fp_line
			(start -0.12065 -0.305054)
			(end -0.12065 -0.2794)
			(stroke
				(width 0.1)
				(type default)
			)
			(layer "F.Fab")
		)
		(pad "1" smd circle
			(at -0.40005 0 270)
			(size 0 0)
			(layers "F.Cu" "F.Mask" "F.Paste")
			(net "PD_CLK_125M_PHY_BMC_RGMII")
		)
		(pad "2" smd circle
			(at 0.40005 0 270)
			(size 0 0)
			(layers "F.Cu" "F.Mask" "F.Paste")
			(net "GND")
		)
	)
	(footprint ""
		(layer "F.Cu")
		(at 15.548864 -57.7342 90)
		(property "Reference" "R902"
			(at 0 0 90)
			(layer "F.SilkS")
			(hide yes)
			(effects
				(font
					(size 1.27 1.27)
				)
			)
		)
		(property "Value" ""
			(at 0 0 90)
			(layer "F.Fab")
			(effects
				(font
					(size 1.27 1.27)
				)
			)
		)
		(duplicate_pad_numbers_are_jumpers no)
		(fp_line
			(start 0.7874 -0.4064)
			(end 0.7874 0.4064)
			(stroke
				(width 0.1524)
				(type default)
			)
			(layer "F.SilkS")
		)
		(fp_line
			(start -0.7874 -0.4064)
			(end 0.7874 -0.4064)
			(stroke
				(width 0.1524)
				(type default)
			)
			(layer "F.SilkS")
		)
		(fp_line
			(start 0.7874 0.4064)
			(end -0.7874 0.4064)
			(stroke
				(width 0.1524)
				(type default)
			)
			(layer "F.SilkS")
		)
		(fp_line
			(start -0.7874 0.4064)
			(end -0.7874 -0.4064)
			(stroke
				(width 0.1524)
				(type default)
			)
			(layer "F.SilkS")
		)
		(fp_line
			(start -0.12065 -0.305054)
			(end -0.12065 -0.2794)
			(stroke
				(width 0.1)
				(type default)
			)
			(layer "F.Fab")
		)
		(fp_line
			(start -0.67945 -0.305054)
			(end -0.12065 -0.305054)
			(stroke
				(width 0.1)
				(type default)
			)
			(layer "F.Fab")
		)
		(fp_line
			(start 0.67945 -0.3048)
			(end 0.67945 0.3048)
			(stroke
				(width 0.1)
				(type default)
			)
			(layer "F.Fab")
		)
		(fp_line
			(start 0.12065 -0.3048)
			(end 0.67945 -0.3048)
			(stroke
				(width 0.1)
				(type default)
			)
			(layer "F.Fab")
		)
		(fp_line
			(start 0.12065 -0.2794)
			(end 0.12065 -0.3048)
			(stroke
				(width 0.1)
				(type default)
			)
			(layer "F.Fab")
		)
		(fp_line
			(start -0.12065 -0.2794)
			(end 0.12065 -0.2794)
			(stroke
				(width 0.1)
				(type default)
			)
			(layer "F.Fab")
		)
		(fp_line
			(start 0.120396 0.2794)
			(end -0.12065 0.2794)
			(stroke
				(width 0.1)
				(type default)
			)
			(layer "F.Fab")
		)
		(fp_line
			(start -0.12065 0.2794)
			(end -0.12065 0.3048)
			(stroke
				(width 0.1)
				(type default)
			)
			(layer "F.Fab")
		)
		(fp_line
			(start 0.67945 0.3048)
			(end 0.120396 0.3048)
			(stroke
				(width 0.1)
				(type default)
			)
			(layer "F.Fab")
		)
		(fp_line
			(start 0.120396 0.3048)
			(end 0.120396 0.2794)
			(stroke
				(width 0.1)
				(type default)
			)
			(layer "F.Fab")
		)
		(fp_line
			(start -0.12065 0.3048)
			(end -0.67945 0.3048)
			(stroke
				(width 0.1)
				(type default)
			)
			(layer "F.Fab")
		)
		(fp_line
			(start -0.67945 0.3048)
			(end -0.67945 -0.305054)
			(stroke
				(width 0.1)
				(type default)
			)
			(layer "F.Fab")
		)
		(pad "1" smd circle
			(at -0.40005 0 90)
			(size 0 0)
			(layers "F.Cu" "F.Mask" "F.Paste")
			(net "UART_BIC_DBG_RX")
		)
		(pad "2" smd circle
			(at 0.40005 0 90)
			(size 0 0)
			(layers "F.Cu" "F.Mask" "F.Paste")
			(net "UART_BIC_DBG_RX_R")
		)
	)
	(footprint ""
		(layer "F.Cu")
		(at 29.845 -105.41 180)
		(property "Reference" "R633"
			(at 0 0 180)
			(layer "F.SilkS")
			(hide yes)
			(effects
				(font
					(size 1.27 1.27)
				)
			)
		)
		(property "Value" ""
			(at 0 0 180)
			(layer "F.Fab")
			(effects
				(font
					(size 1.27 1.27)
				)
			)
		)
		(duplicate_pad_numbers_are_jumpers no)
		(fp_line
			(start 0.7874 0.4064)
			(end -0.7874 0.4064)
			(stroke
				(width 0.1524)
				(type default)
			)
			(layer "F.SilkS")
		)
		(fp_line
			(start 0.7874 -0.4064)
			(end 0.7874 0.4064)
			(stroke
				(width 0.1524)
				(type default)
			)
			(layer "F.SilkS")
		)
		(fp_line
			(start -0.7874 0.4064)
			(end -0.7874 -0.4064)
			(stroke
				(width 0.1524)
				(type default)
			)
			(layer "F.SilkS")
		)
		(fp_line
			(start -0.7874 -0.4064)
			(end 0.7874 -0.4064)
			(stroke
				(width 0.1524)
				(type default)
			)
			(layer "F.SilkS")
		)
		(fp_line
			(start 0.67945 0.3048)
			(end 0.120396 0.3048)
			(stroke
				(width 0.1)
				(type default)
			)
			(layer "F.Fab")
		)
		(fp_line
			(start 0.67945 -0.3048)
			(end 0.67945 0.3048)
			(stroke
				(width 0.1)
				(type default)
			)
			(layer "F.Fab")
		)
		(fp_line
			(start 0.12065 -0.2794)
			(end 0.12065 -0.3048)
			(stroke
				(width 0.1)
				(type default)
			)
			(layer "F.Fab")
		)
		(fp_line
			(start 0.12065 -0.3048)
			(end 0.67945 -0.3048)
			(stroke
				(width 0.1)
				(type default)
			)
			(layer "F.Fab")
		)
		(fp_line
			(start 0.120396 0.3048)
			(end 0.120396 0.2794)
			(stroke
				(width 0.1)
				(type default)
			)
			(layer "F.Fab")
		)
		(fp_line
			(start 0.120396 0.2794)
			(end -0.12065 0.2794)
			(stroke
				(width 0.1)
				(type default)
			)
			(layer "F.Fab")
		)
		(fp_line
			(start -0.12065 0.3048)
			(end -0.67945 0.3048)
			(stroke
				(width 0.1)
				(type default)
			)
			(layer "F.Fab")
		)
		(fp_line
			(start -0.12065 0.2794)
			(end -0.12065 0.3048)
			(stroke
				(width 0.1)
				(type default)
			)
			(layer "F.Fab")
		)
		(fp_line
			(start -0.12065 -0.2794)
			(end 0.12065 -0.2794)
			(stroke
				(width 0.1)
				(type default)
			)
			(layer "F.Fab")
		)
		(fp_line
			(start -0.12065 -0.305054)
			(end -0.12065 -0.2794)
			(stroke
				(width 0.1)
				(type default)
			)
			(layer "F.Fab")
		)
		(fp_line
			(start -0.67945 0.3048)
			(end -0.67945 -0.305054)
			(stroke
				(width 0.1)
				(type default)
			)
			(layer "F.Fab")
		)
		(fp_line
			(start -0.67945 -0.305054)
			(end -0.12065 -0.305054)
			(stroke
				(width 0.1)
				(type default)
			)
			(layer "F.Fab")
		)
		(pad "1" smd circle
			(at -0.40005 0 180)
			(size 0 0)
			(layers "F.Cu" "F.Mask" "F.Paste")
			(net "P3V3_AUX")
		)
		(pad "2" smd circle
			(at 0.40005 0 180)
			(size 0 0)
			(layers "F.Cu" "F.Mask" "F.Paste")
			(net "RST_BMC_HW_OUT")
		)
	)
	(footprint ""
		(layer "F.Cu")
		(at 15.26286 -31.66364 90)
		(property "Reference" "R878"
			(at 0 0 90)
			(layer "F.SilkS")
			(hide yes)
			(effects
				(font
					(size 1.27 1.27)
				)
			)
		)
		(property "Value" ""
			(at 0 0 90)
			(layer "F.Fab")
			(effects
				(font
					(size 1.27 1.27)
				)
			)
		)
		(duplicate_pad_numbers_are_jumpers no)
		(fp_line
			(start 0.7874 -0.4064)
			(end 0.7874 0.4064)
			(stroke
				(width 0.1524)
				(type default)
			)
			(layer "F.SilkS")
		)
		(fp_line
			(start -0.7874 -0.4064)
			(end 0.7874 -0.4064)
			(stroke
				(width 0.1524)
				(type default)
			)
			(layer "F.SilkS")
		)
		(fp_line
			(start 0.7874 0.4064)
			(end -0.7874 0.4064)
			(stroke
				(width 0.1524)
				(type default)
			)
			(layer "F.SilkS")
		)
		(fp_line
			(start -0.7874 0.4064)
			(end -0.7874 -0.4064)
			(stroke
				(width 0.1524)
				(type default)
			)
			(layer "F.SilkS")
		)
		(fp_line
			(start -0.12065 -0.305054)
			(end -0.12065 -0.2794)
			(stroke
				(width 0.1)
				(type default)
			)
			(layer "F.Fab")
		)
		(fp_line
			(start -0.67945 -0.305054)
			(end -0.12065 -0.305054)
			(stroke
				(width 0.1)
				(type default)
			)
			(layer "F.Fab")
		)
		(fp_line
			(start 0.67945 -0.3048)
			(end 0.67945 0.3048)
			(stroke
				(width 0.1)
				(type default)
			)
			(layer "F.Fab")
		)
		(fp_line
			(start 0.12065 -0.3048)
			(end 0.67945 -0.3048)
			(stroke
				(width 0.1)
				(type default)
			)
			(layer "F.Fab")
		)
		(fp_line
			(start 0.12065 -0.2794)
			(end 0.12065 -0.3048)
			(stroke
				(width 0.1)
				(type default)
			)
			(layer "F.Fab")
		)
		(fp_line
			(start -0.12065 -0.2794)
			(end 0.12065 -0.2794)
			(stroke
				(width 0.1)
				(type default)
			)
			(layer "F.Fab")
		)
		(fp_line
			(start 0.120396 0.2794)
			(end -0.12065 0.2794)
			(stroke
				(width 0.1)
				(type default)
			)
			(layer "F.Fab")
		)
		(fp_line
			(start -0.12065 0.2794)
			(end -0.12065 0.3048)
			(stroke
				(width 0.1)
				(type default)
			)
			(layer "F.Fab")
		)
		(fp_line
			(start 0.67945 0.3048)
			(end 0.120396 0.3048)
			(stroke
				(width 0.1)
				(type default)
			)
			(layer "F.Fab")
		)
		(fp_line
			(start 0.120396 0.3048)
			(end 0.120396 0.2794)
			(stroke
				(width 0.1)
				(type default)
			)
			(layer "F.Fab")
		)
		(fp_line
			(start -0.12065 0.3048)
			(end -0.67945 0.3048)
			(stroke
				(width 0.1)
				(type default)
			)
			(layer "F.Fab")
		)
		(fp_line
			(start -0.67945 0.3048)
			(end -0.67945 -0.305054)
			(stroke
				(width 0.1)
				(type default)
			)
			(layer "F.Fab")
		)
		(pad "1" smd circle
			(at -0.40005 0 90)
			(size 0 0)
			(layers "F.Cu" "F.Mask" "F.Paste")
			(net "PWRGD_P1V2_AUX_R2")
		)
		(pad "2" smd circle
			(at 0.40005 0 90)
			(size 0 0)
			(layers "F.Cu" "F.Mask" "F.Paste")
			(net "EN_P1V0_AUX_R")
		)
	)
	(footprint ""
		(layer "F.Cu")
		(at 49.657 -67.26174 180)
		(property "Reference" "R209"
			(at 0 0 180)
			(layer "F.SilkS")
			(hide yes)
			(effects
				(font
					(size 1.27 1.27)
				)
			)
		)
		(property "Value" ""
			(at 0 0 180)
			(layer "F.Fab")
			(effects
				(font
					(size 1.27 1.27)
				)
			)
		)
		(duplicate_pad_numbers_are_jumpers no)
		(fp_line
			(start 0.7874 0.4064)
			(end -0.7874 0.4064)
			(stroke
				(width 0.1524)
				(type default)
			)
			(layer "F.SilkS")
		)
		(fp_line
			(start 0.7874 -0.4064)
			(end 0.7874 0.4064)
			(stroke
				(width 0.1524)
				(type default)
			)
			(layer "F.SilkS")
		)
		(fp_line
			(start -0.7874 0.4064)
			(end -0.7874 -0.4064)
			(stroke
				(width 0.1524)
				(type default)
			)
			(layer "F.SilkS")
		)
		(fp_line
			(start -0.7874 -0.4064)
			(end 0.7874 -0.4064)
			(stroke
				(width 0.1524)
				(type default)
			)
			(layer "F.SilkS")
		)
		(fp_line
			(start 0.67945 0.3048)
			(end 0.120396 0.3048)
			(stroke
				(width 0.1)
				(type default)
			)
			(layer "F.Fab")
		)
		(fp_line
			(start 0.67945 -0.3048)
			(end 0.67945 0.3048)
			(stroke
				(width 0.1)
				(type default)
			)
			(layer "F.Fab")
		)
		(fp_line
			(start 0.12065 -0.2794)
			(end 0.12065 -0.3048)
			(stroke
				(width 0.1)
				(type default)
			)
			(layer "F.Fab")
		)
		(fp_line
			(start 0.12065 -0.3048)
			(end 0.67945 -0.3048)
			(stroke
				(width 0.1)
				(type default)
			)
			(layer "F.Fab")
		)
		(fp_line
			(start 0.120396 0.3048)
			(end 0.120396 0.2794)
			(stroke
				(width 0.1)
				(type default)
			)
			(layer "F.Fab")
		)
		(fp_line
			(start 0.120396 0.2794)
			(end -0.12065 0.2794)
			(stroke
				(width 0.1)
				(type default)
			)
			(layer "F.Fab")
		)
		(fp_line
			(start -0.12065 0.3048)
			(end -0.67945 0.3048)
			(stroke
				(width 0.1)
				(type default)
			)
			(layer "F.Fab")
		)
		(fp_line
			(start -0.12065 0.2794)
			(end -0.12065 0.3048)
			(stroke
				(width 0.1)
				(type default)
			)
			(layer "F.Fab")
		)
		(fp_line
			(start -0.12065 -0.2794)
			(end 0.12065 -0.2794)
			(stroke
				(width 0.1)
				(type default)
			)
			(layer "F.Fab")
		)
		(fp_line
			(start -0.12065 -0.305054)
			(end -0.12065 -0.2794)
			(stroke
				(width 0.1)
				(type default)
			)
			(layer "F.Fab")
		)
		(fp_line
			(start -0.67945 0.3048)
			(end -0.67945 -0.305054)
			(stroke
				(width 0.1)
				(type default)
			)
			(layer "F.Fab")
		)
		(fp_line
			(start -0.67945 -0.305054)
			(end -0.12065 -0.305054)
			(stroke
				(width 0.1)
				(type default)
			)
			(layer "F.Fab")
		)
		(pad "1" smd circle
			(at -0.40005 0 180)
			(size 0 0)
			(layers "F.Cu" "F.Mask" "F.Paste")
			(net "PECI_BMC")
		)
		(pad "2" smd circle
			(at 0.40005 0 180)
			(size 0 0)
			(layers "F.Cu" "F.Mask" "F.Paste")
			(net "GND")
		)
	)
	(footprint ""
		(layer "F.Cu")
		(at 51.84648 -34.637726 90)
		(property "Reference" "R236"
			(at 0 0 90)
			(layer "F.SilkS")
			(hide yes)
			(effects
				(font
					(size 1.27 1.27)
				)
			)
		)
		(property "Value" ""
			(at 0 0 90)
			(layer "F.Fab")
			(effects
				(font
					(size 1.27 1.27)
				)
			)
		)
		(duplicate_pad_numbers_are_jumpers no)
		(fp_line
			(start 0.7874 -0.4064)
			(end 0.7874 0.4064)
			(stroke
				(width 0.1524)
				(type default)
			)
			(layer "F.SilkS")
		)
		(fp_line
			(start -0.7874 -0.4064)
			(end 0.7874 -0.4064)
			(stroke
				(width 0.1524)
				(type default)
			)
			(layer "F.SilkS")
		)
		(fp_line
			(start 0.7874 0.4064)
			(end -0.7874 0.4064)
			(stroke
				(width 0.1524)
				(type default)
			)
			(layer "F.SilkS")
		)
		(fp_line
			(start -0.7874 0.4064)
			(end -0.7874 -0.4064)
			(stroke
				(width 0.1524)
				(type default)
			)
			(layer "F.SilkS")
		)
		(fp_line
			(start -0.12065 -0.305054)
			(end -0.12065 -0.2794)
			(stroke
				(width 0.1)
				(type default)
			)
			(layer "F.Fab")
		)
		(fp_line
			(start -0.67945 -0.305054)
			(end -0.12065 -0.305054)
			(stroke
				(width 0.1)
				(type default)
			)
			(layer "F.Fab")
		)
		(fp_line
			(start 0.67945 -0.3048)
			(end 0.67945 0.3048)
			(stroke
				(width 0.1)
				(type default)
			)
			(layer "F.Fab")
		)
		(fp_line
			(start 0.12065 -0.3048)
			(end 0.67945 -0.3048)
			(stroke
				(width 0.1)
				(type default)
			)
			(layer "F.Fab")
		)
		(fp_line
			(start 0.12065 -0.2794)
			(end 0.12065 -0.3048)
			(stroke
				(width 0.1)
				(type default)
			)
			(layer "F.Fab")
		)
		(fp_line
			(start -0.12065 -0.2794)
			(end 0.12065 -0.2794)
			(stroke
				(width 0.1)
				(type default)
			)
			(layer "F.Fab")
		)
		(fp_line
			(start 0.120396 0.2794)
			(end -0.12065 0.2794)
			(stroke
				(width 0.1)
				(type default)
			)
			(layer "F.Fab")
		)
		(fp_line
			(start -0.12065 0.2794)
			(end -0.12065 0.3048)
			(stroke
				(width 0.1)
				(type default)
			)
			(layer "F.Fab")
		)
		(fp_line
			(start 0.67945 0.3048)
			(end 0.120396 0.3048)
			(stroke
				(width 0.1)
				(type default)
			)
			(layer "F.Fab")
		)
		(fp_line
			(start 0.120396 0.3048)
			(end 0.120396 0.2794)
			(stroke
				(width 0.1)
				(type default)
			)
			(layer "F.Fab")
		)
		(fp_line
			(start -0.12065 0.3048)
			(end -0.67945 0.3048)
			(stroke
				(width 0.1)
				(type default)
			)
			(layer "F.Fab")
		)
		(fp_line
			(start -0.67945 0.3048)
			(end -0.67945 -0.305054)
			(stroke
				(width 0.1)
				(type default)
			)
			(layer "F.Fab")
		)
		(pad "1" smd circle
			(at -0.40005 0 90)
			(size 0 0)
			(layers "F.Cu" "F.Mask" "F.Paste")
			(net "SMB_BMC_MM15_SDA")
		)
		(pad "2" smd circle
			(at 0.40005 0 90)
			(size 0 0)
			(layers "F.Cu" "F.Mask" "F.Paste")
			(net "SMB_BMC_MM15_R_SDA")
		)
	)
	(footprint ""
		(layer "F.Cu")
		(at 20.447 -40.259 -90)
		(property "Reference" "PL32"
			(at 0 0 270)
			(layer "F.SilkS")
			(hide yes)
			(effects
				(font
					(size 1.27 1.27)
				)
			)
		)
		(property "Value" ""
			(at 0 0 270)
			(layer "F.Fab")
			(effects
				(font
					(size 1.27 1.27)
				)
			)
		)
		(duplicate_pad_numbers_are_jumpers no)
		(fp_line
			(start -1.27 0.5842)
			(end -1.27 -0.5842)
			(stroke
				(width 0.1524)
				(type default)
			)
			(layer "F.SilkS")
		)
		(fp_line
			(start -0.127 0.5842)
			(end -0.127 -0.5842)
			(stroke
				(width 0.1524)
				(type default)
			)
			(layer "F.SilkS")
		)
		(fp_line
			(start 0.127 0.5842)
			(end 0.127 -0.5842)
			(stroke
				(width 0.1524)
				(type default)
			)
			(layer "F.SilkS")
		)
		(fp_line
			(start 1.27 0.5842)
			(end -1.27 0.5842)
			(stroke
				(width 0.1524)
				(type default)
			)
			(layer "F.SilkS")
		)
		(fp_line
			(start 1.27 0.5842)
			(end 1.27 -0.5842)
			(stroke
				(width 0.1524)
				(type default)
			)
			(layer "F.SilkS")
		)
		(fp_line
			(start -1.27 -0.5588)
			(end -1.27 -0.5842)
			(stroke
				(width 0.1524)
				(type default)
			)
			(layer "F.SilkS")
		)
		(fp_line
			(start -1.27 -0.5842)
			(end 1.27 -0.5842)
			(stroke
				(width 0.1524)
				(type default)
			)
			(layer "F.SilkS")
		)
		(fp_line
			(start -0.9144 0.508)
			(end -0.9144 0.406654)
			(stroke
				(width 0.1)
				(type default)
			)
			(layer "F.Fab")
		)
		(fp_line
			(start 0.9144 0.508)
			(end -0.9144 0.508)
			(stroke
				(width 0.1)
				(type default)
			)
			(layer "F.Fab")
		)
		(fp_line
			(start -1.194308 0.406654)
			(end -1.194308 -0.406654)
			(stroke
				(width 0.1)
				(type default)
			)
			(layer "F.Fab")
		)
		(fp_line
			(start -0.9144 0.406654)
			(end -1.194308 0.406654)
			(stroke
				(width 0.1)
				(type default)
			)
			(layer "F.Fab")
		)
		(fp_line
			(start 0.9144 0.4064)
			(end 0.9144 0.508)
			(stroke
				(width 0.1)
				(type default)
			)
			(layer "F.Fab")
		)
		(fp_line
			(start 1.1938 0.4064)
			(end 0.9144 0.4064)
			(stroke
				(width 0.1)
				(type default)
			)
			(layer "F.Fab")
		)
		(fp_line
			(start -1.194308 -0.406654)
			(end -0.9144 -0.406654)
			(stroke
				(width 0.1)
				(type default)
			)
			(layer "F.Fab")
		)
		(fp_line
			(start -0.9144 -0.406654)
			(end -0.9144 -0.508)
			(stroke
				(width 0.1)
				(type default)
			)
			(layer "F.Fab")
		)
		(fp_line
			(start 0.9144 -0.406654)
			(end 1.1938 -0.406654)
			(stroke
				(width 0.1)
				(type default)
			)
			(layer "F.Fab")
		)
		(fp_line
			(start 1.1938 -0.406654)
			(end 1.1938 0.4064)
			(stroke
				(width 0.1)
				(type default)
			)
			(layer "F.Fab")
		)
		(fp_line
			(start -0.9144 -0.508)
			(end 0.9144 -0.508)
			(stroke
				(width 0.1)
				(type default)
			)
			(layer "F.Fab")
		)
		(fp_line
			(start 0.9144 -0.508)
			(end 0.9144 -0.406654)
			(stroke
				(width 0.1)
				(type default)
			)
			(layer "F.Fab")
		)
		(pad "1" smd rect
			(at -0.7366 0 180)
			(size 0.7112 0.8128)
			(layers "F.Cu" "F.Mask" "F.Paste")
			(net "P12V_AUX")
		)
		(pad "2" smd rect
			(at 0.7366 0 180)
			(size 0.7112 0.8128)
			(layers "F.Cu" "F.Mask" "F.Paste")
			(net "SW_P1V0_AUX_FLT")
		)
	)
	(footprint ""
		(layer "F.Cu")
		(at 26.75001 -47.389034)
		(property "Reference" "H2"
			(at -2.4892 -4.562348 0)
			(unlocked yes)
			(layer "F.SilkS")
			(effects
				(font
					(size 0.7874 0.5842)
					(thickness 0.1524)
				)
			)
		)
		(property "Value" ""
			(at 0 0 0)
			(layer "F.Fab")
			(effects
				(font
					(size 1.27 1.27)
				)
			)
		)
		(duplicate_pad_numbers_are_jumpers no)
		(pad "" np_thru_hole circle
			(at 0 0)
			(size 0 0)
			(drill oval 3.2004 4.8006)
			(layers "*.Cu" "*.Mask")
			(clearance -1.2192)
			(thermal_gap 0.381)
			(padstack
				(mode front_inner_back)
				(layer "Inner"
					(shape oval)
					(size 3.2004 4.8006)
					(clearance 0.381)
				)
				(layer "B.Cu"
					(shape circle)
					(size 0 0)
					(clearance -1.2192)
				)
			)
		)
		(zone
			(layers "F.Cu" "B.Cu" "In1.Cu" "In2.Cu" "In3.Cu" "In4.Cu" "In5.Cu" "In6.Cu"
				"In7.Cu" "In8.Cu" "In9.Cu" "In10.Cu"
			)
			(hatch none 0.5)
			(connect_pads
				(clearance 0)
			)
			(min_thickness 0.25)
			(keepout
				(tracks not_allowed)
				(vias allowed)
				(pads allowed)
				(copperpour not_allowed)
				(footprints allowed)
			)
			(placement
				(enabled no)
				(sheetname "")
			)
			(fill
				(thermal_gap 0.5)
				(thermal_bridge_width 0.5)
				(island_removal_mode 0)
			)
			(polygon
				(pts
					(arc
						(start 28.85821 -46.588934)
						(mid 26.75001 -44.480734)
						(end 24.64181 -46.588934)
					)
					(arc
						(start 24.64181 -48.189134)
						(mid 26.75001 -50.297334)
						(end 28.85821 -48.189134)
					)
				)
			)
		)
		(zone
			(layers "F.Cu" "B.Cu" "In1.Cu" "In2.Cu" "In3.Cu" "In4.Cu" "In5.Cu" "In6.Cu"
				"In7.Cu" "In8.Cu" "In9.Cu" "In10.Cu"
			)
			(hatch none 0.5)
			(connect_pads
				(clearance 0)
			)
			(min_thickness 0.25)
			(keepout
				(tracks not_allowed)
				(vias allowed)
				(pads allowed)
				(copperpour not_allowed)
				(footprints allowed)
			)
			(placement
				(enabled no)
				(sheetname "")
			)
			(fill
				(thermal_gap 0.5)
				(thermal_bridge_width 0.5)
				(island_removal_mode 0)
			)
			(polygon
				(pts
					(arc
						(start 29.750258 -46.588934)
						(mid 26.75001 -43.588686)
						(end 23.749762 -46.588934)
					)
					(arc
						(start 23.749762 -48.189134)
						(mid 26.75001 -51.189382)
						(end 29.750258 -48.189134)
					)
				)
			)
		)
	)
	(footprint ""
		(layer "F.Cu")
		(at 23.241 -64.897)
		(property "Reference" "R396"
			(at 0 0 0)
			(layer "F.SilkS")
			(hide yes)
			(effects
				(font
					(size 1.27 1.27)
				)
			)
		)
		(property "Value" ""
			(at 0 0 0)
			(layer "F.Fab")
			(effects
				(font
					(size 1.27 1.27)
				)
			)
		)
		(duplicate_pad_numbers_are_jumpers no)
		(fp_line
			(start -0.7874 -0.4064)
			(end 0.7874 -0.4064)
			(stroke
				(width 0.1524)
				(type default)
			)
			(layer "F.SilkS")
		)
		(fp_line
			(start -0.7874 0.4064)
			(end -0.7874 -0.4064)
			(stroke
				(width 0.1524)
				(type default)
			)
			(layer "F.SilkS")
		)
		(fp_line
			(start 0.7874 -0.4064)
			(end 0.7874 0.4064)
			(stroke
				(width 0.1524)
				(type default)
			)
			(layer "F.SilkS")
		)
		(fp_line
			(start 0.7874 0.4064)
			(end -0.7874 0.4064)
			(stroke
				(width 0.1524)
				(type default)
			)
			(layer "F.SilkS")
		)
		(fp_line
			(start -0.67945 -0.305054)
			(end -0.12065 -0.305054)
			(stroke
				(width 0.1)
				(type default)
			)
			(layer "F.Fab")
		)
		(fp_line
			(start -0.67945 0.3048)
			(end -0.67945 -0.305054)
			(stroke
				(width 0.1)
				(type default)
			)
			(layer "F.Fab")
		)
		(fp_line
			(start -0.12065 -0.305054)
			(end -0.12065 -0.2794)
			(stroke
				(width 0.1)
				(type default)
			)
			(layer "F.Fab")
		)
		(fp_line
			(start -0.12065 -0.2794)
			(end 0.12065 -0.2794)
			(stroke
				(width 0.1)
				(type default)
			)
			(layer "F.Fab")
		)
		(fp_line
			(start -0.12065 0.2794)
			(end -0.12065 0.3048)
			(stroke
				(width 0.1)
				(type default)
			)
			(layer "F.Fab")
		)
		(fp_line
			(start -0.12065 0.3048)
			(end -0.67945 0.3048)
			(stroke
				(width 0.1)
				(type default)
			)
			(layer "F.Fab")
		)
		(fp_line
			(start 0.120396 0.2794)
			(end -0.12065 0.2794)
			(stroke
				(width 0.1)
				(type default)
			)
			(layer "F.Fab")
		)
		(fp_line
			(start 0.120396 0.3048)
			(end 0.120396 0.2794)
			(stroke
				(width 0.1)
				(type default)
			)
			(layer "F.Fab")
		)
		(fp_line
			(start 0.12065 -0.3048)
			(end 0.67945 -0.3048)
			(stroke
				(width 0.1)
				(type default)
			)
			(layer "F.Fab")
		)
		(fp_line
			(start 0.12065 -0.2794)
			(end 0.12065 -0.3048)
			(stroke
				(width 0.1)
				(type default)
			)
			(layer "F.Fab")
		)
		(fp_line
			(start 0.67945 -0.3048)
			(end 0.67945 0.3048)
			(stroke
				(width 0.1)
				(type default)
			)
			(layer "F.Fab")
		)
		(fp_line
			(start 0.67945 0.3048)
			(end 0.120396 0.3048)
			(stroke
				(width 0.1)
				(type default)
			)
			(layer "F.Fab")
		)
		(pad "1" smd circle
			(at -0.40005 0)
			(size 0 0)
			(layers "F.Cu" "F.Mask" "F.Paste")
			(net "P3V3_AUX")
		)
		(pad "2" smd circle
			(at 0.40005 0)
			(size 0 0)
			(layers "F.Cu" "F.Mask" "F.Paste")
			(net "UART_BIC_GF_RXD")
		)
	)
	(footprint ""
		(layer "F.Cu")
		(at 72.46493 -30.957774 -90)
		(property "Reference" "R597"
			(at 0 0 270)
			(layer "F.SilkS")
			(hide yes)
			(effects
				(font
					(size 1.27 1.27)
				)
			)
		)
		(property "Value" ""
			(at 0 0 270)
			(layer "F.Fab")
			(effects
				(font
					(size 1.27 1.27)
				)
			)
		)
		(duplicate_pad_numbers_are_jumpers no)
		(fp_line
			(start -0.7874 0.4064)
			(end -0.7874 -0.4064)
			(stroke
				(width 0.1524)
				(type default)
			)
			(layer "F.SilkS")
		)
		(fp_line
			(start 0.7874 0.4064)
			(end -0.7874 0.4064)
			(stroke
				(width 0.1524)
				(type default)
			)
			(layer "F.SilkS")
		)
		(fp_line
			(start -0.7874 -0.4064)
			(end 0.7874 -0.4064)
			(stroke
				(width 0.1524)
				(type default)
			)
			(layer "F.SilkS")
		)
		(fp_line
			(start 0.7874 -0.4064)
			(end 0.7874 0.4064)
			(stroke
				(width 0.1524)
				(type default)
			)
			(layer "F.SilkS")
		)
		(fp_line
			(start -0.67945 0.3048)
			(end -0.67945 -0.305054)
			(stroke
				(width 0.1)
				(type default)
			)
			(layer "F.Fab")
		)
		(fp_line
			(start -0.12065 0.3048)
			(end -0.67945 0.3048)
			(stroke
				(width 0.1)
				(type default)
			)
			(layer "F.Fab")
		)
		(fp_line
			(start 0.120396 0.3048)
			(end 0.120396 0.2794)
			(stroke
				(width 0.1)
				(type default)
			)
			(layer "F.Fab")
		)
		(fp_line
			(start 0.67945 0.3048)
			(end 0.120396 0.3048)
			(stroke
				(width 0.1)
				(type default)
			)
			(layer "F.Fab")
		)
		(fp_line
			(start -0.12065 0.2794)
			(end -0.12065 0.3048)
			(stroke
				(width 0.1)
				(type default)
			)
			(layer "F.Fab")
		)
		(fp_line
			(start 0.120396 0.2794)
			(end -0.12065 0.2794)
			(stroke
				(width 0.1)
				(type default)
			)
			(layer "F.Fab")
		)
		(fp_line
			(start -0.12065 -0.2794)
			(end 0.12065 -0.2794)
			(stroke
				(width 0.1)
				(type default)
			)
			(layer "F.Fab")
		)
		(fp_line
			(start 0.12065 -0.2794)
			(end 0.12065 -0.3048)
			(stroke
				(width 0.1)
				(type default)
			)
			(layer "F.Fab")
		)
		(fp_line
			(start 0.12065 -0.3048)
			(end 0.67945 -0.3048)
			(stroke
				(width 0.1)
				(type default)
			)
			(layer "F.Fab")
		)
		(fp_line
			(start 0.67945 -0.3048)
			(end 0.67945 0.3048)
			(stroke
				(width 0.1)
				(type default)
			)
			(layer "F.Fab")
		)
		(fp_line
			(start -0.67945 -0.305054)
			(end -0.12065 -0.305054)
			(stroke
				(width 0.1)
				(type default)
			)
			(layer "F.Fab")
		)
		(fp_line
			(start -0.12065 -0.305054)
			(end -0.12065 -0.2794)
			(stroke
				(width 0.1)
				(type default)
			)
			(layer "F.Fab")
		)
		(pad "1" smd circle
			(at -0.40005 0 270)
			(size 0 0)
			(layers "F.Cu" "F.Mask" "F.Paste")
			(net "LED_POSTCODE_7")
		)
		(pad "2" smd circle
			(at 0.40005 0 270)
			(size 0 0)
			(layers "F.Cu" "F.Mask" "F.Paste")
			(net "LED_POSTCODE_7_R")
		)
	)
	(footprint ""
		(layer "F.Cu")
		(at 48.650652 -63.966344 -90)
		(property "Reference" "R233"
			(at 0 0 270)
			(layer "F.SilkS")
			(hide yes)
			(effects
				(font
					(size 1.27 1.27)
				)
			)
		)
		(property "Value" ""
			(at 0 0 270)
			(layer "F.Fab")
			(effects
				(font
					(size 1.27 1.27)
				)
			)
		)
		(duplicate_pad_numbers_are_jumpers no)
		(fp_line
			(start -0.7874 0.4064)
			(end -0.7874 -0.4064)
			(stroke
				(width 0.1524)
				(type default)
			)
			(layer "F.SilkS")
		)
		(fp_line
			(start 0.7874 0.4064)
			(end -0.7874 0.4064)
			(stroke
				(width 0.1524)
				(type default)
			)
			(layer "F.SilkS")
		)
		(fp_line
			(start -0.7874 -0.4064)
			(end 0.7874 -0.4064)
			(stroke
				(width 0.1524)
				(type default)
			)
			(layer "F.SilkS")
		)
		(fp_line
			(start 0.7874 -0.4064)
			(end 0.7874 0.4064)
			(stroke
				(width 0.1524)
				(type default)
			)
			(layer "F.SilkS")
		)
		(fp_line
			(start -0.67945 0.3048)
			(end -0.67945 -0.305054)
			(stroke
				(width 0.1)
				(type default)
			)
			(layer "F.Fab")
		)
		(fp_line
			(start -0.12065 0.3048)
			(end -0.67945 0.3048)
			(stroke
				(width 0.1)
				(type default)
			)
			(layer "F.Fab")
		)
		(fp_line
			(start 0.120396 0.3048)
			(end 0.120396 0.2794)
			(stroke
				(width 0.1)
				(type default)
			)
			(layer "F.Fab")
		)
		(fp_line
			(start 0.67945 0.3048)
			(end 0.120396 0.3048)
			(stroke
				(width 0.1)
				(type default)
			)
			(layer "F.Fab")
		)
		(fp_line
			(start -0.12065 0.2794)
			(end -0.12065 0.3048)
			(stroke
				(width 0.1)
				(type default)
			)
			(layer "F.Fab")
		)
		(fp_line
			(start 0.120396 0.2794)
			(end -0.12065 0.2794)
			(stroke
				(width 0.1)
				(type default)
			)
			(layer "F.Fab")
		)
		(fp_line
			(start -0.12065 -0.2794)
			(end 0.12065 -0.2794)
			(stroke
				(width 0.1)
				(type default)
			)
			(layer "F.Fab")
		)
		(fp_line
			(start 0.12065 -0.2794)
			(end 0.12065 -0.3048)
			(stroke
				(width 0.1)
				(type default)
			)
			(layer "F.Fab")
		)
		(fp_line
			(start 0.12065 -0.3048)
			(end 0.67945 -0.3048)
			(stroke
				(width 0.1)
				(type default)
			)
			(layer "F.Fab")
		)
		(fp_line
			(start 0.67945 -0.3048)
			(end 0.67945 0.3048)
			(stroke
				(width 0.1)
				(type default)
			)
			(layer "F.Fab")
		)
		(fp_line
			(start -0.67945 -0.305054)
			(end -0.12065 -0.305054)
			(stroke
				(width 0.1)
				(type default)
			)
			(layer "F.Fab")
		)
		(fp_line
			(start -0.12065 -0.305054)
			(end -0.12065 -0.2794)
			(stroke
				(width 0.1)
				(type default)
			)
			(layer "F.Fab")
		)
		(pad "1" smd circle
			(at -0.40005 0 270)
			(size 0 0)
			(layers "F.Cu" "F.Mask" "F.Paste")
			(net "GND")
		)
		(pad "2" smd circle
			(at 0.40005 0 270)
			(size 0 0)
			(layers "F.Cu" "F.Mask" "F.Paste")
			(net "A_BMC_ADCREXT0")
		)
	)
	(footprint ""
		(layer "F.Cu")
		(at 42.672 -34.671 90)
		(property "Reference" "R56"
			(at 0 0 90)
			(layer "F.SilkS")
			(hide yes)
			(effects
				(font
					(size 1.27 1.27)
				)
			)
		)
		(property "Value" ""
			(at 0 0 90)
			(layer "F.Fab")
			(effects
				(font
					(size 1.27 1.27)
				)
			)
		)
		(duplicate_pad_numbers_are_jumpers no)
		(fp_line
			(start 0.7874 -0.4064)
			(end 0.7874 0.4064)
			(stroke
				(width 0.1524)
				(type default)
			)
			(layer "F.SilkS")
		)
		(fp_line
			(start -0.7874 -0.4064)
			(end 0.7874 -0.4064)
			(stroke
				(width 0.1524)
				(type default)
			)
			(layer "F.SilkS")
		)
		(fp_line
			(start 0.7874 0.4064)
			(end -0.7874 0.4064)
			(stroke
				(width 0.1524)
				(type default)
			)
			(layer "F.SilkS")
		)
		(fp_line
			(start -0.7874 0.4064)
			(end -0.7874 -0.4064)
			(stroke
				(width 0.1524)
				(type default)
			)
			(layer "F.SilkS")
		)
		(fp_line
			(start -0.12065 -0.305054)
			(end -0.12065 -0.2794)
			(stroke
				(width 0.1)
				(type default)
			)
			(layer "F.Fab")
		)
		(fp_line
			(start -0.67945 -0.305054)
			(end -0.12065 -0.305054)
			(stroke
				(width 0.1)
				(type default)
			)
			(layer "F.Fab")
		)
		(fp_line
			(start 0.67945 -0.3048)
			(end 0.67945 0.3048)
			(stroke
				(width 0.1)
				(type default)
			)
			(layer "F.Fab")
		)
		(fp_line
			(start 0.12065 -0.3048)
			(end 0.67945 -0.3048)
			(stroke
				(width 0.1)
				(type default)
			)
			(layer "F.Fab")
		)
		(fp_line
			(start 0.12065 -0.2794)
			(end 0.12065 -0.3048)
			(stroke
				(width 0.1)
				(type default)
			)
			(layer "F.Fab")
		)
		(fp_line
			(start -0.12065 -0.2794)
			(end 0.12065 -0.2794)
			(stroke
				(width 0.1)
				(type default)
			)
			(layer "F.Fab")
		)
		(fp_line
			(start 0.120396 0.2794)
			(end -0.12065 0.2794)
			(stroke
				(width 0.1)
				(type default)
			)
			(layer "F.Fab")
		)
		(fp_line
			(start -0.12065 0.2794)
			(end -0.12065 0.3048)
			(stroke
				(width 0.1)
				(type default)
			)
			(layer "F.Fab")
		)
		(fp_line
			(start 0.67945 0.3048)
			(end 0.120396 0.3048)
			(stroke
				(width 0.1)
				(type default)
			)
			(layer "F.Fab")
		)
		(fp_line
			(start 0.120396 0.3048)
			(end 0.120396 0.2794)
			(stroke
				(width 0.1)
				(type default)
			)
			(layer "F.Fab")
		)
		(fp_line
			(start -0.12065 0.3048)
			(end -0.67945 0.3048)
			(stroke
				(width 0.1)
				(type default)
			)
			(layer "F.Fab")
		)
		(fp_line
			(start -0.67945 0.3048)
			(end -0.67945 -0.305054)
			(stroke
				(width 0.1)
				(type default)
			)
			(layer "F.Fab")
		)
		(pad "1" smd circle
			(at -0.40005 0 90)
			(size 0 0)
			(layers "F.Cu" "F.Mask" "F.Paste")
			(net "P3V3_AUX")
		)
		(pad "2" smd circle
			(at 0.40005 0 90)
			(size 0 0)
			(layers "F.Cu" "F.Mask" "F.Paste")
			(net "FM_BIOS_DEBUG_EN_R_N")
		)
	)
	(footprint ""
		(layer "F.Cu")
		(at 5.01015 -65.983358)
		(property "Reference" "PR532"
			(at 0 0 0)
			(layer "F.SilkS")
			(hide yes)
			(effects
				(font
					(size 1.27 1.27)
				)
			)
		)
		(property "Value" ""
			(at 0 0 0)
			(layer "F.Fab")
			(effects
				(font
					(size 1.27 1.27)
				)
			)
		)
		(duplicate_pad_numbers_are_jumpers no)
		(fp_line
			(start -0.7874 -0.4064)
			(end 0.7874 -0.4064)
			(stroke
				(width 0.1524)
				(type default)
			)
			(layer "F.SilkS")
		)
		(fp_line
			(start -0.7874 0.4064)
			(end -0.7874 -0.4064)
			(stroke
				(width 0.1524)
				(type default)
			)
			(layer "F.SilkS")
		)
		(fp_line
			(start 0.7874 -0.4064)
			(end 0.7874 0.4064)
			(stroke
				(width 0.1524)
				(type default)
			)
			(layer "F.SilkS")
		)
		(fp_line
			(start 0.7874 0.4064)
			(end -0.7874 0.4064)
			(stroke
				(width 0.1524)
				(type default)
			)
			(layer "F.SilkS")
		)
		(fp_line
			(start -0.67945 -0.305054)
			(end -0.12065 -0.305054)
			(stroke
				(width 0.1)
				(type default)
			)
			(layer "F.Fab")
		)
		(fp_line
			(start -0.67945 0.3048)
			(end -0.67945 -0.305054)
			(stroke
				(width 0.1)
				(type default)
			)
			(layer "F.Fab")
		)
		(fp_line
			(start -0.12065 -0.305054)
			(end -0.12065 -0.2794)
			(stroke
				(width 0.1)
				(type default)
			)
			(layer "F.Fab")
		)
		(fp_line
			(start -0.12065 -0.2794)
			(end 0.12065 -0.2794)
			(stroke
				(width 0.1)
				(type default)
			)
			(layer "F.Fab")
		)
		(fp_line
			(start -0.12065 0.2794)
			(end -0.12065 0.3048)
			(stroke
				(width 0.1)
				(type default)
			)
			(layer "F.Fab")
		)
		(fp_line
			(start -0.12065 0.3048)
			(end -0.67945 0.3048)
			(stroke
				(width 0.1)
				(type default)
			)
			(layer "F.Fab")
		)
		(fp_line
			(start 0.120396 0.2794)
			(end -0.12065 0.2794)
			(stroke
				(width 0.1)
				(type default)
			)
			(layer "F.Fab")
		)
		(fp_line
			(start 0.120396 0.3048)
			(end 0.120396 0.2794)
			(stroke
				(width 0.1)
				(type default)
			)
			(layer "F.Fab")
		)
		(fp_line
			(start 0.12065 -0.3048)
			(end 0.67945 -0.3048)
			(stroke
				(width 0.1)
				(type default)
			)
			(layer "F.Fab")
		)
		(fp_line
			(start 0.12065 -0.2794)
			(end 0.12065 -0.3048)
			(stroke
				(width 0.1)
				(type default)
			)
			(layer "F.Fab")
		)
		(fp_line
			(start 0.67945 -0.3048)
			(end 0.67945 0.3048)
			(stroke
				(width 0.1)
				(type default)
			)
			(layer "F.Fab")
		)
		(fp_line
			(start 0.67945 0.3048)
			(end 0.120396 0.3048)
			(stroke
				(width 0.1)
				(type default)
			)
			(layer "F.Fab")
		)
		(pad "1" smd circle
			(at -0.40005 0)
			(size 0 0)
			(layers "F.Cu" "F.Mask" "F.Paste")
			(net "GND")
		)
		(pad "2" smd circle
			(at 0.40005 0)
			(size 0 0)
			(layers "F.Cu" "F.Mask" "F.Paste")
			(net "P3V3_AUX_MODE")
		)
	)
	(footprint ""
		(layer "F.Cu")
		(at 74.09815 -93.347032)
		(property "Reference" "R50"
			(at 0 0 0)
			(layer "F.SilkS")
			(hide yes)
			(effects
				(font
					(size 1.27 1.27)
				)
			)
		)
		(property "Value" ""
			(at 0 0 0)
			(layer "F.Fab")
			(effects
				(font
					(size 1.27 1.27)
				)
			)
		)
		(duplicate_pad_numbers_are_jumpers no)
		(fp_line
			(start -0.7874 -0.4064)
			(end 0.7874 -0.4064)
			(stroke
				(width 0.1524)
				(type default)
			)
			(layer "F.SilkS")
		)
		(fp_line
			(start -0.7874 0.4064)
			(end -0.7874 -0.4064)
			(stroke
				(width 0.1524)
				(type default)
			)
			(layer "F.SilkS")
		)
		(fp_line
			(start 0.7874 -0.4064)
			(end 0.7874 0.4064)
			(stroke
				(width 0.1524)
				(type default)
			)
			(layer "F.SilkS")
		)
		(fp_line
			(start 0.7874 0.4064)
			(end -0.7874 0.4064)
			(stroke
				(width 0.1524)
				(type default)
			)
			(layer "F.SilkS")
		)
		(fp_line
			(start -0.67945 -0.305054)
			(end -0.12065 -0.305054)
			(stroke
				(width 0.1)
				(type default)
			)
			(layer "F.Fab")
		)
		(fp_line
			(start -0.67945 0.3048)
			(end -0.67945 -0.305054)
			(stroke
				(width 0.1)
				(type default)
			)
			(layer "F.Fab")
		)
		(fp_line
			(start -0.12065 -0.305054)
			(end -0.12065 -0.2794)
			(stroke
				(width 0.1)
				(type default)
			)
			(layer "F.Fab")
		)
		(fp_line
			(start -0.12065 -0.2794)
			(end 0.12065 -0.2794)
			(stroke
				(width 0.1)
				(type default)
			)
			(layer "F.Fab")
		)
		(fp_line
			(start -0.12065 0.2794)
			(end -0.12065 0.3048)
			(stroke
				(width 0.1)
				(type default)
			)
			(layer "F.Fab")
		)
		(fp_line
			(start -0.12065 0.3048)
			(end -0.67945 0.3048)
			(stroke
				(width 0.1)
				(type default)
			)
			(layer "F.Fab")
		)
		(fp_line
			(start 0.120396 0.2794)
			(end -0.12065 0.2794)
			(stroke
				(width 0.1)
				(type default)
			)
			(layer "F.Fab")
		)
		(fp_line
			(start 0.120396 0.3048)
			(end 0.120396 0.2794)
			(stroke
				(width 0.1)
				(type default)
			)
			(layer "F.Fab")
		)
		(fp_line
			(start 0.12065 -0.3048)
			(end 0.67945 -0.3048)
			(stroke
				(width 0.1)
				(type default)
			)
			(layer "F.Fab")
		)
		(fp_line
			(start 0.12065 -0.2794)
			(end 0.12065 -0.3048)
			(stroke
				(width 0.1)
				(type default)
			)
			(layer "F.Fab")
		)
		(fp_line
			(start 0.67945 -0.3048)
			(end 0.67945 0.3048)
			(stroke
				(width 0.1)
				(type default)
			)
			(layer "F.Fab")
		)
		(fp_line
			(start 0.67945 0.3048)
			(end 0.120396 0.3048)
			(stroke
				(width 0.1)
				(type default)
			)
			(layer "F.Fab")
		)
		(pad "1" smd circle
			(at -0.40005 0)
			(size 0 0)
			(layers "F.Cu" "F.Mask" "F.Paste")
			(net "P3V3_AUX")
		)
		(pad "2" smd circle
			(at 0.40005 0)
			(size 0 0)
			(layers "F.Cu" "F.Mask" "F.Paste")
			(net "FM_TPM_PRSNT_1_N")
		)
	)
	(footprint ""
		(layer "F.Cu")
		(at 68.4784 -85.7758)
		(property "Reference" ""
			(at 0 0 0)
			(layer "F.SilkS")
			(hide yes)
			(effects
				(font
					(size 1.27 1.27)
				)
			)
		)
		(property "Value" ""
			(at 0 0 0)
			(layer "F.Fab")
			(effects
				(font
					(size 1.27 1.27)
				)
			)
		)
		(duplicate_pad_numbers_are_jumpers no)
		(pad "1" smd circle
			(at 0 0)
			(size 0.9906 0.9906)
			(layers "F.Cu" "F.Mask" "F.Paste")
			(net "Net_327")
		)
		(zone
			(layer "F.Cu")
			(hatch none 0.5)
			(connect_pads
				(clearance 0)
			)
			(min_thickness 0.25)
			(keepout
				(tracks not_allowed)
				(vias allowed)
				(pads allowed)
				(copperpour not_allowed)
				(footprints allowed)
			)
			(placement
				(enabled no)
				(sheetname "")
			)
			(fill
				(thermal_gap 0.5)
				(thermal_bridge_width 0.5)
				(island_removal_mode 0)
			)
			(polygon
				(pts
					(arc
						(start 70.104 -85.7758)
						(mid 66.8528 -85.7758)
						(end 70.104 -85.7758)
					)
				)
			)
		)
	)
	(footprint ""
		(layer "F.Cu")
		(at 54.229 -98.425 -90)
		(property "Reference" "R636"
			(at 0 0 270)
			(layer "F.SilkS")
			(hide yes)
			(effects
				(font
					(size 1.27 1.27)
				)
			)
		)
		(property "Value" ""
			(at 0 0 270)
			(layer "F.Fab")
			(effects
				(font
					(size 1.27 1.27)
				)
			)
		)
		(duplicate_pad_numbers_are_jumpers no)
		(fp_line
			(start -0.7874 0.4064)
			(end -0.7874 -0.4064)
			(stroke
				(width 0.1524)
				(type default)
			)
			(layer "F.SilkS")
		)
		(fp_line
			(start 0.7874 0.4064)
			(end -0.7874 0.4064)
			(stroke
				(width 0.1524)
				(type default)
			)
			(layer "F.SilkS")
		)
		(fp_line
			(start -0.7874 -0.4064)
			(end 0.7874 -0.4064)
			(stroke
				(width 0.1524)
				(type default)
			)
			(layer "F.SilkS")
		)
		(fp_line
			(start 0.7874 -0.4064)
			(end 0.7874 0.4064)
			(stroke
				(width 0.1524)
				(type default)
			)
			(layer "F.SilkS")
		)
		(fp_line
			(start -0.67945 0.3048)
			(end -0.67945 -0.305054)
			(stroke
				(width 0.1)
				(type default)
			)
			(layer "F.Fab")
		)
		(fp_line
			(start -0.12065 0.3048)
			(end -0.67945 0.3048)
			(stroke
				(width 0.1)
				(type default)
			)
			(layer "F.Fab")
		)
		(fp_line
			(start 0.120396 0.3048)
			(end 0.120396 0.2794)
			(stroke
				(width 0.1)
				(type default)
			)
			(layer "F.Fab")
		)
		(fp_line
			(start 0.67945 0.3048)
			(end 0.120396 0.3048)
			(stroke
				(width 0.1)
				(type default)
			)
			(layer "F.Fab")
		)
		(fp_line
			(start -0.12065 0.2794)
			(end -0.12065 0.3048)
			(stroke
				(width 0.1)
				(type default)
			)
			(layer "F.Fab")
		)
		(fp_line
			(start 0.120396 0.2794)
			(end -0.12065 0.2794)
			(stroke
				(width 0.1)
				(type default)
			)
			(layer "F.Fab")
		)
		(fp_line
			(start -0.12065 -0.2794)
			(end 0.12065 -0.2794)
			(stroke
				(width 0.1)
				(type default)
			)
			(layer "F.Fab")
		)
		(fp_line
			(start 0.12065 -0.2794)
			(end 0.12065 -0.3048)
			(stroke
				(width 0.1)
				(type default)
			)
			(layer "F.Fab")
		)
		(fp_line
			(start 0.12065 -0.3048)
			(end 0.67945 -0.3048)
			(stroke
				(width 0.1)
				(type default)
			)
			(layer "F.Fab")
		)
		(fp_line
			(start 0.67945 -0.3048)
			(end 0.67945 0.3048)
			(stroke
				(width 0.1)
				(type default)
			)
			(layer "F.Fab")
		)
		(fp_line
			(start -0.67945 -0.305054)
			(end -0.12065 -0.305054)
			(stroke
				(width 0.1)
				(type default)
			)
			(layer "F.Fab")
		)
		(fp_line
			(start -0.12065 -0.305054)
			(end -0.12065 -0.2794)
			(stroke
				(width 0.1)
				(type default)
			)
			(layer "F.Fab")
		)
		(pad "1" smd circle
			(at -0.40005 0 270)
			(size 0 0)
			(layers "F.Cu" "F.Mask" "F.Paste")
			(net "RST_EXTRST_N")
		)
		(pad "2" smd circle
			(at 0.40005 0 270)
			(size 0 0)
			(layers "F.Cu" "F.Mask" "F.Paste")
			(net "RST_BMC_EXTRST_R2_N")
		)
	)
	(footprint ""
		(layer "F.Cu")
		(at 29.6164 -25.908 180)
		(property "Reference" "R16"
			(at 0 0 180)
			(layer "F.SilkS")
			(hide yes)
			(effects
				(font
					(size 1.27 1.27)
				)
			)
		)
		(property "Value" ""
			(at 0 0 180)
			(layer "F.Fab")
			(effects
				(font
					(size 1.27 1.27)
				)
			)
		)
		(duplicate_pad_numbers_are_jumpers no)
		(fp_line
			(start 0.7874 0.4064)
			(end -0.7874 0.4064)
			(stroke
				(width 0.1524)
				(type default)
			)
			(layer "F.SilkS")
		)
		(fp_line
			(start 0.7874 -0.4064)
			(end 0.7874 0.4064)
			(stroke
				(width 0.1524)
				(type default)
			)
			(layer "F.SilkS")
		)
		(fp_line
			(start -0.7874 0.4064)
			(end -0.7874 -0.4064)
			(stroke
				(width 0.1524)
				(type default)
			)
			(layer "F.SilkS")
		)
		(fp_line
			(start -0.7874 -0.4064)
			(end 0.7874 -0.4064)
			(stroke
				(width 0.1524)
				(type default)
			)
			(layer "F.SilkS")
		)
		(fp_line
			(start 0.67945 0.3048)
			(end 0.120396 0.3048)
			(stroke
				(width 0.1)
				(type default)
			)
			(layer "F.Fab")
		)
		(fp_line
			(start 0.67945 -0.3048)
			(end 0.67945 0.3048)
			(stroke
				(width 0.1)
				(type default)
			)
			(layer "F.Fab")
		)
		(fp_line
			(start 0.12065 -0.2794)
			(end 0.12065 -0.3048)
			(stroke
				(width 0.1)
				(type default)
			)
			(layer "F.Fab")
		)
		(fp_line
			(start 0.12065 -0.3048)
			(end 0.67945 -0.3048)
			(stroke
				(width 0.1)
				(type default)
			)
			(layer "F.Fab")
		)
		(fp_line
			(start 0.120396 0.3048)
			(end 0.120396 0.2794)
			(stroke
				(width 0.1)
				(type default)
			)
			(layer "F.Fab")
		)
		(fp_line
			(start 0.120396 0.2794)
			(end -0.12065 0.2794)
			(stroke
				(width 0.1)
				(type default)
			)
			(layer "F.Fab")
		)
		(fp_line
			(start -0.12065 0.3048)
			(end -0.67945 0.3048)
			(stroke
				(width 0.1)
				(type default)
			)
			(layer "F.Fab")
		)
		(fp_line
			(start -0.12065 0.2794)
			(end -0.12065 0.3048)
			(stroke
				(width 0.1)
				(type default)
			)
			(layer "F.Fab")
		)
		(fp_line
			(start -0.12065 -0.2794)
			(end 0.12065 -0.2794)
			(stroke
				(width 0.1)
				(type default)
			)
			(layer "F.Fab")
		)
		(fp_line
			(start -0.12065 -0.305054)
			(end -0.12065 -0.2794)
			(stroke
				(width 0.1)
				(type default)
			)
			(layer "F.Fab")
		)
		(fp_line
			(start -0.67945 0.3048)
			(end -0.67945 -0.305054)
			(stroke
				(width 0.1)
				(type default)
			)
			(layer "F.Fab")
		)
		(fp_line
			(start -0.67945 -0.305054)
			(end -0.12065 -0.305054)
			(stroke
				(width 0.1)
				(type default)
			)
			(layer "F.Fab")
		)
		(pad "1" smd circle
			(at -0.40005 0 180)
			(size 0 0)
			(layers "F.Cu" "F.Mask" "F.Paste")
			(net "V_BMC_LS_DDC_SCL_R")
		)
		(pad "2" smd circle
			(at 0.40005 0 180)
			(size 0 0)
			(layers "F.Cu" "F.Mask" "F.Paste")
			(net "CRT_VCC5")
		)
	)
	(footprint ""
		(layer "F.Cu")
		(at 95.926656 -98.400362 -90)
		(property "Reference" "J26"
			(at -3.961638 -1.509014 90)
			(unlocked yes)
			(layer "F.SilkS")
			(effects
				(font
					(size 0.7874 0.5842)
					(thickness 0.1524)
				)
				(justify left)
			)
		)
		(property "Value" ""
			(at 0 0 270)
			(layer "F.Fab")
			(effects
				(font
					(size 1.27 1.27)
				)
			)
		)
		(duplicate_pad_numbers_are_jumpers no)
		(fp_line
			(start -1.2192 2.1082)
			(end -1.2192 -2.1082)
			(stroke
				(width 0.1524)
				(type default)
			)
			(layer "F.SilkS")
		)
		(fp_line
			(start 1.2192 2.1082)
			(end -1.2192 2.1082)
			(stroke
				(width 0.1524)
				(type default)
			)
			(layer "F.SilkS")
		)
		(fp_line
			(start 1.2192 0.80137)
			(end 1.2192 2.1082)
			(stroke
				(width 0.1524)
				(type default)
			)
			(layer "F.SilkS")
		)
		(fp_line
			(start -1.2192 -2.1082)
			(end 1.2192 -2.1082)
			(stroke
				(width 0.1524)
				(type default)
			)
			(layer "F.SilkS")
		)
		(fp_line
			(start 1.2192 -2.1082)
			(end 1.2192 -0.816102)
			(stroke
				(width 0.1524)
				(type default)
			)
			(layer "F.SilkS")
		)
		(pad "" np_thru_hole circle
			(at -2.8829 -1.27 180)
			(size 1.0414 1.0414)
			(drill 1.0414)
			(layers "*.Cu" "*.Mask")
			(clearance 0.381)
			(thermal_gap 0.381)
		)
		(pad "" np_thru_hole circle
			(at -2.8829 1.27 180)
			(size 1.0414 1.0414)
			(drill 1.0414)
			(layers "*.Cu" "*.Mask")
			(clearance 0.381)
			(thermal_gap 0.381)
		)
		(pad "" np_thru_hole circle
			(at 3.4671 -1.27 180)
			(size 1.0414 1.0414)
			(drill 1.0414)
			(layers "*.Cu" "*.Mask")
			(clearance 0.381)
			(thermal_gap 0.381)
		)
		(pad "" np_thru_hole circle
			(at 3.4671 1.27 180)
			(size 1.0414 1.0414)
			(drill 1.0414)
			(layers "*.Cu" "*.Mask")
			(clearance 0.381)
			(thermal_gap 0.381)
		)
		(pad "1" smd rect
			(at 0.8255 -0.249936 180)
			(size 0.3048 0.508)
			(layers "F.Cu" "F.Mask" "F.Paste")
			(net "85_10INCH_IN4_DN")
		)
		(pad "2" smd rect
			(at 0.8255 0.249936 180)
			(size 0.3048 0.508)
			(layers "F.Cu" "F.Mask" "F.Paste")
			(net "85_10INCH_IN4_DP")
		)
		(pad "3" smd circle
			(at 0 0 270)
			(size 0 0)
			(layers "F.Cu" "F.Mask" "F.Paste")
			(net "GND_P1")
		)
		(zone
			(layer "F.Cu")
			(hatch none 0.5)
			(connect_pads
				(clearance 0)
			)
			(min_thickness 0.25)
			(keepout
				(tracks not_allowed)
				(vias allowed)
				(pads allowed)
				(copperpour not_allowed)
				(footprints allowed)
			)
			(placement
				(enabled no)
				(sheetname "")
			)
			(fill
				(thermal_gap 0.5)
				(thermal_bridge_width 0.5)
				(island_removal_mode 0)
			)
			(polygon
				(pts
					(xy 96.475296 -97.282762) (xy 96.379792 -97.282762) (xy 96.379792 -97.879662) (xy 95.973392 -97.879662)
					(xy 95.973392 -97.282762) (xy 95.87992 -97.282762) (xy 95.87992 -97.879662) (xy 95.47352 -97.879662)
					(xy 95.47352 -97.282762) (xy 95.378016 -97.282762) (xy 95.378016 -97.981262) (xy 96.475296 -97.981262)
				)
			)
		)
		(zone
			(layers "F.Cu" "B.Cu" "In1.Cu" "In2.Cu" "In3.Cu" "In4.Cu" "In5.Cu" "In6.Cu"
				"In7.Cu" "In8.Cu" "In9.Cu" "In10.Cu"
			)
			(hatch none 0.5)
			(connect_pads
				(clearance 0)
			)
			(min_thickness 0.25)
			(keepout
				(tracks not_allowed)
				(vias allowed)
				(pads allowed)
				(copperpour not_allowed)
				(footprints allowed)
			)
			(placement
				(enabled no)
				(sheetname "")
			)
			(fill
				(thermal_gap 0.5)
				(thermal_bridge_width 0.5)
				(island_removal_mode 0)
			)
			(polygon
				(pts
					(arc
						(start 95.583756 -101.283262)
						(mid 93.729556 -101.283262)
						(end 95.583756 -101.283262)
					)
				)
			)
		)
		(zone
			(layers "F.Cu" "B.Cu" "In1.Cu" "In2.Cu" "In3.Cu" "In4.Cu" "In5.Cu" "In6.Cu"
				"In7.Cu" "In8.Cu" "In9.Cu" "In10.Cu"
			)
			(hatch none 0.5)
			(connect_pads
				(clearance 0)
			)
			(min_thickness 0.25)
			(keepout
				(tracks not_allowed)
				(vias allowed)
				(pads allowed)
				(copperpour not_allowed)
				(footprints allowed)
			)
			(placement
				(enabled no)
				(sheetname "")
			)
			(fill
				(thermal_gap 0.5)
				(thermal_bridge_width 0.5)
				(island_removal_mode 0)
			)
			(polygon
				(pts
					(arc
						(start 95.583756 -94.933262)
						(mid 93.729556 -94.933262)
						(end 95.583756 -94.933262)
					)
				)
			)
		)
		(zone
			(layers "F.Cu" "B.Cu" "In1.Cu" "In2.Cu" "In3.Cu" "In4.Cu" "In5.Cu" "In6.Cu"
				"In7.Cu" "In8.Cu" "In9.Cu" "In10.Cu"
			)
			(hatch none 0.5)
			(connect_pads
				(clearance 0)
			)
			(min_thickness 0.25)
			(keepout
				(tracks not_allowed)
				(vias allowed)
				(pads allowed)
				(copperpour not_allowed)
				(footprints allowed)
			)
			(placement
				(enabled no)
				(sheetname "")
			)
			(fill
				(thermal_gap 0.5)
				(thermal_bridge_width 0.5)
				(island_removal_mode 0)
			)
			(polygon
				(pts
					(arc
						(start 98.123756 -101.283262)
						(mid 96.269556 -101.283262)
						(end 98.123756 -101.283262)
					)
				)
			)
		)
		(zone
			(layers "F.Cu" "B.Cu" "In1.Cu" "In2.Cu" "In3.Cu" "In4.Cu" "In5.Cu" "In6.Cu"
				"In7.Cu" "In8.Cu" "In9.Cu" "In10.Cu"
			)
			(hatch none 0.5)
			(connect_pads
				(clearance 0)
			)
			(min_thickness 0.25)
			(keepout
				(tracks not_allowed)
				(vias allowed)
				(pads allowed)
				(copperpour not_allowed)
				(footprints allowed)
			)
			(placement
				(enabled no)
				(sheetname "")
			)
			(fill
				(thermal_gap 0.5)
				(thermal_bridge_width 0.5)
				(island_removal_mode 0)
			)
			(polygon
				(pts
					(arc
						(start 98.123756 -94.933262)
						(mid 96.269556 -94.933262)
						(end 98.123756 -94.933262)
					)
				)
			)
		)
	)
	(footprint ""
		(layer "F.Cu")
		(at 12.319 -95.504 180)
		(property "Reference" "R537"
			(at 0 0 180)
			(layer "F.SilkS")
			(hide yes)
			(effects
				(font
					(size 1.27 1.27)
				)
			)
		)
		(property "Value" ""
			(at 0 0 180)
			(layer "F.Fab")
			(effects
				(font
					(size 1.27 1.27)
				)
			)
		)
		(duplicate_pad_numbers_are_jumpers no)
		(fp_line
			(start 0.7874 0.4064)
			(end -0.7874 0.4064)
			(stroke
				(width 0.1524)
				(type default)
			)
			(layer "F.SilkS")
		)
		(fp_line
			(start 0.7874 -0.4064)
			(end 0.7874 0.4064)
			(stroke
				(width 0.1524)
				(type default)
			)
			(layer "F.SilkS")
		)
		(fp_line
			(start -0.7874 0.4064)
			(end -0.7874 -0.4064)
			(stroke
				(width 0.1524)
				(type default)
			)
			(layer "F.SilkS")
		)
		(fp_line
			(start -0.7874 -0.4064)
			(end 0.7874 -0.4064)
			(stroke
				(width 0.1524)
				(type default)
			)
			(layer "F.SilkS")
		)
		(fp_line
			(start 0.67945 0.3048)
			(end 0.120396 0.3048)
			(stroke
				(width 0.1)
				(type default)
			)
			(layer "F.Fab")
		)
		(fp_line
			(start 0.67945 -0.3048)
			(end 0.67945 0.3048)
			(stroke
				(width 0.1)
				(type default)
			)
			(layer "F.Fab")
		)
		(fp_line
			(start 0.12065 -0.2794)
			(end 0.12065 -0.3048)
			(stroke
				(width 0.1)
				(type default)
			)
			(layer "F.Fab")
		)
		(fp_line
			(start 0.12065 -0.3048)
			(end 0.67945 -0.3048)
			(stroke
				(width 0.1)
				(type default)
			)
			(layer "F.Fab")
		)
		(fp_line
			(start 0.120396 0.3048)
			(end 0.120396 0.2794)
			(stroke
				(width 0.1)
				(type default)
			)
			(layer "F.Fab")
		)
		(fp_line
			(start 0.120396 0.2794)
			(end -0.12065 0.2794)
			(stroke
				(width 0.1)
				(type default)
			)
			(layer "F.Fab")
		)
		(fp_line
			(start -0.12065 0.3048)
			(end -0.67945 0.3048)
			(stroke
				(width 0.1)
				(type default)
			)
			(layer "F.Fab")
		)
		(fp_line
			(start -0.12065 0.2794)
			(end -0.12065 0.3048)
			(stroke
				(width 0.1)
				(type default)
			)
			(layer "F.Fab")
		)
		(fp_line
			(start -0.12065 -0.2794)
			(end 0.12065 -0.2794)
			(stroke
				(width 0.1)
				(type default)
			)
			(layer "F.Fab")
		)
		(fp_line
			(start -0.12065 -0.305054)
			(end -0.12065 -0.2794)
			(stroke
				(width 0.1)
				(type default)
			)
			(layer "F.Fab")
		)
		(fp_line
			(start -0.67945 0.3048)
			(end -0.67945 -0.305054)
			(stroke
				(width 0.1)
				(type default)
			)
			(layer "F.Fab")
		)
		(fp_line
			(start -0.67945 -0.305054)
			(end -0.12065 -0.305054)
			(stroke
				(width 0.1)
				(type default)
			)
			(layer "F.Fab")
		)
		(pad "1" smd circle
			(at -0.40005 0 180)
			(size 0 0)
			(layers "F.Cu" "F.Mask" "F.Paste")
			(net "BMC_CPLD_GPIO_13_R2")
		)
		(pad "2" smd circle
			(at 0.40005 0 180)
			(size 0 0)
			(layers "F.Cu" "F.Mask" "F.Paste")
			(net "BMC_CPLD_GPIO_13")
		)
	)
	(footprint ""
		(layer "F.Cu")
		(at 12.30376 -64.54394 90)
		(property "Reference" "PC239"
			(at 0 0 90)
			(layer "F.SilkS")
			(hide yes)
			(effects
				(font
					(size 1.27 1.27)
				)
			)
		)
		(property "Value" ""
			(at 0 0 90)
			(layer "F.Fab")
			(effects
				(font
					(size 1.27 1.27)
				)
			)
		)
		(duplicate_pad_numbers_are_jumpers no)
		(fp_line
			(start 0.7874 -0.4064)
			(end 0.7874 0.4064)
			(stroke
				(width 0.1524)
				(type default)
			)
			(layer "F.SilkS")
		)
		(fp_line
			(start -0.7874 -0.4064)
			(end 0.7874 -0.4064)
			(stroke
				(width 0.1524)
				(type default)
			)
			(layer "F.SilkS")
		)
		(fp_line
			(start 0.7874 0.4064)
			(end -0.7874 0.4064)
			(stroke
				(width 0.1524)
				(type default)
			)
			(layer "F.SilkS")
		)
		(fp_line
			(start -0.7874 0.4064)
			(end -0.7874 -0.4064)
			(stroke
				(width 0.1524)
				(type default)
			)
			(layer "F.SilkS")
		)
		(fp_line
			(start -0.12065 -0.305054)
			(end -0.12065 -0.2794)
			(stroke
				(width 0.1)
				(type default)
			)
			(layer "F.Fab")
		)
		(fp_line
			(start -0.67945 -0.305054)
			(end -0.12065 -0.305054)
			(stroke
				(width 0.1)
				(type default)
			)
			(layer "F.Fab")
		)
		(fp_line
			(start 0.67945 -0.3048)
			(end 0.67945 0.3048)
			(stroke
				(width 0.1)
				(type default)
			)
			(layer "F.Fab")
		)
		(fp_line
			(start 0.12065 -0.3048)
			(end 0.67945 -0.3048)
			(stroke
				(width 0.1)
				(type default)
			)
			(layer "F.Fab")
		)
		(fp_line
			(start 0.12065 -0.2794)
			(end 0.12065 -0.3048)
			(stroke
				(width 0.1)
				(type default)
			)
			(layer "F.Fab")
		)
		(fp_line
			(start -0.12065 -0.2794)
			(end 0.12065 -0.2794)
			(stroke
				(width 0.1)
				(type default)
			)
			(layer "F.Fab")
		)
		(fp_line
			(start 0.120396 0.2794)
			(end -0.12065 0.2794)
			(stroke
				(width 0.1)
				(type default)
			)
			(layer "F.Fab")
		)
		(fp_line
			(start -0.12065 0.2794)
			(end -0.12065 0.3048)
			(stroke
				(width 0.1)
				(type default)
			)
			(layer "F.Fab")
		)
		(fp_line
			(start 0.67945 0.3048)
			(end 0.120396 0.3048)
			(stroke
				(width 0.1)
				(type default)
			)
			(layer "F.Fab")
		)
		(fp_line
			(start 0.120396 0.3048)
			(end 0.120396 0.2794)
			(stroke
				(width 0.1)
				(type default)
			)
			(layer "F.Fab")
		)
		(fp_line
			(start -0.12065 0.3048)
			(end -0.67945 0.3048)
			(stroke
				(width 0.1)
				(type default)
			)
			(layer "F.Fab")
		)
		(fp_line
			(start -0.67945 0.3048)
			(end -0.67945 -0.305054)
			(stroke
				(width 0.1)
				(type default)
			)
			(layer "F.Fab")
		)
		(pad "1" smd circle
			(at -0.40005 0 90)
			(size 0 0)
			(layers "F.Cu" "F.Mask" "F.Paste")
			(net "P3V3_AUX_FB_RC")
		)
		(pad "2" smd circle
			(at 0.40005 0 90)
			(size 0 0)
			(layers "F.Cu" "F.Mask" "F.Paste")
			(net "P3V3_AUX")
		)
	)
	(footprint ""
		(layer "F.Cu")
		(at 11.6586 -63.1952 180)
		(property "Reference" "R381"
			(at 0 0 180)
			(layer "F.SilkS")
			(hide yes)
			(effects
				(font
					(size 1.27 1.27)
				)
			)
		)
		(property "Value" ""
			(at 0 0 180)
			(layer "F.Fab")
			(effects
				(font
					(size 1.27 1.27)
				)
			)
		)
		(duplicate_pad_numbers_are_jumpers no)
		(fp_line
			(start 0.7874 0.4064)
			(end -0.7874 0.4064)
			(stroke
				(width 0.1524)
				(type default)
			)
			(layer "F.SilkS")
		)
		(fp_line
			(start 0.7874 -0.4064)
			(end 0.7874 0.4064)
			(stroke
				(width 0.1524)
				(type default)
			)
			(layer "F.SilkS")
		)
		(fp_line
			(start -0.7874 0.4064)
			(end -0.7874 -0.4064)
			(stroke
				(width 0.1524)
				(type default)
			)
			(layer "F.SilkS")
		)
		(fp_line
			(start -0.7874 -0.4064)
			(end 0.7874 -0.4064)
			(stroke
				(width 0.1524)
				(type default)
			)
			(layer "F.SilkS")
		)
		(fp_line
			(start 0.67945 0.3048)
			(end 0.120396 0.3048)
			(stroke
				(width 0.1)
				(type default)
			)
			(layer "F.Fab")
		)
		(fp_line
			(start 0.67945 -0.3048)
			(end 0.67945 0.3048)
			(stroke
				(width 0.1)
				(type default)
			)
			(layer "F.Fab")
		)
		(fp_line
			(start 0.12065 -0.2794)
			(end 0.12065 -0.3048)
			(stroke
				(width 0.1)
				(type default)
			)
			(layer "F.Fab")
		)
		(fp_line
			(start 0.12065 -0.3048)
			(end 0.67945 -0.3048)
			(stroke
				(width 0.1)
				(type default)
			)
			(layer "F.Fab")
		)
		(fp_line
			(start 0.120396 0.3048)
			(end 0.120396 0.2794)
			(stroke
				(width 0.1)
				(type default)
			)
			(layer "F.Fab")
		)
		(fp_line
			(start 0.120396 0.2794)
			(end -0.12065 0.2794)
			(stroke
				(width 0.1)
				(type default)
			)
			(layer "F.Fab")
		)
		(fp_line
			(start -0.12065 0.3048)
			(end -0.67945 0.3048)
			(stroke
				(width 0.1)
				(type default)
			)
			(layer "F.Fab")
		)
		(fp_line
			(start -0.12065 0.2794)
			(end -0.12065 0.3048)
			(stroke
				(width 0.1)
				(type default)
			)
			(layer "F.Fab")
		)
		(fp_line
			(start -0.12065 -0.2794)
			(end 0.12065 -0.2794)
			(stroke
				(width 0.1)
				(type default)
			)
			(layer "F.Fab")
		)
		(fp_line
			(start -0.12065 -0.305054)
			(end -0.12065 -0.2794)
			(stroke
				(width 0.1)
				(type default)
			)
			(layer "F.Fab")
		)
		(fp_line
			(start -0.67945 0.3048)
			(end -0.67945 -0.305054)
			(stroke
				(width 0.1)
				(type default)
			)
			(layer "F.Fab")
		)
		(fp_line
			(start -0.67945 -0.305054)
			(end -0.12065 -0.305054)
			(stroke
				(width 0.1)
				(type default)
			)
			(layer "F.Fab")
		)
		(pad "1" smd circle
			(at -0.40005 0 180)
			(size 0 0)
			(layers "F.Cu" "F.Mask" "F.Paste")
			(net "EN_P3V3")
		)
		(pad "2" smd circle
			(at 0.40005 0 180)
			(size 0 0)
			(layers "F.Cu" "F.Mask" "F.Paste")
			(net "PWRGD_EN_P3V3_R")
		)
	)
	(footprint ""
		(layer "F.Cu")
		(at 29.2608 -32.639)
		(property "Reference" "L30"
			(at 0 0 0)
			(layer "F.SilkS")
			(hide yes)
			(effects
				(font
					(size 1.27 1.27)
				)
			)
		)
		(property "Value" ""
			(at 0 0 0)
			(layer "F.Fab")
			(effects
				(font
					(size 1.27 1.27)
				)
			)
		)
		(duplicate_pad_numbers_are_jumpers no)
		(fp_line
			(start -1.27 -0.5842)
			(end 1.27 -0.5842)
			(stroke
				(width 0.1524)
				(type default)
			)
			(layer "F.SilkS")
		)
		(fp_line
			(start -1.27 -0.5588)
			(end -1.27 -0.5842)
			(stroke
				(width 0.1524)
				(type default)
			)
			(layer "F.SilkS")
		)
		(fp_line
			(start -1.27 0.5842)
			(end -1.27 -0.5842)
			(stroke
				(width 0.1524)
				(type default)
			)
			(layer "F.SilkS")
		)
		(fp_line
			(start -0.127 0.5842)
			(end -0.127 -0.5842)
			(stroke
				(width 0.1524)
				(type default)
			)
			(layer "F.SilkS")
		)
		(fp_line
			(start 0.127 0.5842)
			(end 0.127 -0.5842)
			(stroke
				(width 0.1524)
				(type default)
			)
			(layer "F.SilkS")
		)
		(fp_line
			(start 1.27 0.5842)
			(end -1.27 0.5842)
			(stroke
				(width 0.1524)
				(type default)
			)
			(layer "F.SilkS")
		)
		(fp_line
			(start 1.27 0.5842)
			(end 1.27 -0.5842)
			(stroke
				(width 0.1524)
				(type default)
			)
			(layer "F.SilkS")
		)
		(fp_line
			(start -1.194308 -0.406654)
			(end -0.9144 -0.406654)
			(stroke
				(width 0.1)
				(type default)
			)
			(layer "F.Fab")
		)
		(fp_line
			(start -1.194308 0.406654)
			(end -1.194308 -0.406654)
			(stroke
				(width 0.1)
				(type default)
			)
			(layer "F.Fab")
		)
		(fp_line
			(start -0.9144 -0.508)
			(end 0.9144 -0.508)
			(stroke
				(width 0.1)
				(type default)
			)
			(layer "F.Fab")
		)
		(fp_line
			(start -0.9144 -0.406654)
			(end -0.9144 -0.508)
			(stroke
				(width 0.1)
				(type default)
			)
			(layer "F.Fab")
		)
		(fp_line
			(start -0.9144 0.406654)
			(end -1.194308 0.406654)
			(stroke
				(width 0.1)
				(type default)
			)
			(layer "F.Fab")
		)
		(fp_line
			(start -0.9144 0.508)
			(end -0.9144 0.406654)
			(stroke
				(width 0.1)
				(type default)
			)
			(layer "F.Fab")
		)
		(fp_line
			(start 0.9144 -0.508)
			(end 0.9144 -0.406654)
			(stroke
				(width 0.1)
				(type default)
			)
			(layer "F.Fab")
		)
		(fp_line
			(start 0.9144 -0.406654)
			(end 1.1938 -0.406654)
			(stroke
				(width 0.1)
				(type default)
			)
			(layer "F.Fab")
		)
		(fp_line
			(start 0.9144 0.4064)
			(end 0.9144 0.508)
			(stroke
				(width 0.1)
				(type default)
			)
			(layer "F.Fab")
		)
		(fp_line
			(start 0.9144 0.508)
			(end -0.9144 0.508)
			(stroke
				(width 0.1)
				(type default)
			)
			(layer "F.Fab")
		)
		(fp_line
			(start 1.1938 -0.406654)
			(end 1.1938 0.4064)
			(stroke
				(width 0.1)
				(type default)
			)
			(layer "F.Fab")
		)
		(fp_line
			(start 1.1938 0.4064)
			(end 0.9144 0.4064)
			(stroke
				(width 0.1)
				(type default)
			)
			(layer "F.Fab")
		)
		(pad "1" smd rect
			(at -0.7366 0 270)
			(size 0.7112 0.8128)
			(layers "F.Cu" "F.Mask" "F.Paste")
			(net "V_DACR")
		)
		(pad "2" smd rect
			(at 0.7366 0 270)
			(size 0.7112 0.8128)
			(layers "F.Cu" "F.Mask" "F.Paste")
			(net "V_DACR_IO")
		)
	)
	(footprint ""
		(layer "F.Cu")
		(at 10.739374 -52.008532 90)
		(property "Reference" "PR522"
			(at 0 0 90)
			(layer "F.SilkS")
			(hide yes)
			(effects
				(font
					(size 1.27 1.27)
				)
			)
		)
		(property "Value" ""
			(at 0 0 90)
			(layer "F.Fab")
			(effects
				(font
					(size 1.27 1.27)
				)
			)
		)
		(duplicate_pad_numbers_are_jumpers no)
		(fp_line
			(start 0.7874 -0.4064)
			(end 0.7874 0.4064)
			(stroke
				(width 0.1524)
				(type default)
			)
			(layer "F.SilkS")
		)
		(fp_line
			(start -0.7874 -0.4064)
			(end 0.7874 -0.4064)
			(stroke
				(width 0.1524)
				(type default)
			)
			(layer "F.SilkS")
		)
		(fp_line
			(start 0.7874 0.4064)
			(end -0.7874 0.4064)
			(stroke
				(width 0.1524)
				(type default)
			)
			(layer "F.SilkS")
		)
		(fp_line
			(start -0.7874 0.4064)
			(end -0.7874 -0.4064)
			(stroke
				(width 0.1524)
				(type default)
			)
			(layer "F.SilkS")
		)
		(fp_line
			(start -0.12065 -0.305054)
			(end -0.12065 -0.2794)
			(stroke
				(width 0.1)
				(type default)
			)
			(layer "F.Fab")
		)
		(fp_line
			(start -0.67945 -0.305054)
			(end -0.12065 -0.305054)
			(stroke
				(width 0.1)
				(type default)
			)
			(layer "F.Fab")
		)
		(fp_line
			(start 0.67945 -0.3048)
			(end 0.67945 0.3048)
			(stroke
				(width 0.1)
				(type default)
			)
			(layer "F.Fab")
		)
		(fp_line
			(start 0.12065 -0.3048)
			(end 0.67945 -0.3048)
			(stroke
				(width 0.1)
				(type default)
			)
			(layer "F.Fab")
		)
		(fp_line
			(start 0.12065 -0.2794)
			(end 0.12065 -0.3048)
			(stroke
				(width 0.1)
				(type default)
			)
			(layer "F.Fab")
		)
		(fp_line
			(start -0.12065 -0.2794)
			(end 0.12065 -0.2794)
			(stroke
				(width 0.1)
				(type default)
			)
			(layer "F.Fab")
		)
		(fp_line
			(start 0.120396 0.2794)
			(end -0.12065 0.2794)
			(stroke
				(width 0.1)
				(type default)
			)
			(layer "F.Fab")
		)
		(fp_line
			(start -0.12065 0.2794)
			(end -0.12065 0.3048)
			(stroke
				(width 0.1)
				(type default)
			)
			(layer "F.Fab")
		)
		(fp_line
			(start 0.67945 0.3048)
			(end 0.120396 0.3048)
			(stroke
				(width 0.1)
				(type default)
			)
			(layer "F.Fab")
		)
		(fp_line
			(start 0.120396 0.3048)
			(end 0.120396 0.2794)
			(stroke
				(width 0.1)
				(type default)
			)
			(layer "F.Fab")
		)
		(fp_line
			(start -0.12065 0.3048)
			(end -0.67945 0.3048)
			(stroke
				(width 0.1)
				(type default)
			)
			(layer "F.Fab")
		)
		(fp_line
			(start -0.67945 0.3048)
			(end -0.67945 -0.305054)
			(stroke
				(width 0.1)
				(type default)
			)
			(layer "F.Fab")
		)
		(pad "1" smd circle
			(at -0.40005 0 90)
			(size 0 0)
			(layers "F.Cu" "F.Mask" "F.Paste")
			(net "EN_P5V_AUX")
		)
		(pad "2" smd circle
			(at 0.40005 0 90)
			(size 0 0)
			(layers "F.Cu" "F.Mask" "F.Paste")
			(net "GND")
		)
	)
	(footprint ""
		(layer "F.Cu")
		(at 78.723744 -37.559488 -90)
		(property "Reference" "R361"
			(at 0 0 270)
			(layer "F.SilkS")
			(hide yes)
			(effects
				(font
					(size 1.27 1.27)
				)
			)
		)
		(property "Value" ""
			(at 0 0 270)
			(layer "F.Fab")
			(effects
				(font
					(size 1.27 1.27)
				)
			)
		)
		(duplicate_pad_numbers_are_jumpers no)
		(fp_line
			(start -0.7874 0.4064)
			(end -0.7874 -0.4064)
			(stroke
				(width 0.1524)
				(type default)
			)
			(layer "F.SilkS")
		)
		(fp_line
			(start 0.7874 0.4064)
			(end -0.7874 0.4064)
			(stroke
				(width 0.1524)
				(type default)
			)
			(layer "F.SilkS")
		)
		(fp_line
			(start -0.7874 -0.4064)
			(end 0.7874 -0.4064)
			(stroke
				(width 0.1524)
				(type default)
			)
			(layer "F.SilkS")
		)
		(fp_line
			(start 0.7874 -0.4064)
			(end 0.7874 0.4064)
			(stroke
				(width 0.1524)
				(type default)
			)
			(layer "F.SilkS")
		)
		(fp_line
			(start -0.67945 0.3048)
			(end -0.67945 -0.305054)
			(stroke
				(width 0.1)
				(type default)
			)
			(layer "F.Fab")
		)
		(fp_line
			(start -0.12065 0.3048)
			(end -0.67945 0.3048)
			(stroke
				(width 0.1)
				(type default)
			)
			(layer "F.Fab")
		)
		(fp_line
			(start 0.120396 0.3048)
			(end 0.120396 0.2794)
			(stroke
				(width 0.1)
				(type default)
			)
			(layer "F.Fab")
		)
		(fp_line
			(start 0.67945 0.3048)
			(end 0.120396 0.3048)
			(stroke
				(width 0.1)
				(type default)
			)
			(layer "F.Fab")
		)
		(fp_line
			(start -0.12065 0.2794)
			(end -0.12065 0.3048)
			(stroke
				(width 0.1)
				(type default)
			)
			(layer "F.Fab")
		)
		(fp_line
			(start 0.120396 0.2794)
			(end -0.12065 0.2794)
			(stroke
				(width 0.1)
				(type default)
			)
			(layer "F.Fab")
		)
		(fp_line
			(start -0.12065 -0.2794)
			(end 0.12065 -0.2794)
			(stroke
				(width 0.1)
				(type default)
			)
			(layer "F.Fab")
		)
		(fp_line
			(start 0.12065 -0.2794)
			(end 0.12065 -0.3048)
			(stroke
				(width 0.1)
				(type default)
			)
			(layer "F.Fab")
		)
		(fp_line
			(start 0.12065 -0.3048)
			(end 0.67945 -0.3048)
			(stroke
				(width 0.1)
				(type default)
			)
			(layer "F.Fab")
		)
		(fp_line
			(start 0.67945 -0.3048)
			(end 0.67945 0.3048)
			(stroke
				(width 0.1)
				(type default)
			)
			(layer "F.Fab")
		)
		(fp_line
			(start -0.67945 -0.305054)
			(end -0.12065 -0.305054)
			(stroke
				(width 0.1)
				(type default)
			)
			(layer "F.Fab")
		)
		(fp_line
			(start -0.12065 -0.305054)
			(end -0.12065 -0.2794)
			(stroke
				(width 0.1)
				(type default)
			)
			(layer "F.Fab")
		)
		(pad "1" smd circle
			(at -0.40005 0 270)
			(size 0 0)
			(layers "F.Cu" "F.Mask" "F.Paste")
			(net "M_BMC_DDR4_MA<10>")
		)
		(pad "2" smd circle
			(at 0.40005 0 270)
			(size 0 0)
			(layers "F.Cu" "F.Mask" "F.Paste")
			(net "P1V2_AUX")
		)
	)
	(footprint ""
		(layer "F.Cu")
		(at 11.3538 -109.347 90)
		(property "Reference" "R838"
			(at 0 0 90)
			(layer "F.SilkS")
			(hide yes)
			(effects
				(font
					(size 1.27 1.27)
				)
			)
		)
		(property "Value" ""
			(at 0 0 90)
			(layer "F.Fab")
			(effects
				(font
					(size 1.27 1.27)
				)
			)
		)
		(duplicate_pad_numbers_are_jumpers no)
		(fp_line
			(start 0.7874 -0.4064)
			(end 0.7874 0.4064)
			(stroke
				(width 0.1524)
				(type default)
			)
			(layer "F.SilkS")
		)
		(fp_line
			(start -0.7874 -0.4064)
			(end 0.7874 -0.4064)
			(stroke
				(width 0.1524)
				(type default)
			)
			(layer "F.SilkS")
		)
		(fp_line
			(start 0.7874 0.4064)
			(end -0.7874 0.4064)
			(stroke
				(width 0.1524)
				(type default)
			)
			(layer "F.SilkS")
		)
		(fp_line
			(start -0.7874 0.4064)
			(end -0.7874 -0.4064)
			(stroke
				(width 0.1524)
				(type default)
			)
			(layer "F.SilkS")
		)
		(fp_line
			(start -0.12065 -0.305054)
			(end -0.12065 -0.2794)
			(stroke
				(width 0.1)
				(type default)
			)
			(layer "F.Fab")
		)
		(fp_line
			(start -0.67945 -0.305054)
			(end -0.12065 -0.305054)
			(stroke
				(width 0.1)
				(type default)
			)
			(layer "F.Fab")
		)
		(fp_line
			(start 0.67945 -0.3048)
			(end 0.67945 0.3048)
			(stroke
				(width 0.1)
				(type default)
			)
			(layer "F.Fab")
		)
		(fp_line
			(start 0.12065 -0.3048)
			(end 0.67945 -0.3048)
			(stroke
				(width 0.1)
				(type default)
			)
			(layer "F.Fab")
		)
		(fp_line
			(start 0.12065 -0.2794)
			(end 0.12065 -0.3048)
			(stroke
				(width 0.1)
				(type default)
			)
			(layer "F.Fab")
		)
		(fp_line
			(start -0.12065 -0.2794)
			(end 0.12065 -0.2794)
			(stroke
				(width 0.1)
				(type default)
			)
			(layer "F.Fab")
		)
		(fp_line
			(start 0.120396 0.2794)
			(end -0.12065 0.2794)
			(stroke
				(width 0.1)
				(type default)
			)
			(layer "F.Fab")
		)
		(fp_line
			(start -0.12065 0.2794)
			(end -0.12065 0.3048)
			(stroke
				(width 0.1)
				(type default)
			)
			(layer "F.Fab")
		)
		(fp_line
			(start 0.67945 0.3048)
			(end 0.120396 0.3048)
			(stroke
				(width 0.1)
				(type default)
			)
			(layer "F.Fab")
		)
		(fp_line
			(start 0.120396 0.3048)
			(end 0.120396 0.2794)
			(stroke
				(width 0.1)
				(type default)
			)
			(layer "F.Fab")
		)
		(fp_line
			(start -0.12065 0.3048)
			(end -0.67945 0.3048)
			(stroke
				(width 0.1)
				(type default)
			)
			(layer "F.Fab")
		)
		(fp_line
			(start -0.67945 0.3048)
			(end -0.67945 -0.305054)
			(stroke
				(width 0.1)
				(type default)
			)
			(layer "F.Fab")
		)
		(pad "1" smd circle
			(at -0.40005 0 90)
			(size 0 0)
			(layers "F.Cu" "F.Mask" "F.Paste")
			(net "HDD_LED_N")
		)
		(pad "2" smd circle
			(at 0.40005 0 90)
			(size 0 0)
			(layers "F.Cu" "F.Mask" "F.Paste")
			(net "FM_HDD_LED_N")
		)
	)
	(footprint ""
		(layer "F.Cu")
		(at 74.09815 -91.061032 180)
		(property "Reference" "C143"
			(at 0 0 180)
			(layer "F.SilkS")
			(hide yes)
			(effects
				(font
					(size 1.27 1.27)
				)
			)
		)
		(property "Value" ""
			(at 0 0 180)
			(layer "F.Fab")
			(effects
				(font
					(size 1.27 1.27)
				)
			)
		)
		(duplicate_pad_numbers_are_jumpers no)
		(fp_line
			(start 0.7874 0.4064)
			(end -0.7874 0.4064)
			(stroke
				(width 0.1524)
				(type default)
			)
			(layer "F.SilkS")
		)
		(fp_line
			(start 0.7874 -0.4064)
			(end 0.7874 0.4064)
			(stroke
				(width 0.1524)
				(type default)
			)
			(layer "F.SilkS")
		)
		(fp_line
			(start -0.7874 0.4064)
			(end -0.7874 -0.4064)
			(stroke
				(width 0.1524)
				(type default)
			)
			(layer "F.SilkS")
		)
		(fp_line
			(start -0.7874 -0.4064)
			(end 0.7874 -0.4064)
			(stroke
				(width 0.1524)
				(type default)
			)
			(layer "F.SilkS")
		)
		(fp_line
			(start 0.67945 0.3048)
			(end 0.120396 0.3048)
			(stroke
				(width 0.1)
				(type default)
			)
			(layer "F.Fab")
		)
		(fp_line
			(start 0.67945 -0.3048)
			(end 0.67945 0.3048)
			(stroke
				(width 0.1)
				(type default)
			)
			(layer "F.Fab")
		)
		(fp_line
			(start 0.12065 -0.2794)
			(end 0.12065 -0.3048)
			(stroke
				(width 0.1)
				(type default)
			)
			(layer "F.Fab")
		)
		(fp_line
			(start 0.12065 -0.3048)
			(end 0.67945 -0.3048)
			(stroke
				(width 0.1)
				(type default)
			)
			(layer "F.Fab")
		)
		(fp_line
			(start 0.120396 0.3048)
			(end 0.120396 0.2794)
			(stroke
				(width 0.1)
				(type default)
			)
			(layer "F.Fab")
		)
		(fp_line
			(start 0.120396 0.2794)
			(end -0.12065 0.2794)
			(stroke
				(width 0.1)
				(type default)
			)
			(layer "F.Fab")
		)
		(fp_line
			(start -0.12065 0.3048)
			(end -0.67945 0.3048)
			(stroke
				(width 0.1)
				(type default)
			)
			(layer "F.Fab")
		)
		(fp_line
			(start -0.12065 0.2794)
			(end -0.12065 0.3048)
			(stroke
				(width 0.1)
				(type default)
			)
			(layer "F.Fab")
		)
		(fp_line
			(start -0.12065 -0.2794)
			(end 0.12065 -0.2794)
			(stroke
				(width 0.1)
				(type default)
			)
			(layer "F.Fab")
		)
		(fp_line
			(start -0.12065 -0.305054)
			(end -0.12065 -0.2794)
			(stroke
				(width 0.1)
				(type default)
			)
			(layer "F.Fab")
		)
		(fp_line
			(start -0.67945 0.3048)
			(end -0.67945 -0.305054)
			(stroke
				(width 0.1)
				(type default)
			)
			(layer "F.Fab")
		)
		(fp_line
			(start -0.67945 -0.305054)
			(end -0.12065 -0.305054)
			(stroke
				(width 0.1)
				(type default)
			)
			(layer "F.Fab")
		)
		(pad "1" smd circle
			(at -0.40005 0 180)
			(size 0 0)
			(layers "F.Cu" "F.Mask" "F.Paste")
			(net "P3V3_AUX")
		)
		(pad "2" smd circle
			(at 0.40005 0 180)
			(size 0 0)
			(layers "F.Cu" "F.Mask" "F.Paste")
			(net "GND")
		)
	)
	(footprint ""
		(layer "F.Cu")
		(at 36.56203 -88.937592 -90)
		(property "Reference" "C244"
			(at 0 0 270)
			(layer "F.SilkS")
			(hide yes)
			(effects
				(font
					(size 1.27 1.27)
				)
			)
		)
		(property "Value" ""
			(at 0 0 270)
			(layer "F.Fab")
			(effects
				(font
					(size 1.27 1.27)
				)
			)
		)
		(duplicate_pad_numbers_are_jumpers no)
		(fp_line
			(start -0.7874 0.4064)
			(end -0.7874 -0.4064)
			(stroke
				(width 0.1524)
				(type default)
			)
			(layer "F.SilkS")
		)
		(fp_line
			(start 0.7874 0.4064)
			(end -0.7874 0.4064)
			(stroke
				(width 0.1524)
				(type default)
			)
			(layer "F.SilkS")
		)
		(fp_line
			(start -0.7874 -0.4064)
			(end 0.7874 -0.4064)
			(stroke
				(width 0.1524)
				(type default)
			)
			(layer "F.SilkS")
		)
		(fp_line
			(start 0.7874 -0.4064)
			(end 0.7874 0.4064)
			(stroke
				(width 0.1524)
				(type default)
			)
			(layer "F.SilkS")
		)
		(fp_line
			(start -0.67945 0.3048)
			(end -0.67945 -0.305054)
			(stroke
				(width 0.1)
				(type default)
			)
			(layer "F.Fab")
		)
		(fp_line
			(start -0.12065 0.3048)
			(end -0.67945 0.3048)
			(stroke
				(width 0.1)
				(type default)
			)
			(layer "F.Fab")
		)
		(fp_line
			(start 0.120396 0.3048)
			(end 0.120396 0.2794)
			(stroke
				(width 0.1)
				(type default)
			)
			(layer "F.Fab")
		)
		(fp_line
			(start 0.67945 0.3048)
			(end 0.120396 0.3048)
			(stroke
				(width 0.1)
				(type default)
			)
			(layer "F.Fab")
		)
		(fp_line
			(start -0.12065 0.2794)
			(end -0.12065 0.3048)
			(stroke
				(width 0.1)
				(type default)
			)
			(layer "F.Fab")
		)
		(fp_line
			(start 0.120396 0.2794)
			(end -0.12065 0.2794)
			(stroke
				(width 0.1)
				(type default)
			)
			(layer "F.Fab")
		)
		(fp_line
			(start -0.12065 -0.2794)
			(end 0.12065 -0.2794)
			(stroke
				(width 0.1)
				(type default)
			)
			(layer "F.Fab")
		)
		(fp_line
			(start 0.12065 -0.2794)
			(end 0.12065 -0.3048)
			(stroke
				(width 0.1)
				(type default)
			)
			(layer "F.Fab")
		)
		(fp_line
			(start 0.12065 -0.3048)
			(end 0.67945 -0.3048)
			(stroke
				(width 0.1)
				(type default)
			)
			(layer "F.Fab")
		)
		(fp_line
			(start 0.67945 -0.3048)
			(end 0.67945 0.3048)
			(stroke
				(width 0.1)
				(type default)
			)
			(layer "F.Fab")
		)
		(fp_line
			(start -0.67945 -0.305054)
			(end -0.12065 -0.305054)
			(stroke
				(width 0.1)
				(type default)
			)
			(layer "F.Fab")
		)
		(fp_line
			(start -0.12065 -0.305054)
			(end -0.12065 -0.2794)
			(stroke
				(width 0.1)
				(type default)
			)
			(layer "F.Fab")
		)
		(pad "1" smd circle
			(at -0.40005 0 270)
			(size 0 0)
			(layers "F.Cu" "F.Mask" "F.Paste")
			(net "P3V3_AUX")
		)
		(pad "2" smd circle
			(at 0.40005 0 270)
			(size 0 0)
			(layers "F.Cu" "F.Mask" "F.Paste")
			(net "GND")
		)
	)
	(footprint ""
		(layer "F.Cu")
		(at 80.280764 -28.54579 90)
		(property "Reference" "R604"
			(at 0 0 90)
			(layer "F.SilkS")
			(hide yes)
			(effects
				(font
					(size 1.27 1.27)
				)
			)
		)
		(property "Value" ""
			(at 0 0 90)
			(layer "F.Fab")
			(effects
				(font
					(size 1.27 1.27)
				)
			)
		)
		(duplicate_pad_numbers_are_jumpers no)
		(fp_line
			(start 0.7874 -0.4064)
			(end 0.7874 0.4064)
			(stroke
				(width 0.1524)
				(type default)
			)
			(layer "F.SilkS")
		)
		(fp_line
			(start -0.7874 -0.4064)
			(end 0.7874 -0.4064)
			(stroke
				(width 0.1524)
				(type default)
			)
			(layer "F.SilkS")
		)
		(fp_line
			(start 0.7874 0.4064)
			(end -0.7874 0.4064)
			(stroke
				(width 0.1524)
				(type default)
			)
			(layer "F.SilkS")
		)
		(fp_line
			(start -0.7874 0.4064)
			(end -0.7874 -0.4064)
			(stroke
				(width 0.1524)
				(type default)
			)
			(layer "F.SilkS")
		)
		(fp_line
			(start -0.12065 -0.305054)
			(end -0.12065 -0.2794)
			(stroke
				(width 0.1)
				(type default)
			)
			(layer "F.Fab")
		)
		(fp_line
			(start -0.67945 -0.305054)
			(end -0.12065 -0.305054)
			(stroke
				(width 0.1)
				(type default)
			)
			(layer "F.Fab")
		)
		(fp_line
			(start 0.67945 -0.3048)
			(end 0.67945 0.3048)
			(stroke
				(width 0.1)
				(type default)
			)
			(layer "F.Fab")
		)
		(fp_line
			(start 0.12065 -0.3048)
			(end 0.67945 -0.3048)
			(stroke
				(width 0.1)
				(type default)
			)
			(layer "F.Fab")
		)
		(fp_line
			(start 0.12065 -0.2794)
			(end 0.12065 -0.3048)
			(stroke
				(width 0.1)
				(type default)
			)
			(layer "F.Fab")
		)
		(fp_line
			(start -0.12065 -0.2794)
			(end 0.12065 -0.2794)
			(stroke
				(width 0.1)
				(type default)
			)
			(layer "F.Fab")
		)
		(fp_line
			(start 0.120396 0.2794)
			(end -0.12065 0.2794)
			(stroke
				(width 0.1)
				(type default)
			)
			(layer "F.Fab")
		)
		(fp_line
			(start -0.12065 0.2794)
			(end -0.12065 0.3048)
			(stroke
				(width 0.1)
				(type default)
			)
			(layer "F.Fab")
		)
		(fp_line
			(start 0.67945 0.3048)
			(end 0.120396 0.3048)
			(stroke
				(width 0.1)
				(type default)
			)
			(layer "F.Fab")
		)
		(fp_line
			(start 0.120396 0.3048)
			(end 0.120396 0.2794)
			(stroke
				(width 0.1)
				(type default)
			)
			(layer "F.Fab")
		)
		(fp_line
			(start -0.12065 0.3048)
			(end -0.67945 0.3048)
			(stroke
				(width 0.1)
				(type default)
			)
			(layer "F.Fab")
		)
		(fp_line
			(start -0.67945 0.3048)
			(end -0.67945 -0.305054)
			(stroke
				(width 0.1)
				(type default)
			)
			(layer "F.Fab")
		)
		(pad "1" smd circle
			(at -0.40005 0 90)
			(size 0 0)
			(layers "F.Cu" "F.Mask" "F.Paste")
			(net "LED_POSTCODE_0")
		)
		(pad "2" smd circle
			(at 0.40005 0 90)
			(size 0 0)
			(layers "F.Cu" "F.Mask" "F.Paste")
			(net "LED_POSTCODE_0_R")
		)
	)
	(footprint ""
		(layer "F.Cu")
		(at 85.35924 -31.877)
		(property "Reference" "C287"
			(at 0 0 0)
			(layer "F.SilkS")
			(hide yes)
			(effects
				(font
					(size 1.27 1.27)
				)
			)
		)
		(property "Value" ""
			(at 0 0 0)
			(layer "F.Fab")
			(effects
				(font
					(size 1.27 1.27)
				)
			)
		)
		(duplicate_pad_numbers_are_jumpers no)
		(fp_line
			(start -0.7874 -0.4064)
			(end 0.7874 -0.4064)
			(stroke
				(width 0.1524)
				(type default)
			)
			(layer "F.SilkS")
		)
		(fp_line
			(start -0.7874 0.4064)
			(end -0.7874 -0.4064)
			(stroke
				(width 0.1524)
				(type default)
			)
			(layer "F.SilkS")
		)
		(fp_line
			(start 0.7874 -0.4064)
			(end 0.7874 0.4064)
			(stroke
				(width 0.1524)
				(type default)
			)
			(layer "F.SilkS")
		)
		(fp_line
			(start 0.7874 0.4064)
			(end -0.7874 0.4064)
			(stroke
				(width 0.1524)
				(type default)
			)
			(layer "F.SilkS")
		)
		(fp_line
			(start -0.67945 -0.305054)
			(end -0.12065 -0.305054)
			(stroke
				(width 0.1)
				(type default)
			)
			(layer "F.Fab")
		)
		(fp_line
			(start -0.67945 0.3048)
			(end -0.67945 -0.305054)
			(stroke
				(width 0.1)
				(type default)
			)
			(layer "F.Fab")
		)
		(fp_line
			(start -0.12065 -0.305054)
			(end -0.12065 -0.2794)
			(stroke
				(width 0.1)
				(type default)
			)
			(layer "F.Fab")
		)
		(fp_line
			(start -0.12065 -0.2794)
			(end 0.12065 -0.2794)
			(stroke
				(width 0.1)
				(type default)
			)
			(layer "F.Fab")
		)
		(fp_line
			(start -0.12065 0.2794)
			(end -0.12065 0.3048)
			(stroke
				(width 0.1)
				(type default)
			)
			(layer "F.Fab")
		)
		(fp_line
			(start -0.12065 0.3048)
			(end -0.67945 0.3048)
			(stroke
				(width 0.1)
				(type default)
			)
			(layer "F.Fab")
		)
		(fp_line
			(start 0.120396 0.2794)
			(end -0.12065 0.2794)
			(stroke
				(width 0.1)
				(type default)
			)
			(layer "F.Fab")
		)
		(fp_line
			(start 0.120396 0.3048)
			(end 0.120396 0.2794)
			(stroke
				(width 0.1)
				(type default)
			)
			(layer "F.Fab")
		)
		(fp_line
			(start 0.12065 -0.3048)
			(end 0.67945 -0.3048)
			(stroke
				(width 0.1)
				(type default)
			)
			(layer "F.Fab")
		)
		(fp_line
			(start 0.12065 -0.2794)
			(end 0.12065 -0.3048)
			(stroke
				(width 0.1)
				(type default)
			)
			(layer "F.Fab")
		)
		(fp_line
			(start 0.67945 -0.3048)
			(end 0.67945 0.3048)
			(stroke
				(width 0.1)
				(type default)
			)
			(layer "F.Fab")
		)
		(fp_line
			(start 0.67945 0.3048)
			(end 0.120396 0.3048)
			(stroke
				(width 0.1)
				(type default)
			)
			(layer "F.Fab")
		)
		(pad "1" smd circle
			(at -0.40005 0)
			(size 0 0)
			(layers "F.Cu" "F.Mask" "F.Paste")
			(net "P5V_AUX")
		)
		(pad "2" smd circle
			(at 0.40005 0)
			(size 0 0)
			(layers "F.Cu" "F.Mask" "F.Paste")
			(net "GND")
		)
	)
	(footprint ""
		(layer "F.Cu")
		(at 34.1884 -108.966 180)
		(property "Reference" "R68"
			(at 0 0 180)
			(layer "F.SilkS")
			(hide yes)
			(effects
				(font
					(size 1.27 1.27)
				)
			)
		)
		(property "Value" ""
			(at 0 0 180)
			(layer "F.Fab")
			(effects
				(font
					(size 1.27 1.27)
				)
			)
		)
		(duplicate_pad_numbers_are_jumpers no)
		(fp_line
			(start 0.7874 0.4064)
			(end -0.7874 0.4064)
			(stroke
				(width 0.1524)
				(type default)
			)
			(layer "F.SilkS")
		)
		(fp_line
			(start 0.7874 -0.4064)
			(end 0.7874 0.4064)
			(stroke
				(width 0.1524)
				(type default)
			)
			(layer "F.SilkS")
		)
		(fp_line
			(start -0.7874 0.4064)
			(end -0.7874 -0.4064)
			(stroke
				(width 0.1524)
				(type default)
			)
			(layer "F.SilkS")
		)
		(fp_line
			(start -0.7874 -0.4064)
			(end 0.7874 -0.4064)
			(stroke
				(width 0.1524)
				(type default)
			)
			(layer "F.SilkS")
		)
		(fp_line
			(start 0.67945 0.3048)
			(end 0.120396 0.3048)
			(stroke
				(width 0.1)
				(type default)
			)
			(layer "F.Fab")
		)
		(fp_line
			(start 0.67945 -0.3048)
			(end 0.67945 0.3048)
			(stroke
				(width 0.1)
				(type default)
			)
			(layer "F.Fab")
		)
		(fp_line
			(start 0.12065 -0.2794)
			(end 0.12065 -0.3048)
			(stroke
				(width 0.1)
				(type default)
			)
			(layer "F.Fab")
		)
		(fp_line
			(start 0.12065 -0.3048)
			(end 0.67945 -0.3048)
			(stroke
				(width 0.1)
				(type default)
			)
			(layer "F.Fab")
		)
		(fp_line
			(start 0.120396 0.3048)
			(end 0.120396 0.2794)
			(stroke
				(width 0.1)
				(type default)
			)
			(layer "F.Fab")
		)
		(fp_line
			(start 0.120396 0.2794)
			(end -0.12065 0.2794)
			(stroke
				(width 0.1)
				(type default)
			)
			(layer "F.Fab")
		)
		(fp_line
			(start -0.12065 0.3048)
			(end -0.67945 0.3048)
			(stroke
				(width 0.1)
				(type default)
			)
			(layer "F.Fab")
		)
		(fp_line
			(start -0.12065 0.2794)
			(end -0.12065 0.3048)
			(stroke
				(width 0.1)
				(type default)
			)
			(layer "F.Fab")
		)
		(fp_line
			(start -0.12065 -0.2794)
			(end 0.12065 -0.2794)
			(stroke
				(width 0.1)
				(type default)
			)
			(layer "F.Fab")
		)
		(fp_line
			(start -0.12065 -0.305054)
			(end -0.12065 -0.2794)
			(stroke
				(width 0.1)
				(type default)
			)
			(layer "F.Fab")
		)
		(fp_line
			(start -0.67945 0.3048)
			(end -0.67945 -0.305054)
			(stroke
				(width 0.1)
				(type default)
			)
			(layer "F.Fab")
		)
		(fp_line
			(start -0.67945 -0.305054)
			(end -0.12065 -0.305054)
			(stroke
				(width 0.1)
				(type default)
			)
			(layer "F.Fab")
		)
		(pad "1" smd circle
			(at -0.40005 0 180)
			(size 0 0)
			(layers "F.Cu" "F.Mask" "F.Paste")
			(net "P3V3_AUX")
		)
		(pad "2" smd circle
			(at 0.40005 0 180)
			(size 0 0)
			(layers "F.Cu" "F.Mask" "F.Paste")
			(net "IRQ_SGPIO_N")
		)
	)
	(footprint ""
		(layer "F.Cu")
		(at -14.404086 -10.924032)
		(property "Reference" "DB5"
			(at -3.5052 -5.552948 0)
			(unlocked yes)
			(layer "F.SilkS")
			(effects
				(font
					(size 0.7874 0.5842)
					(thickness 0.1524)
				)
				(justify left)
			)
		)
		(property "Value" ""
			(at 0 0 0)
			(layer "F.Fab")
			(effects
				(font
					(size 1.27 1.27)
				)
			)
		)
		(duplicate_pad_numbers_are_jumpers no)
		(fp_line
			(start -3.330702 -4.771136)
			(end 3.330702 -4.771136)
			(stroke
				(width 0.1524)
				(type default)
			)
			(layer "F.SilkS")
		)
		(fp_line
			(start 0 4.011168)
			(end -3.330702 -4.771136)
			(stroke
				(width 0.1524)
				(type default)
			)
			(layer "F.SilkS")
		)
		(fp_line
			(start 3.330702 -4.771136)
			(end 0 4.011168)
			(stroke
				(width 0.1524)
				(type default)
			)
			(layer "F.SilkS")
		)
		(fp_line
			(start -3.330702 -4.771136)
			(end 3.330702 -4.771136)
			(stroke
				(width 0.1)
				(type default)
			)
			(layer "F.Fab")
		)
		(fp_line
			(start 0 4.011168)
			(end -3.330702 -4.771136)
			(stroke
				(width 0.1)
				(type default)
			)
			(layer "F.Fab")
		)
		(fp_line
			(start 3.330702 -4.771136)
			(end 0 4.011168)
			(stroke
				(width 0.1)
				(type default)
			)
			(layer "F.Fab")
		)
		(pad "1" thru_hole circle
			(at 0 0)
			(size 2.159 2.159)
			(drill 1.7018)
			(layers "*.Cu" "*.Mask")
			(remove_unused_layers no)
			(net "T_GND")
			(clearance 0.0254)
			(thermal_gap 0.0254)
		)
		(pad "2" thru_hole circle
			(at -1.27 -3.348736)
			(size 2.159 2.159)
			(drill 1.7018)
			(layers "*.Cu" "*.Mask")
			(remove_unused_layers no)
			(net "TDR_SE_50_OHM_IN4")
			(clearance 0.0254)
			(thermal_gap 0.0254)
		)
		(pad "3" thru_hole circle
			(at 1.27 -3.348736)
			(size 2.159 2.159)
			(drill 1.7018)
			(layers "*.Cu" "*.Mask")
			(remove_unused_layers no)
			(net "TDR_SE_50_OHM_IN4")
			(clearance 0.0254)
			(thermal_gap 0.0254)
		)
	)
	(footprint ""
		(layer "F.Cu")
		(at 11.43 -31.837122 -90)
		(property "Reference" "PC217"
			(at 0 0 270)
			(layer "F.SilkS")
			(hide yes)
			(effects
				(font
					(size 1.27 1.27)
				)
			)
		)
		(property "Value" ""
			(at 0 0 270)
			(layer "F.Fab")
			(effects
				(font
					(size 1.27 1.27)
				)
			)
		)
		(duplicate_pad_numbers_are_jumpers no)
		(fp_line
			(start -1.651 0.8382)
			(end -1.651 -0.8382)
			(stroke
				(width 0.1524)
				(type default)
			)
			(layer "F.SilkS")
		)
		(fp_line
			(start 0 0.8382)
			(end 0 -0.8382)
			(stroke
				(width 0.1524)
				(type default)
			)
			(layer "F.SilkS")
		)
		(fp_line
			(start 1.651 0.8382)
			(end -1.651 0.8382)
			(stroke
				(width 0.1524)
				(type default)
			)
			(layer "F.SilkS")
		)
		(fp_line
			(start -1.651 -0.8382)
			(end 1.651 -0.8382)
			(stroke
				(width 0.1524)
				(type default)
			)
			(layer "F.SilkS")
		)
		(fp_line
			(start 1.651 -0.8382)
			(end 1.651 0.8382)
			(stroke
				(width 0.1524)
				(type default)
			)
			(layer "F.SilkS")
		)
		(fp_line
			(start -1.55956 0.7366)
			(end -1.524 0.7366)
			(stroke
				(width 0.1)
				(type default)
			)
			(layer "F.Fab")
		)
		(fp_line
			(start -1.524 0.7366)
			(end 1.524 0.7366)
			(stroke
				(width 0.1)
				(type default)
			)
			(layer "F.Fab")
		)
		(fp_line
			(start 1.524 0.7366)
			(end 1.55956 0.7366)
			(stroke
				(width 0.1)
				(type default)
			)
			(layer "F.Fab")
		)
		(fp_line
			(start 1.55956 0.7366)
			(end 1.55956 -0.7366)
			(stroke
				(width 0.1)
				(type default)
			)
			(layer "F.Fab")
		)
		(fp_line
			(start -1.55956 -0.7366)
			(end -1.55956 0.7366)
			(stroke
				(width 0.1)
				(type default)
			)
			(layer "F.Fab")
		)
		(fp_line
			(start -1.524 -0.7366)
			(end -1.55956 -0.7366)
			(stroke
				(width 0.1)
				(type default)
			)
			(layer "F.Fab")
		)
		(fp_line
			(start 1.524 -0.7366)
			(end -1.524 -0.7366)
			(stroke
				(width 0.1)
				(type default)
			)
			(layer "F.Fab")
		)
		(fp_line
			(start 1.55956 -0.7366)
			(end 1.524 -0.7366)
			(stroke
				(width 0.1)
				(type default)
			)
			(layer "F.Fab")
		)
		(pad "1" smd rect
			(at -0.94996 0 90)
			(size 1.1176 1.3716)
			(layers "F.Cu" "F.Mask" "F.Paste")
			(net "P5V_AUX")
		)
		(pad "2" smd rect
			(at 0.94996 0 90)
			(size 1.1176 1.3716)
			(layers "F.Cu" "F.Mask" "F.Paste")
			(net "GND")
		)
	)
	(footprint ""
		(layer "F.Cu")
		(at 46.863 -24.384)
		(property "Reference" "R383"
			(at 0 0 0)
			(layer "F.SilkS")
			(hide yes)
			(effects
				(font
					(size 1.27 1.27)
				)
			)
		)
		(property "Value" ""
			(at 0 0 0)
			(layer "F.Fab")
			(effects
				(font
					(size 1.27 1.27)
				)
			)
		)
		(duplicate_pad_numbers_are_jumpers no)
		(fp_line
			(start -0.7874 -0.4064)
			(end 0.7874 -0.4064)
			(stroke
				(width 0.1524)
				(type default)
			)
			(layer "F.SilkS")
		)
		(fp_line
			(start -0.7874 0.4064)
			(end -0.7874 -0.4064)
			(stroke
				(width 0.1524)
				(type default)
			)
			(layer "F.SilkS")
		)
		(fp_line
			(start 0.7874 -0.4064)
			(end 0.7874 0.4064)
			(stroke
				(width 0.1524)
				(type default)
			)
			(layer "F.SilkS")
		)
		(fp_line
			(start 0.7874 0.4064)
			(end -0.7874 0.4064)
			(stroke
				(width 0.1524)
				(type default)
			)
			(layer "F.SilkS")
		)
		(fp_line
			(start -0.67945 -0.305054)
			(end -0.12065 -0.305054)
			(stroke
				(width 0.1)
				(type default)
			)
			(layer "F.Fab")
		)
		(fp_line
			(start -0.67945 0.3048)
			(end -0.67945 -0.305054)
			(stroke
				(width 0.1)
				(type default)
			)
			(layer "F.Fab")
		)
		(fp_line
			(start -0.12065 -0.305054)
			(end -0.12065 -0.2794)
			(stroke
				(width 0.1)
				(type default)
			)
			(layer "F.Fab")
		)
		(fp_line
			(start -0.12065 -0.2794)
			(end 0.12065 -0.2794)
			(stroke
				(width 0.1)
				(type default)
			)
			(layer "F.Fab")
		)
		(fp_line
			(start -0.12065 0.2794)
			(end -0.12065 0.3048)
			(stroke
				(width 0.1)
				(type default)
			)
			(layer "F.Fab")
		)
		(fp_line
			(start -0.12065 0.3048)
			(end -0.67945 0.3048)
			(stroke
				(width 0.1)
				(type default)
			)
			(layer "F.Fab")
		)
		(fp_line
			(start 0.120396 0.2794)
			(end -0.12065 0.2794)
			(stroke
				(width 0.1)
				(type default)
			)
			(layer "F.Fab")
		)
		(fp_line
			(start 0.120396 0.3048)
			(end 0.120396 0.2794)
			(stroke
				(width 0.1)
				(type default)
			)
			(layer "F.Fab")
		)
		(fp_line
			(start 0.12065 -0.3048)
			(end 0.67945 -0.3048)
			(stroke
				(width 0.1)
				(type default)
			)
			(layer "F.Fab")
		)
		(fp_line
			(start 0.12065 -0.2794)
			(end 0.12065 -0.3048)
			(stroke
				(width 0.1)
				(type default)
			)
			(layer "F.Fab")
		)
		(fp_line
			(start 0.67945 -0.3048)
			(end 0.67945 0.3048)
			(stroke
				(width 0.1)
				(type default)
			)
			(layer "F.Fab")
		)
		(fp_line
			(start 0.67945 0.3048)
			(end 0.120396 0.3048)
			(stroke
				(width 0.1)
				(type default)
			)
			(layer "F.Fab")
		)
		(pad "1" smd circle
			(at -0.40005 0)
			(size 0 0)
			(layers "F.Cu" "F.Mask" "F.Paste")
			(net "P3V3_AUX")
		)
		(pad "2" smd circle
			(at 0.40005 0)
			(size 0 0)
			(layers "F.Cu" "F.Mask" "F.Paste")
			(net "USB_OC0_REAR_N")
		)
	)
	(footprint ""
		(layer "F.Cu")
		(at 53.537612 -28.027376 -90)
		(property "Reference" "C37"
			(at 0 0 270)
			(layer "F.SilkS")
			(hide yes)
			(effects
				(font
					(size 1.27 1.27)
				)
			)
		)
		(property "Value" ""
			(at 0 0 270)
			(layer "F.Fab")
			(effects
				(font
					(size 1.27 1.27)
				)
			)
		)
		(duplicate_pad_numbers_are_jumpers no)
		(fp_line
			(start -0.7874 0.4064)
			(end -0.7874 -0.4064)
			(stroke
				(width 0.1524)
				(type default)
			)
			(layer "F.SilkS")
		)
		(fp_line
			(start 0.7874 0.4064)
			(end -0.7874 0.4064)
			(stroke
				(width 0.1524)
				(type default)
			)
			(layer "F.SilkS")
		)
		(fp_line
			(start -0.7874 -0.4064)
			(end 0.7874 -0.4064)
			(stroke
				(width 0.1524)
				(type default)
			)
			(layer "F.SilkS")
		)
		(fp_line
			(start 0.7874 -0.4064)
			(end 0.7874 0.4064)
			(stroke
				(width 0.1524)
				(type default)
			)
			(layer "F.SilkS")
		)
		(fp_line
			(start -0.67945 0.3048)
			(end -0.67945 -0.305054)
			(stroke
				(width 0.1)
				(type default)
			)
			(layer "F.Fab")
		)
		(fp_line
			(start -0.12065 0.3048)
			(end -0.67945 0.3048)
			(stroke
				(width 0.1)
				(type default)
			)
			(layer "F.Fab")
		)
		(fp_line
			(start 0.120396 0.3048)
			(end 0.120396 0.2794)
			(stroke
				(width 0.1)
				(type default)
			)
			(layer "F.Fab")
		)
		(fp_line
			(start 0.67945 0.3048)
			(end 0.120396 0.3048)
			(stroke
				(width 0.1)
				(type default)
			)
			(layer "F.Fab")
		)
		(fp_line
			(start -0.12065 0.2794)
			(end -0.12065 0.3048)
			(stroke
				(width 0.1)
				(type default)
			)
			(layer "F.Fab")
		)
		(fp_line
			(start 0.120396 0.2794)
			(end -0.12065 0.2794)
			(stroke
				(width 0.1)
				(type default)
			)
			(layer "F.Fab")
		)
		(fp_line
			(start -0.12065 -0.2794)
			(end 0.12065 -0.2794)
			(stroke
				(width 0.1)
				(type default)
			)
			(layer "F.Fab")
		)
		(fp_line
			(start 0.12065 -0.2794)
			(end 0.12065 -0.3048)
			(stroke
				(width 0.1)
				(type default)
			)
			(layer "F.Fab")
		)
		(fp_line
			(start 0.12065 -0.3048)
			(end 0.67945 -0.3048)
			(stroke
				(width 0.1)
				(type default)
			)
			(layer "F.Fab")
		)
		(fp_line
			(start 0.67945 -0.3048)
			(end 0.67945 0.3048)
			(stroke
				(width 0.1)
				(type default)
			)
			(layer "F.Fab")
		)
		(fp_line
			(start -0.67945 -0.305054)
			(end -0.12065 -0.305054)
			(stroke
				(width 0.1)
				(type default)
			)
			(layer "F.Fab")
		)
		(fp_line
			(start -0.12065 -0.305054)
			(end -0.12065 -0.2794)
			(stroke
				(width 0.1)
				(type default)
			)
			(layer "F.Fab")
		)
		(pad "1" smd circle
			(at -0.40005 0 270)
			(size 0 0)
			(layers "F.Cu" "F.Mask" "F.Paste")
			(net "P3V3_RGM")
		)
		(pad "2" smd circle
			(at 0.40005 0 270)
			(size 0 0)
			(layers "F.Cu" "F.Mask" "F.Paste")
			(net "GND")
		)
	)
	(footprint ""
		(layer "F.Cu")
		(at 32.512 -13.7922)
		(property "Reference" "C276"
			(at 0 0 0)
			(layer "F.SilkS")
			(hide yes)
			(effects
				(font
					(size 1.27 1.27)
				)
			)
		)
		(property "Value" ""
			(at 0 0 0)
			(layer "F.Fab")
			(effects
				(font
					(size 1.27 1.27)
				)
			)
		)
		(duplicate_pad_numbers_are_jumpers no)
		(fp_line
			(start -0.7874 -0.4064)
			(end 0.7874 -0.4064)
			(stroke
				(width 0.1524)
				(type default)
			)
			(layer "F.SilkS")
		)
		(fp_line
			(start -0.7874 0.4064)
			(end -0.7874 -0.4064)
			(stroke
				(width 0.1524)
				(type default)
			)
			(layer "F.SilkS")
		)
		(fp_line
			(start 0.7874 -0.4064)
			(end 0.7874 0.4064)
			(stroke
				(width 0.1524)
				(type default)
			)
			(layer "F.SilkS")
		)
		(fp_line
			(start 0.7874 0.4064)
			(end -0.7874 0.4064)
			(stroke
				(width 0.1524)
				(type default)
			)
			(layer "F.SilkS")
		)
		(fp_line
			(start -0.67945 -0.305054)
			(end -0.12065 -0.305054)
			(stroke
				(width 0.1)
				(type default)
			)
			(layer "F.Fab")
		)
		(fp_line
			(start -0.67945 0.3048)
			(end -0.67945 -0.305054)
			(stroke
				(width 0.1)
				(type default)
			)
			(layer "F.Fab")
		)
		(fp_line
			(start -0.12065 -0.305054)
			(end -0.12065 -0.2794)
			(stroke
				(width 0.1)
				(type default)
			)
			(layer "F.Fab")
		)
		(fp_line
			(start -0.12065 -0.2794)
			(end 0.12065 -0.2794)
			(stroke
				(width 0.1)
				(type default)
			)
			(layer "F.Fab")
		)
		(fp_line
			(start -0.12065 0.2794)
			(end -0.12065 0.3048)
			(stroke
				(width 0.1)
				(type default)
			)
			(layer "F.Fab")
		)
		(fp_line
			(start -0.12065 0.3048)
			(end -0.67945 0.3048)
			(stroke
				(width 0.1)
				(type default)
			)
			(layer "F.Fab")
		)
		(fp_line
			(start 0.120396 0.2794)
			(end -0.12065 0.2794)
			(stroke
				(width 0.1)
				(type default)
			)
			(layer "F.Fab")
		)
		(fp_line
			(start 0.120396 0.3048)
			(end 0.120396 0.2794)
			(stroke
				(width 0.1)
				(type default)
			)
			(layer "F.Fab")
		)
		(fp_line
			(start 0.12065 -0.3048)
			(end 0.67945 -0.3048)
			(stroke
				(width 0.1)
				(type default)
			)
			(layer "F.Fab")
		)
		(fp_line
			(start 0.12065 -0.2794)
			(end 0.12065 -0.3048)
			(stroke
				(width 0.1)
				(type default)
			)
			(layer "F.Fab")
		)
		(fp_line
			(start 0.67945 -0.3048)
			(end 0.67945 0.3048)
			(stroke
				(width 0.1)
				(type default)
			)
			(layer "F.Fab")
		)
		(fp_line
			(start 0.67945 0.3048)
			(end 0.120396 0.3048)
			(stroke
				(width 0.1)
				(type default)
			)
			(layer "F.Fab")
		)
		(pad "1" smd circle
			(at -0.40005 0)
			(size 0 0)
			(layers "F.Cu" "F.Mask" "F.Paste")
			(net "P3V3_AUX")
		)
		(pad "2" smd circle
			(at 0.40005 0)
			(size 0 0)
			(layers "F.Cu" "F.Mask" "F.Paste")
			(net "GND")
		)
	)
	(footprint ""
		(layer "F.Cu")
		(at 85.29955 -46.717204 180)
		(property "Reference" "R347"
			(at 0 0 180)
			(layer "F.SilkS")
			(hide yes)
			(effects
				(font
					(size 1.27 1.27)
				)
			)
		)
		(property "Value" ""
			(at 0 0 180)
			(layer "F.Fab")
			(effects
				(font
					(size 1.27 1.27)
				)
			)
		)
		(duplicate_pad_numbers_are_jumpers no)
		(fp_line
			(start 0.7874 0.4064)
			(end -0.7874 0.4064)
			(stroke
				(width 0.1524)
				(type default)
			)
			(layer "F.SilkS")
		)
		(fp_line
			(start 0.7874 -0.4064)
			(end 0.7874 0.4064)
			(stroke
				(width 0.1524)
				(type default)
			)
			(layer "F.SilkS")
		)
		(fp_line
			(start -0.7874 0.4064)
			(end -0.7874 -0.4064)
			(stroke
				(width 0.1524)
				(type default)
			)
			(layer "F.SilkS")
		)
		(fp_line
			(start -0.7874 -0.4064)
			(end 0.7874 -0.4064)
			(stroke
				(width 0.1524)
				(type default)
			)
			(layer "F.SilkS")
		)
		(fp_line
			(start 0.67945 0.3048)
			(end 0.120396 0.3048)
			(stroke
				(width 0.1)
				(type default)
			)
			(layer "F.Fab")
		)
		(fp_line
			(start 0.67945 -0.3048)
			(end 0.67945 0.3048)
			(stroke
				(width 0.1)
				(type default)
			)
			(layer "F.Fab")
		)
		(fp_line
			(start 0.12065 -0.2794)
			(end 0.12065 -0.3048)
			(stroke
				(width 0.1)
				(type default)
			)
			(layer "F.Fab")
		)
		(fp_line
			(start 0.12065 -0.3048)
			(end 0.67945 -0.3048)
			(stroke
				(width 0.1)
				(type default)
			)
			(layer "F.Fab")
		)
		(fp_line
			(start 0.120396 0.3048)
			(end 0.120396 0.2794)
			(stroke
				(width 0.1)
				(type default)
			)
			(layer "F.Fab")
		)
		(fp_line
			(start 0.120396 0.2794)
			(end -0.12065 0.2794)
			(stroke
				(width 0.1)
				(type default)
			)
			(layer "F.Fab")
		)
		(fp_line
			(start -0.12065 0.3048)
			(end -0.67945 0.3048)
			(stroke
				(width 0.1)
				(type default)
			)
			(layer "F.Fab")
		)
		(fp_line
			(start -0.12065 0.2794)
			(end -0.12065 0.3048)
			(stroke
				(width 0.1)
				(type default)
			)
			(layer "F.Fab")
		)
		(fp_line
			(start -0.12065 -0.2794)
			(end 0.12065 -0.2794)
			(stroke
				(width 0.1)
				(type default)
			)
			(layer "F.Fab")
		)
		(fp_line
			(start -0.12065 -0.305054)
			(end -0.12065 -0.2794)
			(stroke
				(width 0.1)
				(type default)
			)
			(layer "F.Fab")
		)
		(fp_line
			(start -0.67945 0.3048)
			(end -0.67945 -0.305054)
			(stroke
				(width 0.1)
				(type default)
			)
			(layer "F.Fab")
		)
		(fp_line
			(start -0.67945 -0.305054)
			(end -0.12065 -0.305054)
			(stroke
				(width 0.1)
				(type default)
			)
			(layer "F.Fab")
		)
		(pad "1" smd circle
			(at -0.40005 0 180)
			(size 0 0)
			(layers "F.Cu" "F.Mask" "F.Paste")
			(net "GND")
		)
		(pad "2" smd circle
			(at 0.40005 0 180)
			(size 0 0)
			(layers "F.Cu" "F.Mask" "F.Paste")
			(net "M_BMC_DDR4_MBA1")
		)
	)
	(footprint ""
		(layer "F.Cu")
		(at 37.61232 -106.4895 180)
		(property "Reference" "R482"
			(at 0 0 180)
			(layer "F.SilkS")
			(hide yes)
			(effects
				(font
					(size 1.27 1.27)
				)
			)
		)
		(property "Value" ""
			(at 0 0 180)
			(layer "F.Fab")
			(effects
				(font
					(size 1.27 1.27)
				)
			)
		)
		(duplicate_pad_numbers_are_jumpers no)
		(fp_line
			(start 0.7874 0.4064)
			(end -0.7874 0.4064)
			(stroke
				(width 0.1524)
				(type default)
			)
			(layer "F.SilkS")
		)
		(fp_line
			(start 0.7874 -0.4064)
			(end 0.7874 0.4064)
			(stroke
				(width 0.1524)
				(type default)
			)
			(layer "F.SilkS")
		)
		(fp_line
			(start -0.7874 0.4064)
			(end -0.7874 -0.4064)
			(stroke
				(width 0.1524)
				(type default)
			)
			(layer "F.SilkS")
		)
		(fp_line
			(start -0.7874 -0.4064)
			(end 0.7874 -0.4064)
			(stroke
				(width 0.1524)
				(type default)
			)
			(layer "F.SilkS")
		)
		(fp_line
			(start 0.67945 0.3048)
			(end 0.120396 0.3048)
			(stroke
				(width 0.1)
				(type default)
			)
			(layer "F.Fab")
		)
		(fp_line
			(start 0.67945 -0.3048)
			(end 0.67945 0.3048)
			(stroke
				(width 0.1)
				(type default)
			)
			(layer "F.Fab")
		)
		(fp_line
			(start 0.12065 -0.2794)
			(end 0.12065 -0.3048)
			(stroke
				(width 0.1)
				(type default)
			)
			(layer "F.Fab")
		)
		(fp_line
			(start 0.12065 -0.3048)
			(end 0.67945 -0.3048)
			(stroke
				(width 0.1)
				(type default)
			)
			(layer "F.Fab")
		)
		(fp_line
			(start 0.120396 0.3048)
			(end 0.120396 0.2794)
			(stroke
				(width 0.1)
				(type default)
			)
			(layer "F.Fab")
		)
		(fp_line
			(start 0.120396 0.2794)
			(end -0.12065 0.2794)
			(stroke
				(width 0.1)
				(type default)
			)
			(layer "F.Fab")
		)
		(fp_line
			(start -0.12065 0.3048)
			(end -0.67945 0.3048)
			(stroke
				(width 0.1)
				(type default)
			)
			(layer "F.Fab")
		)
		(fp_line
			(start -0.12065 0.2794)
			(end -0.12065 0.3048)
			(stroke
				(width 0.1)
				(type default)
			)
			(layer "F.Fab")
		)
		(fp_line
			(start -0.12065 -0.2794)
			(end 0.12065 -0.2794)
			(stroke
				(width 0.1)
				(type default)
			)
			(layer "F.Fab")
		)
		(fp_line
			(start -0.12065 -0.305054)
			(end -0.12065 -0.2794)
			(stroke
				(width 0.1)
				(type default)
			)
			(layer "F.Fab")
		)
		(fp_line
			(start -0.67945 0.3048)
			(end -0.67945 -0.305054)
			(stroke
				(width 0.1)
				(type default)
			)
			(layer "F.Fab")
		)
		(fp_line
			(start -0.67945 -0.305054)
			(end -0.12065 -0.305054)
			(stroke
				(width 0.1)
				(type default)
			)
			(layer "F.Fab")
		)
		(pad "1" smd circle
			(at -0.40005 0 180)
			(size 0 0)
			(layers "F.Cu" "F.Mask" "F.Paste")
			(net "SPI_PCH_MUXED_IO0")
		)
		(pad "2" smd circle
			(at 0.40005 0 180)
			(size 0 0)
			(layers "F.Cu" "F.Mask" "F.Paste")
			(net "SPI_PCH_IO0_FLASH_R1")
		)
	)
	(footprint ""
		(layer "F.Cu")
		(at 16.002 -102.743 -90)
		(property "Reference" "R574"
			(at 0 0 270)
			(layer "F.SilkS")
			(hide yes)
			(effects
				(font
					(size 1.27 1.27)
				)
			)
		)
		(property "Value" ""
			(at 0 0 270)
			(layer "F.Fab")
			(effects
				(font
					(size 1.27 1.27)
				)
			)
		)
		(duplicate_pad_numbers_are_jumpers no)
		(fp_line
			(start -0.7874 0.4064)
			(end -0.7874 -0.4064)
			(stroke
				(width 0.1524)
				(type default)
			)
			(layer "F.SilkS")
		)
		(fp_line
			(start 0.7874 0.4064)
			(end -0.7874 0.4064)
			(stroke
				(width 0.1524)
				(type default)
			)
			(layer "F.SilkS")
		)
		(fp_line
			(start -0.7874 -0.4064)
			(end 0.7874 -0.4064)
			(stroke
				(width 0.1524)
				(type default)
			)
			(layer "F.SilkS")
		)
		(fp_line
			(start 0.7874 -0.4064)
			(end 0.7874 0.4064)
			(stroke
				(width 0.1524)
				(type default)
			)
			(layer "F.SilkS")
		)
		(fp_line
			(start -0.67945 0.3048)
			(end -0.67945 -0.305054)
			(stroke
				(width 0.1)
				(type default)
			)
			(layer "F.Fab")
		)
		(fp_line
			(start -0.12065 0.3048)
			(end -0.67945 0.3048)
			(stroke
				(width 0.1)
				(type default)
			)
			(layer "F.Fab")
		)
		(fp_line
			(start 0.120396 0.3048)
			(end 0.120396 0.2794)
			(stroke
				(width 0.1)
				(type default)
			)
			(layer "F.Fab")
		)
		(fp_line
			(start 0.67945 0.3048)
			(end 0.120396 0.3048)
			(stroke
				(width 0.1)
				(type default)
			)
			(layer "F.Fab")
		)
		(fp_line
			(start -0.12065 0.2794)
			(end -0.12065 0.3048)
			(stroke
				(width 0.1)
				(type default)
			)
			(layer "F.Fab")
		)
		(fp_line
			(start 0.120396 0.2794)
			(end -0.12065 0.2794)
			(stroke
				(width 0.1)
				(type default)
			)
			(layer "F.Fab")
		)
		(fp_line
			(start -0.12065 -0.2794)
			(end 0.12065 -0.2794)
			(stroke
				(width 0.1)
				(type default)
			)
			(layer "F.Fab")
		)
		(fp_line
			(start 0.12065 -0.2794)
			(end 0.12065 -0.3048)
			(stroke
				(width 0.1)
				(type default)
			)
			(layer "F.Fab")
		)
		(fp_line
			(start 0.12065 -0.3048)
			(end 0.67945 -0.3048)
			(stroke
				(width 0.1)
				(type default)
			)
			(layer "F.Fab")
		)
		(fp_line
			(start 0.67945 -0.3048)
			(end 0.67945 0.3048)
			(stroke
				(width 0.1)
				(type default)
			)
			(layer "F.Fab")
		)
		(fp_line
			(start -0.67945 -0.305054)
			(end -0.12065 -0.305054)
			(stroke
				(width 0.1)
				(type default)
			)
			(layer "F.Fab")
		)
		(fp_line
			(start -0.12065 -0.305054)
			(end -0.12065 -0.2794)
			(stroke
				(width 0.1)
				(type default)
			)
			(layer "F.Fab")
		)
		(pad "1" smd circle
			(at -0.40005 0 270)
			(size 0 0)
			(layers "F.Cu" "F.Mask" "F.Paste")
			(net "SMB_BMC_ALERT16_N")
		)
		(pad "2" smd circle
			(at 0.40005 0 270)
			(size 0 0)
			(layers "F.Cu" "F.Mask" "F.Paste")
			(net "SMB_BMC_ALERT16_R2_N")
		)
	)
	(footprint ""
		(layer "F.Cu")
		(at 39.8272 -77.4954)
		(property "Reference" "R549"
			(at 0 0 0)
			(layer "F.SilkS")
			(hide yes)
			(effects
				(font
					(size 1.27 1.27)
				)
			)
		)
		(property "Value" ""
			(at 0 0 0)
			(layer "F.Fab")
			(effects
				(font
					(size 1.27 1.27)
				)
			)
		)
		(duplicate_pad_numbers_are_jumpers no)
		(fp_line
			(start -0.7874 -0.4064)
			(end 0.7874 -0.4064)
			(stroke
				(width 0.1524)
				(type default)
			)
			(layer "F.SilkS")
		)
		(fp_line
			(start -0.7874 0.4064)
			(end -0.7874 -0.4064)
			(stroke
				(width 0.1524)
				(type default)
			)
			(layer "F.SilkS")
		)
		(fp_line
			(start 0.7874 -0.4064)
			(end 0.7874 0.4064)
			(stroke
				(width 0.1524)
				(type default)
			)
			(layer "F.SilkS")
		)
		(fp_line
			(start 0.7874 0.4064)
			(end -0.7874 0.4064)
			(stroke
				(width 0.1524)
				(type default)
			)
			(layer "F.SilkS")
		)
		(fp_line
			(start -0.67945 -0.305054)
			(end -0.12065 -0.305054)
			(stroke
				(width 0.1)
				(type default)
			)
			(layer "F.Fab")
		)
		(fp_line
			(start -0.67945 0.3048)
			(end -0.67945 -0.305054)
			(stroke
				(width 0.1)
				(type default)
			)
			(layer "F.Fab")
		)
		(fp_line
			(start -0.12065 -0.305054)
			(end -0.12065 -0.2794)
			(stroke
				(width 0.1)
				(type default)
			)
			(layer "F.Fab")
		)
		(fp_line
			(start -0.12065 -0.2794)
			(end 0.12065 -0.2794)
			(stroke
				(width 0.1)
				(type default)
			)
			(layer "F.Fab")
		)
		(fp_line
			(start -0.12065 0.2794)
			(end -0.12065 0.3048)
			(stroke
				(width 0.1)
				(type default)
			)
			(layer "F.Fab")
		)
		(fp_line
			(start -0.12065 0.3048)
			(end -0.67945 0.3048)
			(stroke
				(width 0.1)
				(type default)
			)
			(layer "F.Fab")
		)
		(fp_line
			(start 0.120396 0.2794)
			(end -0.12065 0.2794)
			(stroke
				(width 0.1)
				(type default)
			)
			(layer "F.Fab")
		)
		(fp_line
			(start 0.120396 0.3048)
			(end 0.120396 0.2794)
			(stroke
				(width 0.1)
				(type default)
			)
			(layer "F.Fab")
		)
		(fp_line
			(start 0.12065 -0.3048)
			(end 0.67945 -0.3048)
			(stroke
				(width 0.1)
				(type default)
			)
			(layer "F.Fab")
		)
		(fp_line
			(start 0.12065 -0.2794)
			(end 0.12065 -0.3048)
			(stroke
				(width 0.1)
				(type default)
			)
			(layer "F.Fab")
		)
		(fp_line
			(start 0.67945 -0.3048)
			(end 0.67945 0.3048)
			(stroke
				(width 0.1)
				(type default)
			)
			(layer "F.Fab")
		)
		(fp_line
			(start 0.67945 0.3048)
			(end 0.120396 0.3048)
			(stroke
				(width 0.1)
				(type default)
			)
			(layer "F.Fab")
		)
		(pad "1" smd circle
			(at -0.40005 0)
			(size 0 0)
			(layers "F.Cu" "F.Mask" "F.Paste")
			(net "SPI_BMC_CLK_FLASH_R")
		)
		(pad "2" smd circle
			(at 0.40005 0)
			(size 0 0)
			(layers "F.Cu" "F.Mask" "F.Paste")
			(net "SPI_BMC_BOOT_CLK")
		)
	)
	(footprint ""
		(layer "F.Cu")
		(at 11.303 -17.399 -90)
		(property "Reference" "Q12"
			(at -0.714502 1.600708 90)
			(unlocked yes)
			(layer "F.SilkS")
			(effects
				(font
					(size 0.7874 0.5842)
					(thickness 0.1524)
				)
				(justify left)
			)
		)
		(property "Value" ""
			(at 0 0 270)
			(layer "F.Fab")
			(effects
				(font
					(size 1.27 1.27)
				)
			)
		)
		(duplicate_pad_numbers_are_jumpers no)
		(fp_line
			(start -1.332738 1.100074)
			(end -1.332738 -1.100074)
			(stroke
				(width 0.1524)
				(type default)
			)
			(layer "F.SilkS")
		)
		(fp_line
			(start 1.332738 1.100074)
			(end -1.332738 1.100074)
			(stroke
				(width 0.1524)
				(type default)
			)
			(layer "F.SilkS")
		)
		(fp_line
			(start 0 -0.541274)
			(end 0.4826 -1.100074)
			(stroke
				(width 0.1524)
				(type default)
			)
			(layer "F.SilkS")
		)
		(fp_line
			(start -1.332738 -1.100074)
			(end -0.4826 -1.100074)
			(stroke
				(width 0.1524)
				(type default)
			)
			(layer "F.SilkS")
		)
		(fp_line
			(start -0.4826 -1.100074)
			(end 0 -0.541274)
			(stroke
				(width 0.1524)
				(type default)
			)
			(layer "F.SilkS")
		)
		(fp_line
			(start 0.4826 -1.100074)
			(end 1.332738 -1.100074)
			(stroke
				(width 0.1524)
				(type default)
			)
			(layer "F.SilkS")
		)
		(fp_line
			(start 1.332738 -1.100074)
			(end 1.332738 1.100074)
			(stroke
				(width 0.1524)
				(type default)
			)
			(layer "F.SilkS")
		)
		(fp_poly
			(pts
				(xy -1.78181 0.260604) (xy -2.278126 -0.235712) (xy -1.533398 -0.484124)
			)
			(stroke
				(width 0)
				(type default)
			)
			(fill yes)
			(layer "F.SilkS")
		)
		(fp_line
			(start -0.674878 1.100074)
			(end -0.674878 -1.100074)
			(stroke
				(width 0.1)
				(type default)
			)
			(layer "F.Fab")
		)
		(fp_line
			(start 0.674878 1.100074)
			(end -0.674878 1.100074)
			(stroke
				(width 0.1)
				(type default)
			)
			(layer "F.Fab")
		)
		(fp_line
			(start -0.674878 -1.100074)
			(end 0.674878 -1.100074)
			(stroke
				(width 0.1)
				(type default)
			)
			(layer "F.Fab")
		)
		(fp_line
			(start 0.674878 -1.100074)
			(end 0.674878 1.100074)
			(stroke
				(width 0.1)
				(type default)
			)
			(layer "F.Fab")
		)
		(fp_poly
			(pts
				(xy -2.2352 -0.298958) (xy -2.2352 -1.001014) (xy -1.533144 -0.649986)
			)
			(stroke
				(width 0)
				(type default)
			)
			(fill yes)
			(layer "F.Fab")
		)
		(pad "1" smd rect
			(at -0.94996 -0.649986)
			(size 0.4318 0.508)
			(layers "F.Cu" "F.Mask" "F.Paste")
			(net "GND")
		)
		(pad "2" smd rect
			(at -0.94996 0)
			(size 0.4318 0.508)
			(layers "F.Cu" "F.Mask" "F.Paste")
			(net "PWR_LED")
		)
		(pad "3" smd rect
			(at -0.94996 0.649986)
			(size 0.4318 0.508)
			(layers "F.Cu" "F.Mask" "F.Paste")
			(net "HDD_LED_BUF")
		)
		(pad "4" smd rect
			(at 0.94996 0.649986)
			(size 0.4318 0.508)
			(layers "F.Cu" "F.Mask" "F.Paste")
			(net "GND")
		)
		(pad "5" smd rect
			(at 0.94996 0)
			(size 0.4318 0.508)
			(layers "F.Cu" "F.Mask" "F.Paste")
			(net "HDD_LED_N")
		)
		(pad "6" smd rect
			(at 0.94996 -0.649986)
			(size 0.4318 0.508)
			(layers "F.Cu" "F.Mask" "F.Paste")
			(net "PWR_LED_BUF_N")
		)
	)
	(footprint ""
		(layer "F.Cu")
		(at 73.72223 -10.922762 90)
		(property "Reference" "C181"
			(at 0 0 90)
			(layer "F.SilkS")
			(hide yes)
			(effects
				(font
					(size 1.27 1.27)
				)
			)
		)
		(property "Value" ""
			(at 0 0 90)
			(layer "F.Fab")
			(effects
				(font
					(size 1.27 1.27)
				)
			)
		)
		(duplicate_pad_numbers_are_jumpers no)
		(fp_line
			(start 0.7874 -0.4064)
			(end 0.7874 0.4064)
			(stroke
				(width 0.1524)
				(type default)
			)
			(layer "F.SilkS")
		)
		(fp_line
			(start -0.7874 -0.4064)
			(end 0.7874 -0.4064)
			(stroke
				(width 0.1524)
				(type default)
			)
			(layer "F.SilkS")
		)
		(fp_line
			(start 0.7874 0.4064)
			(end -0.7874 0.4064)
			(stroke
				(width 0.1524)
				(type default)
			)
			(layer "F.SilkS")
		)
		(fp_line
			(start -0.7874 0.4064)
			(end -0.7874 -0.4064)
			(stroke
				(width 0.1524)
				(type default)
			)
			(layer "F.SilkS")
		)
		(fp_line
			(start -0.12065 -0.305054)
			(end -0.12065 -0.2794)
			(stroke
				(width 0.1)
				(type default)
			)
			(layer "F.Fab")
		)
		(fp_line
			(start -0.67945 -0.305054)
			(end -0.12065 -0.305054)
			(stroke
				(width 0.1)
				(type default)
			)
			(layer "F.Fab")
		)
		(fp_line
			(start 0.67945 -0.3048)
			(end 0.67945 0.3048)
			(stroke
				(width 0.1)
				(type default)
			)
			(layer "F.Fab")
		)
		(fp_line
			(start 0.12065 -0.3048)
			(end 0.67945 -0.3048)
			(stroke
				(width 0.1)
				(type default)
			)
			(layer "F.Fab")
		)
		(fp_line
			(start 0.12065 -0.2794)
			(end 0.12065 -0.3048)
			(stroke
				(width 0.1)
				(type default)
			)
			(layer "F.Fab")
		)
		(fp_line
			(start -0.12065 -0.2794)
			(end 0.12065 -0.2794)
			(stroke
				(width 0.1)
				(type default)
			)
			(layer "F.Fab")
		)
		(fp_line
			(start 0.120396 0.2794)
			(end -0.12065 0.2794)
			(stroke
				(width 0.1)
				(type default)
			)
			(layer "F.Fab")
		)
		(fp_line
			(start -0.12065 0.2794)
			(end -0.12065 0.3048)
			(stroke
				(width 0.1)
				(type default)
			)
			(layer "F.Fab")
		)
		(fp_line
			(start 0.67945 0.3048)
			(end 0.120396 0.3048)
			(stroke
				(width 0.1)
				(type default)
			)
			(layer "F.Fab")
		)
		(fp_line
			(start 0.120396 0.3048)
			(end 0.120396 0.2794)
			(stroke
				(width 0.1)
				(type default)
			)
			(layer "F.Fab")
		)
		(fp_line
			(start -0.12065 0.3048)
			(end -0.67945 0.3048)
			(stroke
				(width 0.1)
				(type default)
			)
			(layer "F.Fab")
		)
		(fp_line
			(start -0.67945 0.3048)
			(end -0.67945 -0.305054)
			(stroke
				(width 0.1)
				(type default)
			)
			(layer "F.Fab")
		)
		(pad "1" smd circle
			(at -0.40005 0 90)
			(size 0 0)
			(layers "F.Cu" "F.Mask" "F.Paste")
			(net "REAR_AC_PWR_BTN")
		)
		(pad "2" smd circle
			(at 0.40005 0 90)
			(size 0 0)
			(layers "F.Cu" "F.Mask" "F.Paste")
			(net "GND")
		)
	)
	(footprint ""
		(layer "F.Cu")
		(at 10.897616 -65.948052)
		(property "Reference" "PC273"
			(at 0 0 0)
			(layer "F.SilkS")
			(hide yes)
			(effects
				(font
					(size 1.27 1.27)
				)
			)
		)
		(property "Value" ""
			(at 0 0 0)
			(layer "F.Fab")
			(effects
				(font
					(size 1.27 1.27)
				)
			)
		)
		(duplicate_pad_numbers_are_jumpers no)
		(fp_line
			(start -0.7874 -0.4064)
			(end 0.7874 -0.4064)
			(stroke
				(width 0.1524)
				(type default)
			)
			(layer "F.SilkS")
		)
		(fp_line
			(start -0.7874 0.4064)
			(end -0.7874 -0.4064)
			(stroke
				(width 0.1524)
				(type default)
			)
			(layer "F.SilkS")
		)
		(fp_line
			(start 0.7874 -0.4064)
			(end 0.7874 0.4064)
			(stroke
				(width 0.1524)
				(type default)
			)
			(layer "F.SilkS")
		)
		(fp_line
			(start 0.7874 0.4064)
			(end -0.7874 0.4064)
			(stroke
				(width 0.1524)
				(type default)
			)
			(layer "F.SilkS")
		)
		(fp_line
			(start -0.67945 -0.305054)
			(end -0.12065 -0.305054)
			(stroke
				(width 0.1)
				(type default)
			)
			(layer "F.Fab")
		)
		(fp_line
			(start -0.67945 0.3048)
			(end -0.67945 -0.305054)
			(stroke
				(width 0.1)
				(type default)
			)
			(layer "F.Fab")
		)
		(fp_line
			(start -0.12065 -0.305054)
			(end -0.12065 -0.2794)
			(stroke
				(width 0.1)
				(type default)
			)
			(layer "F.Fab")
		)
		(fp_line
			(start -0.12065 -0.2794)
			(end 0.12065 -0.2794)
			(stroke
				(width 0.1)
				(type default)
			)
			(layer "F.Fab")
		)
		(fp_line
			(start -0.12065 0.2794)
			(end -0.12065 0.3048)
			(stroke
				(width 0.1)
				(type default)
			)
			(layer "F.Fab")
		)
		(fp_line
			(start -0.12065 0.3048)
			(end -0.67945 0.3048)
			(stroke
				(width 0.1)
				(type default)
			)
			(layer "F.Fab")
		)
		(fp_line
			(start 0.120396 0.2794)
			(end -0.12065 0.2794)
			(stroke
				(width 0.1)
				(type default)
			)
			(layer "F.Fab")
		)
		(fp_line
			(start 0.120396 0.3048)
			(end 0.120396 0.2794)
			(stroke
				(width 0.1)
				(type default)
			)
			(layer "F.Fab")
		)
		(fp_line
			(start 0.12065 -0.3048)
			(end 0.67945 -0.3048)
			(stroke
				(width 0.1)
				(type default)
			)
			(layer "F.Fab")
		)
		(fp_line
			(start 0.12065 -0.2794)
			(end 0.12065 -0.3048)
			(stroke
				(width 0.1)
				(type default)
			)
			(layer "F.Fab")
		)
		(fp_line
			(start 0.67945 -0.3048)
			(end 0.67945 0.3048)
			(stroke
				(width 0.1)
				(type default)
			)
			(layer "F.Fab")
		)
		(fp_line
			(start 0.67945 0.3048)
			(end 0.120396 0.3048)
			(stroke
				(width 0.1)
				(type default)
			)
			(layer "F.Fab")
		)
		(pad "1" smd circle
			(at -0.40005 0)
			(size 0 0)
			(layers "F.Cu" "F.Mask" "F.Paste")
			(net "P3V3_AUX_REF")
		)
		(pad "2" smd circle
			(at 0.40005 0)
			(size 0 0)
			(layers "F.Cu" "F.Mask" "F.Paste")
			(net "GND")
		)
	)
	(footprint ""
		(layer "F.Cu")
		(at 4.572 -58.8264 90)
		(property "Reference" "C241"
			(at 0 0 90)
			(layer "F.SilkS")
			(hide yes)
			(effects
				(font
					(size 1.27 1.27)
				)
			)
		)
		(property "Value" ""
			(at 0 0 90)
			(layer "F.Fab")
			(effects
				(font
					(size 1.27 1.27)
				)
			)
		)
		(duplicate_pad_numbers_are_jumpers no)
		(fp_line
			(start 0.7874 -0.4064)
			(end 0.7874 0.4064)
			(stroke
				(width 0.1524)
				(type default)
			)
			(layer "F.SilkS")
		)
		(fp_line
			(start -0.7874 -0.4064)
			(end 0.7874 -0.4064)
			(stroke
				(width 0.1524)
				(type default)
			)
			(layer "F.SilkS")
		)
		(fp_line
			(start 0.7874 0.4064)
			(end -0.7874 0.4064)
			(stroke
				(width 0.1524)
				(type default)
			)
			(layer "F.SilkS")
		)
		(fp_line
			(start -0.7874 0.4064)
			(end -0.7874 -0.4064)
			(stroke
				(width 0.1524)
				(type default)
			)
			(layer "F.SilkS")
		)
		(fp_line
			(start -0.12065 -0.305054)
			(end -0.12065 -0.2794)
			(stroke
				(width 0.1)
				(type default)
			)
			(layer "F.Fab")
		)
		(fp_line
			(start -0.67945 -0.305054)
			(end -0.12065 -0.305054)
			(stroke
				(width 0.1)
				(type default)
			)
			(layer "F.Fab")
		)
		(fp_line
			(start 0.67945 -0.3048)
			(end 0.67945 0.3048)
			(stroke
				(width 0.1)
				(type default)
			)
			(layer "F.Fab")
		)
		(fp_line
			(start 0.12065 -0.3048)
			(end 0.67945 -0.3048)
			(stroke
				(width 0.1)
				(type default)
			)
			(layer "F.Fab")
		)
		(fp_line
			(start 0.12065 -0.2794)
			(end 0.12065 -0.3048)
			(stroke
				(width 0.1)
				(type default)
			)
			(layer "F.Fab")
		)
		(fp_line
			(start -0.12065 -0.2794)
			(end 0.12065 -0.2794)
			(stroke
				(width 0.1)
				(type default)
			)
			(layer "F.Fab")
		)
		(fp_line
			(start 0.120396 0.2794)
			(end -0.12065 0.2794)
			(stroke
				(width 0.1)
				(type default)
			)
			(layer "F.Fab")
		)
		(fp_line
			(start -0.12065 0.2794)
			(end -0.12065 0.3048)
			(stroke
				(width 0.1)
				(type default)
			)
			(layer "F.Fab")
		)
		(fp_line
			(start 0.67945 0.3048)
			(end 0.120396 0.3048)
			(stroke
				(width 0.1)
				(type default)
			)
			(layer "F.Fab")
		)
		(fp_line
			(start 0.120396 0.3048)
			(end 0.120396 0.2794)
			(stroke
				(width 0.1)
				(type default)
			)
			(layer "F.Fab")
		)
		(fp_line
			(start -0.12065 0.3048)
			(end -0.67945 0.3048)
			(stroke
				(width 0.1)
				(type default)
			)
			(layer "F.Fab")
		)
		(fp_line
			(start -0.67945 0.3048)
			(end -0.67945 -0.305054)
			(stroke
				(width 0.1)
				(type default)
			)
			(layer "F.Fab")
		)
		(pad "1" smd circle
			(at -0.40005 0 90)
			(size 0 0)
			(layers "F.Cu" "F.Mask" "F.Paste")
			(net "P12V_AUX")
		)
		(pad "2" smd circle
			(at 0.40005 0 90)
			(size 0 0)
			(layers "F.Cu" "F.Mask" "F.Paste")
			(net "GND")
		)
	)
	(footprint ""
		(layer "F.Cu")
		(at 26.3398 -105.4608 180)
		(property "Reference" "D17"
			(at 2.3368 1.44653 0)
			(unlocked yes)
			(layer "F.SilkS")
			(effects
				(font
					(size 0.7874 0.5842)
					(thickness 0.1524)
				)
				(justify left)
			)
		)
		(property "Value" ""
			(at 0 0 180)
			(layer "F.Fab")
			(effects
				(font
					(size 1.27 1.27)
				)
			)
		)
		(duplicate_pad_numbers_are_jumpers no)
		(fp_line
			(start 2.343404 0.6985)
			(end 2.216404 0.6985)
			(stroke
				(width 0.1524)
				(type default)
			)
			(layer "F.SilkS")
		)
		(fp_line
			(start 2.343404 -0.6985)
			(end 2.343404 0.6985)
			(stroke
				(width 0.1524)
				(type default)
			)
			(layer "F.SilkS")
		)
		(fp_line
			(start 2.229104 0.6985)
			(end 2.051304 0.6985)
			(stroke
				(width 0.1524)
				(type default)
			)
			(layer "F.SilkS")
		)
		(fp_line
			(start 2.229104 -0.6985)
			(end 2.229104 0.6985)
			(stroke
				(width 0.1524)
				(type default)
			)
			(layer "F.SilkS")
		)
		(fp_line
			(start 2.152904 0.635)
			(end 2.152904 -0.6985)
			(stroke
				(width 0.1524)
				(type default)
			)
			(layer "F.SilkS")
		)
		(fp_line
			(start 2.152904 -0.6985)
			(end 2.343404 -0.6985)
			(stroke
				(width 0.1524)
				(type default)
			)
			(layer "F.SilkS")
		)
		(fp_line
			(start 2.064004 -0.6731)
			(end 2.064004 -0.6985)
			(stroke
				(width 0.1524)
				(type default)
			)
			(layer "F.SilkS")
		)
		(fp_line
			(start 2.064004 -0.6985)
			(end 2.229104 -0.6985)
			(stroke
				(width 0.1524)
				(type default)
			)
			(layer "F.SilkS")
		)
		(fp_line
			(start 2.051304 0.6985)
			(end 2.051304 0.635)
			(stroke
				(width 0.1524)
				(type default)
			)
			(layer "F.SilkS")
		)
		(fp_line
			(start 2.051304 0.635)
			(end 2.152904 0.635)
			(stroke
				(width 0.1524)
				(type default)
			)
			(layer "F.SilkS")
		)
		(fp_line
			(start 2.050796 0.700024)
			(end -2.050796 0.700024)
			(stroke
				(width 0.1524)
				(type default)
			)
			(layer "F.SilkS")
		)
		(fp_line
			(start 2.050796 -0.700024)
			(end 2.050796 0.700024)
			(stroke
				(width 0.1524)
				(type default)
			)
			(layer "F.SilkS")
		)
		(fp_line
			(start 0.293878 -0.500126)
			(end 0.293878 0.500126)
			(stroke
				(width 0.1524)
				(type default)
			)
			(layer "F.SilkS")
		)
		(fp_line
			(start 0.193802 0)
			(end -0.30607 -0.500126)
			(stroke
				(width 0.1524)
				(type default)
			)
			(layer "F.SilkS")
		)
		(fp_line
			(start -0.30607 0.500126)
			(end 0.193802 0)
			(stroke
				(width 0.1524)
				(type default)
			)
			(layer "F.SilkS")
		)
		(fp_line
			(start -0.30607 -0.500126)
			(end -0.30607 0.500126)
			(stroke
				(width 0.1524)
				(type default)
			)
			(layer "F.SilkS")
		)
		(fp_line
			(start -2.050796 0.700024)
			(end -2.050796 -0.700024)
			(stroke
				(width 0.1524)
				(type default)
			)
			(layer "F.SilkS")
		)
		(fp_line
			(start -2.050796 -0.700024)
			(end 2.050796 -0.700024)
			(stroke
				(width 0.1524)
				(type default)
			)
			(layer "F.SilkS")
		)
		(fp_line
			(start 0.899922 0.700024)
			(end -0.899922 0.700024)
			(stroke
				(width 0.1)
				(type default)
			)
			(layer "F.Fab")
		)
		(fp_line
			(start 0.899922 -0.700024)
			(end 0.899922 0.700024)
			(stroke
				(width 0.1)
				(type default)
			)
			(layer "F.Fab")
		)
		(fp_line
			(start -0.899922 0.700024)
			(end -0.899922 -0.700024)
			(stroke
				(width 0.1)
				(type default)
			)
			(layer "F.Fab")
		)
		(fp_line
			(start -0.899922 -0.700024)
			(end 0.899922 -0.700024)
			(stroke
				(width 0.1)
				(type default)
			)
			(layer "F.Fab")
		)
		(fp_text user "-"
			(at 2.1082 -0.92075 0)
			(unlocked yes)
			(layer "F.SilkS")
			(effects
				(font
					(size 1.905 1.4224)
					(thickness 0.1524)
				)
				(justify left)
			)
		)
		(fp_text user "+"
			(at -1.94945 -0.5588 270)
			(unlocked yes)
			(layer "F.SilkS")
			(effects
				(font
					(size 1.905 1.4224)
					(thickness 0.1524)
				)
				(justify left)
			)
		)
		(fp_text user "-"
			(at 3.880104 0.23495 0)
			(unlocked yes)
			(layer "F.Fab")
			(effects
				(font
					(size 1.905 1.4224)
					(thickness 0.1524)
				)
				(justify left)
			)
		)
		(fp_text user "+"
			(at -3.123946 0.762 270)
			(unlocked yes)
			(layer "F.Fab")
			(effects
				(font
					(size 1.905 1.4224)
					(thickness 0.1524)
				)
				(justify left)
			)
		)
		(pad "1" smd rect
			(at -1.199896 0 90)
			(size 0.6604 1.3716)
			(layers "F.Cu" "F.Mask" "F.Paste")
			(net "RST_BMC_HW_OUT")
		)
		(pad "2" smd rect
			(at 1.199896 0 270)
			(size 0.6604 1.3716)
			(layers "F.Cu" "F.Mask" "F.Paste")
			(net "RST_BMC_SELF_HW_D")
		)
	)
	(footprint ""
		(layer "F.Cu")
		(at 32.0548 -20.574 -90)
		(property "Reference" "R31"
			(at 0 0 270)
			(layer "F.SilkS")
			(hide yes)
			(effects
				(font
					(size 1.27 1.27)
				)
			)
		)
		(property "Value" ""
			(at 0 0 270)
			(layer "F.Fab")
			(effects
				(font
					(size 1.27 1.27)
				)
			)
		)
		(duplicate_pad_numbers_are_jumpers no)
		(fp_line
			(start -0.7874 0.4064)
			(end -0.7874 -0.4064)
			(stroke
				(width 0.1524)
				(type default)
			)
			(layer "F.SilkS")
		)
		(fp_line
			(start 0.7874 0.4064)
			(end -0.7874 0.4064)
			(stroke
				(width 0.1524)
				(type default)
			)
			(layer "F.SilkS")
		)
		(fp_line
			(start -0.7874 -0.4064)
			(end 0.7874 -0.4064)
			(stroke
				(width 0.1524)
				(type default)
			)
			(layer "F.SilkS")
		)
		(fp_line
			(start 0.7874 -0.4064)
			(end 0.7874 0.4064)
			(stroke
				(width 0.1524)
				(type default)
			)
			(layer "F.SilkS")
		)
		(fp_line
			(start -0.67945 0.3048)
			(end -0.67945 -0.305054)
			(stroke
				(width 0.1)
				(type default)
			)
			(layer "F.Fab")
		)
		(fp_line
			(start -0.12065 0.3048)
			(end -0.67945 0.3048)
			(stroke
				(width 0.1)
				(type default)
			)
			(layer "F.Fab")
		)
		(fp_line
			(start 0.120396 0.3048)
			(end 0.120396 0.2794)
			(stroke
				(width 0.1)
				(type default)
			)
			(layer "F.Fab")
		)
		(fp_line
			(start 0.67945 0.3048)
			(end 0.120396 0.3048)
			(stroke
				(width 0.1)
				(type default)
			)
			(layer "F.Fab")
		)
		(fp_line
			(start -0.12065 0.2794)
			(end -0.12065 0.3048)
			(stroke
				(width 0.1)
				(type default)
			)
			(layer "F.Fab")
		)
		(fp_line
			(start 0.120396 0.2794)
			(end -0.12065 0.2794)
			(stroke
				(width 0.1)
				(type default)
			)
			(layer "F.Fab")
		)
		(fp_line
			(start -0.12065 -0.2794)
			(end 0.12065 -0.2794)
			(stroke
				(width 0.1)
				(type default)
			)
			(layer "F.Fab")
		)
		(fp_line
			(start 0.12065 -0.2794)
			(end 0.12065 -0.3048)
			(stroke
				(width 0.1)
				(type default)
			)
			(layer "F.Fab")
		)
		(fp_line
			(start 0.12065 -0.3048)
			(end 0.67945 -0.3048)
			(stroke
				(width 0.1)
				(type default)
			)
			(layer "F.Fab")
		)
		(fp_line
			(start 0.67945 -0.3048)
			(end 0.67945 0.3048)
			(stroke
				(width 0.1)
				(type default)
			)
			(layer "F.Fab")
		)
		(fp_line
			(start -0.67945 -0.305054)
			(end -0.12065 -0.305054)
			(stroke
				(width 0.1)
				(type default)
			)
			(layer "F.Fab")
		)
		(fp_line
			(start -0.12065 -0.305054)
			(end -0.12065 -0.2794)
			(stroke
				(width 0.1)
				(type default)
			)
			(layer "F.Fab")
		)
		(pad "1" smd circle
			(at -0.40005 0 270)
			(size 0 0)
			(layers "F.Cu" "F.Mask" "F.Paste")
			(net "P3V3_RGM")
		)
		(pad "2" smd circle
			(at 0.40005 0 270)
			(size 0 0)
			(layers "F.Cu" "F.Mask" "F.Paste")
			(net "V_BMC_DDC_SDA")
		)
	)
	(footprint ""
		(layer "F.Cu")
		(at 27.813 -27.305 180)
		(property "Reference" "C213"
			(at 0 0 180)
			(layer "F.SilkS")
			(hide yes)
			(effects
				(font
					(size 1.27 1.27)
				)
			)
		)
		(property "Value" ""
			(at 0 0 180)
			(layer "F.Fab")
			(effects
				(font
					(size 1.27 1.27)
				)
			)
		)
		(duplicate_pad_numbers_are_jumpers no)
		(fp_line
			(start 0.7874 0.4064)
			(end -0.7874 0.4064)
			(stroke
				(width 0.1524)
				(type default)
			)
			(layer "F.SilkS")
		)
		(fp_line
			(start 0.7874 -0.4064)
			(end 0.7874 0.4064)
			(stroke
				(width 0.1524)
				(type default)
			)
			(layer "F.SilkS")
		)
		(fp_line
			(start -0.7874 0.4064)
			(end -0.7874 -0.4064)
			(stroke
				(width 0.1524)
				(type default)
			)
			(layer "F.SilkS")
		)
		(fp_line
			(start -0.7874 -0.4064)
			(end 0.7874 -0.4064)
			(stroke
				(width 0.1524)
				(type default)
			)
			(layer "F.SilkS")
		)
		(fp_line
			(start 0.67945 0.3048)
			(end 0.120396 0.3048)
			(stroke
				(width 0.1)
				(type default)
			)
			(layer "F.Fab")
		)
		(fp_line
			(start 0.67945 -0.3048)
			(end 0.67945 0.3048)
			(stroke
				(width 0.1)
				(type default)
			)
			(layer "F.Fab")
		)
		(fp_line
			(start 0.12065 -0.2794)
			(end 0.12065 -0.3048)
			(stroke
				(width 0.1)
				(type default)
			)
			(layer "F.Fab")
		)
		(fp_line
			(start 0.12065 -0.3048)
			(end 0.67945 -0.3048)
			(stroke
				(width 0.1)
				(type default)
			)
			(layer "F.Fab")
		)
		(fp_line
			(start 0.120396 0.3048)
			(end 0.120396 0.2794)
			(stroke
				(width 0.1)
				(type default)
			)
			(layer "F.Fab")
		)
		(fp_line
			(start 0.120396 0.2794)
			(end -0.12065 0.2794)
			(stroke
				(width 0.1)
				(type default)
			)
			(layer "F.Fab")
		)
		(fp_line
			(start -0.12065 0.3048)
			(end -0.67945 0.3048)
			(stroke
				(width 0.1)
				(type default)
			)
			(layer "F.Fab")
		)
		(fp_line
			(start -0.12065 0.2794)
			(end -0.12065 0.3048)
			(stroke
				(width 0.1)
				(type default)
			)
			(layer "F.Fab")
		)
		(fp_line
			(start -0.12065 -0.2794)
			(end 0.12065 -0.2794)
			(stroke
				(width 0.1)
				(type default)
			)
			(layer "F.Fab")
		)
		(fp_line
			(start -0.12065 -0.305054)
			(end -0.12065 -0.2794)
			(stroke
				(width 0.1)
				(type default)
			)
			(layer "F.Fab")
		)
		(fp_line
			(start -0.67945 0.3048)
			(end -0.67945 -0.305054)
			(stroke
				(width 0.1)
				(type default)
			)
			(layer "F.Fab")
		)
		(fp_line
			(start -0.67945 -0.305054)
			(end -0.12065 -0.305054)
			(stroke
				(width 0.1)
				(type default)
			)
			(layer "F.Fab")
		)
		(pad "1" smd circle
			(at -0.40005 0 180)
			(size 0 0)
			(layers "F.Cu" "F.Mask" "F.Paste")
			(net "V_BMC_LS_DDC_SDA_R")
		)
		(pad "2" smd circle
			(at 0.40005 0 180)
			(size 0 0)
			(layers "F.Cu" "F.Mask" "F.Paste")
			(net "GND")
		)
	)
	(footprint ""
		(layer "F.Cu")
		(at 6.9342 -17.3228 90)
		(property "Reference" "H2B2"
			(at -1.47447 -6.4262 0)
			(unlocked yes)
			(layer "F.SilkS")
			(effects
				(font
					(size 0.7874 0.5842)
					(thickness 0.1524)
				)
				(justify left)
			)
		)
		(property "Value" ""
			(at 0 0 90)
			(layer "F.Fab")
			(effects
				(font
					(size 1.27 1.27)
				)
			)
		)
		(duplicate_pad_numbers_are_jumpers no)
		(fp_arc
			(start -1.834134 -1.548384)
			(mid 0.134587 -2.396606)
			(end 1.995932 -1.333246)
			(stroke
				(width 0.1524)
				(type default)
			)
			(layer "F.SilkS")
		)
		(fp_arc
			(start 2.2479 0.841756)
			(mid 1.367667 1.972542)
			(end 0 2.4003)
			(stroke
				(width 0.1524)
				(type default)
			)
			(layer "F.SilkS")
		)
		(fp_arc
			(start 0 2.4003)
			(mid -1.444342 1.917049)
			(end -2.307082 0.661924)
			(stroke
				(width 0.1524)
				(type default)
			)
			(layer "F.SilkS")
		)
		(fp_arc
			(start 1.212596 -6.478778)
			(mid 1.432628 -6.433742)
			(end 1.651 -6.381242)
			(stroke
				(width 0.1524)
				(type default)
			)
			(layer "B.SilkS")
		)
		(fp_arc
			(start 5.66801 3.364484)
			(mid 3.261093 5.728087)
			(end 0 6.5913)
			(stroke
				(width 0.1524)
				(type default)
			)
			(layer "B.SilkS")
		)
		(fp_arc
			(start 0 6.5913)
			(mid -3.324795 5.691563)
			(end -5.74167 3.237484)
			(stroke
				(width 0.1524)
				(type default)
			)
			(layer "B.SilkS")
		)
		(fp_circle
			(center 0 0)
			(end 0 6.5913)
			(stroke
				(width 0.1)
				(type default)
			)
			(fill no)
			(layer "B.Fab")
		)
		(fp_circle
			(center 0 0)
			(end 0 2.4003)
			(stroke
				(width 0.1)
				(type default)
			)
			(fill no)
			(layer "F.Fab")
		)
		(pad "" np_thru_hole circle
			(at 0 0 90)
			(size 3.175 3.175)
			(drill 3.175)
			(layers "*.Cu" "*.Mask")
			(clearance 0.381)
			(thermal_gap 0.381)
		)
		(zone
			(layers "F.Cu" "B.Cu" "In1.Cu" "In2.Cu" "In3.Cu" "In4.Cu" "In5.Cu" "In6.Cu"
				"In7.Cu" "In8.Cu" "In9.Cu" "In10.Cu"
			)
			(hatch none 0.5)
			(connect_pads
				(clearance 0)
			)
			(min_thickness 0.25)
			(keepout
				(tracks not_allowed)
				(vias allowed)
				(pads allowed)
				(copperpour not_allowed)
				(footprints allowed)
			)
			(placement
				(enabled no)
				(sheetname "")
			)
			(fill
				(thermal_gap 0.5)
				(thermal_bridge_width 0.5)
				(island_removal_mode 0)
			)
			(polygon
				(pts
					(arc
						(start 9.0297 -17.3228)
						(mid 4.8387 -17.3228)
						(end 9.0297 -17.3228)
					)
				)
			)
		)
	)
	(footprint ""
		(layer "F.Cu")
		(at 39.631112 -55.427626 90)
		(property "Reference" "R831"
			(at 0 0 90)
			(layer "F.SilkS")
			(hide yes)
			(effects
				(font
					(size 1.27 1.27)
				)
			)
		)
		(property "Value" ""
			(at 0 0 90)
			(layer "F.Fab")
			(effects
				(font
					(size 1.27 1.27)
				)
			)
		)
		(duplicate_pad_numbers_are_jumpers no)
		(fp_line
			(start 0.7874 -0.4064)
			(end 0.7874 0.4064)
			(stroke
				(width 0.1524)
				(type default)
			)
			(layer "F.SilkS")
		)
		(fp_line
			(start -0.7874 -0.4064)
			(end 0.7874 -0.4064)
			(stroke
				(width 0.1524)
				(type default)
			)
			(layer "F.SilkS")
		)
		(fp_line
			(start 0.7874 0.4064)
			(end -0.7874 0.4064)
			(stroke
				(width 0.1524)
				(type default)
			)
			(layer "F.SilkS")
		)
		(fp_line
			(start -0.7874 0.4064)
			(end -0.7874 -0.4064)
			(stroke
				(width 0.1524)
				(type default)
			)
			(layer "F.SilkS")
		)
		(fp_line
			(start -0.12065 -0.305054)
			(end -0.12065 -0.2794)
			(stroke
				(width 0.1)
				(type default)
			)
			(layer "F.Fab")
		)
		(fp_line
			(start -0.67945 -0.305054)
			(end -0.12065 -0.305054)
			(stroke
				(width 0.1)
				(type default)
			)
			(layer "F.Fab")
		)
		(fp_line
			(start 0.67945 -0.3048)
			(end 0.67945 0.3048)
			(stroke
				(width 0.1)
				(type default)
			)
			(layer "F.Fab")
		)
		(fp_line
			(start 0.12065 -0.3048)
			(end 0.67945 -0.3048)
			(stroke
				(width 0.1)
				(type default)
			)
			(layer "F.Fab")
		)
		(fp_line
			(start 0.12065 -0.2794)
			(end 0.12065 -0.3048)
			(stroke
				(width 0.1)
				(type default)
			)
			(layer "F.Fab")
		)
		(fp_line
			(start -0.12065 -0.2794)
			(end 0.12065 -0.2794)
			(stroke
				(width 0.1)
				(type default)
			)
			(layer "F.Fab")
		)
		(fp_line
			(start 0.120396 0.2794)
			(end -0.12065 0.2794)
			(stroke
				(width 0.1)
				(type default)
			)
			(layer "F.Fab")
		)
		(fp_line
			(start -0.12065 0.2794)
			(end -0.12065 0.3048)
			(stroke
				(width 0.1)
				(type default)
			)
			(layer "F.Fab")
		)
		(fp_line
			(start 0.67945 0.3048)
			(end 0.120396 0.3048)
			(stroke
				(width 0.1)
				(type default)
			)
			(layer "F.Fab")
		)
		(fp_line
			(start 0.120396 0.3048)
			(end 0.120396 0.2794)
			(stroke
				(width 0.1)
				(type default)
			)
			(layer "F.Fab")
		)
		(fp_line
			(start -0.12065 0.3048)
			(end -0.67945 0.3048)
			(stroke
				(width 0.1)
				(type default)
			)
			(layer "F.Fab")
		)
		(fp_line
			(start -0.67945 0.3048)
			(end -0.67945 -0.305054)
			(stroke
				(width 0.1)
				(type default)
			)
			(layer "F.Fab")
		)
		(pad "1" smd circle
			(at -0.40005 0 90)
			(size 0 0)
			(layers "F.Cu" "F.Mask" "F.Paste")
			(net "P1V8_AUX")
		)
		(pad "2" smd circle
			(at 0.40005 0 90)
			(size 0 0)
			(layers "F.Cu" "F.Mask" "F.Paste")
			(net "U41_ADJ")
		)
	)
	(footprint ""
		(layer "F.Cu")
		(at 51.6636 -109.3978 90)
		(property "Reference" "R161"
			(at 0 0 90)
			(layer "F.SilkS")
			(hide yes)
			(effects
				(font
					(size 1.27 1.27)
				)
			)
		)
		(property "Value" ""
			(at 0 0 90)
			(layer "F.Fab")
			(effects
				(font
					(size 1.27 1.27)
				)
			)
		)
		(duplicate_pad_numbers_are_jumpers no)
		(fp_line
			(start 0.7874 -0.4064)
			(end 0.7874 0.4064)
			(stroke
				(width 0.1524)
				(type default)
			)
			(layer "F.SilkS")
		)
		(fp_line
			(start -0.7874 -0.4064)
			(end 0.7874 -0.4064)
			(stroke
				(width 0.1524)
				(type default)
			)
			(layer "F.SilkS")
		)
		(fp_line
			(start 0.7874 0.4064)
			(end -0.7874 0.4064)
			(stroke
				(width 0.1524)
				(type default)
			)
			(layer "F.SilkS")
		)
		(fp_line
			(start -0.7874 0.4064)
			(end -0.7874 -0.4064)
			(stroke
				(width 0.1524)
				(type default)
			)
			(layer "F.SilkS")
		)
		(fp_line
			(start -0.12065 -0.305054)
			(end -0.12065 -0.2794)
			(stroke
				(width 0.1)
				(type default)
			)
			(layer "F.Fab")
		)
		(fp_line
			(start -0.67945 -0.305054)
			(end -0.12065 -0.305054)
			(stroke
				(width 0.1)
				(type default)
			)
			(layer "F.Fab")
		)
		(fp_line
			(start 0.67945 -0.3048)
			(end 0.67945 0.3048)
			(stroke
				(width 0.1)
				(type default)
			)
			(layer "F.Fab")
		)
		(fp_line
			(start 0.12065 -0.3048)
			(end 0.67945 -0.3048)
			(stroke
				(width 0.1)
				(type default)
			)
			(layer "F.Fab")
		)
		(fp_line
			(start 0.12065 -0.2794)
			(end 0.12065 -0.3048)
			(stroke
				(width 0.1)
				(type default)
			)
			(layer "F.Fab")
		)
		(fp_line
			(start -0.12065 -0.2794)
			(end 0.12065 -0.2794)
			(stroke
				(width 0.1)
				(type default)
			)
			(layer "F.Fab")
		)
		(fp_line
			(start 0.120396 0.2794)
			(end -0.12065 0.2794)
			(stroke
				(width 0.1)
				(type default)
			)
			(layer "F.Fab")
		)
		(fp_line
			(start -0.12065 0.2794)
			(end -0.12065 0.3048)
			(stroke
				(width 0.1)
				(type default)
			)
			(layer "F.Fab")
		)
		(fp_line
			(start 0.67945 0.3048)
			(end 0.120396 0.3048)
			(stroke
				(width 0.1)
				(type default)
			)
			(layer "F.Fab")
		)
		(fp_line
			(start 0.120396 0.3048)
			(end 0.120396 0.2794)
			(stroke
				(width 0.1)
				(type default)
			)
			(layer "F.Fab")
		)
		(fp_line
			(start -0.12065 0.3048)
			(end -0.67945 0.3048)
			(stroke
				(width 0.1)
				(type default)
			)
			(layer "F.Fab")
		)
		(fp_line
			(start -0.67945 0.3048)
			(end -0.67945 -0.305054)
			(stroke
				(width 0.1)
				(type default)
			)
			(layer "F.Fab")
		)
		(pad "1" smd circle
			(at -0.40005 0 90)
			(size 0 0)
			(layers "F.Cu" "F.Mask" "F.Paste")
			(net "P3V3_AUX")
		)
		(pad "2" smd circle
			(at 0.40005 0 90)
			(size 0 0)
			(layers "F.Cu" "F.Mask" "F.Paste")
			(net "RMII_CSRDV")
		)
	)
	(footprint ""
		(layer "F.Cu")
		(at 85.29955 -48.237394 180)
		(property "Reference" "R341"
			(at 0 0 180)
			(layer "F.SilkS")
			(hide yes)
			(effects
				(font
					(size 1.27 1.27)
				)
			)
		)
		(property "Value" ""
			(at 0 0 180)
			(layer "F.Fab")
			(effects
				(font
					(size 1.27 1.27)
				)
			)
		)
		(duplicate_pad_numbers_are_jumpers no)
		(fp_line
			(start 0.7874 0.4064)
			(end -0.7874 0.4064)
			(stroke
				(width 0.1524)
				(type default)
			)
			(layer "F.SilkS")
		)
		(fp_line
			(start 0.7874 -0.4064)
			(end 0.7874 0.4064)
			(stroke
				(width 0.1524)
				(type default)
			)
			(layer "F.SilkS")
		)
		(fp_line
			(start -0.7874 0.4064)
			(end -0.7874 -0.4064)
			(stroke
				(width 0.1524)
				(type default)
			)
			(layer "F.SilkS")
		)
		(fp_line
			(start -0.7874 -0.4064)
			(end 0.7874 -0.4064)
			(stroke
				(width 0.1524)
				(type default)
			)
			(layer "F.SilkS")
		)
		(fp_line
			(start 0.67945 0.3048)
			(end 0.120396 0.3048)
			(stroke
				(width 0.1)
				(type default)
			)
			(layer "F.Fab")
		)
		(fp_line
			(start 0.67945 -0.3048)
			(end 0.67945 0.3048)
			(stroke
				(width 0.1)
				(type default)
			)
			(layer "F.Fab")
		)
		(fp_line
			(start 0.12065 -0.2794)
			(end 0.12065 -0.3048)
			(stroke
				(width 0.1)
				(type default)
			)
			(layer "F.Fab")
		)
		(fp_line
			(start 0.12065 -0.3048)
			(end 0.67945 -0.3048)
			(stroke
				(width 0.1)
				(type default)
			)
			(layer "F.Fab")
		)
		(fp_line
			(start 0.120396 0.3048)
			(end 0.120396 0.2794)
			(stroke
				(width 0.1)
				(type default)
			)
			(layer "F.Fab")
		)
		(fp_line
			(start 0.120396 0.2794)
			(end -0.12065 0.2794)
			(stroke
				(width 0.1)
				(type default)
			)
			(layer "F.Fab")
		)
		(fp_line
			(start -0.12065 0.3048)
			(end -0.67945 0.3048)
			(stroke
				(width 0.1)
				(type default)
			)
			(layer "F.Fab")
		)
		(fp_line
			(start -0.12065 0.2794)
			(end -0.12065 0.3048)
			(stroke
				(width 0.1)
				(type default)
			)
			(layer "F.Fab")
		)
		(fp_line
			(start -0.12065 -0.2794)
			(end 0.12065 -0.2794)
			(stroke
				(width 0.1)
				(type default)
			)
			(layer "F.Fab")
		)
		(fp_line
			(start -0.12065 -0.305054)
			(end -0.12065 -0.2794)
			(stroke
				(width 0.1)
				(type default)
			)
			(layer "F.Fab")
		)
		(fp_line
			(start -0.67945 0.3048)
			(end -0.67945 -0.305054)
			(stroke
				(width 0.1)
				(type default)
			)
			(layer "F.Fab")
		)
		(fp_line
			(start -0.67945 -0.305054)
			(end -0.12065 -0.305054)
			(stroke
				(width 0.1)
				(type default)
			)
			(layer "F.Fab")
		)
		(pad "1" smd circle
			(at -0.40005 0 180)
			(size 0 0)
			(layers "F.Cu" "F.Mask" "F.Paste")
			(net "GND")
		)
		(pad "2" smd circle
			(at 0.40005 0 180)
			(size 0 0)
			(layers "F.Cu" "F.Mask" "F.Paste")
			(net "M_BMC_DDR4_MCAS_N")
		)
	)
	(footprint ""
		(layer "F.Cu")
		(at 39.42207 -13.379958)
		(property "Reference" "J2"
			(at -3.7719 -3.470148 0)
			(unlocked yes)
			(layer "F.SilkS")
			(effects
				(font
					(size 0.7874 0.5842)
					(thickness 0.1524)
				)
				(justify left)
			)
		)
		(property "Value" ""
			(at 0 0 0)
			(layer "F.Fab")
			(effects
				(font
					(size 1.27 1.27)
				)
			)
		)
		(duplicate_pad_numbers_are_jumpers no)
		(fp_line
			(start -3.700018 -1.952752)
			(end -3.700018 0.3175)
			(stroke
				(width 0.1524)
				(type default)
			)
			(layer "F.SilkS")
		)
		(fp_line
			(start -3.700018 3.683)
			(end -3.700018 13.780008)
			(stroke
				(width 0.1524)
				(type default)
			)
			(layer "F.SilkS")
		)
		(fp_line
			(start -3.700018 13.780008)
			(end 10.700004 13.780008)
			(stroke
				(width 0.1524)
				(type default)
			)
			(layer "F.SilkS")
		)
		(fp_line
			(start 0.350774 -2.720086)
			(end -2.489962 -2.720086)
			(stroke
				(width 0.1524)
				(type default)
			)
			(layer "F.SilkS")
		)
		(fp_line
			(start 3.49758 -2.720086)
			(end 2.034286 -2.720086)
			(stroke
				(width 0.1524)
				(type default)
			)
			(layer "F.SilkS")
		)
		(fp_line
			(start 10.700004 -2.720086)
			(end 6.785356 -2.720086)
			(stroke
				(width 0.1524)
				(type default)
			)
			(layer "F.SilkS")
		)
		(fp_line
			(start 10.700004 0.3175)
			(end 10.700004 -2.720086)
			(stroke
				(width 0.1524)
				(type default)
			)
			(layer "F.SilkS")
		)
		(fp_line
			(start 10.700004 13.780008)
			(end 10.700004 3.683)
			(stroke
				(width 0.1524)
				(type default)
			)
			(layer "F.SilkS")
		)
		(fp_poly
			(pts
				(xy -4.936998 0.508) (xy -4.936998 -0.508) (xy -3.920998 0)
			)
			(stroke
				(width 0)
				(type default)
			)
			(fill yes)
			(layer "F.SilkS")
		)
		(fp_line
			(start -3.700018 -2.720086)
			(end -3.700018 13.780008)
			(stroke
				(width 0.1)
				(type default)
			)
			(layer "F.Fab")
		)
		(fp_line
			(start -3.700018 13.780008)
			(end 10.700004 13.780008)
			(stroke
				(width 0.1)
				(type default)
			)
			(layer "F.Fab")
		)
		(fp_line
			(start 10.700004 -2.720086)
			(end -3.700018 -2.720086)
			(stroke
				(width 0.1)
				(type default)
			)
			(layer "F.Fab")
		)
		(fp_line
			(start 10.700004 13.780008)
			(end 10.700004 -2.720086)
			(stroke
				(width 0.1)
				(type default)
			)
			(layer "F.Fab")
		)
		(fp_poly
			(pts
				(xy -4.936998 0.508) (xy -4.936998 -0.508) (xy -3.920998 0)
			)
			(stroke
				(width 0)
				(type default)
			)
			(fill yes)
			(layer "F.Fab")
		)
		(pad "1" thru_hole rect
			(at 0 0 90)
			(size 1.1176 1.1176)
			(drill 0.7112)
			(layers "*.Cu" "*.Mask")
			(remove_unused_layers no)
			(net "P5V_USB_REAR")
			(clearance 0.0508)
			(thermal_gap 0.0508)
			(padstack
				(mode front_inner_back)
				(layer "Inner"
					(shape circle)
					(size 1.1176 1.1176)
					(clearance 0.0508)
				)
				(layer "B.Cu"
					(shape rect)
					(size 1.1176 1.1176)
					(clearance 0.0508)
				)
			)
		)
		(pad "2" thru_hole circle
			(at 2.500122 0 90)
			(size 1.1176 1.1176)
			(drill 0.7112)
			(layers "*.Cu" "*.Mask")
			(remove_unused_layers no)
			(net "USB2_01_F_DN")
			(clearance 0.0508)
			(thermal_gap 0.0508)
		)
		(pad "3" thru_hole circle
			(at 4.500118 0 90)
			(size 1.1176 1.1176)
			(drill 0.7112)
			(layers "*.Cu" "*.Mask")
			(remove_unused_layers no)
			(net "USB2_01_F_DP")
			(clearance 0.0508)
			(thermal_gap 0.0508)
		)
		(pad "4" thru_hole circle
			(at 6.999986 0 90)
			(size 1.1176 1.1176)
			(drill 0.7112)
			(layers "*.Cu" "*.Mask")
			(remove_unused_layers no)
			(net "GND")
			(clearance 0.0508)
			(thermal_gap 0.0508)
		)
		(pad "5" thru_hole circle
			(at 7.500112 -1.500124 90)
			(size 1.1176 1.1176)
			(drill 0.7112)
			(layers "*.Cu" "*.Mask")
			(remove_unused_layers no)
			(net "USB3_01_FB_RXN")
			(clearance 0.0508)
			(thermal_gap 0.0508)
		)
		(pad "6" thru_hole circle
			(at 5.500116 -1.500124 90)
			(size 1.1176 1.1176)
			(drill 0.7112)
			(layers "*.Cu" "*.Mask")
			(remove_unused_layers no)
			(net "USB3_01_FB_RXP")
			(clearance 0.0508)
			(thermal_gap 0.0508)
		)
		(pad "7" thru_hole circle
			(at 3.50012 -1.500124 90)
			(size 1.1176 1.1176)
			(drill 0.7112)
			(layers "*.Cu" "*.Mask")
			(remove_unused_layers no)
			(net "DEBUG_PORT_PRSNT_R")
			(clearance 0.0508)
			(thermal_gap 0.0508)
		)
		(pad "8" thru_hole circle
			(at 1.500124 -1.500124 90)
			(size 1.1176 1.1176)
			(drill 0.7112)
			(layers "*.Cu" "*.Mask")
			(remove_unused_layers no)
			(net "USB3_01_FB_TXN")
			(clearance 0.0508)
			(thermal_gap 0.0508)
		)
		(pad "9" thru_hole circle
			(at -0.499872 -1.500124 90)
			(size 1.1176 1.1176)
			(drill 0.7112)
			(layers "*.Cu" "*.Mask")
			(remove_unused_layers no)
			(net "USB3_01_FB_TXP")
			(clearance 0.0508)
			(thermal_gap 0.0508)
		)
		(pad "G1" thru_hole circle
			(at -3.070098 1.999996 90)
			(size 3.3274 3.3274)
			(drill 2.3114)
			(layers "*.Cu" "*.Mask")
			(remove_unused_layers no)
			(net "GND")
			(clearance -0.254)
		)
		(pad "G2" thru_hole circle
			(at 10.070084 1.999996 90)
			(size 3.3274 3.3274)
			(drill 2.3114)
			(layers "*.Cu" "*.Mask")
			(remove_unused_layers no)
			(net "GND")
			(clearance -0.254)
		)
	)
	(footprint ""
		(layer "F.Cu")
		(at 22.479 -102.743 -90)
		(property "Reference" "R746"
			(at 0 0 270)
			(layer "F.SilkS")
			(hide yes)
			(effects
				(font
					(size 1.27 1.27)
				)
			)
		)
		(property "Value" ""
			(at 0 0 270)
			(layer "F.Fab")
			(effects
				(font
					(size 1.27 1.27)
				)
			)
		)
		(duplicate_pad_numbers_are_jumpers no)
		(fp_line
			(start -0.7874 0.4064)
			(end -0.7874 -0.4064)
			(stroke
				(width 0.1524)
				(type default)
			)
			(layer "F.SilkS")
		)
		(fp_line
			(start 0.7874 0.4064)
			(end -0.7874 0.4064)
			(stroke
				(width 0.1524)
				(type default)
			)
			(layer "F.SilkS")
		)
		(fp_line
			(start -0.7874 -0.4064)
			(end 0.7874 -0.4064)
			(stroke
				(width 0.1524)
				(type default)
			)
			(layer "F.SilkS")
		)
		(fp_line
			(start 0.7874 -0.4064)
			(end 0.7874 0.4064)
			(stroke
				(width 0.1524)
				(type default)
			)
			(layer "F.SilkS")
		)
		(fp_line
			(start -0.67945 0.3048)
			(end -0.67945 -0.305054)
			(stroke
				(width 0.1)
				(type default)
			)
			(layer "F.Fab")
		)
		(fp_line
			(start -0.12065 0.3048)
			(end -0.67945 0.3048)
			(stroke
				(width 0.1)
				(type default)
			)
			(layer "F.Fab")
		)
		(fp_line
			(start 0.120396 0.3048)
			(end 0.120396 0.2794)
			(stroke
				(width 0.1)
				(type default)
			)
			(layer "F.Fab")
		)
		(fp_line
			(start 0.67945 0.3048)
			(end 0.120396 0.3048)
			(stroke
				(width 0.1)
				(type default)
			)
			(layer "F.Fab")
		)
		(fp_line
			(start -0.12065 0.2794)
			(end -0.12065 0.3048)
			(stroke
				(width 0.1)
				(type default)
			)
			(layer "F.Fab")
		)
		(fp_line
			(start 0.120396 0.2794)
			(end -0.12065 0.2794)
			(stroke
				(width 0.1)
				(type default)
			)
			(layer "F.Fab")
		)
		(fp_line
			(start -0.12065 -0.2794)
			(end 0.12065 -0.2794)
			(stroke
				(width 0.1)
				(type default)
			)
			(layer "F.Fab")
		)
		(fp_line
			(start 0.12065 -0.2794)
			(end 0.12065 -0.3048)
			(stroke
				(width 0.1)
				(type default)
			)
			(layer "F.Fab")
		)
		(fp_line
			(start 0.12065 -0.3048)
			(end 0.67945 -0.3048)
			(stroke
				(width 0.1)
				(type default)
			)
			(layer "F.Fab")
		)
		(fp_line
			(start 0.67945 -0.3048)
			(end 0.67945 0.3048)
			(stroke
				(width 0.1)
				(type default)
			)
			(layer "F.Fab")
		)
		(fp_line
			(start -0.67945 -0.305054)
			(end -0.12065 -0.305054)
			(stroke
				(width 0.1)
				(type default)
			)
			(layer "F.Fab")
		)
		(fp_line
			(start -0.12065 -0.305054)
			(end -0.12065 -0.2794)
			(stroke
				(width 0.1)
				(type default)
			)
			(layer "F.Fab")
		)
		(pad "1" smd circle
			(at -0.40005 0 270)
			(size 0 0)
			(layers "F.Cu" "F.Mask" "F.Paste")
			(net "IRQ_PCH_TPM_SPI_N")
		)
		(pad "2" smd circle
			(at 0.40005 0 270)
			(size 0 0)
			(layers "F.Cu" "F.Mask" "F.Paste")
			(net "IRQ_PCH_TPM_SPI_R2_N")
		)
	)
	(footprint ""
		(layer "F.Cu")
		(at 57.5691 -95.96374 90)
		(property "Reference" "R505"
			(at 0 0 90)
			(layer "F.SilkS")
			(hide yes)
			(effects
				(font
					(size 1.27 1.27)
				)
			)
		)
		(property "Value" ""
			(at 0 0 90)
			(layer "F.Fab")
			(effects
				(font
					(size 1.27 1.27)
				)
			)
		)
		(duplicate_pad_numbers_are_jumpers no)
		(fp_line
			(start 0.7874 -0.4064)
			(end 0.7874 0.4064)
			(stroke
				(width 0.1524)
				(type default)
			)
			(layer "F.SilkS")
		)
		(fp_line
			(start -0.7874 -0.4064)
			(end 0.7874 -0.4064)
			(stroke
				(width 0.1524)
				(type default)
			)
			(layer "F.SilkS")
		)
		(fp_line
			(start 0.7874 0.4064)
			(end -0.7874 0.4064)
			(stroke
				(width 0.1524)
				(type default)
			)
			(layer "F.SilkS")
		)
		(fp_line
			(start -0.7874 0.4064)
			(end -0.7874 -0.4064)
			(stroke
				(width 0.1524)
				(type default)
			)
			(layer "F.SilkS")
		)
		(fp_line
			(start -0.12065 -0.305054)
			(end -0.12065 -0.2794)
			(stroke
				(width 0.1)
				(type default)
			)
			(layer "F.Fab")
		)
		(fp_line
			(start -0.67945 -0.305054)
			(end -0.12065 -0.305054)
			(stroke
				(width 0.1)
				(type default)
			)
			(layer "F.Fab")
		)
		(fp_line
			(start 0.67945 -0.3048)
			(end 0.67945 0.3048)
			(stroke
				(width 0.1)
				(type default)
			)
			(layer "F.Fab")
		)
		(fp_line
			(start 0.12065 -0.3048)
			(end 0.67945 -0.3048)
			(stroke
				(width 0.1)
				(type default)
			)
			(layer "F.Fab")
		)
		(fp_line
			(start 0.12065 -0.2794)
			(end 0.12065 -0.3048)
			(stroke
				(width 0.1)
				(type default)
			)
			(layer "F.Fab")
		)
		(fp_line
			(start -0.12065 -0.2794)
			(end 0.12065 -0.2794)
			(stroke
				(width 0.1)
				(type default)
			)
			(layer "F.Fab")
		)
		(fp_line
			(start 0.120396 0.2794)
			(end -0.12065 0.2794)
			(stroke
				(width 0.1)
				(type default)
			)
			(layer "F.Fab")
		)
		(fp_line
			(start -0.12065 0.2794)
			(end -0.12065 0.3048)
			(stroke
				(width 0.1)
				(type default)
			)
			(layer "F.Fab")
		)
		(fp_line
			(start 0.67945 0.3048)
			(end 0.120396 0.3048)
			(stroke
				(width 0.1)
				(type default)
			)
			(layer "F.Fab")
		)
		(fp_line
			(start 0.120396 0.3048)
			(end 0.120396 0.2794)
			(stroke
				(width 0.1)
				(type default)
			)
			(layer "F.Fab")
		)
		(fp_line
			(start -0.12065 0.3048)
			(end -0.67945 0.3048)
			(stroke
				(width 0.1)
				(type default)
			)
			(layer "F.Fab")
		)
		(fp_line
			(start -0.67945 0.3048)
			(end -0.67945 -0.305054)
			(stroke
				(width 0.1)
				(type default)
			)
			(layer "F.Fab")
		)
		(pad "1" smd circle
			(at -0.40005 0 90)
			(size 0 0)
			(layers "F.Cu" "F.Mask" "F.Paste")
			(net "IRQ_PCH_TPM_SPI_N")
		)
		(pad "2" smd circle
			(at 0.40005 0 90)
			(size 0 0)
			(layers "F.Cu" "F.Mask" "F.Paste")
			(net "IRQ_PCH_TPM_SPI_R_N")
		)
	)
	(footprint ""
		(layer "F.Cu")
		(at 40.005 -58.547 90)
		(property "Reference" "C154"
			(at 0 0 90)
			(layer "F.SilkS")
			(hide yes)
			(effects
				(font
					(size 1.27 1.27)
				)
			)
		)
		(property "Value" ""
			(at 0 0 90)
			(layer "F.Fab")
			(effects
				(font
					(size 1.27 1.27)
				)
			)
		)
		(duplicate_pad_numbers_are_jumpers no)
		(fp_line
			(start 0.7874 -0.4064)
			(end 0.7874 0.4064)
			(stroke
				(width 0.1524)
				(type default)
			)
			(layer "F.SilkS")
		)
		(fp_line
			(start -0.7874 -0.4064)
			(end 0.7874 -0.4064)
			(stroke
				(width 0.1524)
				(type default)
			)
			(layer "F.SilkS")
		)
		(fp_line
			(start 0.7874 0.4064)
			(end -0.7874 0.4064)
			(stroke
				(width 0.1524)
				(type default)
			)
			(layer "F.SilkS")
		)
		(fp_line
			(start -0.7874 0.4064)
			(end -0.7874 -0.4064)
			(stroke
				(width 0.1524)
				(type default)
			)
			(layer "F.SilkS")
		)
		(fp_line
			(start -0.12065 -0.305054)
			(end -0.12065 -0.2794)
			(stroke
				(width 0.1)
				(type default)
			)
			(layer "F.Fab")
		)
		(fp_line
			(start -0.67945 -0.305054)
			(end -0.12065 -0.305054)
			(stroke
				(width 0.1)
				(type default)
			)
			(layer "F.Fab")
		)
		(fp_line
			(start 0.67945 -0.3048)
			(end 0.67945 0.3048)
			(stroke
				(width 0.1)
				(type default)
			)
			(layer "F.Fab")
		)
		(fp_line
			(start 0.12065 -0.3048)
			(end 0.67945 -0.3048)
			(stroke
				(width 0.1)
				(type default)
			)
			(layer "F.Fab")
		)
		(fp_line
			(start 0.12065 -0.2794)
			(end 0.12065 -0.3048)
			(stroke
				(width 0.1)
				(type default)
			)
			(layer "F.Fab")
		)
		(fp_line
			(start -0.12065 -0.2794)
			(end 0.12065 -0.2794)
			(stroke
				(width 0.1)
				(type default)
			)
			(layer "F.Fab")
		)
		(fp_line
			(start 0.120396 0.2794)
			(end -0.12065 0.2794)
			(stroke
				(width 0.1)
				(type default)
			)
			(layer "F.Fab")
		)
		(fp_line
			(start -0.12065 0.2794)
			(end -0.12065 0.3048)
			(stroke
				(width 0.1)
				(type default)
			)
			(layer "F.Fab")
		)
		(fp_line
			(start 0.67945 0.3048)
			(end 0.120396 0.3048)
			(stroke
				(width 0.1)
				(type default)
			)
			(layer "F.Fab")
		)
		(fp_line
			(start 0.120396 0.3048)
			(end 0.120396 0.2794)
			(stroke
				(width 0.1)
				(type default)
			)
			(layer "F.Fab")
		)
		(fp_line
			(start -0.12065 0.3048)
			(end -0.67945 0.3048)
			(stroke
				(width 0.1)
				(type default)
			)
			(layer "F.Fab")
		)
		(fp_line
			(start -0.67945 0.3048)
			(end -0.67945 -0.305054)
			(stroke
				(width 0.1)
				(type default)
			)
			(layer "F.Fab")
		)
		(pad "1" smd circle
			(at -0.40005 0 90)
			(size 0 0)
			(layers "F.Cu" "F.Mask" "F.Paste")
			(net "PWRGD_P1V8_AUX_R")
		)
		(pad "2" smd circle
			(at 0.40005 0 90)
			(size 0 0)
			(layers "F.Cu" "F.Mask" "F.Paste")
			(net "GND")
		)
	)
	(footprint ""
		(layer "F.Cu")
		(at 36.07054 -45.50664 180)
		(property "Reference" "R405"
			(at 0 0 180)
			(layer "F.SilkS")
			(hide yes)
			(effects
				(font
					(size 1.27 1.27)
				)
			)
		)
		(property "Value" ""
			(at 0 0 180)
			(layer "F.Fab")
			(effects
				(font
					(size 1.27 1.27)
				)
			)
		)
		(duplicate_pad_numbers_are_jumpers no)
		(fp_line
			(start 0.7874 0.4064)
			(end -0.7874 0.4064)
			(stroke
				(width 0.1524)
				(type default)
			)
			(layer "F.SilkS")
		)
		(fp_line
			(start 0.7874 -0.4064)
			(end 0.7874 0.4064)
			(stroke
				(width 0.1524)
				(type default)
			)
			(layer "F.SilkS")
		)
		(fp_line
			(start -0.7874 0.4064)
			(end -0.7874 -0.4064)
			(stroke
				(width 0.1524)
				(type default)
			)
			(layer "F.SilkS")
		)
		(fp_line
			(start -0.7874 -0.4064)
			(end 0.7874 -0.4064)
			(stroke
				(width 0.1524)
				(type default)
			)
			(layer "F.SilkS")
		)
		(fp_line
			(start 0.67945 0.3048)
			(end 0.120396 0.3048)
			(stroke
				(width 0.1)
				(type default)
			)
			(layer "F.Fab")
		)
		(fp_line
			(start 0.67945 -0.3048)
			(end 0.67945 0.3048)
			(stroke
				(width 0.1)
				(type default)
			)
			(layer "F.Fab")
		)
		(fp_line
			(start 0.12065 -0.2794)
			(end 0.12065 -0.3048)
			(stroke
				(width 0.1)
				(type default)
			)
			(layer "F.Fab")
		)
		(fp_line
			(start 0.12065 -0.3048)
			(end 0.67945 -0.3048)
			(stroke
				(width 0.1)
				(type default)
			)
			(layer "F.Fab")
		)
		(fp_line
			(start 0.120396 0.3048)
			(end 0.120396 0.2794)
			(stroke
				(width 0.1)
				(type default)
			)
			(layer "F.Fab")
		)
		(fp_line
			(start 0.120396 0.2794)
			(end -0.12065 0.2794)
			(stroke
				(width 0.1)
				(type default)
			)
			(layer "F.Fab")
		)
		(fp_line
			(start -0.12065 0.3048)
			(end -0.67945 0.3048)
			(stroke
				(width 0.1)
				(type default)
			)
			(layer "F.Fab")
		)
		(fp_line
			(start -0.12065 0.2794)
			(end -0.12065 0.3048)
			(stroke
				(width 0.1)
				(type default)
			)
			(layer "F.Fab")
		)
		(fp_line
			(start -0.12065 -0.2794)
			(end 0.12065 -0.2794)
			(stroke
				(width 0.1)
				(type default)
			)
			(layer "F.Fab")
		)
		(fp_line
			(start -0.12065 -0.305054)
			(end -0.12065 -0.2794)
			(stroke
				(width 0.1)
				(type default)
			)
			(layer "F.Fab")
		)
		(fp_line
			(start -0.67945 0.3048)
			(end -0.67945 -0.305054)
			(stroke
				(width 0.1)
				(type default)
			)
			(layer "F.Fab")
		)
		(fp_line
			(start -0.67945 -0.305054)
			(end -0.12065 -0.305054)
			(stroke
				(width 0.1)
				(type default)
			)
			(layer "F.Fab")
		)
		(pad "1" smd circle
			(at -0.40005 0 180)
			(size 0 0)
			(layers "F.Cu" "F.Mask" "F.Paste")
			(net "PD_BIOS_MUX_EN_R_N")
		)
		(pad "2" smd circle
			(at 0.40005 0 180)
			(size 0 0)
			(layers "F.Cu" "F.Mask" "F.Paste")
			(net "PD_BIOS_MUX_EN_N")
		)
	)
	(footprint ""
		(layer "F.Cu")
		(at 68.189094 -96.79305 180)
		(property "Reference" "R499"
			(at 0 0 180)
			(layer "F.SilkS")
			(hide yes)
			(effects
				(font
					(size 1.27 1.27)
				)
			)
		)
		(property "Value" ""
			(at 0 0 180)
			(layer "F.Fab")
			(effects
				(font
					(size 1.27 1.27)
				)
			)
		)
		(duplicate_pad_numbers_are_jumpers no)
		(fp_line
			(start 0.7874 0.4064)
			(end -0.7874 0.4064)
			(stroke
				(width 0.1524)
				(type default)
			)
			(layer "F.SilkS")
		)
		(fp_line
			(start 0.7874 -0.4064)
			(end 0.7874 0.4064)
			(stroke
				(width 0.1524)
				(type default)
			)
			(layer "F.SilkS")
		)
		(fp_line
			(start -0.7874 0.4064)
			(end -0.7874 -0.4064)
			(stroke
				(width 0.1524)
				(type default)
			)
			(layer "F.SilkS")
		)
		(fp_line
			(start -0.7874 -0.4064)
			(end 0.7874 -0.4064)
			(stroke
				(width 0.1524)
				(type default)
			)
			(layer "F.SilkS")
		)
		(fp_line
			(start 0.67945 0.3048)
			(end 0.120396 0.3048)
			(stroke
				(width 0.1)
				(type default)
			)
			(layer "F.Fab")
		)
		(fp_line
			(start 0.67945 -0.3048)
			(end 0.67945 0.3048)
			(stroke
				(width 0.1)
				(type default)
			)
			(layer "F.Fab")
		)
		(fp_line
			(start 0.12065 -0.2794)
			(end 0.12065 -0.3048)
			(stroke
				(width 0.1)
				(type default)
			)
			(layer "F.Fab")
		)
		(fp_line
			(start 0.12065 -0.3048)
			(end 0.67945 -0.3048)
			(stroke
				(width 0.1)
				(type default)
			)
			(layer "F.Fab")
		)
		(fp_line
			(start 0.120396 0.3048)
			(end 0.120396 0.2794)
			(stroke
				(width 0.1)
				(type default)
			)
			(layer "F.Fab")
		)
		(fp_line
			(start 0.120396 0.2794)
			(end -0.12065 0.2794)
			(stroke
				(width 0.1)
				(type default)
			)
			(layer "F.Fab")
		)
		(fp_line
			(start -0.12065 0.3048)
			(end -0.67945 0.3048)
			(stroke
				(width 0.1)
				(type default)
			)
			(layer "F.Fab")
		)
		(fp_line
			(start -0.12065 0.2794)
			(end -0.12065 0.3048)
			(stroke
				(width 0.1)
				(type default)
			)
			(layer "F.Fab")
		)
		(fp_line
			(start -0.12065 -0.2794)
			(end 0.12065 -0.2794)
			(stroke
				(width 0.1)
				(type default)
			)
			(layer "F.Fab")
		)
		(fp_line
			(start -0.12065 -0.305054)
			(end -0.12065 -0.2794)
			(stroke
				(width 0.1)
				(type default)
			)
			(layer "F.Fab")
		)
		(fp_line
			(start -0.67945 0.3048)
			(end -0.67945 -0.305054)
			(stroke
				(width 0.1)
				(type default)
			)
			(layer "F.Fab")
		)
		(fp_line
			(start -0.67945 -0.305054)
			(end -0.12065 -0.305054)
			(stroke
				(width 0.1)
				(type default)
			)
			(layer "F.Fab")
		)
		(pad "1" smd circle
			(at -0.40005 0 180)
			(size 0 0)
			(layers "F.Cu" "F.Mask" "F.Paste")
			(net "SPI_SYS_R_MISO")
		)
		(pad "2" smd circle
			(at 0.40005 0 180)
			(size 0 0)
			(layers "F.Cu" "F.Mask" "F.Paste")
			(net "SPI_SYS_R1_MISO")
		)
	)
	(footprint ""
		(layer "F.Cu")
		(at 39.9796 -40.2082)
		(property "Reference" "R122"
			(at 0 0 0)
			(layer "F.SilkS")
			(hide yes)
			(effects
				(font
					(size 1.27 1.27)
				)
			)
		)
		(property "Value" ""
			(at 0 0 0)
			(layer "F.Fab")
			(effects
				(font
					(size 1.27 1.27)
				)
			)
		)
		(duplicate_pad_numbers_are_jumpers no)
		(fp_line
			(start -0.7874 -0.4064)
			(end 0.7874 -0.4064)
			(stroke
				(width 0.1524)
				(type default)
			)
			(layer "F.SilkS")
		)
		(fp_line
			(start -0.7874 0.4064)
			(end -0.7874 -0.4064)
			(stroke
				(width 0.1524)
				(type default)
			)
			(layer "F.SilkS")
		)
		(fp_line
			(start 0.7874 -0.4064)
			(end 0.7874 0.4064)
			(stroke
				(width 0.1524)
				(type default)
			)
			(layer "F.SilkS")
		)
		(fp_line
			(start 0.7874 0.4064)
			(end -0.7874 0.4064)
			(stroke
				(width 0.1524)
				(type default)
			)
			(layer "F.SilkS")
		)
		(fp_line
			(start -0.67945 -0.305054)
			(end -0.12065 -0.305054)
			(stroke
				(width 0.1)
				(type default)
			)
			(layer "F.Fab")
		)
		(fp_line
			(start -0.67945 0.3048)
			(end -0.67945 -0.305054)
			(stroke
				(width 0.1)
				(type default)
			)
			(layer "F.Fab")
		)
		(fp_line
			(start -0.12065 -0.305054)
			(end -0.12065 -0.2794)
			(stroke
				(width 0.1)
				(type default)
			)
			(layer "F.Fab")
		)
		(fp_line
			(start -0.12065 -0.2794)
			(end 0.12065 -0.2794)
			(stroke
				(width 0.1)
				(type default)
			)
			(layer "F.Fab")
		)
		(fp_line
			(start -0.12065 0.2794)
			(end -0.12065 0.3048)
			(stroke
				(width 0.1)
				(type default)
			)
			(layer "F.Fab")
		)
		(fp_line
			(start -0.12065 0.3048)
			(end -0.67945 0.3048)
			(stroke
				(width 0.1)
				(type default)
			)
			(layer "F.Fab")
		)
		(fp_line
			(start 0.120396 0.2794)
			(end -0.12065 0.2794)
			(stroke
				(width 0.1)
				(type default)
			)
			(layer "F.Fab")
		)
		(fp_line
			(start 0.120396 0.3048)
			(end 0.120396 0.2794)
			(stroke
				(width 0.1)
				(type default)
			)
			(layer "F.Fab")
		)
		(fp_line
			(start 0.12065 -0.3048)
			(end 0.67945 -0.3048)
			(stroke
				(width 0.1)
				(type default)
			)
			(layer "F.Fab")
		)
		(fp_line
			(start 0.12065 -0.2794)
			(end 0.12065 -0.3048)
			(stroke
				(width 0.1)
				(type default)
			)
			(layer "F.Fab")
		)
		(fp_line
			(start 0.67945 -0.3048)
			(end 0.67945 0.3048)
			(stroke
				(width 0.1)
				(type default)
			)
			(layer "F.Fab")
		)
		(fp_line
			(start 0.67945 0.3048)
			(end 0.120396 0.3048)
			(stroke
				(width 0.1)
				(type default)
			)
			(layer "F.Fab")
		)
		(pad "1" smd circle
			(at -0.40005 0)
			(size 0 0)
			(layers "F.Cu" "F.Mask" "F.Paste")
			(net "FM_BIC_DEBUG_SW_N")
		)
		(pad "2" smd circle
			(at 0.40005 0)
			(size 0 0)
			(layers "F.Cu" "F.Mask" "F.Paste")
			(net "FM_BIC_DEBUG_SW_N_R")
		)
	)
	(footprint ""
		(layer "F.Cu")
		(at 12.4206 -100.1649 180)
		(property "Reference" "R318"
			(at 0 0 180)
			(layer "F.SilkS")
			(hide yes)
			(effects
				(font
					(size 1.27 1.27)
				)
			)
		)
		(property "Value" ""
			(at 0 0 180)
			(layer "F.Fab")
			(effects
				(font
					(size 1.27 1.27)
				)
			)
		)
		(duplicate_pad_numbers_are_jumpers no)
		(fp_line
			(start 0.7874 0.4064)
			(end -0.7874 0.4064)
			(stroke
				(width 0.1524)
				(type default)
			)
			(layer "F.SilkS")
		)
		(fp_line
			(start 0.7874 -0.4064)
			(end 0.7874 0.4064)
			(stroke
				(width 0.1524)
				(type default)
			)
			(layer "F.SilkS")
		)
		(fp_line
			(start -0.7874 0.4064)
			(end -0.7874 -0.4064)
			(stroke
				(width 0.1524)
				(type default)
			)
			(layer "F.SilkS")
		)
		(fp_line
			(start -0.7874 -0.4064)
			(end 0.7874 -0.4064)
			(stroke
				(width 0.1524)
				(type default)
			)
			(layer "F.SilkS")
		)
		(fp_line
			(start 0.67945 0.3048)
			(end 0.120396 0.3048)
			(stroke
				(width 0.1)
				(type default)
			)
			(layer "F.Fab")
		)
		(fp_line
			(start 0.67945 -0.3048)
			(end 0.67945 0.3048)
			(stroke
				(width 0.1)
				(type default)
			)
			(layer "F.Fab")
		)
		(fp_line
			(start 0.12065 -0.2794)
			(end 0.12065 -0.3048)
			(stroke
				(width 0.1)
				(type default)
			)
			(layer "F.Fab")
		)
		(fp_line
			(start 0.12065 -0.3048)
			(end 0.67945 -0.3048)
			(stroke
				(width 0.1)
				(type default)
			)
			(layer "F.Fab")
		)
		(fp_line
			(start 0.120396 0.3048)
			(end 0.120396 0.2794)
			(stroke
				(width 0.1)
				(type default)
			)
			(layer "F.Fab")
		)
		(fp_line
			(start 0.120396 0.2794)
			(end -0.12065 0.2794)
			(stroke
				(width 0.1)
				(type default)
			)
			(layer "F.Fab")
		)
		(fp_line
			(start -0.12065 0.3048)
			(end -0.67945 0.3048)
			(stroke
				(width 0.1)
				(type default)
			)
			(layer "F.Fab")
		)
		(fp_line
			(start -0.12065 0.2794)
			(end -0.12065 0.3048)
			(stroke
				(width 0.1)
				(type default)
			)
			(layer "F.Fab")
		)
		(fp_line
			(start -0.12065 -0.2794)
			(end 0.12065 -0.2794)
			(stroke
				(width 0.1)
				(type default)
			)
			(layer "F.Fab")
		)
		(fp_line
			(start -0.12065 -0.305054)
			(end -0.12065 -0.2794)
			(stroke
				(width 0.1)
				(type default)
			)
			(layer "F.Fab")
		)
		(fp_line
			(start -0.67945 0.3048)
			(end -0.67945 -0.305054)
			(stroke
				(width 0.1)
				(type default)
			)
			(layer "F.Fab")
		)
		(fp_line
			(start -0.67945 -0.305054)
			(end -0.12065 -0.305054)
			(stroke
				(width 0.1)
				(type default)
			)
			(layer "F.Fab")
		)
		(pad "1" smd circle
			(at -0.40005 0 180)
			(size 0 0)
			(layers "F.Cu" "F.Mask" "F.Paste")
			(net "PWRGD_P3V3_AUX_R1")
		)
		(pad "2" smd circle
			(at 0.40005 0 180)
			(size 0 0)
			(layers "F.Cu" "F.Mask" "F.Paste")
			(net "PWRGD_P3V3_AUX")
		)
	)
	(footprint ""
		(layer "F.Cu")
		(at 13.262864 -9.779 180)
		(property "Reference" "C191"
			(at 0 0 180)
			(layer "F.SilkS")
			(hide yes)
			(effects
				(font
					(size 1.27 1.27)
				)
			)
		)
		(property "Value" ""
			(at 0 0 180)
			(layer "F.Fab")
			(effects
				(font
					(size 1.27 1.27)
				)
			)
		)
		(duplicate_pad_numbers_are_jumpers no)
		(fp_line
			(start 0.7874 0.4064)
			(end -0.7874 0.4064)
			(stroke
				(width 0.1524)
				(type default)
			)
			(layer "F.SilkS")
		)
		(fp_line
			(start 0.7874 -0.4064)
			(end 0.7874 0.4064)
			(stroke
				(width 0.1524)
				(type default)
			)
			(layer "F.SilkS")
		)
		(fp_line
			(start -0.7874 0.4064)
			(end -0.7874 -0.4064)
			(stroke
				(width 0.1524)
				(type default)
			)
			(layer "F.SilkS")
		)
		(fp_line
			(start -0.7874 -0.4064)
			(end 0.7874 -0.4064)
			(stroke
				(width 0.1524)
				(type default)
			)
			(layer "F.SilkS")
		)
		(fp_line
			(start 0.67945 0.3048)
			(end 0.120396 0.3048)
			(stroke
				(width 0.1)
				(type default)
			)
			(layer "F.Fab")
		)
		(fp_line
			(start 0.67945 -0.3048)
			(end 0.67945 0.3048)
			(stroke
				(width 0.1)
				(type default)
			)
			(layer "F.Fab")
		)
		(fp_line
			(start 0.12065 -0.2794)
			(end 0.12065 -0.3048)
			(stroke
				(width 0.1)
				(type default)
			)
			(layer "F.Fab")
		)
		(fp_line
			(start 0.12065 -0.3048)
			(end 0.67945 -0.3048)
			(stroke
				(width 0.1)
				(type default)
			)
			(layer "F.Fab")
		)
		(fp_line
			(start 0.120396 0.3048)
			(end 0.120396 0.2794)
			(stroke
				(width 0.1)
				(type default)
			)
			(layer "F.Fab")
		)
		(fp_line
			(start 0.120396 0.2794)
			(end -0.12065 0.2794)
			(stroke
				(width 0.1)
				(type default)
			)
			(layer "F.Fab")
		)
		(fp_line
			(start -0.12065 0.3048)
			(end -0.67945 0.3048)
			(stroke
				(width 0.1)
				(type default)
			)
			(layer "F.Fab")
		)
		(fp_line
			(start -0.12065 0.2794)
			(end -0.12065 0.3048)
			(stroke
				(width 0.1)
				(type default)
			)
			(layer "F.Fab")
		)
		(fp_line
			(start -0.12065 -0.2794)
			(end 0.12065 -0.2794)
			(stroke
				(width 0.1)
				(type default)
			)
			(layer "F.Fab")
		)
		(fp_line
			(start -0.12065 -0.305054)
			(end -0.12065 -0.2794)
			(stroke
				(width 0.1)
				(type default)
			)
			(layer "F.Fab")
		)
		(fp_line
			(start -0.67945 0.3048)
			(end -0.67945 -0.305054)
			(stroke
				(width 0.1)
				(type default)
			)
			(layer "F.Fab")
		)
		(fp_line
			(start -0.67945 -0.305054)
			(end -0.12065 -0.305054)
			(stroke
				(width 0.1)
				(type default)
			)
			(layer "F.Fab")
		)
		(pad "1" smd circle
			(at -0.40005 0 180)
			(size 0 0)
			(layers "F.Cu" "F.Mask" "F.Paste")
			(net "P3V3_AUX")
		)
		(pad "2" smd circle
			(at 0.40005 0 180)
			(size 0 0)
			(layers "F.Cu" "F.Mask" "F.Paste")
			(net "GND")
		)
	)
	(footprint ""
		(layer "F.Cu")
		(at 2.65938 -18.161)
		(property "Reference" ""
			(at 0 0 0)
			(layer "F.SilkS")
			(hide yes)
			(effects
				(font
					(size 1.27 1.27)
				)
			)
		)
		(property "Value" ""
			(at 0 0 0)
			(layer "F.Fab")
			(effects
				(font
					(size 1.27 1.27)
				)
			)
		)
		(duplicate_pad_numbers_are_jumpers no)
		(pad "1" smd circle
			(at 0 0)
			(size 0.9906 0.9906)
			(layers "F.Cu" "F.Mask" "F.Paste")
			(net "Net_596")
		)
		(zone
			(layer "F.Cu")
			(hatch none 0.5)
			(connect_pads
				(clearance 0)
			)
			(min_thickness 0.25)
			(keepout
				(tracks not_allowed)
				(vias allowed)
				(pads allowed)
				(copperpour not_allowed)
				(footprints allowed)
			)
			(placement
				(enabled no)
				(sheetname "")
			)
			(fill
				(thermal_gap 0.5)
				(thermal_bridge_width 0.5)
				(island_removal_mode 0)
			)
			(polygon
				(pts
					(arc
						(start 4.28498 -18.161)
						(mid 1.03378 -18.161)
						(end 4.28498 -18.161)
					)
				)
			)
		)
	)
	(footprint ""
		(layer "F.Cu")
		(at 5.334 -80.899 -90)
		(property "Reference" "R614"
			(at 0 0 270)
			(layer "F.SilkS")
			(hide yes)
			(effects
				(font
					(size 1.27 1.27)
				)
			)
		)
		(property "Value" ""
			(at 0 0 270)
			(layer "F.Fab")
			(effects
				(font
					(size 1.27 1.27)
				)
			)
		)
		(duplicate_pad_numbers_are_jumpers no)
		(fp_line
			(start -0.7874 0.4064)
			(end -0.7874 -0.4064)
			(stroke
				(width 0.1524)
				(type default)
			)
			(layer "F.SilkS")
		)
		(fp_line
			(start 0.7874 0.4064)
			(end -0.7874 0.4064)
			(stroke
				(width 0.1524)
				(type default)
			)
			(layer "F.SilkS")
		)
		(fp_line
			(start -0.7874 -0.4064)
			(end 0.7874 -0.4064)
			(stroke
				(width 0.1524)
				(type default)
			)
			(layer "F.SilkS")
		)
		(fp_line
			(start 0.7874 -0.4064)
			(end 0.7874 0.4064)
			(stroke
				(width 0.1524)
				(type default)
			)
			(layer "F.SilkS")
		)
		(fp_line
			(start -0.67945 0.3048)
			(end -0.67945 -0.305054)
			(stroke
				(width 0.1)
				(type default)
			)
			(layer "F.Fab")
		)
		(fp_line
			(start -0.12065 0.3048)
			(end -0.67945 0.3048)
			(stroke
				(width 0.1)
				(type default)
			)
			(layer "F.Fab")
		)
		(fp_line
			(start 0.120396 0.3048)
			(end 0.120396 0.2794)
			(stroke
				(width 0.1)
				(type default)
			)
			(layer "F.Fab")
		)
		(fp_line
			(start 0.67945 0.3048)
			(end 0.120396 0.3048)
			(stroke
				(width 0.1)
				(type default)
			)
			(layer "F.Fab")
		)
		(fp_line
			(start -0.12065 0.2794)
			(end -0.12065 0.3048)
			(stroke
				(width 0.1)
				(type default)
			)
			(layer "F.Fab")
		)
		(fp_line
			(start 0.120396 0.2794)
			(end -0.12065 0.2794)
			(stroke
				(width 0.1)
				(type default)
			)
			(layer "F.Fab")
		)
		(fp_line
			(start -0.12065 -0.2794)
			(end 0.12065 -0.2794)
			(stroke
				(width 0.1)
				(type default)
			)
			(layer "F.Fab")
		)
		(fp_line
			(start 0.12065 -0.2794)
			(end 0.12065 -0.3048)
			(stroke
				(width 0.1)
				(type default)
			)
			(layer "F.Fab")
		)
		(fp_line
			(start 0.12065 -0.3048)
			(end 0.67945 -0.3048)
			(stroke
				(width 0.1)
				(type default)
			)
			(layer "F.Fab")
		)
		(fp_line
			(start 0.67945 -0.3048)
			(end 0.67945 0.3048)
			(stroke
				(width 0.1)
				(type default)
			)
			(layer "F.Fab")
		)
		(fp_line
			(start -0.67945 -0.305054)
			(end -0.12065 -0.305054)
			(stroke
				(width 0.1)
				(type default)
			)
			(layer "F.Fab")
		)
		(fp_line
			(start -0.12065 -0.305054)
			(end -0.12065 -0.2794)
			(stroke
				(width 0.1)
				(type default)
			)
			(layer "F.Fab")
		)
		(pad "1" smd circle
			(at -0.40005 0 270)
			(size 0 0)
			(layers "F.Cu" "F.Mask" "F.Paste")
			(net "RST_SRST_PLD_BMC_R1_N")
		)
		(pad "2" smd circle
			(at 0.40005 0 270)
			(size 0 0)
			(layers "F.Cu" "F.Mask" "F.Paste")
			(net "GND")
		)
	)
	(footprint ""
		(layer "F.Cu")
		(at 45.062902 -63.756794 -90)
		(property "Reference" "R23"
			(at 0 0 270)
			(layer "F.SilkS")
			(hide yes)
			(effects
				(font
					(size 1.27 1.27)
				)
			)
		)
		(property "Value" ""
			(at 0 0 270)
			(layer "F.Fab")
			(effects
				(font
					(size 1.27 1.27)
				)
			)
		)
		(duplicate_pad_numbers_are_jumpers no)
		(fp_line
			(start -0.7874 0.4064)
			(end -0.7874 -0.4064)
			(stroke
				(width 0.1524)
				(type default)
			)
			(layer "F.SilkS")
		)
		(fp_line
			(start 0.7874 0.4064)
			(end -0.7874 0.4064)
			(stroke
				(width 0.1524)
				(type default)
			)
			(layer "F.SilkS")
		)
		(fp_line
			(start -0.7874 -0.4064)
			(end 0.7874 -0.4064)
			(stroke
				(width 0.1524)
				(type default)
			)
			(layer "F.SilkS")
		)
		(fp_line
			(start 0.7874 -0.4064)
			(end 0.7874 0.4064)
			(stroke
				(width 0.1524)
				(type default)
			)
			(layer "F.SilkS")
		)
		(fp_line
			(start -0.67945 0.3048)
			(end -0.67945 -0.305054)
			(stroke
				(width 0.1)
				(type default)
			)
			(layer "F.Fab")
		)
		(fp_line
			(start -0.12065 0.3048)
			(end -0.67945 0.3048)
			(stroke
				(width 0.1)
				(type default)
			)
			(layer "F.Fab")
		)
		(fp_line
			(start 0.120396 0.3048)
			(end 0.120396 0.2794)
			(stroke
				(width 0.1)
				(type default)
			)
			(layer "F.Fab")
		)
		(fp_line
			(start 0.67945 0.3048)
			(end 0.120396 0.3048)
			(stroke
				(width 0.1)
				(type default)
			)
			(layer "F.Fab")
		)
		(fp_line
			(start -0.12065 0.2794)
			(end -0.12065 0.3048)
			(stroke
				(width 0.1)
				(type default)
			)
			(layer "F.Fab")
		)
		(fp_line
			(start 0.120396 0.2794)
			(end -0.12065 0.2794)
			(stroke
				(width 0.1)
				(type default)
			)
			(layer "F.Fab")
		)
		(fp_line
			(start -0.12065 -0.2794)
			(end 0.12065 -0.2794)
			(stroke
				(width 0.1)
				(type default)
			)
			(layer "F.Fab")
		)
		(fp_line
			(start 0.12065 -0.2794)
			(end 0.12065 -0.3048)
			(stroke
				(width 0.1)
				(type default)
			)
			(layer "F.Fab")
		)
		(fp_line
			(start 0.12065 -0.3048)
			(end 0.67945 -0.3048)
			(stroke
				(width 0.1)
				(type default)
			)
			(layer "F.Fab")
		)
		(fp_line
			(start 0.67945 -0.3048)
			(end 0.67945 0.3048)
			(stroke
				(width 0.1)
				(type default)
			)
			(layer "F.Fab")
		)
		(fp_line
			(start -0.67945 -0.305054)
			(end -0.12065 -0.305054)
			(stroke
				(width 0.1)
				(type default)
			)
			(layer "F.Fab")
		)
		(fp_line
			(start -0.12065 -0.305054)
			(end -0.12065 -0.2794)
			(stroke
				(width 0.1)
				(type default)
			)
			(layer "F.Fab")
		)
		(pad "1" smd circle
			(at -0.40005 0 270)
			(size 0 0)
			(layers "F.Cu" "F.Mask" "F.Paste")
			(net "V_DACG_R")
		)
		(pad "2" smd circle
			(at 0.40005 0 270)
			(size 0 0)
			(layers "F.Cu" "F.Mask" "F.Paste")
			(net "GND")
		)
	)
	(footprint ""
		(layer "F.Cu")
		(at 35.941 -60.96 90)
		(property "Reference" "R65"
			(at 0 0 90)
			(layer "F.SilkS")
			(hide yes)
			(effects
				(font
					(size 1.27 1.27)
				)
			)
		)
		(property "Value" ""
			(at 0 0 90)
			(layer "F.Fab")
			(effects
				(font
					(size 1.27 1.27)
				)
			)
		)
		(duplicate_pad_numbers_are_jumpers no)
		(fp_line
			(start 0.7874 -0.4064)
			(end 0.7874 0.4064)
			(stroke
				(width 0.1524)
				(type default)
			)
			(layer "F.SilkS")
		)
		(fp_line
			(start -0.7874 -0.4064)
			(end 0.7874 -0.4064)
			(stroke
				(width 0.1524)
				(type default)
			)
			(layer "F.SilkS")
		)
		(fp_line
			(start 0.7874 0.4064)
			(end -0.7874 0.4064)
			(stroke
				(width 0.1524)
				(type default)
			)
			(layer "F.SilkS")
		)
		(fp_line
			(start -0.7874 0.4064)
			(end -0.7874 -0.4064)
			(stroke
				(width 0.1524)
				(type default)
			)
			(layer "F.SilkS")
		)
		(fp_line
			(start -0.12065 -0.305054)
			(end -0.12065 -0.2794)
			(stroke
				(width 0.1)
				(type default)
			)
			(layer "F.Fab")
		)
		(fp_line
			(start -0.67945 -0.305054)
			(end -0.12065 -0.305054)
			(stroke
				(width 0.1)
				(type default)
			)
			(layer "F.Fab")
		)
		(fp_line
			(start 0.67945 -0.3048)
			(end 0.67945 0.3048)
			(stroke
				(width 0.1)
				(type default)
			)
			(layer "F.Fab")
		)
		(fp_line
			(start 0.12065 -0.3048)
			(end 0.67945 -0.3048)
			(stroke
				(width 0.1)
				(type default)
			)
			(layer "F.Fab")
		)
		(fp_line
			(start 0.12065 -0.2794)
			(end 0.12065 -0.3048)
			(stroke
				(width 0.1)
				(type default)
			)
			(layer "F.Fab")
		)
		(fp_line
			(start -0.12065 -0.2794)
			(end 0.12065 -0.2794)
			(stroke
				(width 0.1)
				(type default)
			)
			(layer "F.Fab")
		)
		(fp_line
			(start 0.120396 0.2794)
			(end -0.12065 0.2794)
			(stroke
				(width 0.1)
				(type default)
			)
			(layer "F.Fab")
		)
		(fp_line
			(start -0.12065 0.2794)
			(end -0.12065 0.3048)
			(stroke
				(width 0.1)
				(type default)
			)
			(layer "F.Fab")
		)
		(fp_line
			(start 0.67945 0.3048)
			(end 0.120396 0.3048)
			(stroke
				(width 0.1)
				(type default)
			)
			(layer "F.Fab")
		)
		(fp_line
			(start 0.120396 0.3048)
			(end 0.120396 0.2794)
			(stroke
				(width 0.1)
				(type default)
			)
			(layer "F.Fab")
		)
		(fp_line
			(start -0.12065 0.3048)
			(end -0.67945 0.3048)
			(stroke
				(width 0.1)
				(type default)
			)
			(layer "F.Fab")
		)
		(fp_line
			(start -0.67945 0.3048)
			(end -0.67945 -0.305054)
			(stroke
				(width 0.1)
				(type default)
			)
			(layer "F.Fab")
		)
		(pad "1" smd circle
			(at -0.40005 0 90)
			(size 0 0)
			(layers "F.Cu" "F.Mask" "F.Paste")
			(net "BMC_CPLD_GPIO_2_R1")
		)
		(pad "2" smd circle
			(at 0.40005 0 90)
			(size 0 0)
			(layers "F.Cu" "F.Mask" "F.Paste")
			(net "BMC_CPLD_GPIO_2")
		)
	)
	(footprint ""
		(layer "F.Cu")
		(at 18.034 -102.743 90)
		(property "Reference" "R114"
			(at 0 0 90)
			(layer "F.SilkS")
			(hide yes)
			(effects
				(font
					(size 1.27 1.27)
				)
			)
		)
		(property "Value" ""
			(at 0 0 90)
			(layer "F.Fab")
			(effects
				(font
					(size 1.27 1.27)
				)
			)
		)
		(duplicate_pad_numbers_are_jumpers no)
		(fp_line
			(start 0.7874 -0.4064)
			(end 0.7874 0.4064)
			(stroke
				(width 0.1524)
				(type default)
			)
			(layer "F.SilkS")
		)
		(fp_line
			(start -0.7874 -0.4064)
			(end 0.7874 -0.4064)
			(stroke
				(width 0.1524)
				(type default)
			)
			(layer "F.SilkS")
		)
		(fp_line
			(start 0.7874 0.4064)
			(end -0.7874 0.4064)
			(stroke
				(width 0.1524)
				(type default)
			)
			(layer "F.SilkS")
		)
		(fp_line
			(start -0.7874 0.4064)
			(end -0.7874 -0.4064)
			(stroke
				(width 0.1524)
				(type default)
			)
			(layer "F.SilkS")
		)
		(fp_line
			(start -0.12065 -0.305054)
			(end -0.12065 -0.2794)
			(stroke
				(width 0.1)
				(type default)
			)
			(layer "F.Fab")
		)
		(fp_line
			(start -0.67945 -0.305054)
			(end -0.12065 -0.305054)
			(stroke
				(width 0.1)
				(type default)
			)
			(layer "F.Fab")
		)
		(fp_line
			(start 0.67945 -0.3048)
			(end 0.67945 0.3048)
			(stroke
				(width 0.1)
				(type default)
			)
			(layer "F.Fab")
		)
		(fp_line
			(start 0.12065 -0.3048)
			(end 0.67945 -0.3048)
			(stroke
				(width 0.1)
				(type default)
			)
			(layer "F.Fab")
		)
		(fp_line
			(start 0.12065 -0.2794)
			(end 0.12065 -0.3048)
			(stroke
				(width 0.1)
				(type default)
			)
			(layer "F.Fab")
		)
		(fp_line
			(start -0.12065 -0.2794)
			(end 0.12065 -0.2794)
			(stroke
				(width 0.1)
				(type default)
			)
			(layer "F.Fab")
		)
		(fp_line
			(start 0.120396 0.2794)
			(end -0.12065 0.2794)
			(stroke
				(width 0.1)
				(type default)
			)
			(layer "F.Fab")
		)
		(fp_line
			(start -0.12065 0.2794)
			(end -0.12065 0.3048)
			(stroke
				(width 0.1)
				(type default)
			)
			(layer "F.Fab")
		)
		(fp_line
			(start 0.67945 0.3048)
			(end 0.120396 0.3048)
			(stroke
				(width 0.1)
				(type default)
			)
			(layer "F.Fab")
		)
		(fp_line
			(start 0.120396 0.3048)
			(end 0.120396 0.2794)
			(stroke
				(width 0.1)
				(type default)
			)
			(layer "F.Fab")
		)
		(fp_line
			(start -0.12065 0.3048)
			(end -0.67945 0.3048)
			(stroke
				(width 0.1)
				(type default)
			)
			(layer "F.Fab")
		)
		(fp_line
			(start -0.67945 0.3048)
			(end -0.67945 -0.305054)
			(stroke
				(width 0.1)
				(type default)
			)
			(layer "F.Fab")
		)
		(pad "1" smd circle
			(at -0.40005 0 90)
			(size 0 0)
			(layers "F.Cu" "F.Mask" "F.Paste")
			(net "SMB_BMC_MM16_R4_SDA")
		)
		(pad "2" smd circle
			(at 0.40005 0 90)
			(size 0 0)
			(layers "F.Cu" "F.Mask" "F.Paste")
			(net "SMB_BMC_MM16_R5_SDA")
		)
	)
	(footprint ""
		(layer "F.Cu")
		(at 26.924 -20.32)
		(property "Reference" "R32"
			(at 0 0 0)
			(layer "F.SilkS")
			(hide yes)
			(effects
				(font
					(size 1.27 1.27)
				)
			)
		)
		(property "Value" ""
			(at 0 0 0)
			(layer "F.Fab")
			(effects
				(font
					(size 1.27 1.27)
				)
			)
		)
		(duplicate_pad_numbers_are_jumpers no)
		(fp_line
			(start -0.7874 -0.4064)
			(end 0.7874 -0.4064)
			(stroke
				(width 0.1524)
				(type default)
			)
			(layer "F.SilkS")
		)
		(fp_line
			(start -0.7874 0.4064)
			(end -0.7874 -0.4064)
			(stroke
				(width 0.1524)
				(type default)
			)
			(layer "F.SilkS")
		)
		(fp_line
			(start 0.7874 -0.4064)
			(end 0.7874 0.4064)
			(stroke
				(width 0.1524)
				(type default)
			)
			(layer "F.SilkS")
		)
		(fp_line
			(start 0.7874 0.4064)
			(end -0.7874 0.4064)
			(stroke
				(width 0.1524)
				(type default)
			)
			(layer "F.SilkS")
		)
		(fp_line
			(start -0.67945 -0.305054)
			(end -0.12065 -0.305054)
			(stroke
				(width 0.1)
				(type default)
			)
			(layer "F.Fab")
		)
		(fp_line
			(start -0.67945 0.3048)
			(end -0.67945 -0.305054)
			(stroke
				(width 0.1)
				(type default)
			)
			(layer "F.Fab")
		)
		(fp_line
			(start -0.12065 -0.305054)
			(end -0.12065 -0.2794)
			(stroke
				(width 0.1)
				(type default)
			)
			(layer "F.Fab")
		)
		(fp_line
			(start -0.12065 -0.2794)
			(end 0.12065 -0.2794)
			(stroke
				(width 0.1)
				(type default)
			)
			(layer "F.Fab")
		)
		(fp_line
			(start -0.12065 0.2794)
			(end -0.12065 0.3048)
			(stroke
				(width 0.1)
				(type default)
			)
			(layer "F.Fab")
		)
		(fp_line
			(start -0.12065 0.3048)
			(end -0.67945 0.3048)
			(stroke
				(width 0.1)
				(type default)
			)
			(layer "F.Fab")
		)
		(fp_line
			(start 0.120396 0.2794)
			(end -0.12065 0.2794)
			(stroke
				(width 0.1)
				(type default)
			)
			(layer "F.Fab")
		)
		(fp_line
			(start 0.120396 0.3048)
			(end 0.120396 0.2794)
			(stroke
				(width 0.1)
				(type default)
			)
			(layer "F.Fab")
		)
		(fp_line
			(start 0.12065 -0.3048)
			(end 0.67945 -0.3048)
			(stroke
				(width 0.1)
				(type default)
			)
			(layer "F.Fab")
		)
		(fp_line
			(start 0.12065 -0.2794)
			(end 0.12065 -0.3048)
			(stroke
				(width 0.1)
				(type default)
			)
			(layer "F.Fab")
		)
		(fp_line
			(start 0.67945 -0.3048)
			(end 0.67945 0.3048)
			(stroke
				(width 0.1)
				(type default)
			)
			(layer "F.Fab")
		)
		(fp_line
			(start 0.67945 0.3048)
			(end 0.120396 0.3048)
			(stroke
				(width 0.1)
				(type default)
			)
			(layer "F.Fab")
		)
		(pad "1" smd circle
			(at -0.40005 0)
			(size 0 0)
			(layers "F.Cu" "F.Mask" "F.Paste")
			(net "P3V3_RGM")
		)
		(pad "2" smd circle
			(at 0.40005 0)
			(size 0 0)
			(layers "F.Cu" "F.Mask" "F.Paste")
			(net "V_BMC_DDC_SCL")
		)
	)
	(footprint ""
		(layer "F.Cu")
		(at 30.564074 -61.341 -90)
		(property "Reference" "R72"
			(at 0 0 270)
			(layer "F.SilkS")
			(hide yes)
			(effects
				(font
					(size 1.27 1.27)
				)
			)
		)
		(property "Value" ""
			(at 0 0 270)
			(layer "F.Fab")
			(effects
				(font
					(size 1.27 1.27)
				)
			)
		)
		(duplicate_pad_numbers_are_jumpers no)
		(fp_line
			(start -0.7874 0.4064)
			(end -0.7874 -0.4064)
			(stroke
				(width 0.1524)
				(type default)
			)
			(layer "F.SilkS")
		)
		(fp_line
			(start 0.7874 0.4064)
			(end -0.7874 0.4064)
			(stroke
				(width 0.1524)
				(type default)
			)
			(layer "F.SilkS")
		)
		(fp_line
			(start -0.7874 -0.4064)
			(end 0.7874 -0.4064)
			(stroke
				(width 0.1524)
				(type default)
			)
			(layer "F.SilkS")
		)
		(fp_line
			(start 0.7874 -0.4064)
			(end 0.7874 0.4064)
			(stroke
				(width 0.1524)
				(type default)
			)
			(layer "F.SilkS")
		)
		(fp_line
			(start -0.67945 0.3048)
			(end -0.67945 -0.305054)
			(stroke
				(width 0.1)
				(type default)
			)
			(layer "F.Fab")
		)
		(fp_line
			(start -0.12065 0.3048)
			(end -0.67945 0.3048)
			(stroke
				(width 0.1)
				(type default)
			)
			(layer "F.Fab")
		)
		(fp_line
			(start 0.120396 0.3048)
			(end 0.120396 0.2794)
			(stroke
				(width 0.1)
				(type default)
			)
			(layer "F.Fab")
		)
		(fp_line
			(start 0.67945 0.3048)
			(end 0.120396 0.3048)
			(stroke
				(width 0.1)
				(type default)
			)
			(layer "F.Fab")
		)
		(fp_line
			(start -0.12065 0.2794)
			(end -0.12065 0.3048)
			(stroke
				(width 0.1)
				(type default)
			)
			(layer "F.Fab")
		)
		(fp_line
			(start 0.120396 0.2794)
			(end -0.12065 0.2794)
			(stroke
				(width 0.1)
				(type default)
			)
			(layer "F.Fab")
		)
		(fp_line
			(start -0.12065 -0.2794)
			(end 0.12065 -0.2794)
			(stroke
				(width 0.1)
				(type default)
			)
			(layer "F.Fab")
		)
		(fp_line
			(start 0.12065 -0.2794)
			(end 0.12065 -0.3048)
			(stroke
				(width 0.1)
				(type default)
			)
			(layer "F.Fab")
		)
		(fp_line
			(start 0.12065 -0.3048)
			(end 0.67945 -0.3048)
			(stroke
				(width 0.1)
				(type default)
			)
			(layer "F.Fab")
		)
		(fp_line
			(start 0.67945 -0.3048)
			(end 0.67945 0.3048)
			(stroke
				(width 0.1)
				(type default)
			)
			(layer "F.Fab")
		)
		(fp_line
			(start -0.67945 -0.305054)
			(end -0.12065 -0.305054)
			(stroke
				(width 0.1)
				(type default)
			)
			(layer "F.Fab")
		)
		(fp_line
			(start -0.12065 -0.305054)
			(end -0.12065 -0.2794)
			(stroke
				(width 0.1)
				(type default)
			)
			(layer "F.Fab")
		)
		(pad "1" smd circle
			(at -0.40005 0 270)
			(size 0 0)
			(layers "F.Cu" "F.Mask" "F.Paste")
			(net "P3V3_AUX")
		)
		(pad "2" smd circle
			(at 0.40005 0 270)
			(size 0 0)
			(layers "F.Cu" "F.Mask" "F.Paste")
			(net "UART_BMC_5_RXD_BUF1")
		)
	)
	(footprint ""
		(layer "F.Cu")
		(at 23.241 -68.834 90)
		(property "Reference" "R57"
			(at 0 0 90)
			(layer "F.SilkS")
			(hide yes)
			(effects
				(font
					(size 1.27 1.27)
				)
			)
		)
		(property "Value" ""
			(at 0 0 90)
			(layer "F.Fab")
			(effects
				(font
					(size 1.27 1.27)
				)
			)
		)
		(duplicate_pad_numbers_are_jumpers no)
		(fp_line
			(start 0.7874 -0.4064)
			(end 0.7874 0.4064)
			(stroke
				(width 0.1524)
				(type default)
			)
			(layer "F.SilkS")
		)
		(fp_line
			(start -0.7874 -0.4064)
			(end 0.7874 -0.4064)
			(stroke
				(width 0.1524)
				(type default)
			)
			(layer "F.SilkS")
		)
		(fp_line
			(start 0.7874 0.4064)
			(end -0.7874 0.4064)
			(stroke
				(width 0.1524)
				(type default)
			)
			(layer "F.SilkS")
		)
		(fp_line
			(start -0.7874 0.4064)
			(end -0.7874 -0.4064)
			(stroke
				(width 0.1524)
				(type default)
			)
			(layer "F.SilkS")
		)
		(fp_line
			(start -0.12065 -0.305054)
			(end -0.12065 -0.2794)
			(stroke
				(width 0.1)
				(type default)
			)
			(layer "F.Fab")
		)
		(fp_line
			(start -0.67945 -0.305054)
			(end -0.12065 -0.305054)
			(stroke
				(width 0.1)
				(type default)
			)
			(layer "F.Fab")
		)
		(fp_line
			(start 0.67945 -0.3048)
			(end 0.67945 0.3048)
			(stroke
				(width 0.1)
				(type default)
			)
			(layer "F.Fab")
		)
		(fp_line
			(start 0.12065 -0.3048)
			(end 0.67945 -0.3048)
			(stroke
				(width 0.1)
				(type default)
			)
			(layer "F.Fab")
		)
		(fp_line
			(start 0.12065 -0.2794)
			(end 0.12065 -0.3048)
			(stroke
				(width 0.1)
				(type default)
			)
			(layer "F.Fab")
		)
		(fp_line
			(start -0.12065 -0.2794)
			(end 0.12065 -0.2794)
			(stroke
				(width 0.1)
				(type default)
			)
			(layer "F.Fab")
		)
		(fp_line
			(start 0.120396 0.2794)
			(end -0.12065 0.2794)
			(stroke
				(width 0.1)
				(type default)
			)
			(layer "F.Fab")
		)
		(fp_line
			(start -0.12065 0.2794)
			(end -0.12065 0.3048)
			(stroke
				(width 0.1)
				(type default)
			)
			(layer "F.Fab")
		)
		(fp_line
			(start 0.67945 0.3048)
			(end 0.120396 0.3048)
			(stroke
				(width 0.1)
				(type default)
			)
			(layer "F.Fab")
		)
		(fp_line
			(start 0.120396 0.3048)
			(end 0.120396 0.2794)
			(stroke
				(width 0.1)
				(type default)
			)
			(layer "F.Fab")
		)
		(fp_line
			(start -0.12065 0.3048)
			(end -0.67945 0.3048)
			(stroke
				(width 0.1)
				(type default)
			)
			(layer "F.Fab")
		)
		(fp_line
			(start -0.67945 0.3048)
			(end -0.67945 -0.305054)
			(stroke
				(width 0.1)
				(type default)
			)
			(layer "F.Fab")
		)
		(pad "1" smd circle
			(at -0.40005 0 90)
			(size 0 0)
			(layers "F.Cu" "F.Mask" "F.Paste")
			(net "BSM_PRSNT_R_N")
		)
		(pad "2" smd circle
			(at 0.40005 0 90)
			(size 0 0)
			(layers "F.Cu" "F.Mask" "F.Paste")
			(net "BSM_PRSNT_N")
		)
	)
	(footprint ""
		(layer "F.Cu")
		(at 51.7525 -92.837 90)
		(property "Reference" "Q3"
			(at 1.29413 2.2225 0)
			(unlocked yes)
			(layer "F.SilkS")
			(effects
				(font
					(size 0.7874 0.5842)
					(thickness 0.1524)
				)
				(justify left)
			)
		)
		(property "Value" ""
			(at 0 0 90)
			(layer "F.Fab")
			(effects
				(font
					(size 1.27 1.27)
				)
			)
		)
		(duplicate_pad_numbers_are_jumpers no)
		(fp_line
			(start 1.905 -1.651)
			(end 1.905 1.651)
			(stroke
				(width 0.1524)
				(type default)
			)
			(layer "F.SilkS")
		)
		(fp_line
			(start -1.905 -1.651)
			(end 1.905 -1.651)
			(stroke
				(width 0.1524)
				(type default)
			)
			(layer "F.SilkS")
		)
		(fp_line
			(start 1.905 1.651)
			(end -1.905 1.651)
			(stroke
				(width 0.1524)
				(type default)
			)
			(layer "F.SilkS")
		)
		(fp_line
			(start -1.905 1.651)
			(end -1.905 -1.651)
			(stroke
				(width 0.1524)
				(type default)
			)
			(layer "F.SilkS")
		)
		(fp_line
			(start 0.6985 -1.524)
			(end 0.6985 -0.219964)
			(stroke
				(width 0.1)
				(type default)
			)
			(layer "F.Fab")
		)
		(fp_line
			(start -0.649986 -1.524)
			(end 0.6985 -1.524)
			(stroke
				(width 0.1)
				(type default)
			)
			(layer "F.Fab")
		)
		(fp_line
			(start -0.649986 -1.169924)
			(end -0.649986 -1.524)
			(stroke
				(width 0.1)
				(type default)
			)
			(layer "F.Fab")
		)
		(fp_line
			(start -1.249934 -1.169924)
			(end -0.649986 -1.169924)
			(stroke
				(width 0.1)
				(type default)
			)
			(layer "F.Fab")
		)
		(fp_line
			(start -0.6985 -0.729996)
			(end -1.249934 -0.729996)
			(stroke
				(width 0.1)
				(type default)
			)
			(layer "F.Fab")
		)
		(fp_line
			(start -1.249934 -0.729996)
			(end -1.249934 -1.169924)
			(stroke
				(width 0.1)
				(type default)
			)
			(layer "F.Fab")
		)
		(fp_line
			(start 1.249934 -0.219964)
			(end 1.249934 0.219964)
			(stroke
				(width 0.1)
				(type default)
			)
			(layer "F.Fab")
		)
		(fp_line
			(start 0.6985 -0.219964)
			(end 1.249934 -0.219964)
			(stroke
				(width 0.1)
				(type default)
			)
			(layer "F.Fab")
		)
		(fp_line
			(start 1.249934 0.219964)
			(end 0.6985 0.219964)
			(stroke
				(width 0.1)
				(type default)
			)
			(layer "F.Fab")
		)
		(fp_line
			(start 0.6985 0.219964)
			(end 0.6985 1.524)
			(stroke
				(width 0.1)
				(type default)
			)
			(layer "F.Fab")
		)
		(fp_line
			(start -0.6985 0.729996)
			(end -0.6985 -0.729996)
			(stroke
				(width 0.1)
				(type default)
			)
			(layer "F.Fab")
		)
		(fp_line
			(start -1.249934 0.729996)
			(end -0.6985 0.729996)
			(stroke
				(width 0.1)
				(type default)
			)
			(layer "F.Fab")
		)
		(fp_line
			(start -0.649986 1.169924)
			(end -1.249934 1.169924)
			(stroke
				(width 0.1)
				(type default)
			)
			(layer "F.Fab")
		)
		(fp_line
			(start -1.249934 1.169924)
			(end -1.249934 0.729996)
			(stroke
				(width 0.1)
				(type default)
			)
			(layer "F.Fab")
		)
		(fp_line
			(start 0.6985 1.524)
			(end -0.649986 1.524)
			(stroke
				(width 0.1)
				(type default)
			)
			(layer "F.Fab")
		)
		(fp_line
			(start -0.649986 1.524)
			(end -0.649986 1.169924)
			(stroke
				(width 0.1)
				(type default)
			)
			(layer "F.Fab")
		)
		(pad "B" smd rect
			(at -1.1176 -1.016)
			(size 1.016 1.27)
			(layers "F.Cu" "F.Mask" "F.Paste")
			(net "BJT_Q3_B")
		)
		(pad "C" smd rect
			(at 1.1176 0)
			(size 1.016 1.27)
			(layers "F.Cu" "F.Mask" "F.Paste")
			(net "BJT_Q3_C")
		)
		(pad "E" smd rect
			(at -1.1176 1.016)
			(size 1.016 1.27)
			(layers "F.Cu" "F.Mask" "F.Paste")
			(net "GND")
		)
	)
	(footprint ""
		(layer "F.Cu")
		(at 8.955024 -39.94531 -90)
		(property "Reference" "PL34"
			(at 5.50037 6.228334 90)
			(unlocked yes)
			(layer "F.SilkS")
			(effects
				(font
					(size 0.7874 0.5842)
					(thickness 0.1524)
				)
				(justify left)
			)
		)
		(property "Value" ""
			(at 0 0 270)
			(layer "F.Fab")
			(effects
				(font
					(size 1.27 1.27)
				)
			)
		)
		(duplicate_pad_numbers_are_jumpers no)
		(fp_line
			(start -5.588 5.150104)
			(end 5.588 5.150104)
			(stroke
				(width 0.1524)
				(type default)
			)
			(layer "F.SilkS")
		)
		(fp_line
			(start 5.588 5.150104)
			(end 5.588 1.8034)
			(stroke
				(width 0.1524)
				(type default)
			)
			(layer "F.SilkS")
		)
		(fp_line
			(start -5.588 1.8288)
			(end -5.588 5.150104)
			(stroke
				(width 0.1524)
				(type default)
			)
			(layer "F.SilkS")
		)
		(fp_line
			(start 5.588 -1.8288)
			(end 5.588 -5.150104)
			(stroke
				(width 0.1524)
				(type default)
			)
			(layer "F.SilkS")
		)
		(fp_line
			(start -5.588 -5.150104)
			(end -5.588 -1.8542)
			(stroke
				(width 0.1524)
				(type default)
			)
			(layer "F.SilkS")
		)
		(fp_line
			(start 5.588 -5.150104)
			(end -5.588 -5.150104)
			(stroke
				(width 0.1524)
				(type default)
			)
			(layer "F.SilkS")
		)
		(fp_line
			(start -5.599938 5.150104)
			(end -5.599938 -5.150104)
			(stroke
				(width 0.1)
				(type default)
			)
			(layer "F.Fab")
		)
		(fp_line
			(start 5.599938 5.150104)
			(end -5.599938 5.150104)
			(stroke
				(width 0.1)
				(type default)
			)
			(layer "F.Fab")
		)
		(fp_line
			(start -5.599938 -5.150104)
			(end 5.599938 -5.150104)
			(stroke
				(width 0.1)
				(type default)
			)
			(layer "F.Fab")
		)
		(fp_line
			(start 5.599938 -5.150104)
			(end 5.599938 5.150104)
			(stroke
				(width 0.1)
				(type default)
			)
			(layer "F.Fab")
		)
		(pad "1" smd rect
			(at -4.338828 0 270)
			(size 3.302 3.302)
			(layers "F.Cu" "F.Mask" "F.Paste")
			(net "SW_P5V_AUX_SW")
		)
		(pad "2" smd rect
			(at 4.338828 0 270)
			(size 3.302 3.302)
			(layers "F.Cu" "F.Mask" "F.Paste")
			(net "P5V_AUX")
		)
	)
	(footprint ""
		(layer "F.Cu")
		(at 65.913 -17.653 180)
		(property "Reference" "J13"
			(at -1.651 -1.04267 0)
			(unlocked yes)
			(layer "F.SilkS")
			(effects
				(font
					(size 0.7874 0.5842)
					(thickness 0.1524)
				)
				(justify left)
			)
		)
		(property "Value" ""
			(at 0 0 180)
			(layer "F.Fab")
			(effects
				(font
					(size 1.27 1.27)
				)
			)
		)
		(duplicate_pad_numbers_are_jumpers no)
		(fp_line
			(start 1.249934 3.860038)
			(end 1.249934 0.6477)
			(stroke
				(width 0.1524)
				(type default)
			)
			(layer "F.SilkS")
		)
		(fp_line
			(start 1.249934 -0.6477)
			(end 1.249934 -3.860038)
			(stroke
				(width 0.1524)
				(type default)
			)
			(layer "F.SilkS")
		)
		(fp_line
			(start 1.249934 -3.860038)
			(end -1.249934 -3.860038)
			(stroke
				(width 0.1524)
				(type default)
			)
			(layer "F.SilkS")
		)
		(fp_line
			(start -1.249934 3.860038)
			(end 1.249934 3.860038)
			(stroke
				(width 0.1524)
				(type default)
			)
			(layer "F.SilkS")
		)
		(fp_line
			(start -1.249934 3.1877)
			(end -1.249934 3.860038)
			(stroke
				(width 0.1524)
				(type default)
			)
			(layer "F.SilkS")
		)
		(fp_line
			(start -1.249934 -1.8923)
			(end -1.249934 1.8923)
			(stroke
				(width 0.1524)
				(type default)
			)
			(layer "F.SilkS")
		)
		(fp_line
			(start -1.249934 -3.860038)
			(end -1.249934 -3.1877)
			(stroke
				(width 0.1524)
				(type default)
			)
			(layer "F.SilkS")
		)
		(fp_poly
			(pts
				(xy -4.2164 -3.048) (xy -3.2004 -2.54) (xy -4.2164 -2.032)
			)
			(stroke
				(width 0)
				(type default)
			)
			(fill yes)
			(layer "F.SilkS")
		)
		(fp_line
			(start 1.249934 3.860038)
			(end 1.249934 -3.860038)
			(stroke
				(width 0.1)
				(type default)
			)
			(layer "F.Fab")
		)
		(fp_line
			(start 1.249934 -3.860038)
			(end -1.249934 -3.860038)
			(stroke
				(width 0.1)
				(type default)
			)
			(layer "F.Fab")
		)
		(fp_line
			(start -1.249934 3.860038)
			(end 1.249934 3.860038)
			(stroke
				(width 0.1)
				(type default)
			)
			(layer "F.Fab")
		)
		(fp_line
			(start -1.249934 -3.860038)
			(end -1.249934 3.860038)
			(stroke
				(width 0.1)
				(type default)
			)
			(layer "F.Fab")
		)
		(fp_poly
			(pts
				(xy -4.2164 -3.048) (xy -3.2004 -2.54) (xy -4.2164 -2.032)
			)
			(stroke
				(width 0)
				(type default)
			)
			(fill yes)
			(layer "F.Fab")
		)
		(pad "1" smd rect
			(at -1.374902 -2.54 90)
			(size 1.016 2.7686)
			(layers "F.Cu" "F.Mask" "F.Paste")
			(net "PU_J13_P1")
		)
		(pad "2" smd rect
			(at 1.374902 0 90)
			(size 1.016 2.7686)
			(layers "F.Cu" "F.Mask" "F.Paste")
			(net "FM_DBG_SW_N")
		)
		(pad "3" smd rect
			(at -1.374902 2.54 90)
			(size 1.016 2.7686)
			(layers "F.Cu" "F.Mask" "F.Paste")
			(net "GND")
		)
	)
	(footprint ""
		(layer "F.Cu")
		(at 12.319 -94.488 180)
		(property "Reference" "R536"
			(at 0 0 180)
			(layer "F.SilkS")
			(hide yes)
			(effects
				(font
					(size 1.27 1.27)
				)
			)
		)
		(property "Value" ""
			(at 0 0 180)
			(layer "F.Fab")
			(effects
				(font
					(size 1.27 1.27)
				)
			)
		)
		(duplicate_pad_numbers_are_jumpers no)
		(fp_line
			(start 0.7874 0.4064)
			(end -0.7874 0.4064)
			(stroke
				(width 0.1524)
				(type default)
			)
			(layer "F.SilkS")
		)
		(fp_line
			(start 0.7874 -0.4064)
			(end 0.7874 0.4064)
			(stroke
				(width 0.1524)
				(type default)
			)
			(layer "F.SilkS")
		)
		(fp_line
			(start -0.7874 0.4064)
			(end -0.7874 -0.4064)
			(stroke
				(width 0.1524)
				(type default)
			)
			(layer "F.SilkS")
		)
		(fp_line
			(start -0.7874 -0.4064)
			(end 0.7874 -0.4064)
			(stroke
				(width 0.1524)
				(type default)
			)
			(layer "F.SilkS")
		)
		(fp_line
			(start 0.67945 0.3048)
			(end 0.120396 0.3048)
			(stroke
				(width 0.1)
				(type default)
			)
			(layer "F.Fab")
		)
		(fp_line
			(start 0.67945 -0.3048)
			(end 0.67945 0.3048)
			(stroke
				(width 0.1)
				(type default)
			)
			(layer "F.Fab")
		)
		(fp_line
			(start 0.12065 -0.2794)
			(end 0.12065 -0.3048)
			(stroke
				(width 0.1)
				(type default)
			)
			(layer "F.Fab")
		)
		(fp_line
			(start 0.12065 -0.3048)
			(end 0.67945 -0.3048)
			(stroke
				(width 0.1)
				(type default)
			)
			(layer "F.Fab")
		)
		(fp_line
			(start 0.120396 0.3048)
			(end 0.120396 0.2794)
			(stroke
				(width 0.1)
				(type default)
			)
			(layer "F.Fab")
		)
		(fp_line
			(start 0.120396 0.2794)
			(end -0.12065 0.2794)
			(stroke
				(width 0.1)
				(type default)
			)
			(layer "F.Fab")
		)
		(fp_line
			(start -0.12065 0.3048)
			(end -0.67945 0.3048)
			(stroke
				(width 0.1)
				(type default)
			)
			(layer "F.Fab")
		)
		(fp_line
			(start -0.12065 0.2794)
			(end -0.12065 0.3048)
			(stroke
				(width 0.1)
				(type default)
			)
			(layer "F.Fab")
		)
		(fp_line
			(start -0.12065 -0.2794)
			(end 0.12065 -0.2794)
			(stroke
				(width 0.1)
				(type default)
			)
			(layer "F.Fab")
		)
		(fp_line
			(start -0.12065 -0.305054)
			(end -0.12065 -0.2794)
			(stroke
				(width 0.1)
				(type default)
			)
			(layer "F.Fab")
		)
		(fp_line
			(start -0.67945 0.3048)
			(end -0.67945 -0.305054)
			(stroke
				(width 0.1)
				(type default)
			)
			(layer "F.Fab")
		)
		(fp_line
			(start -0.67945 -0.305054)
			(end -0.12065 -0.305054)
			(stroke
				(width 0.1)
				(type default)
			)
			(layer "F.Fab")
		)
		(pad "1" smd circle
			(at -0.40005 0 180)
			(size 0 0)
			(layers "F.Cu" "F.Mask" "F.Paste")
			(net "BMC_CPLD_GPIO_12_R2")
		)
		(pad "2" smd circle
			(at 0.40005 0 180)
			(size 0 0)
			(layers "F.Cu" "F.Mask" "F.Paste")
			(net "BMC_CPLD_GPIO_12")
		)
	)
	(footprint ""
		(layer "F.Cu")
		(at 77.281786 -27.738832 90)
		(property "Reference" "D1"
			(at -1.780032 7.911084 90)
			(unlocked yes)
			(layer "F.SilkS")
			(effects
				(font
					(size 0.7874 0.5842)
					(thickness 0.1524)
				)
				(justify left)
			)
		)
		(property "Value" ""
			(at 0 0 90)
			(layer "F.Fab")
			(effects
				(font
					(size 1.27 1.27)
				)
			)
		)
		(duplicate_pad_numbers_are_jumpers no)
		(fp_line
			(start 1.778 -0.5588)
			(end 1.3208 -0.5588)
			(stroke
				(width 0.1524)
				(type default)
			)
			(layer "F.SilkS")
		)
		(fp_line
			(start 1.778 -0.5588)
			(end 1.778 0.5588)
			(stroke
				(width 0.1524)
				(type default)
			)
			(layer "F.SilkS")
		)
		(fp_line
			(start 1.4732 -0.5588)
			(end 1.4732 0.5588)
			(stroke
				(width 0.1524)
				(type default)
			)
			(layer "F.SilkS")
		)
		(fp_line
			(start 1.3208 -0.5588)
			(end 1.3208 0.5588)
			(stroke
				(width 0.1524)
				(type default)
			)
			(layer "F.SilkS")
		)
		(fp_line
			(start -1.3208 -0.5588)
			(end 1.3208 -0.5588)
			(stroke
				(width 0.1524)
				(type default)
			)
			(layer "F.SilkS")
		)
		(fp_line
			(start 1.778 0.5588)
			(end 1.3208 0.5588)
			(stroke
				(width 0.1524)
				(type default)
			)
			(layer "F.SilkS")
		)
		(fp_line
			(start 1.6256 0.5588)
			(end 1.6256 -0.5588)
			(stroke
				(width 0.1524)
				(type default)
			)
			(layer "F.SilkS")
		)
		(fp_line
			(start 1.3208 0.5588)
			(end -1.3208 0.5588)
			(stroke
				(width 0.1524)
				(type default)
			)
			(layer "F.SilkS")
		)
		(fp_line
			(start -1.3208 0.5588)
			(end -1.3208 -0.5588)
			(stroke
				(width 0.1524)
				(type default)
			)
			(layer "F.SilkS")
		)
		(fp_line
			(start 1.236726 -0.508)
			(end 1.1684 -0.508)
			(stroke
				(width 0.1)
				(type default)
			)
			(layer "F.Fab")
		)
		(fp_line
			(start 1.1684 -0.508)
			(end -1.1684 -0.508)
			(stroke
				(width 0.1)
				(type default)
			)
			(layer "F.Fab")
		)
		(fp_line
			(start -1.1684 -0.508)
			(end -1.235964 -0.508)
			(stroke
				(width 0.1)
				(type default)
			)
			(layer "F.Fab")
		)
		(fp_line
			(start -1.235964 -0.508)
			(end -1.235964 0.508)
			(stroke
				(width 0.1)
				(type default)
			)
			(layer "F.Fab")
		)
		(fp_line
			(start 1.236726 0.508)
			(end 1.236726 -0.508)
			(stroke
				(width 0.1)
				(type default)
			)
			(layer "F.Fab")
		)
		(fp_line
			(start 1.1684 0.508)
			(end 1.236726 0.508)
			(stroke
				(width 0.1)
				(type default)
			)
			(layer "F.Fab")
		)
		(fp_line
			(start -1.1684 0.508)
			(end 1.1684 0.508)
			(stroke
				(width 0.1)
				(type default)
			)
			(layer "F.Fab")
		)
		(fp_line
			(start -1.235964 0.508)
			(end -1.1684 0.508)
			(stroke
				(width 0.1)
				(type default)
			)
			(layer "F.Fab")
		)
		(fp_text user "+"
			(at -2.669032 -0.186436 90)
			(unlocked yes)
			(layer "F.SilkS")
			(effects
				(font
					(size 1.905 1.4224)
					(thickness 0.1524)
				)
				(justify left)
			)
		)
		(fp_text user "-"
			(at 0.675386 0.592582 90)
			(unlocked yes)
			(layer "F.SilkS")
			(effects
				(font
					(size 1.905 1.4224)
					(thickness 0.1524)
				)
				(justify left)
			)
		)
		(fp_text user "-"
			(at 1.524 -0.24765 90)
			(unlocked yes)
			(layer "F.Fab")
			(effects
				(font
					(size 1.905 1.4224)
					(thickness 0.1524)
				)
				(justify left)
			)
		)
		(fp_text user "+"
			(at -2.5654 -0.24765 90)
			(unlocked yes)
			(layer "F.Fab")
			(effects
				(font
					(size 1.905 1.4224)
					(thickness 0.1524)
				)
				(justify left)
			)
		)
		(pad "A" smd rect
			(at -0.750062 0 90)
			(size 0.8128 0.8128)
			(layers "F.Cu" "F.Mask" "F.Paste")
			(net "LED_POSTCODE_1_R")
		)
		(pad "C" smd rect
			(at 0.750062 0 90)
			(size 0.8128 0.8128)
			(layers "F.Cu" "F.Mask" "F.Paste")
			(net "GND")
		)
	)
	(footprint ""
		(layer "F.Cu")
		(at 52.9082 -106.5784 180)
		(property "Reference" "R862"
			(at 0 0 180)
			(layer "F.SilkS")
			(hide yes)
			(effects
				(font
					(size 1.27 1.27)
				)
			)
		)
		(property "Value" ""
			(at 0 0 180)
			(layer "F.Fab")
			(effects
				(font
					(size 1.27 1.27)
				)
			)
		)
		(duplicate_pad_numbers_are_jumpers no)
		(fp_line
			(start 0.7874 0.4064)
			(end -0.7874 0.4064)
			(stroke
				(width 0.1524)
				(type default)
			)
			(layer "F.SilkS")
		)
		(fp_line
			(start 0.7874 -0.4064)
			(end 0.7874 0.4064)
			(stroke
				(width 0.1524)
				(type default)
			)
			(layer "F.SilkS")
		)
		(fp_line
			(start -0.7874 0.4064)
			(end -0.7874 -0.4064)
			(stroke
				(width 0.1524)
				(type default)
			)
			(layer "F.SilkS")
		)
		(fp_line
			(start -0.7874 -0.4064)
			(end 0.7874 -0.4064)
			(stroke
				(width 0.1524)
				(type default)
			)
			(layer "F.SilkS")
		)
		(fp_line
			(start 0.67945 0.3048)
			(end 0.120396 0.3048)
			(stroke
				(width 0.1)
				(type default)
			)
			(layer "F.Fab")
		)
		(fp_line
			(start 0.67945 -0.3048)
			(end 0.67945 0.3048)
			(stroke
				(width 0.1)
				(type default)
			)
			(layer "F.Fab")
		)
		(fp_line
			(start 0.12065 -0.2794)
			(end 0.12065 -0.3048)
			(stroke
				(width 0.1)
				(type default)
			)
			(layer "F.Fab")
		)
		(fp_line
			(start 0.12065 -0.3048)
			(end 0.67945 -0.3048)
			(stroke
				(width 0.1)
				(type default)
			)
			(layer "F.Fab")
		)
		(fp_line
			(start 0.120396 0.3048)
			(end 0.120396 0.2794)
			(stroke
				(width 0.1)
				(type default)
			)
			(layer "F.Fab")
		)
		(fp_line
			(start 0.120396 0.2794)
			(end -0.12065 0.2794)
			(stroke
				(width 0.1)
				(type default)
			)
			(layer "F.Fab")
		)
		(fp_line
			(start -0.12065 0.3048)
			(end -0.67945 0.3048)
			(stroke
				(width 0.1)
				(type default)
			)
			(layer "F.Fab")
		)
		(fp_line
			(start -0.12065 0.2794)
			(end -0.12065 0.3048)
			(stroke
				(width 0.1)
				(type default)
			)
			(layer "F.Fab")
		)
		(fp_line
			(start -0.12065 -0.2794)
			(end 0.12065 -0.2794)
			(stroke
				(width 0.1)
				(type default)
			)
			(layer "F.Fab")
		)
		(fp_line
			(start -0.12065 -0.305054)
			(end -0.12065 -0.2794)
			(stroke
				(width 0.1)
				(type default)
			)
			(layer "F.Fab")
		)
		(fp_line
			(start -0.67945 0.3048)
			(end -0.67945 -0.305054)
			(stroke
				(width 0.1)
				(type default)
			)
			(layer "F.Fab")
		)
		(fp_line
			(start -0.67945 -0.305054)
			(end -0.12065 -0.305054)
			(stroke
				(width 0.1)
				(type default)
			)
			(layer "F.Fab")
		)
		(pad "1" smd circle
			(at -0.40005 0 180)
			(size 0 0)
			(layers "F.Cu" "F.Mask" "F.Paste")
			(net "SPI_SYS_WP_R_IO2")
		)
		(pad "2" smd circle
			(at 0.40005 0 180)
			(size 0 0)
			(layers "F.Cu" "F.Mask" "F.Paste")
			(net "SPI_SYS_MUX_WP_IO2")
		)
	)
	(footprint ""
		(layer "F.Cu")
		(at 45.212 -26.8732 90)
		(property "Reference" "R395"
			(at 0 0 90)
			(layer "F.SilkS")
			(hide yes)
			(effects
				(font
					(size 1.27 1.27)
				)
			)
		)
		(property "Value" ""
			(at 0 0 90)
			(layer "F.Fab")
			(effects
				(font
					(size 1.27 1.27)
				)
			)
		)
		(duplicate_pad_numbers_are_jumpers no)
		(fp_line
			(start 0.7874 -0.4064)
			(end 0.7874 0.4064)
			(stroke
				(width 0.1524)
				(type default)
			)
			(layer "F.SilkS")
		)
		(fp_line
			(start -0.7874 -0.4064)
			(end 0.7874 -0.4064)
			(stroke
				(width 0.1524)
				(type default)
			)
			(layer "F.SilkS")
		)
		(fp_line
			(start 0.7874 0.4064)
			(end -0.7874 0.4064)
			(stroke
				(width 0.1524)
				(type default)
			)
			(layer "F.SilkS")
		)
		(fp_line
			(start -0.7874 0.4064)
			(end -0.7874 -0.4064)
			(stroke
				(width 0.1524)
				(type default)
			)
			(layer "F.SilkS")
		)
		(fp_line
			(start -0.12065 -0.305054)
			(end -0.12065 -0.2794)
			(stroke
				(width 0.1)
				(type default)
			)
			(layer "F.Fab")
		)
		(fp_line
			(start -0.67945 -0.305054)
			(end -0.12065 -0.305054)
			(stroke
				(width 0.1)
				(type default)
			)
			(layer "F.Fab")
		)
		(fp_line
			(start 0.67945 -0.3048)
			(end 0.67945 0.3048)
			(stroke
				(width 0.1)
				(type default)
			)
			(layer "F.Fab")
		)
		(fp_line
			(start 0.12065 -0.3048)
			(end 0.67945 -0.3048)
			(stroke
				(width 0.1)
				(type default)
			)
			(layer "F.Fab")
		)
		(fp_line
			(start 0.12065 -0.2794)
			(end 0.12065 -0.3048)
			(stroke
				(width 0.1)
				(type default)
			)
			(layer "F.Fab")
		)
		(fp_line
			(start -0.12065 -0.2794)
			(end 0.12065 -0.2794)
			(stroke
				(width 0.1)
				(type default)
			)
			(layer "F.Fab")
		)
		(fp_line
			(start 0.120396 0.2794)
			(end -0.12065 0.2794)
			(stroke
				(width 0.1)
				(type default)
			)
			(layer "F.Fab")
		)
		(fp_line
			(start -0.12065 0.2794)
			(end -0.12065 0.3048)
			(stroke
				(width 0.1)
				(type default)
			)
			(layer "F.Fab")
		)
		(fp_line
			(start 0.67945 0.3048)
			(end 0.120396 0.3048)
			(stroke
				(width 0.1)
				(type default)
			)
			(layer "F.Fab")
		)
		(fp_line
			(start 0.120396 0.3048)
			(end 0.120396 0.2794)
			(stroke
				(width 0.1)
				(type default)
			)
			(layer "F.Fab")
		)
		(fp_line
			(start -0.12065 0.3048)
			(end -0.67945 0.3048)
			(stroke
				(width 0.1)
				(type default)
			)
			(layer "F.Fab")
		)
		(fp_line
			(start -0.67945 0.3048)
			(end -0.67945 -0.305054)
			(stroke
				(width 0.1)
				(type default)
			)
			(layer "F.Fab")
		)
		(pad "1" smd circle
			(at -0.40005 0 90)
			(size 0 0)
			(layers "F.Cu" "F.Mask" "F.Paste")
			(net "PWRGD_P1V0_AUX_DELAY_R")
		)
		(pad "2" smd circle
			(at 0.40005 0 90)
			(size 0 0)
			(layers "F.Cu" "F.Mask" "F.Paste")
			(net "PWRGD_P1V0_AUX_DELAY")
		)
	)
	(footprint ""
		(layer "F.Cu")
		(at 45.5676 -69.2912)
		(property "Reference" "R805"
			(at 0 0 0)
			(layer "F.SilkS")
			(hide yes)
			(effects
				(font
					(size 1.27 1.27)
				)
			)
		)
		(property "Value" ""
			(at 0 0 0)
			(layer "F.Fab")
			(effects
				(font
					(size 1.27 1.27)
				)
			)
		)
		(duplicate_pad_numbers_are_jumpers no)
		(fp_line
			(start -0.7874 -0.4064)
			(end 0.7874 -0.4064)
			(stroke
				(width 0.1524)
				(type default)
			)
			(layer "F.SilkS")
		)
		(fp_line
			(start -0.7874 0.4064)
			(end -0.7874 -0.4064)
			(stroke
				(width 0.1524)
				(type default)
			)
			(layer "F.SilkS")
		)
		(fp_line
			(start 0.7874 -0.4064)
			(end 0.7874 0.4064)
			(stroke
				(width 0.1524)
				(type default)
			)
			(layer "F.SilkS")
		)
		(fp_line
			(start 0.7874 0.4064)
			(end -0.7874 0.4064)
			(stroke
				(width 0.1524)
				(type default)
			)
			(layer "F.SilkS")
		)
		(fp_line
			(start -0.67945 -0.305054)
			(end -0.12065 -0.305054)
			(stroke
				(width 0.1)
				(type default)
			)
			(layer "F.Fab")
		)
		(fp_line
			(start -0.67945 0.3048)
			(end -0.67945 -0.305054)
			(stroke
				(width 0.1)
				(type default)
			)
			(layer "F.Fab")
		)
		(fp_line
			(start -0.12065 -0.305054)
			(end -0.12065 -0.2794)
			(stroke
				(width 0.1)
				(type default)
			)
			(layer "F.Fab")
		)
		(fp_line
			(start -0.12065 -0.2794)
			(end 0.12065 -0.2794)
			(stroke
				(width 0.1)
				(type default)
			)
			(layer "F.Fab")
		)
		(fp_line
			(start -0.12065 0.2794)
			(end -0.12065 0.3048)
			(stroke
				(width 0.1)
				(type default)
			)
			(layer "F.Fab")
		)
		(fp_line
			(start -0.12065 0.3048)
			(end -0.67945 0.3048)
			(stroke
				(width 0.1)
				(type default)
			)
			(layer "F.Fab")
		)
		(fp_line
			(start 0.120396 0.2794)
			(end -0.12065 0.2794)
			(stroke
				(width 0.1)
				(type default)
			)
			(layer "F.Fab")
		)
		(fp_line
			(start 0.120396 0.3048)
			(end 0.120396 0.2794)
			(stroke
				(width 0.1)
				(type default)
			)
			(layer "F.Fab")
		)
		(fp_line
			(start 0.12065 -0.3048)
			(end 0.67945 -0.3048)
			(stroke
				(width 0.1)
				(type default)
			)
			(layer "F.Fab")
		)
		(fp_line
			(start 0.12065 -0.2794)
			(end 0.12065 -0.3048)
			(stroke
				(width 0.1)
				(type default)
			)
			(layer "F.Fab")
		)
		(fp_line
			(start 0.67945 -0.3048)
			(end 0.67945 0.3048)
			(stroke
				(width 0.1)
				(type default)
			)
			(layer "F.Fab")
		)
		(fp_line
			(start 0.67945 0.3048)
			(end 0.120396 0.3048)
			(stroke
				(width 0.1)
				(type default)
			)
			(layer "F.Fab")
		)
		(pad "1" smd circle
			(at -0.40005 0)
			(size 0 0)
			(layers "F.Cu" "F.Mask" "F.Paste")
			(net "P3V3_AUX")
		)
		(pad "2" smd circle
			(at 0.40005 0)
			(size 0 0)
			(layers "F.Cu" "F.Mask" "F.Paste")
			(net "BMC_HEARTBEAT_N")
		)
	)
	(footprint ""
		(layer "F.Cu")
		(at 63.373 -11.176)
		(property "Reference" "Q13"
			(at -1.4224 -1.768348 0)
			(unlocked yes)
			(layer "F.SilkS")
			(effects
				(font
					(size 0.7874 0.5842)
					(thickness 0.1524)
				)
				(justify left)
			)
		)
		(property "Value" ""
			(at 0 0 0)
			(layer "F.Fab")
			(effects
				(font
					(size 1.27 1.27)
				)
			)
		)
		(duplicate_pad_numbers_are_jumpers no)
		(fp_line
			(start -1.332738 -1.100074)
			(end -0.4826 -1.100074)
			(stroke
				(width 0.1524)
				(type default)
			)
			(layer "F.SilkS")
		)
		(fp_line
			(start -1.332738 1.100074)
			(end -1.332738 -1.100074)
			(stroke
				(width 0.1524)
				(type default)
			)
			(layer "F.SilkS")
		)
		(fp_line
			(start -0.4826 -1.100074)
			(end 0 -0.541274)
			(stroke
				(width 0.1524)
				(type default)
			)
			(layer "F.SilkS")
		)
		(fp_line
			(start 0 -0.541274)
			(end 0.4826 -1.100074)
			(stroke
				(width 0.1524)
				(type default)
			)
			(layer "F.SilkS")
		)
		(fp_line
			(start 0.4826 -1.100074)
			(end 1.332738 -1.100074)
			(stroke
				(width 0.1524)
				(type default)
			)
			(layer "F.SilkS")
		)
		(fp_line
			(start 1.332738 -1.100074)
			(end 1.332738 1.100074)
			(stroke
				(width 0.1524)
				(type default)
			)
			(layer "F.SilkS")
		)
		(fp_line
			(start 1.332738 1.100074)
			(end -1.332738 1.100074)
			(stroke
				(width 0.1524)
				(type default)
			)
			(layer "F.SilkS")
		)
		(fp_poly
			(pts
				(xy -2.2352 -0.298958) (xy -2.2352 -1.001014) (xy -1.533144 -0.649986)
			)
			(stroke
				(width 0)
				(type default)
			)
			(fill yes)
			(layer "F.SilkS")
		)
		(fp_line
			(start -0.674878 -1.100074)
			(end 0.674878 -1.100074)
			(stroke
				(width 0.1)
				(type default)
			)
			(layer "F.Fab")
		)
		(fp_line
			(start -0.674878 1.100074)
			(end -0.674878 -1.100074)
			(stroke
				(width 0.1)
				(type default)
			)
			(layer "F.Fab")
		)
		(fp_line
			(start 0.674878 -1.100074)
			(end 0.674878 1.100074)
			(stroke
				(width 0.1)
				(type default)
			)
			(layer "F.Fab")
		)
		(fp_line
			(start 0.674878 1.100074)
			(end -0.674878 1.100074)
			(stroke
				(width 0.1)
				(type default)
			)
			(layer "F.Fab")
		)
		(fp_poly
			(pts
				(xy -2.2352 -0.298958) (xy -2.2352 -1.001014) (xy -1.533144 -0.649986)
			)
			(stroke
				(width 0)
				(type default)
			)
			(fill yes)
			(layer "F.Fab")
		)
		(pad "1" smd rect
			(at -0.94996 -0.649986 90)
			(size 0.4318 0.508)
			(layers "F.Cu" "F.Mask" "F.Paste")
			(net "GND")
		)
		(pad "2" smd rect
			(at -0.94996 0 90)
			(size 0.4318 0.508)
			(layers "F.Cu" "F.Mask" "F.Paste")
			(net "PWRGD_P1V0_AUX_DELAY")
		)
		(pad "3" smd rect
			(at -0.94996 0.649986 90)
			(size 0.4318 0.508)
			(layers "F.Cu" "F.Mask" "F.Paste")
			(net "Net_30")
		)
		(pad "4" smd rect
			(at 0.94996 0.649986 90)
			(size 0.4318 0.508)
			(layers "F.Cu" "F.Mask" "F.Paste")
			(net "Net_32")
		)
		(pad "5" smd rect
			(at 0.94996 0 90)
			(size 0.4318 0.508)
			(layers "F.Cu" "F.Mask" "F.Paste")
			(net "Net_31")
		)
		(pad "6" smd rect
			(at 0.94996 -0.649986 90)
			(size 0.4318 0.508)
			(layers "F.Cu" "F.Mask" "F.Paste")
			(net "LED_D22_R1")
		)
	)
	(footprint ""
		(layer "F.Cu")
		(at 35.031172 -83.816952 -90)
		(property "Reference" "R657"
			(at 0 0 270)
			(layer "F.SilkS")
			(hide yes)
			(effects
				(font
					(size 1.27 1.27)
				)
			)
		)
		(property "Value" ""
			(at 0 0 270)
			(layer "F.Fab")
			(effects
				(font
					(size 1.27 1.27)
				)
			)
		)
		(duplicate_pad_numbers_are_jumpers no)
		(fp_line
			(start -0.7874 0.4064)
			(end -0.7874 -0.4064)
			(stroke
				(width 0.1524)
				(type default)
			)
			(layer "F.SilkS")
		)
		(fp_line
			(start 0.7874 0.4064)
			(end -0.7874 0.4064)
			(stroke
				(width 0.1524)
				(type default)
			)
			(layer "F.SilkS")
		)
		(fp_line
			(start -0.7874 -0.4064)
			(end 0.7874 -0.4064)
			(stroke
				(width 0.1524)
				(type default)
			)
			(layer "F.SilkS")
		)
		(fp_line
			(start 0.7874 -0.4064)
			(end 0.7874 0.4064)
			(stroke
				(width 0.1524)
				(type default)
			)
			(layer "F.SilkS")
		)
		(fp_line
			(start -0.67945 0.3048)
			(end -0.67945 -0.305054)
			(stroke
				(width 0.1)
				(type default)
			)
			(layer "F.Fab")
		)
		(fp_line
			(start -0.12065 0.3048)
			(end -0.67945 0.3048)
			(stroke
				(width 0.1)
				(type default)
			)
			(layer "F.Fab")
		)
		(fp_line
			(start 0.120396 0.3048)
			(end 0.120396 0.2794)
			(stroke
				(width 0.1)
				(type default)
			)
			(layer "F.Fab")
		)
		(fp_line
			(start 0.67945 0.3048)
			(end 0.120396 0.3048)
			(stroke
				(width 0.1)
				(type default)
			)
			(layer "F.Fab")
		)
		(fp_line
			(start -0.12065 0.2794)
			(end -0.12065 0.3048)
			(stroke
				(width 0.1)
				(type default)
			)
			(layer "F.Fab")
		)
		(fp_line
			(start 0.120396 0.2794)
			(end -0.12065 0.2794)
			(stroke
				(width 0.1)
				(type default)
			)
			(layer "F.Fab")
		)
		(fp_line
			(start -0.12065 -0.2794)
			(end 0.12065 -0.2794)
			(stroke
				(width 0.1)
				(type default)
			)
			(layer "F.Fab")
		)
		(fp_line
			(start 0.12065 -0.2794)
			(end 0.12065 -0.3048)
			(stroke
				(width 0.1)
				(type default)
			)
			(layer "F.Fab")
		)
		(fp_line
			(start 0.12065 -0.3048)
			(end 0.67945 -0.3048)
			(stroke
				(width 0.1)
				(type default)
			)
			(layer "F.Fab")
		)
		(fp_line
			(start 0.67945 -0.3048)
			(end 0.67945 0.3048)
			(stroke
				(width 0.1)
				(type default)
			)
			(layer "F.Fab")
		)
		(fp_line
			(start -0.67945 -0.305054)
			(end -0.12065 -0.305054)
			(stroke
				(width 0.1)
				(type default)
			)
			(layer "F.Fab")
		)
		(fp_line
			(start -0.12065 -0.305054)
			(end -0.12065 -0.2794)
			(stroke
				(width 0.1)
				(type default)
			)
			(layer "F.Fab")
		)
		(pad "1" smd circle
			(at -0.40005 0 270)
			(size 0 0)
			(layers "F.Cu" "F.Mask" "F.Paste")
			(net "P3V3_AUX")
		)
		(pad "2" smd circle
			(at 0.40005 0 270)
			(size 0 0)
			(layers "F.Cu" "F.Mask" "F.Paste")
			(net "EMMC_DT2_R")
		)
	)
	(footprint ""
		(layer "F.Cu")
		(at 19.320002 -32.312356 -90)
		(property "Reference" "PU42"
			(at -0.174244 -3.007868 90)
			(unlocked yes)
			(layer "F.SilkS")
			(effects
				(font
					(size 0.7874 0.5842)
					(thickness 0.1524)
				)
				(justify left)
			)
		)
		(property "Value" ""
			(at 0 0 270)
			(layer "F.Fab")
			(effects
				(font
					(size 1.27 1.27)
				)
			)
		)
		(duplicate_pad_numbers_are_jumpers no)
		(fp_line
			(start -1.050036 1.549908)
			(end -1.016 1.549908)
			(stroke
				(width 0.1524)
				(type default)
			)
			(layer "F.SilkS")
		)
		(fp_line
			(start 1.016 1.549908)
			(end 1.050036 1.549908)
			(stroke
				(width 0.1524)
				(type default)
			)
			(layer "F.SilkS")
		)
		(fp_line
			(start 1.050036 1.549908)
			(end 1.050036 0.762)
			(stroke
				(width 0.1524)
				(type default)
			)
			(layer "F.SilkS")
		)
		(fp_line
			(start -1.050036 0.762)
			(end -1.050036 1.549908)
			(stroke
				(width 0.1524)
				(type default)
			)
			(layer "F.SilkS")
		)
		(fp_line
			(start -1.050036 -0.2286)
			(end -1.050036 0.2286)
			(stroke
				(width 0.1524)
				(type default)
			)
			(layer "F.SilkS")
		)
		(fp_line
			(start 1.050036 -0.762)
			(end 1.050036 -1.549908)
			(stroke
				(width 0.1524)
				(type default)
			)
			(layer "F.SilkS")
		)
		(fp_line
			(start -1.050036 -1.549908)
			(end -1.050036 -0.762)
			(stroke
				(width 0.1524)
				(type default)
			)
			(layer "F.SilkS")
		)
		(fp_line
			(start -1.016 -1.549908)
			(end -1.050036 -1.549908)
			(stroke
				(width 0.1524)
				(type default)
			)
			(layer "F.SilkS")
		)
		(fp_line
			(start 1.050036 -1.549908)
			(end 1.016 -1.549908)
			(stroke
				(width 0.1524)
				(type default)
			)
			(layer "F.SilkS")
		)
		(fp_poly
			(pts
				(xy -1.52908 -1.280668) (xy -1.373124 -0.813054) (xy -1.840484 -0.96901)
			)
			(stroke
				(width 0)
				(type default)
			)
			(fill yes)
			(layer "F.SilkS")
		)
		(fp_line
			(start -1.050036 1.549908)
			(end 1.050036 1.549908)
			(stroke
				(width 0.1)
				(type default)
			)
			(layer "F.Fab")
		)
		(fp_line
			(start 1.050036 1.549908)
			(end 1.050036 -1.549908)
			(stroke
				(width 0.1)
				(type default)
			)
			(layer "F.Fab")
		)
		(fp_line
			(start -1.050036 -1.549908)
			(end -1.050036 1.549908)
			(stroke
				(width 0.1)
				(type default)
			)
			(layer "F.Fab")
		)
		(fp_line
			(start 1.050036 -1.549908)
			(end -1.050036 -1.549908)
			(stroke
				(width 0.1)
				(type default)
			)
			(layer "F.Fab")
		)
		(fp_poly
			(pts
				(xy -1.851914 -0.720344) (xy -1.411224 -0.499872) (xy -1.851914 -0.279654)
			)
			(stroke
				(width 0)
				(type default)
			)
			(fill yes)
			(layer "F.Fab")
		)
		(pad "1" smd rect
			(at -0.54991 -0.499872)
			(size 0.254 1.4986)
			(layers "F.Cu" "F.Mask" "F.Paste")
			(net "SW_P1V0_AUX_FLT")
		)
		(pad "2" smd rect
			(at -0.54991 0.499872)
			(size 0.254 1.4986)
			(layers "F.Cu" "F.Mask" "F.Paste")
			(net "GND")
		)
		(pad "3" smd rect
			(at -0.750062 1.450086 270)
			(size 0.254 0.7112)
			(layers "F.Cu" "F.Mask" "F.Paste")
			(net "P1V0_AUX_VCC")
		)
		(pad "4" smd rect
			(at -0.249936 1.450086 270)
			(size 0.254 0.7112)
			(layers "F.Cu" "F.Mask" "F.Paste")
			(net "GND")
		)
		(pad "5" smd rect
			(at 0.249936 1.450086 270)
			(size 0.254 0.7112)
			(layers "F.Cu" "F.Mask" "F.Paste")
			(net "EN_P1V0_AUX_R")
		)
		(pad "6" smd rect
			(at 0.750062 1.450086 270)
			(size 0.254 0.7112)
			(layers "F.Cu" "F.Mask" "F.Paste")
			(net "P1V0_AUX_VCC")
		)
		(pad "7" smd rect
			(at 0.94996 0.499872)
			(size 0.254 0.7112)
			(layers "F.Cu" "F.Mask" "F.Paste")
			(net "P1V0_AUX_MODE")
		)
		(pad "8" smd rect
			(at 0.54991 0)
			(size 0.254 1.4986)
			(layers "F.Cu" "F.Mask" "F.Paste")
			(net "SW_P1V0_AUX_SW")
		)
		(pad "9" smd rect
			(at 0.94996 -0.499872)
			(size 0.254 0.7112)
			(layers "F.Cu" "F.Mask" "F.Paste")
			(net "SW_P1V0_AUX_BST")
		)
		(pad "10" smd rect
			(at 0.750062 -1.450086 270)
			(size 0.254 0.7112)
			(layers "F.Cu" "F.Mask" "F.Paste")
			(net "P1V0_AUX_VCC")
		)
		(pad "11" smd rect
			(at 0.249936 -1.450086 270)
			(size 0.254 0.7112)
			(layers "F.Cu" "F.Mask" "F.Paste")
			(net "GND")
		)
		(pad "12" smd rect
			(at -0.249936 -1.450086 270)
			(size 0.254 0.7112)
			(layers "F.Cu" "F.Mask" "F.Paste")
			(net "P1V0_AUX")
		)
		(pad "13" smd rect
			(at -0.750062 -1.450086 270)
			(size 0.254 0.7112)
			(layers "F.Cu" "F.Mask" "F.Paste")
			(net "PWRGD_P1V0_AUX_R")
		)
	)
	(footprint ""
		(layer "F.Cu")
		(at 17.5768 -46.3042 90)
		(property "Reference" "R827"
			(at 0 0 90)
			(layer "F.SilkS")
			(hide yes)
			(effects
				(font
					(size 1.27 1.27)
				)
			)
		)
		(property "Value" ""
			(at 0 0 90)
			(layer "F.Fab")
			(effects
				(font
					(size 1.27 1.27)
				)
			)
		)
		(duplicate_pad_numbers_are_jumpers no)
		(fp_line
			(start 0.7874 -0.4064)
			(end 0.7874 0.4064)
			(stroke
				(width 0.1524)
				(type default)
			)
			(layer "F.SilkS")
		)
		(fp_line
			(start -0.7874 -0.4064)
			(end 0.7874 -0.4064)
			(stroke
				(width 0.1524)
				(type default)
			)
			(layer "F.SilkS")
		)
		(fp_line
			(start 0.7874 0.4064)
			(end -0.7874 0.4064)
			(stroke
				(width 0.1524)
				(type default)
			)
			(layer "F.SilkS")
		)
		(fp_line
			(start -0.7874 0.4064)
			(end -0.7874 -0.4064)
			(stroke
				(width 0.1524)
				(type default)
			)
			(layer "F.SilkS")
		)
		(fp_line
			(start -0.12065 -0.305054)
			(end -0.12065 -0.2794)
			(stroke
				(width 0.1)
				(type default)
			)
			(layer "F.Fab")
		)
		(fp_line
			(start -0.67945 -0.305054)
			(end -0.12065 -0.305054)
			(stroke
				(width 0.1)
				(type default)
			)
			(layer "F.Fab")
		)
		(fp_line
			(start 0.67945 -0.3048)
			(end 0.67945 0.3048)
			(stroke
				(width 0.1)
				(type default)
			)
			(layer "F.Fab")
		)
		(fp_line
			(start 0.12065 -0.3048)
			(end 0.67945 -0.3048)
			(stroke
				(width 0.1)
				(type default)
			)
			(layer "F.Fab")
		)
		(fp_line
			(start 0.12065 -0.2794)
			(end 0.12065 -0.3048)
			(stroke
				(width 0.1)
				(type default)
			)
			(layer "F.Fab")
		)
		(fp_line
			(start -0.12065 -0.2794)
			(end 0.12065 -0.2794)
			(stroke
				(width 0.1)
				(type default)
			)
			(layer "F.Fab")
		)
		(fp_line
			(start 0.120396 0.2794)
			(end -0.12065 0.2794)
			(stroke
				(width 0.1)
				(type default)
			)
			(layer "F.Fab")
		)
		(fp_line
			(start -0.12065 0.2794)
			(end -0.12065 0.3048)
			(stroke
				(width 0.1)
				(type default)
			)
			(layer "F.Fab")
		)
		(fp_line
			(start 0.67945 0.3048)
			(end 0.120396 0.3048)
			(stroke
				(width 0.1)
				(type default)
			)
			(layer "F.Fab")
		)
		(fp_line
			(start 0.120396 0.3048)
			(end 0.120396 0.2794)
			(stroke
				(width 0.1)
				(type default)
			)
			(layer "F.Fab")
		)
		(fp_line
			(start -0.12065 0.3048)
			(end -0.67945 0.3048)
			(stroke
				(width 0.1)
				(type default)
			)
			(layer "F.Fab")
		)
		(fp_line
			(start -0.67945 0.3048)
			(end -0.67945 -0.305054)
			(stroke
				(width 0.1)
				(type default)
			)
			(layer "F.Fab")
		)
		(pad "1" smd circle
			(at -0.40005 0 90)
			(size 0 0)
			(layers "F.Cu" "F.Mask" "F.Paste")
			(net "RST_SPI_FLASH_BUF_R3_N")
		)
		(pad "2" smd circle
			(at 0.40005 0 90)
			(size 0 0)
			(layers "F.Cu" "F.Mask" "F.Paste")
			(net "RST_SPI_FLASH_BUF_N")
		)
	)
	(footprint ""
		(layer "F.Cu")
		(at 83.952842 -59.047634 -90)
		(property "Reference" "PC256"
			(at 0 0 270)
			(layer "F.SilkS")
			(hide yes)
			(effects
				(font
					(size 1.27 1.27)
				)
			)
		)
		(property "Value" ""
			(at 0 0 270)
			(layer "F.Fab")
			(effects
				(font
					(size 1.27 1.27)
				)
			)
		)
		(duplicate_pad_numbers_are_jumpers no)
		(fp_line
			(start -1.651 0.8382)
			(end -1.651 -0.8382)
			(stroke
				(width 0.1524)
				(type default)
			)
			(layer "F.SilkS")
		)
		(fp_line
			(start 0 0.8382)
			(end 0 -0.8382)
			(stroke
				(width 0.1524)
				(type default)
			)
			(layer "F.SilkS")
		)
		(fp_line
			(start 1.651 0.8382)
			(end -1.651 0.8382)
			(stroke
				(width 0.1524)
				(type default)
			)
			(layer "F.SilkS")
		)
		(fp_line
			(start -1.651 -0.8382)
			(end 1.651 -0.8382)
			(stroke
				(width 0.1524)
				(type default)
			)
			(layer "F.SilkS")
		)
		(fp_line
			(start 1.651 -0.8382)
			(end 1.651 0.8382)
			(stroke
				(width 0.1524)
				(type default)
			)
			(layer "F.SilkS")
		)
		(fp_line
			(start -1.55956 0.7366)
			(end -1.524 0.7366)
			(stroke
				(width 0.1)
				(type default)
			)
			(layer "F.Fab")
		)
		(fp_line
			(start -1.524 0.7366)
			(end 1.524 0.7366)
			(stroke
				(width 0.1)
				(type default)
			)
			(layer "F.Fab")
		)
		(fp_line
			(start 1.524 0.7366)
			(end 1.55956 0.7366)
			(stroke
				(width 0.1)
				(type default)
			)
			(layer "F.Fab")
		)
		(fp_line
			(start 1.55956 0.7366)
			(end 1.55956 -0.7366)
			(stroke
				(width 0.1)
				(type default)
			)
			(layer "F.Fab")
		)
		(fp_line
			(start -1.55956 -0.7366)
			(end -1.55956 0.7366)
			(stroke
				(width 0.1)
				(type default)
			)
			(layer "F.Fab")
		)
		(fp_line
			(start -1.524 -0.7366)
			(end -1.55956 -0.7366)
			(stroke
				(width 0.1)
				(type default)
			)
			(layer "F.Fab")
		)
		(fp_line
			(start 1.524 -0.7366)
			(end -1.524 -0.7366)
			(stroke
				(width 0.1)
				(type default)
			)
			(layer "F.Fab")
		)
		(fp_line
			(start 1.55956 -0.7366)
			(end 1.524 -0.7366)
			(stroke
				(width 0.1)
				(type default)
			)
			(layer "F.Fab")
		)
		(pad "1" smd rect
			(at -0.94996 0 90)
			(size 1.1176 1.3716)
			(layers "F.Cu" "F.Mask" "F.Paste")
			(net "P1V2_AUX")
		)
		(pad "2" smd rect
			(at 0.94996 0 90)
			(size 1.1176 1.3716)
			(layers "F.Cu" "F.Mask" "F.Paste")
			(net "GND")
		)
	)
	(footprint ""
		(layer "F.Cu")
		(at 56.20004 -79.21244 90)
		(property "Reference" "R560"
			(at 0 0 90)
			(layer "F.SilkS")
			(hide yes)
			(effects
				(font
					(size 1.27 1.27)
				)
			)
		)
		(property "Value" ""
			(at 0 0 90)
			(layer "F.Fab")
			(effects
				(font
					(size 1.27 1.27)
				)
			)
		)
		(duplicate_pad_numbers_are_jumpers no)
		(fp_line
			(start 0.7874 -0.4064)
			(end 0.7874 0.4064)
			(stroke
				(width 0.1524)
				(type default)
			)
			(layer "F.SilkS")
		)
		(fp_line
			(start -0.7874 -0.4064)
			(end 0.7874 -0.4064)
			(stroke
				(width 0.1524)
				(type default)
			)
			(layer "F.SilkS")
		)
		(fp_line
			(start 0.7874 0.4064)
			(end -0.7874 0.4064)
			(stroke
				(width 0.1524)
				(type default)
			)
			(layer "F.SilkS")
		)
		(fp_line
			(start -0.7874 0.4064)
			(end -0.7874 -0.4064)
			(stroke
				(width 0.1524)
				(type default)
			)
			(layer "F.SilkS")
		)
		(fp_line
			(start -0.12065 -0.305054)
			(end -0.12065 -0.2794)
			(stroke
				(width 0.1)
				(type default)
			)
			(layer "F.Fab")
		)
		(fp_line
			(start -0.67945 -0.305054)
			(end -0.12065 -0.305054)
			(stroke
				(width 0.1)
				(type default)
			)
			(layer "F.Fab")
		)
		(fp_line
			(start 0.67945 -0.3048)
			(end 0.67945 0.3048)
			(stroke
				(width 0.1)
				(type default)
			)
			(layer "F.Fab")
		)
		(fp_line
			(start 0.12065 -0.3048)
			(end 0.67945 -0.3048)
			(stroke
				(width 0.1)
				(type default)
			)
			(layer "F.Fab")
		)
		(fp_line
			(start 0.12065 -0.2794)
			(end 0.12065 -0.3048)
			(stroke
				(width 0.1)
				(type default)
			)
			(layer "F.Fab")
		)
		(fp_line
			(start -0.12065 -0.2794)
			(end 0.12065 -0.2794)
			(stroke
				(width 0.1)
				(type default)
			)
			(layer "F.Fab")
		)
		(fp_line
			(start 0.120396 0.2794)
			(end -0.12065 0.2794)
			(stroke
				(width 0.1)
				(type default)
			)
			(layer "F.Fab")
		)
		(fp_line
			(start -0.12065 0.2794)
			(end -0.12065 0.3048)
			(stroke
				(width 0.1)
				(type default)
			)
			(layer "F.Fab")
		)
		(fp_line
			(start 0.67945 0.3048)
			(end 0.120396 0.3048)
			(stroke
				(width 0.1)
				(type default)
			)
			(layer "F.Fab")
		)
		(fp_line
			(start 0.120396 0.3048)
			(end 0.120396 0.2794)
			(stroke
				(width 0.1)
				(type default)
			)
			(layer "F.Fab")
		)
		(fp_line
			(start -0.12065 0.3048)
			(end -0.67945 0.3048)
			(stroke
				(width 0.1)
				(type default)
			)
			(layer "F.Fab")
		)
		(fp_line
			(start -0.67945 0.3048)
			(end -0.67945 -0.305054)
			(stroke
				(width 0.1)
				(type default)
			)
			(layer "F.Fab")
		)
		(pad "1" smd circle
			(at -0.40005 0 90)
			(size 0 0)
			(layers "F.Cu" "F.Mask" "F.Paste")
			(net "FLASH_LATCH_Q_N_R1")
		)
		(pad "2" smd circle
			(at 0.40005 0 90)
			(size 0 0)
			(layers "F.Cu" "F.Mask" "F.Paste")
			(net "FLASH_LATCH_Q_N_R2")
		)
	)
	(footprint ""
		(layer "F.Cu")
		(at 30.607 -10.287 90)
		(property "Reference" "R43"
			(at 0 0 90)
			(layer "F.SilkS")
			(hide yes)
			(effects
				(font
					(size 1.27 1.27)
				)
			)
		)
		(property "Value" ""
			(at 0 0 90)
			(layer "F.Fab")
			(effects
				(font
					(size 1.27 1.27)
				)
			)
		)
		(duplicate_pad_numbers_are_jumpers no)
		(fp_line
			(start 0.7874 -0.4064)
			(end 0.7874 0.4064)
			(stroke
				(width 0.1524)
				(type default)
			)
			(layer "F.SilkS")
		)
		(fp_line
			(start -0.7874 -0.4064)
			(end 0.7874 -0.4064)
			(stroke
				(width 0.1524)
				(type default)
			)
			(layer "F.SilkS")
		)
		(fp_line
			(start 0.7874 0.4064)
			(end -0.7874 0.4064)
			(stroke
				(width 0.1524)
				(type default)
			)
			(layer "F.SilkS")
		)
		(fp_line
			(start -0.7874 0.4064)
			(end -0.7874 -0.4064)
			(stroke
				(width 0.1524)
				(type default)
			)
			(layer "F.SilkS")
		)
		(fp_line
			(start -0.12065 -0.305054)
			(end -0.12065 -0.2794)
			(stroke
				(width 0.1)
				(type default)
			)
			(layer "F.Fab")
		)
		(fp_line
			(start -0.67945 -0.305054)
			(end -0.12065 -0.305054)
			(stroke
				(width 0.1)
				(type default)
			)
			(layer "F.Fab")
		)
		(fp_line
			(start 0.67945 -0.3048)
			(end 0.67945 0.3048)
			(stroke
				(width 0.1)
				(type default)
			)
			(layer "F.Fab")
		)
		(fp_line
			(start 0.12065 -0.3048)
			(end 0.67945 -0.3048)
			(stroke
				(width 0.1)
				(type default)
			)
			(layer "F.Fab")
		)
		(fp_line
			(start 0.12065 -0.2794)
			(end 0.12065 -0.3048)
			(stroke
				(width 0.1)
				(type default)
			)
			(layer "F.Fab")
		)
		(fp_line
			(start -0.12065 -0.2794)
			(end 0.12065 -0.2794)
			(stroke
				(width 0.1)
				(type default)
			)
			(layer "F.Fab")
		)
		(fp_line
			(start 0.120396 0.2794)
			(end -0.12065 0.2794)
			(stroke
				(width 0.1)
				(type default)
			)
			(layer "F.Fab")
		)
		(fp_line
			(start -0.12065 0.2794)
			(end -0.12065 0.3048)
			(stroke
				(width 0.1)
				(type default)
			)
			(layer "F.Fab")
		)
		(fp_line
			(start 0.67945 0.3048)
			(end 0.120396 0.3048)
			(stroke
				(width 0.1)
				(type default)
			)
			(layer "F.Fab")
		)
		(fp_line
			(start 0.120396 0.3048)
			(end 0.120396 0.2794)
			(stroke
				(width 0.1)
				(type default)
			)
			(layer "F.Fab")
		)
		(fp_line
			(start -0.12065 0.3048)
			(end -0.67945 0.3048)
			(stroke
				(width 0.1)
				(type default)
			)
			(layer "F.Fab")
		)
		(fp_line
			(start -0.67945 0.3048)
			(end -0.67945 -0.305054)
			(stroke
				(width 0.1)
				(type default)
			)
			(layer "F.Fab")
		)
		(pad "1" smd circle
			(at -0.40005 0 90)
			(size 0 0)
			(layers "F.Cu" "F.Mask" "F.Paste")
			(net "ID_LED_P3V3_AUX")
		)
		(pad "2" smd circle
			(at 0.40005 0 90)
			(size 0 0)
			(layers "F.Cu" "F.Mask" "F.Paste")
			(net "P3V3_AUX")
		)
	)
	(footprint ""
		(layer "F.Cu")
		(at 114.554 -32.004 -90)
		(property "Reference" "X11"
			(at 2.0955 -2.83337 90)
			(unlocked yes)
			(layer "F.SilkS")
			(effects
				(font
					(size 0.7874 0.5842)
					(thickness 0.1524)
				)
				(justify left)
			)
		)
		(property "Value" ""
			(at 0 0 270)
			(layer "F.Fab")
			(effects
				(font
					(size 1.27 1.27)
				)
			)
		)
		(property "Device Type" "TP_TDR_4P_FTS_TH-TP_TDR_4P_DIPA"
			(at 1.30175 1.27 0)
			(unlocked yes)
			(layer "F.Fab")
			(hide yes)
			(effects
				(font
					(size 0.635 0.4064)
					(thickness 0.1524)
				)
			)
		)
		(property "User Part Number" "N_A"
			(at 1.30175 1.27 0)
			(unlocked yes)
			(layer "Cmts.User")
			(hide yes)
			(effects
				(font
					(size 0.635 0.4064)
					(thickness 0.1524)
				)
			)
		)
		(duplicate_pad_numbers_are_jumpers no)
		(fp_line
			(start 0 3.81)
			(end 2.54 3.81)
			(stroke
				(width 0.1524)
				(type default)
			)
			(layer "F.SilkS")
		)
		(fp_line
			(start 2.54 3.81)
			(end 2.54 3.6703)
			(stroke
				(width 0.1524)
				(type default)
			)
			(layer "F.SilkS")
		)
		(fp_line
			(start 0 3.175)
			(end 0 3.81)
			(stroke
				(width 0.1524)
				(type default)
			)
			(layer "F.SilkS")
		)
		(fp_line
			(start 2.54 1.4097)
			(end 2.54 1.1303)
			(stroke
				(width 0.1524)
				(type default)
			)
			(layer "F.SilkS")
		)
		(fp_line
			(start 0 0.635)
			(end 0 1.905)
			(stroke
				(width 0.1524)
				(type default)
			)
			(layer "F.SilkS")
		)
		(fp_line
			(start 2.54 -1.1303)
			(end 2.54 -1.27)
			(stroke
				(width 0.1524)
				(type default)
			)
			(layer "F.SilkS")
		)
		(fp_line
			(start 0 -1.27)
			(end 0 -0.635)
			(stroke
				(width 0.1524)
				(type default)
			)
			(layer "F.SilkS")
		)
		(fp_line
			(start 2.54 -1.27)
			(end 0 -1.27)
			(stroke
				(width 0.1524)
				(type default)
			)
			(layer "F.SilkS")
		)
		(fp_poly
			(pts
				(xy -0.761746 0) (xy -2.285746 -0.762) (xy -2.285746 0.762)
			)
			(stroke
				(width 0)
				(type default)
			)
			(fill yes)
			(layer "F.SilkS")
		)
		(fp_line
			(start 0 3.81)
			(end 2.54 3.81)
			(stroke
				(width 0.1)
				(type default)
			)
			(layer "F.Fab")
		)
		(fp_line
			(start 2.54 3.81)
			(end 2.54 -1.27)
			(stroke
				(width 0.1)
				(type default)
			)
			(layer "F.Fab")
		)
		(fp_line
			(start 0 -1.27)
			(end 0 3.81)
			(stroke
				(width 0.1)
				(type default)
			)
			(layer "F.Fab")
		)
		(fp_line
			(start 2.54 -1.27)
			(end 0 -1.27)
			(stroke
				(width 0.1)
				(type default)
			)
			(layer "F.Fab")
		)
		(fp_poly
			(pts
				(xy -0.761746 0) (xy -2.285746 -0.762) (xy -2.285746 0.762)
			)
			(stroke
				(width 0)
				(type default)
			)
			(fill yes)
			(layer "F.Fab")
		)
		(pad "1" thru_hole circle
			(at 0 0 270)
			(size 1.0033 1.0033)
			(drill 0.249936)
			(layers "*.Cu" "*.Mask")
			(remove_unused_layers no)
			(net "TDR_DIFF_85_IN4_DN")
			(clearance 0.10795)
			(thermal_gap 0.10795)
			(padstack
				(mode front_inner_back)
				(layer "Inner"
					(shape circle)
					(size 0.8001 0.8001)
					(clearance 0.1524)
				)
				(layer "B.Cu"
					(shape circle)
					(size 1.0033 1.0033)
					(clearance 0.10795)
				)
			)
		)
		(pad "2" thru_hole circle
			(at 2.54 0 270)
			(size 1.9939 1.9939)
			(drill 0.249936)
			(layers "*.Cu" "*.Mask")
			(remove_unused_layers no)
			(net "GND_P1")
			(clearance 0.10795)
			(thermal_gap 0.10795)
			(padstack
				(mode front_inner_back)
				(layer "Inner"
					(shape circle)
					(size 0.8001 0.8001)
					(clearance 0.1524)
				)
				(layer "B.Cu"
					(shape circle)
					(size 1.9939 1.9939)
					(clearance 0.10795)
				)
			)
		)
		(pad "3" thru_hole circle
			(at 2.54 2.54 270)
			(size 1.9939 1.9939)
			(drill 0.249936)
			(layers "*.Cu" "*.Mask")
			(remove_unused_layers no)
			(net "GND_P1")
			(clearance 0.10795)
			(thermal_gap 0.10795)
			(padstack
				(mode front_inner_back)
				(layer "Inner"
					(shape circle)
					(size 0.8001 0.8001)
					(clearance 0.1524)
				)
				(layer "B.Cu"
					(shape circle)
					(size 1.9939 1.9939)
					(clearance 0.10795)
				)
			)
		)
		(pad "4" thru_hole circle
			(at 0 2.54 270)
			(size 1.0033 1.0033)
			(drill 0.249936)
			(layers "*.Cu" "*.Mask")
			(remove_unused_layers no)
			(net "TDR_DIFF_85_IN4_DP")
			(clearance 0.10795)
			(thermal_gap 0.10795)
			(padstack
				(mode front_inner_back)
				(layer "Inner"
					(shape circle)
					(size 0.8001 0.8001)
					(clearance 0.1524)
				)
				(layer "B.Cu"
					(shape circle)
					(size 1.0033 1.0033)
					(clearance 0.10795)
				)
			)
		)
	)
	(footprint ""
		(layer "F.Cu")
		(at 78.6892 -34.1122)
		(property "Reference" "R600"
			(at 0 0 0)
			(layer "F.SilkS")
			(hide yes)
			(effects
				(font
					(size 1.27 1.27)
				)
			)
		)
		(property "Value" ""
			(at 0 0 0)
			(layer "F.Fab")
			(effects
				(font
					(size 1.27 1.27)
				)
			)
		)
		(duplicate_pad_numbers_are_jumpers no)
		(fp_line
			(start -0.7874 -0.4064)
			(end 0.7874 -0.4064)
			(stroke
				(width 0.1524)
				(type default)
			)
			(layer "F.SilkS")
		)
		(fp_line
			(start -0.7874 0.4064)
			(end -0.7874 -0.4064)
			(stroke
				(width 0.1524)
				(type default)
			)
			(layer "F.SilkS")
		)
		(fp_line
			(start 0.7874 -0.4064)
			(end 0.7874 0.4064)
			(stroke
				(width 0.1524)
				(type default)
			)
			(layer "F.SilkS")
		)
		(fp_line
			(start 0.7874 0.4064)
			(end -0.7874 0.4064)
			(stroke
				(width 0.1524)
				(type default)
			)
			(layer "F.SilkS")
		)
		(fp_line
			(start -0.67945 -0.305054)
			(end -0.12065 -0.305054)
			(stroke
				(width 0.1)
				(type default)
			)
			(layer "F.Fab")
		)
		(fp_line
			(start -0.67945 0.3048)
			(end -0.67945 -0.305054)
			(stroke
				(width 0.1)
				(type default)
			)
			(layer "F.Fab")
		)
		(fp_line
			(start -0.12065 -0.305054)
			(end -0.12065 -0.2794)
			(stroke
				(width 0.1)
				(type default)
			)
			(layer "F.Fab")
		)
		(fp_line
			(start -0.12065 -0.2794)
			(end 0.12065 -0.2794)
			(stroke
				(width 0.1)
				(type default)
			)
			(layer "F.Fab")
		)
		(fp_line
			(start -0.12065 0.2794)
			(end -0.12065 0.3048)
			(stroke
				(width 0.1)
				(type default)
			)
			(layer "F.Fab")
		)
		(fp_line
			(start -0.12065 0.3048)
			(end -0.67945 0.3048)
			(stroke
				(width 0.1)
				(type default)
			)
			(layer "F.Fab")
		)
		(fp_line
			(start 0.120396 0.2794)
			(end -0.12065 0.2794)
			(stroke
				(width 0.1)
				(type default)
			)
			(layer "F.Fab")
		)
		(fp_line
			(start 0.120396 0.3048)
			(end 0.120396 0.2794)
			(stroke
				(width 0.1)
				(type default)
			)
			(layer "F.Fab")
		)
		(fp_line
			(start 0.12065 -0.3048)
			(end 0.67945 -0.3048)
			(stroke
				(width 0.1)
				(type default)
			)
			(layer "F.Fab")
		)
		(fp_line
			(start 0.12065 -0.2794)
			(end 0.12065 -0.3048)
			(stroke
				(width 0.1)
				(type default)
			)
			(layer "F.Fab")
		)
		(fp_line
			(start 0.67945 -0.3048)
			(end 0.67945 0.3048)
			(stroke
				(width 0.1)
				(type default)
			)
			(layer "F.Fab")
		)
		(fp_line
			(start 0.67945 0.3048)
			(end 0.120396 0.3048)
			(stroke
				(width 0.1)
				(type default)
			)
			(layer "F.Fab")
		)
		(pad "1" smd circle
			(at -0.40005 0)
			(size 0 0)
			(layers "F.Cu" "F.Mask" "F.Paste")
			(net "LED_POSTCODE_4")
		)
		(pad "2" smd circle
			(at 0.40005 0)
			(size 0 0)
			(layers "F.Cu" "F.Mask" "F.Paste")
			(net "LED_POSTCODE_4_R")
		)
	)
	(footprint ""
		(layer "F.Cu")
		(at 70.4342 -27.2796 90)
		(property "Reference" "R869"
			(at 0 0 90)
			(layer "F.SilkS")
			(hide yes)
			(effects
				(font
					(size 1.27 1.27)
				)
			)
		)
		(property "Value" ""
			(at 0 0 90)
			(layer "F.Fab")
			(effects
				(font
					(size 1.27 1.27)
				)
			)
		)
		(duplicate_pad_numbers_are_jumpers no)
		(fp_line
			(start 0.7874 -0.4064)
			(end 0.7874 0.4064)
			(stroke
				(width 0.1524)
				(type default)
			)
			(layer "F.SilkS")
		)
		(fp_line
			(start -0.7874 -0.4064)
			(end 0.7874 -0.4064)
			(stroke
				(width 0.1524)
				(type default)
			)
			(layer "F.SilkS")
		)
		(fp_line
			(start 0.7874 0.4064)
			(end -0.7874 0.4064)
			(stroke
				(width 0.1524)
				(type default)
			)
			(layer "F.SilkS")
		)
		(fp_line
			(start -0.7874 0.4064)
			(end -0.7874 -0.4064)
			(stroke
				(width 0.1524)
				(type default)
			)
			(layer "F.SilkS")
		)
		(fp_line
			(start -0.12065 -0.305054)
			(end -0.12065 -0.2794)
			(stroke
				(width 0.1)
				(type default)
			)
			(layer "F.Fab")
		)
		(fp_line
			(start -0.67945 -0.305054)
			(end -0.12065 -0.305054)
			(stroke
				(width 0.1)
				(type default)
			)
			(layer "F.Fab")
		)
		(fp_line
			(start 0.67945 -0.3048)
			(end 0.67945 0.3048)
			(stroke
				(width 0.1)
				(type default)
			)
			(layer "F.Fab")
		)
		(fp_line
			(start 0.12065 -0.3048)
			(end 0.67945 -0.3048)
			(stroke
				(width 0.1)
				(type default)
			)
			(layer "F.Fab")
		)
		(fp_line
			(start 0.12065 -0.2794)
			(end 0.12065 -0.3048)
			(stroke
				(width 0.1)
				(type default)
			)
			(layer "F.Fab")
		)
		(fp_line
			(start -0.12065 -0.2794)
			(end 0.12065 -0.2794)
			(stroke
				(width 0.1)
				(type default)
			)
			(layer "F.Fab")
		)
		(fp_line
			(start 0.120396 0.2794)
			(end -0.12065 0.2794)
			(stroke
				(width 0.1)
				(type default)
			)
			(layer "F.Fab")
		)
		(fp_line
			(start -0.12065 0.2794)
			(end -0.12065 0.3048)
			(stroke
				(width 0.1)
				(type default)
			)
			(layer "F.Fab")
		)
		(fp_line
			(start 0.67945 0.3048)
			(end 0.120396 0.3048)
			(stroke
				(width 0.1)
				(type default)
			)
			(layer "F.Fab")
		)
		(fp_line
			(start 0.120396 0.3048)
			(end 0.120396 0.2794)
			(stroke
				(width 0.1)
				(type default)
			)
			(layer "F.Fab")
		)
		(fp_line
			(start -0.12065 0.3048)
			(end -0.67945 0.3048)
			(stroke
				(width 0.1)
				(type default)
			)
			(layer "F.Fab")
		)
		(fp_line
			(start -0.67945 0.3048)
			(end -0.67945 -0.305054)
			(stroke
				(width 0.1)
				(type default)
			)
			(layer "F.Fab")
		)
		(pad "1" smd circle
			(at -0.40005 0 90)
			(size 0 0)
			(layers "F.Cu" "F.Mask" "F.Paste")
			(net "PWRGD_P1V8_AUX_R3")
		)
		(pad "2" smd circle
			(at 0.40005 0 90)
			(size 0 0)
			(layers "F.Cu" "F.Mask" "F.Paste")
			(net "EN_P3V3_RGM_R")
		)
	)
	(footprint ""
		(layer "F.Cu")
		(at 54.894988 -49.37125 180)
		(property "Reference" "U5"
			(at -11.094212 -12.07262 0)
			(unlocked yes)
			(layer "F.SilkS")
			(effects
				(font
					(size 0.7874 0.5842)
					(thickness 0.1524)
				)
				(justify left)
			)
		)
		(property "Value" ""
			(at 0 0 180)
			(layer "F.Fab")
			(effects
				(font
					(size 1.27 1.27)
				)
			)
		)
		(duplicate_pad_numbers_are_jumpers no)
		(fp_line
			(start 10.54989 10.54989)
			(end -10.54989 10.54989)
			(stroke
				(width 0.1524)
				(type default)
			)
			(layer "F.SilkS")
		)
		(fp_line
			(start 10.54989 -10.54989)
			(end 10.54989 10.54989)
			(stroke
				(width 0.1524)
				(type default)
			)
			(layer "F.SilkS")
		)
		(fp_line
			(start -5.800598 -10.54989)
			(end 10.54989 -10.54989)
			(stroke
				(width 0.1524)
				(type default)
			)
			(layer "F.SilkS")
		)
		(fp_line
			(start -7.279132 -10.54989)
			(end -6.825996 -10.54989)
			(stroke
				(width 0.1524)
				(type default)
			)
			(layer "F.SilkS")
		)
		(fp_line
			(start -10.54989 10.54989)
			(end -10.54989 -2.50825)
			(stroke
				(width 0.1524)
				(type default)
			)
			(layer "F.SilkS")
		)
		(fp_line
			(start -10.54989 -3.39725)
			(end -10.54989 -10.54989)
			(stroke
				(width 0.1524)
				(type default)
			)
			(layer "F.SilkS")
		)
		(fp_line
			(start -10.54989 -10.54989)
			(end -8.448548 -10.54989)
			(stroke
				(width 0.1524)
				(type default)
			)
			(layer "F.SilkS")
		)
		(fp_poly
			(pts
				(xy -10.54989 -10.54989) (xy -9.19988 -10.54989) (xy -9.19988 -11.31189) (xy -11.31189 -11.31189)
				(xy -11.31189 -9.19988) (xy -10.54989 -9.19988)
			)
			(stroke
				(width 0)
				(type default)
			)
			(fill yes)
			(layer "F.SilkS")
		)
		(fp_line
			(start 10.54989 10.54989)
			(end -10.54989 10.54989)
			(stroke
				(width 0.1)
				(type default)
			)
			(layer "F.Fab")
		)
		(fp_line
			(start 10.54989 -10.54989)
			(end 10.54989 10.54989)
			(stroke
				(width 0.1)
				(type default)
			)
			(layer "F.Fab")
		)
		(fp_line
			(start -10.54989 10.54989)
			(end -10.54989 -10.54989)
			(stroke
				(width 0.1)
				(type default)
			)
			(layer "F.Fab")
		)
		(fp_line
			(start -10.54989 -10.54989)
			(end 10.54989 -10.54989)
			(stroke
				(width 0.1)
				(type default)
			)
			(layer "F.Fab")
		)
		(fp_poly
			(pts
				(xy -10.54989 -10.54989) (xy -9.19988 -10.54989) (xy -9.19988 -11.31189) (xy -11.31189 -11.31189)
				(xy -11.31189 -9.19988) (xy -10.54989 -9.19988)
			)
			(stroke
				(width 0)
				(type default)
			)
			(fill yes)
			(layer "F.Fab")
		)
		(pad "A1" smd circle
			(at -9.99998 -9.99998 180)
			(size 0.4064 0.4064)
			(layers "F.Cu" "F.Mask" "F.Paste")
			(net "GND")
		)
		(pad "A2" smd circle
			(at -9.19988 -9.99998 180)
			(size 0.4064 0.4064)
			(layers "F.Cu" "F.Mask" "F.Paste")
			(net "Net_35")
		)
		(pad "A3" smd circle
			(at -8.400034 -9.99998 180)
			(size 0.4064 0.4064)
			(layers "F.Cu" "F.Mask" "F.Paste")
			(net "Net_42")
		)
		(pad "A4" smd circle
			(at -7.599934 -9.99998 180)
			(size 0.4064 0.4064)
			(layers "F.Cu" "F.Mask" "F.Paste")
			(net "USB_HOST_BMC_A_R_DP")
		)
		(pad "A5" smd circle
			(at -6.800088 -9.99998 180)
			(size 0.4064 0.4064)
			(layers "F.Cu" "F.Mask" "F.Paste")
			(net "GND")
		)
		(pad "A6" smd circle
			(at -5.999988 -9.99998 180)
			(size 0.4064 0.4064)
			(layers "F.Cu" "F.Mask" "F.Paste")
			(net "USB_HOST_BMC_B_R_DP")
		)
		(pad "A7" smd circle
			(at -5.199888 -9.99998 180)
			(size 0.4064 0.4064)
			(layers "F.Cu" "F.Mask" "F.Paste")
			(net "RST_PLTRST_N")
		)
		(pad "A8" smd circle
			(at -4.400042 -9.99998 180)
			(size 0.4064 0.4064)
			(layers "F.Cu" "F.Mask" "F.Paste")
			(net "V_BMC_DDC_SDA")
		)
		(pad "A9" smd circle
			(at -3.599942 -9.99998 180)
			(size 0.4064 0.4064)
			(layers "F.Cu" "F.Mask" "F.Paste")
			(net "JTAG_SCM_TMS")
		)
		(pad "A10" smd circle
			(at -2.800096 -9.99998 180)
			(size 0.4064 0.4064)
			(layers "F.Cu" "F.Mask" "F.Paste")
			(net "PD_CLK_125M_PHY_BMC_RGMII")
		)
		(pad "A11" smd circle
			(at -1.999996 -9.99998 180)
			(size 0.4064 0.4064)
			(layers "F.Cu" "F.Mask" "F.Paste")
			(net "SMB_BMC_MM5_R_SCL")
		)
		(pad "A12" smd circle
			(at -1.199896 -9.99998 180)
			(size 0.4064 0.4064)
			(layers "F.Cu" "F.Mask" "F.Paste")
			(net "PWRGD_PSU_AC_PWROK_BMC")
		)
		(pad "A13" smd circle
			(at -0.40005 -9.99998 180)
			(size 0.4064 0.4064)
			(layers "F.Cu" "F.Mask" "F.Paste")
			(net "SMB_BMC_MM10_R_SDA")
		)
		(pad "A14" smd circle
			(at 0.40005 -9.99998 180)
			(size 0.4064 0.4064)
			(layers "F.Cu" "F.Mask" "F.Paste")
			(net "SMB_BMC_MM9_R_SDA")
		)
		(pad "A15" smd circle
			(at 1.199896 -9.99998 180)
			(size 0.4064 0.4064)
			(layers "F.Cu" "F.Mask" "F.Paste")
			(net "IRQ_PCH_SCI_WHEA_R_N")
		)
		(pad "A16" smd circle
			(at 1.999996 -9.99998 180)
			(size 0.4064 0.4064)
			(layers "F.Cu" "F.Mask" "F.Paste")
			(net "JTAG_1_BMC_TDI_R")
		)
		(pad "A17" smd circle
			(at 2.800096 -9.99998 180)
			(size 0.4064 0.4064)
			(layers "F.Cu" "F.Mask" "F.Paste")
			(net "SGPIO_BMC_M1_DI")
		)
		(pad "A18" smd circle
			(at 3.599942 -9.99998 180)
			(size 0.4064 0.4064)
			(layers "F.Cu" "F.Mask" "F.Paste")
			(net "SGPIO_BMC_M1_CLK")
		)
		(pad "A19" smd circle
			(at 4.400042 -9.99998 180)
			(size 0.4064 0.4064)
			(layers "F.Cu" "F.Mask" "F.Paste")
			(net "SMB_BMC_MM3_R_SDA")
		)
		(pad "A20" smd circle
			(at 5.199888 -9.99998 180)
			(size 0.4064 0.4064)
			(layers "F.Cu" "F.Mask" "F.Paste")
			(net "SMB_BMC_MM1_R_SDA")
		)
		(pad "A21" smd circle
			(at 5.999988 -9.99998 180)
			(size 0.4064 0.4064)
			(layers "F.Cu" "F.Mask" "F.Paste")
			(net "BMC_EMMC_DT6")
		)
		(pad "A22" smd circle
			(at 6.800088 -9.99998 180)
			(size 0.4064 0.4064)
			(layers "F.Cu" "F.Mask" "F.Paste")
			(net "BMC_EMMC_DT5")
		)
		(pad "A23" smd circle
			(at 7.599934 -9.99998 180)
			(size 0.4064 0.4064)
			(layers "F.Cu" "F.Mask" "F.Paste")
			(net "BMC_EMMC_WP_N")
		)
		(pad "A24" smd circle
			(at 8.400034 -9.99998 180)
			(size 0.4064 0.4064)
			(layers "F.Cu" "F.Mask" "F.Paste")
			(net "BMC_EMMC_CD_N")
		)
		(pad "A25" smd circle
			(at 9.19988 -9.99998 180)
			(size 0.4064 0.4064)
			(layers "F.Cu" "F.Mask" "F.Paste")
			(net "BMC_EMMC_DT3")
		)
		(pad "A26" smd circle
			(at 9.99998 -9.99998 180)
			(size 0.4064 0.4064)
			(layers "F.Cu" "F.Mask" "F.Paste")
			(net "GND")
		)
		(pad "AA1" smd circle
			(at -9.99998 5.999988 180)
			(size 0.4064 0.4064)
			(layers "F.Cu" "F.Mask" "F.Paste")
			(net "GND")
		)
		(pad "AA2" smd circle
			(at -9.19988 5.999988 180)
			(size 0.4064 0.4064)
			(layers "F.Cu" "F.Mask" "F.Paste")
			(net "NC_DP_BMC_TX1_N")
		)
		(pad "AA3" smd circle
			(at -8.400034 5.999988 180)
			(size 0.4064 0.4064)
			(layers "F.Cu" "F.Mask" "F.Paste")
			(net "GND")
		)
		(pad "AA4" smd circle
			(at -7.599934 5.999988 180)
			(size 0.4064 0.4064)
			(layers "F.Cu" "F.Mask" "F.Paste")
			(net "Net_67")
		)
		(pad "AA5" smd circle
			(at -6.800088 5.999988 180)
			(size 0.4064 0.4064)
			(layers "F.Cu" "F.Mask" "F.Paste")
			(net "Net_65")
		)
		(pad "AA6" smd circle
			(at -5.999988 5.999988 180)
			(size 0.4064 0.4064)
			(layers "F.Cu" "F.Mask" "F.Paste")
			(net "GND")
		)
		(pad "AA7" smd circle
			(at -5.199888 5.999988 180)
			(size 0.4064 0.4064)
			(layers "F.Cu" "F.Mask" "F.Paste")
			(net "GND")
		)
		(pad "AA8" smd circle
			(at -4.400042 5.999988 180)
			(size 0.4064 0.4064)
			(layers "F.Cu" "F.Mask" "F.Paste")
			(net "GND")
		)
		(pad "AA9" smd circle
			(at -3.599942 5.999988 180)
			(size 0.4064 0.4064)
			(layers "F.Cu" "F.Mask" "F.Paste")
			(net "PWRGD_DSW_PWROK_R1")
		)
		(pad "AA10" smd circle
			(at -2.800096 5.999988 180)
			(size 0.4064 0.4064)
			(layers "F.Cu" "F.Mask" "F.Paste")
			(net "GND")
		)
		(pad "AA11" smd circle
			(at -1.999996 5.999988 180)
			(size 0.4064 0.4064)
			(layers "F.Cu" "F.Mask" "F.Paste")
			(net "SPI_BMC_TPM_MISO_R1")
		)
		(pad "AA12" smd circle
			(at -1.199896 5.999988 180)
			(size 0.4064 0.4064)
			(layers "F.Cu" "F.Mask" "F.Paste")
			(net "BMC_EMMC_RST_R_N")
		)
		(pad "AA13" smd circle
			(at -0.40005 5.999988 180)
			(size 0.4064 0.4064)
			(layers "F.Cu" "F.Mask" "F.Paste")
			(net "SPI_BMC_BOOT_CS1_R1_N")
		)
		(pad "AA14" smd circle
			(at 0.40005 5.999988 180)
			(size 0.4064 0.4064)
			(layers "F.Cu" "F.Mask" "F.Paste")
			(net "GND")
		)
		(pad "AA15" smd circle
			(at 1.199896 5.999988 180)
			(size 0.4064 0.4064)
			(layers "F.Cu" "F.Mask" "F.Paste")
			(net "GND")
		)
		(pad "AA16" smd circle
			(at 1.999996 5.999988 180)
			(size 0.4064 0.4064)
			(layers "F.Cu" "F.Mask" "F.Paste")
			(net "FM_BMC_EN_DET_R")
		)
		(pad "AA17" smd circle
			(at 2.800096 5.999988 180)
			(size 0.4064 0.4064)
			(layers "F.Cu" "F.Mask" "F.Paste")
			(net "SMB_BMC_ALERT10_R_N")
		)
		(pad "AA18" smd circle
			(at 3.599942 5.999988 180)
			(size 0.4064 0.4064)
			(layers "F.Cu" "F.Mask" "F.Paste")
			(net "PVCCIO_PECI_BMC")
		)
		(pad "AA19" smd circle
			(at 4.400042 5.999988 180)
			(size 0.4064 0.4064)
			(layers "F.Cu" "F.Mask" "F.Paste")
			(net "GND")
		)
		(pad "AA20" smd circle
			(at 5.199888 5.999988 180)
			(size 0.4064 0.4064)
			(layers "F.Cu" "F.Mask" "F.Paste")
			(net "GND")
		)
		(pad "AA21" smd circle
			(at 5.999988 5.999988 180)
			(size 0.4064 0.4064)
			(layers "F.Cu" "F.Mask" "F.Paste")
			(net "A_BMC_ADCAV33")
		)
		(pad "AA22" smd circle
			(at 6.800088 5.999988 180)
			(size 0.4064 0.4064)
			(layers "F.Cu" "F.Mask" "F.Paste")
			(net "GND")
		)
		(pad "AA23" smd circle
			(at 7.599934 5.999988 180)
			(size 0.4064 0.4064)
			(layers "F.Cu" "F.Mask" "F.Paste")
			(net "ID_RST_BTN_BMC_R_N")
		)
		(pad "AA24" smd circle
			(at 8.400034 5.999988 180)
			(size 0.4064 0.4064)
			(layers "F.Cu" "F.Mask" "F.Paste")
			(net "RST_BMC_RSTBTN_OUT_R_N")
		)
		(pad "AA25" smd circle
			(at 9.19988 5.999988 180)
			(size 0.4064 0.4064)
			(layers "F.Cu" "F.Mask" "F.Paste")
			(net "IRQ_PCH_TPM_SPI_N")
		)
		(pad "AA26" smd circle
			(at 9.99998 5.999988 180)
			(size 0.4064 0.4064)
			(layers "F.Cu" "F.Mask" "F.Paste")
			(net "FM_SOL_UART_CH_SEL_R1")
		)
		(pad "AB1" smd circle
			(at -9.99998 6.800088 180)
			(size 0.4064 0.4064)
			(layers "F.Cu" "F.Mask" "F.Paste")
			(net "NC_DP_BMC_TX0_N")
		)
		(pad "AB2" smd circle
			(at -9.19988 6.800088 180)
			(size 0.4064 0.4064)
			(layers "F.Cu" "F.Mask" "F.Paste")
			(net "NC_DP_BMC_TX1_P")
		)
		(pad "AB3" smd circle
			(at -8.400034 6.800088 180)
			(size 0.4064 0.4064)
			(layers "F.Cu" "F.Mask" "F.Paste")
			(net "NC_DP_BMC_AUX_N")
		)
		(pad "AB4" smd circle
			(at -7.599934 6.800088 180)
			(size 0.4064 0.4064)
			(layers "F.Cu" "F.Mask" "F.Paste")
			(net "Net_68")
		)
		(pad "AB5" smd circle
			(at -6.800088 6.800088 180)
			(size 0.4064 0.4064)
			(layers "F.Cu" "F.Mask" "F.Paste")
			(net "Net_63")
		)
		(pad "AB6" smd circle
			(at -5.999988 6.800088 180)
			(size 0.4064 0.4064)
			(layers "F.Cu" "F.Mask" "F.Paste")
			(net "Net_61")
		)
		(pad "AB7" smd circle
			(at -5.199888 6.800088 180)
			(size 0.4064 0.4064)
			(layers "F.Cu" "F.Mask" "F.Paste")
			(net "ESPI_LPC_D0_IO0")
		)
		(pad "AB8" smd circle
			(at -4.400042 6.800088 180)
			(size 0.4064 0.4064)
			(layers "F.Cu" "F.Mask" "F.Paste")
			(net "ESPI_LPC_D1_IO1")
		)
		(pad "AB9" smd circle
			(at -3.599942 6.800088 180)
			(size 0.4064 0.4064)
			(layers "F.Cu" "F.Mask" "F.Paste")
			(net "SPI_BMC_BIOS_ROM_MOSI")
		)
		(pad "AB10" smd circle
			(at -2.800096 6.800088 180)
			(size 0.4064 0.4064)
			(layers "F.Cu" "F.Mask" "F.Paste")
			(net "SPI_BMC_BIOS_ROM_IO3")
		)
		(pad "AB11" smd circle
			(at -1.999996 6.800088 180)
			(size 0.4064 0.4064)
			(layers "F.Cu" "F.Mask" "F.Paste")
			(net "SPI_BMC_TPM_CLK_R1")
		)
		(pad "AB12" smd circle
			(at -1.199896 6.800088 180)
			(size 0.4064 0.4064)
			(layers "F.Cu" "F.Mask" "F.Paste")
			(net "PU_FWSPIWP_N_R")
		)
		(pad "AB13" smd circle
			(at -0.40005 6.800088 180)
			(size 0.4064 0.4064)
			(layers "F.Cu" "F.Mask" "F.Paste")
			(net "SPI_BMC_MISO_IO1_R")
		)
		(pad "AB14" smd circle
			(at 0.40005 6.800088 180)
			(size 0.4064 0.4064)
			(layers "F.Cu" "F.Mask" "F.Paste")
			(net "SPI_BMC_BOOT_CS0_R1_N")
		)
		(pad "AB15" smd circle
			(at 1.199896 6.800088 180)
			(size 0.4064 0.4064)
			(layers "F.Cu" "F.Mask" "F.Paste")
			(net "FM_SLPS3_GF_R1_N")
		)
		(pad "AB16" smd circle
			(at 1.999996 6.800088 180)
			(size 0.4064 0.4064)
			(layers "F.Cu" "F.Mask" "F.Paste")
			(net "SMB_BMC_ALERT9_R_N")
		)
		(pad "AB17" smd circle
			(at 2.800096 6.800088 180)
			(size 0.4064 0.4064)
			(layers "F.Cu" "F.Mask" "F.Paste")
			(net "P1V0_SENSOR")
		)
		(pad "AB18" smd circle
			(at 3.599942 6.800088 180)
			(size 0.4064 0.4064)
			(layers "F.Cu" "F.Mask" "F.Paste")
			(net "P1V2_SENSOR")
		)
		(pad "AB19" smd circle
			(at 4.400042 6.800088 180)
			(size 0.4064 0.4064)
			(layers "F.Cu" "F.Mask" "F.Paste")
			(net "PGPPA_BMC_AUX_SENSOR")
		)
		(pad "AB20" smd circle
			(at 5.199888 6.800088 180)
			(size 0.4064 0.4064)
			(layers "F.Cu" "F.Mask" "F.Paste")
			(net "A_BMC_ADCVREFN0")
		)
		(pad "AB21" smd circle
			(at 5.999988 6.800088 180)
			(size 0.4064 0.4064)
			(layers "F.Cu" "F.Mask" "F.Paste")
			(net "FM_INTRUDER_R_N")
		)
		(pad "AB22" smd circle
			(at 6.800088 6.800088 180)
			(size 0.4064 0.4064)
			(layers "F.Cu" "F.Mask" "F.Paste")
			(net "FM_PWR_BTN")
		)
		(pad "AB23" smd circle
			(at 7.599934 6.800088 180)
			(size 0.4064 0.4064)
			(layers "F.Cu" "F.Mask" "F.Paste")
			(net "H_CPU0_MEMTRIP_LVC1_N")
		)
		(pad "AB24" smd circle
			(at 8.400034 6.800088 180)
			(size 0.4064 0.4064)
			(layers "F.Cu" "F.Mask" "F.Paste")
			(net "H_CPU1_MEMTRIP_LVC1_N")
		)
		(pad "AB25" smd circle
			(at 9.19988 6.800088 180)
			(size 0.4064 0.4064)
			(layers "F.Cu" "F.Mask" "F.Paste")
			(net "USB_OC0_REAR_R_N")
		)
		(pad "AB26" smd circle
			(at 9.99998 6.800088 180)
			(size 0.4064 0.4064)
			(layers "F.Cu" "F.Mask" "F.Paste")
			(net "GPU_WP_HW_CTRL_R_N")
		)
		(pad "AC1" smd circle
			(at -9.99998 7.599934 180)
			(size 0.4064 0.4064)
			(layers "F.Cu" "F.Mask" "F.Paste")
			(net "NC_DP_BMC_TX0_P")
		)
		(pad "AC2" smd circle
			(at -9.19988 7.599934 180)
			(size 0.4064 0.4064)
			(layers "F.Cu" "F.Mask" "F.Paste")
			(net "GND")
		)
		(pad "AC3" smd circle
			(at -8.400034 7.599934 180)
			(size 0.4064 0.4064)
			(layers "F.Cu" "F.Mask" "F.Paste")
			(net "NC_DP_BMC_AUX_P")
		)
		(pad "AC4" smd circle
			(at -7.599934 7.599934 180)
			(size 0.4064 0.4064)
			(layers "F.Cu" "F.Mask" "F.Paste")
			(net "Net_66")
		)
		(pad "AC5" smd circle
			(at -6.800088 7.599934 180)
			(size 0.4064 0.4064)
			(layers "F.Cu" "F.Mask" "F.Paste")
			(net "Net_62")
		)
		(pad "AC6" smd circle
			(at -5.999988 7.599934 180)
			(size 0.4064 0.4064)
			(layers "F.Cu" "F.Mask" "F.Paste")
			(net "GND")
		)
		(pad "AC7" smd circle
			(at -5.199888 7.599934 180)
			(size 0.4064 0.4064)
			(layers "F.Cu" "F.Mask" "F.Paste")
			(net "ESPI_LPC_D3_IO3")
		)
		(pad "AC8" smd circle
			(at -4.400042 7.599934 180)
			(size 0.4064 0.4064)
			(layers "F.Cu" "F.Mask" "F.Paste")
			(net "ESPI_LPC_D2_IO2")
		)
		(pad "AC9" smd circle
			(at -3.599942 7.599934 180)
			(size 0.4064 0.4064)
			(layers "F.Cu" "F.Mask" "F.Paste")
			(net "IRQ_SMI_ACTIVE_BMC_N")
		)
		(pad "AC10" smd circle
			(at -2.800096 7.599934 180)
			(size 0.4064 0.4064)
			(layers "F.Cu" "F.Mask" "F.Paste")
			(net "SPI_BMC_TPM_CS2_R1_N")
		)
		(pad "AC11" smd circle
			(at -1.999996 7.599934 180)
			(size 0.4064 0.4064)
			(layers "F.Cu" "F.Mask" "F.Paste")
			(net "SPI_BMC_TPM_MOSI_R1")
		)
		(pad "AC12" smd circle
			(at -1.199896 7.599934 180)
			(size 0.4064 0.4064)
			(layers "F.Cu" "F.Mask" "F.Paste")
			(net "PU_BMC_FWSPIABR_N_R")
		)
		(pad "AC13" smd circle
			(at -0.40005 7.599934 180)
			(size 0.4064 0.4064)
			(layers "F.Cu" "F.Mask" "F.Paste")
			(net "TP_BMC_SPICS2_N")
		)
		(pad "AC14" smd circle
			(at 0.40005 7.599934 180)
			(size 0.4064 0.4064)
			(layers "F.Cu" "F.Mask" "F.Paste")
			(net "SPI_BMC_MOSI_IO0_R")
		)
		(pad "AC15" smd circle
			(at 1.199896 7.599934 180)
			(size 0.4064 0.4064)
			(layers "F.Cu" "F.Mask" "F.Paste")
			(net "FM_BMC_ONCTL_R_N")
		)
		(pad "AC16" smd circle
			(at 1.999996 7.599934 180)
			(size 0.4064 0.4064)
			(layers "F.Cu" "F.Mask" "F.Paste")
			(net "BSM_PRSNT_R_N")
		)
		(pad "AC17" smd circle
			(at 2.800096 7.599934 180)
			(size 0.4064 0.4064)
			(layers "F.Cu" "F.Mask" "F.Paste")
			(net "SMB_BMC_ALERT16_N")
		)
		(pad "AC18" smd circle
			(at 3.599942 7.599934 180)
			(size 0.4064 0.4064)
			(layers "F.Cu" "F.Mask" "F.Paste")
			(net "P5V_SENSOR")
		)
		(pad "AC19" smd circle
			(at 4.400042 7.599934 180)
			(size 0.4064 0.4064)
			(layers "F.Cu" "F.Mask" "F.Paste")
			(net "P1V8_SENSOR")
		)
		(pad "AC20" smd circle
			(at 5.199888 7.599934 180)
			(size 0.4064 0.4064)
			(layers "F.Cu" "F.Mask" "F.Paste")
			(net "A_BMC_ADCVREFP0")
		)
		(pad "AC21" smd circle
			(at 5.999988 7.599934 180)
			(size 0.4064 0.4064)
			(layers "F.Cu" "F.Mask" "F.Paste")
			(net "A_BMC_DACREST")
		)
		(pad "AC22" smd circle
			(at 6.800088 7.599934 180)
			(size 0.4064 0.4064)
			(layers "F.Cu" "F.Mask" "F.Paste")
			(net "FM_TPM_PRSNT_0_N")
		)
		(pad "AC23" smd circle
			(at 7.599934 7.599934 180)
			(size 0.4064 0.4064)
			(layers "F.Cu" "F.Mask" "F.Paste")
			(net "FM_SPD_REMOTE_EN_R")
		)
		(pad "AC24" smd circle
			(at 8.400034 7.599934 180)
			(size 0.4064 0.4064)
			(layers "F.Cu" "F.Mask" "F.Paste")
			(net "FM_ADR_COMPLETE")
		)
		(pad "AC25" smd circle
			(at 9.19988 7.599934 180)
			(size 0.4064 0.4064)
			(layers "F.Cu" "F.Mask" "F.Paste")
			(net "GND")
		)
		(pad "AC26" smd circle
			(at 9.99998 7.599934 180)
			(size 0.4064 0.4064)
			(layers "F.Cu" "F.Mask" "F.Paste")
			(net "FM_P12V_HSC_ENABLE_R1")
		)
		(pad "AD1" smd circle
			(at -9.99998 8.400034 180)
			(size 0.4064 0.4064)
			(layers "F.Cu" "F.Mask" "F.Paste")
			(net "GND")
		)
		(pad "AD2" smd circle
			(at -9.19988 8.400034 180)
			(size 0.4064 0.4064)
			(layers "F.Cu" "F.Mask" "F.Paste")
			(net "P2E_GPU_RX_DP")
		)
		(pad "AD3" smd circle
			(at -8.400034 8.400034 180)
			(size 0.4064 0.4064)
			(layers "F.Cu" "F.Mask" "F.Paste")
			(net "P2E_GPU_RX_DN")
		)
		(pad "AD4" smd circle
			(at -7.599934 8.400034 180)
			(size 0.4064 0.4064)
			(layers "F.Cu" "F.Mask" "F.Paste")
			(net "GND")
		)
		(pad "AD5" smd circle
			(at -6.800088 8.400034 180)
			(size 0.4064 0.4064)
			(layers "F.Cu" "F.Mask" "F.Paste")
			(net "CLK_100M_PCH_DP")
		)
		(pad "AD6" smd circle
			(at -5.999988 8.400034 180)
			(size 0.4064 0.4064)
			(layers "F.Cu" "F.Mask" "F.Paste")
			(net "CLK_100M_PCH_DN")
		)
		(pad "AD7" smd circle
			(at -5.199888 8.400034 180)
			(size 0.4064 0.4064)
			(layers "F.Cu" "F.Mask" "F.Paste")
			(net "IRQ_ESPI_LPC_SERIRQ_ALERT0_N")
		)
		(pad "AD8" smd circle
			(at -4.400042 8.400034 180)
			(size 0.4064 0.4064)
			(layers "F.Cu" "F.Mask" "F.Paste")
			(net "RST_ESPI_LPC_BMC_N")
		)
		(pad "AD9" smd circle
			(at -3.599942 8.400034 180)
			(size 0.4064 0.4064)
			(layers "F.Cu" "F.Mask" "F.Paste")
			(net "SPI_BMC_BIOS_ROM_MISO")
		)
		(pad "AD10" smd circle
			(at -2.800096 8.400034 180)
			(size 0.4064 0.4064)
			(layers "F.Cu" "F.Mask" "F.Paste")
			(net "PU_SPI1ABR")
		)
		(pad "AD11" smd circle
			(at -1.999996 8.400034 180)
			(size 0.4064 0.4064)
			(layers "F.Cu" "F.Mask" "F.Paste")
			(net "FM_DEBUG_PORT_PRSNT_R1_N")
		)
		(pad "AD12" smd circle
			(at -1.199896 8.400034 180)
			(size 0.4064 0.4064)
			(layers "F.Cu" "F.Mask" "F.Paste")
			(net "RST_WDTRST_PLD_R1_N")
		)
		(pad "AD13" smd circle
			(at -0.40005 8.400034 180)
			(size 0.4064 0.4064)
			(layers "F.Cu" "F.Mask" "F.Paste")
			(net "TP_BMC_SPICS0_N")
		)
		(pad "AD14" smd circle
			(at 0.40005 8.400034 180)
			(size 0.4064 0.4064)
			(layers "F.Cu" "F.Mask" "F.Paste")
			(net "BMC_ID_BEEP_SEL_R1")
		)
		(pad "AD15" smd circle
			(at 1.199896 8.400034 180)
			(size 0.4064 0.4064)
			(layers "F.Cu" "F.Mask" "F.Paste")
			(net "FM_BMC_SUSACK_R1_N")
		)
		(pad "AD16" smd circle
			(at 1.999996 8.400034 180)
			(size 0.4064 0.4064)
			(layers "F.Cu" "F.Mask" "F.Paste")
			(net "FM_PCHHOT_R_N")
		)
		(pad "AD17" smd circle
			(at 2.800096 8.400034 180)
			(size 0.4064 0.4064)
			(layers "F.Cu" "F.Mask" "F.Paste")
			(net "A_BMC_ADCVREFP1")
		)
		(pad "AD18" smd circle
			(at 3.599942 8.400034 180)
			(size 0.4064 0.4064)
			(layers "F.Cu" "F.Mask" "F.Paste")
			(net "A_BMC_ADCVREFN1")
		)
		(pad "AD19" smd circle
			(at 4.400042 8.400034 180)
			(size 0.4064 0.4064)
			(layers "F.Cu" "F.Mask" "F.Paste")
			(net "P2V5_SENSOR")
		)
		(pad "AD20" smd circle
			(at 5.199888 8.400034 180)
			(size 0.4064 0.4064)
			(layers "F.Cu" "F.Mask" "F.Paste")
			(net "P12V_SENSOR")
		)
		(pad "AD21" smd circle
			(at 5.999988 8.400034 180)
			(size 0.4064 0.4064)
			(layers "F.Cu" "F.Mask" "F.Paste")
			(net "V_DACB_R")
		)
		(pad "AD22" smd circle
			(at 6.800088 8.400034 180)
			(size 0.4064 0.4064)
			(layers "F.Cu" "F.Mask" "F.Paste")
			(net "Net_33")
		)
		(pad "AD23" smd circle
			(at 7.599934 8.400034 180)
			(size 0.4064 0.4064)
			(layers "F.Cu" "F.Mask" "F.Paste")
			(net "FM_PCIE_M2_SSD0_PRSNT_N")
		)
		(pad "AD24" smd circle
			(at 8.400034 8.400034 180)
			(size 0.4064 0.4064)
			(layers "F.Cu" "F.Mask" "F.Paste")
			(net "FM_JTAG_BMC_MUX_SEL_R1")
		)
		(pad "AD25" smd circle
			(at 9.19988 8.400034 180)
			(size 0.4064 0.4064)
			(layers "F.Cu" "F.Mask" "F.Paste")
			(net "FM_ADR_TRIGGER_N")
		)
		(pad "AD26" smd circle
			(at 9.99998 8.400034 180)
			(size 0.4064 0.4064)
			(layers "F.Cu" "F.Mask" "F.Paste")
			(net "FM_PMBUS_ALERT_EN")
		)
		(pad "AE1" smd circle
			(at -9.99998 9.19988 180)
			(size 0.4064 0.4064)
			(layers "F.Cu" "F.Mask" "F.Paste")
			(net "CLK_100M_GPU_DP")
		)
		(pad "AE2" smd circle
			(at -9.19988 9.19988 180)
			(size 0.4064 0.4064)
			(layers "F.Cu" "F.Mask" "F.Paste")
			(net "CLK_100M_GPU_DN")
		)
		(pad "AE3" smd circle
			(at -8.400034 9.19988 180)
			(size 0.4064 0.4064)
			(layers "F.Cu" "F.Mask" "F.Paste")
			(net "GND")
		)
		(pad "AE4" smd circle
			(at -7.599934 9.19988 180)
			(size 0.4064 0.4064)
			(layers "F.Cu" "F.Mask" "F.Paste")
			(net "P2E_PCH_TX_DP")
		)
		(pad "AE5" smd circle
			(at -6.800088 9.19988 180)
			(size 0.4064 0.4064)
			(layers "F.Cu" "F.Mask" "F.Paste")
			(net "P2E_PCH_TX_DN")
		)
		(pad "AE6" smd circle
			(at -5.999988 9.19988 180)
			(size 0.4064 0.4064)
			(layers "F.Cu" "F.Mask" "F.Paste")
			(net "GND")
		)
		(pad "AE7" smd circle
			(at -5.199888 9.19988 180)
			(size 0.4064 0.4064)
			(layers "F.Cu" "F.Mask" "F.Paste")
			(net "ESPI_HOST_LPC_BMC_CLK_R")
		)
		(pad "AE8" smd circle
			(at -4.400042 9.19988 180)
			(size 0.4064 0.4064)
			(layers "F.Cu" "F.Mask" "F.Paste")
			(net "SPI_BMC_BIOS_CS0_R1_N")
		)
		(pad "AE9" smd circle
			(at -3.599942 9.19988 180)
			(size 0.4064 0.4064)
			(layers "F.Cu" "F.Mask" "F.Paste")
			(net "GND")
		)
		(pad "AE10" smd circle
			(at -2.800096 9.19988 180)
			(size 0.4064 0.4064)
			(layers "F.Cu" "F.Mask" "F.Paste")
			(net "PU_SPI1WP_N")
		)
		(pad "AE11" smd circle
			(at -1.999996 9.19988 180)
			(size 0.4064 0.4064)
			(layers "F.Cu" "F.Mask" "F.Paste")
			(net "FM_FLASH_LATCH_N_R1")
		)
		(pad "AE12" smd circle
			(at -1.199896 9.19988 180)
			(size 0.4064 0.4064)
			(layers "F.Cu" "F.Mask" "F.Paste")
			(net "SPI_BMC_IO2_R")
		)
		(pad "AE13" smd circle
			(at -0.40005 9.19988 180)
			(size 0.4064 0.4064)
			(layers "F.Cu" "F.Mask" "F.Paste")
			(net "GND")
		)
		(pad "AE14" smd circle
			(at 0.40005 9.19988 180)
			(size 0.4064 0.4064)
			(layers "F.Cu" "F.Mask" "F.Paste")
			(net "FM_BMC_READY_R_PLD_N")
		)
		(pad "AE15" smd circle
			(at 1.199896 9.19988 180)
			(size 0.4064 0.4064)
			(layers "F.Cu" "F.Mask" "F.Paste")
			(net "BATTERY_DETECT")
		)
		(pad "AE16" smd circle
			(at 1.999996 9.19988 180)
			(size 0.4064 0.4064)
			(layers "F.Cu" "F.Mask" "F.Paste")
			(net "SMB_BMC_ALERT12_N")
		)
		(pad "AE17" smd circle
			(at 2.800096 9.19988 180)
			(size 0.4064 0.4064)
			(layers "F.Cu" "F.Mask" "F.Paste")
			(net "GND")
		)
		(pad "AE18" smd circle
			(at 3.599942 9.19988 180)
			(size 0.4064 0.4064)
			(layers "F.Cu" "F.Mask" "F.Paste")
			(net "P3V_BAT_SENSOR")
		)
		(pad "AE19" smd circle
			(at 4.400042 9.19988 180)
			(size 0.4064 0.4064)
			(layers "F.Cu" "F.Mask" "F.Paste")
			(net "P3V3_SENSOR")
		)
		(pad "AE20" smd circle
			(at 5.199888 9.19988 180)
			(size 0.4064 0.4064)
			(layers "F.Cu" "F.Mask" "F.Paste")
			(net "GND")
		)
		(pad "AE21" smd circle
			(at 5.999988 9.19988 180)
			(size 0.4064 0.4064)
			(layers "F.Cu" "F.Mask" "F.Paste")
			(net "V_DACG_R")
		)
		(pad "AE22" smd circle
			(at 6.800088 9.19988 180)
			(size 0.4064 0.4064)
			(layers "F.Cu" "F.Mask" "F.Paste")
			(net "I3C2_SDA_R")
		)
		(pad "AE23" smd circle
			(at 7.599934 9.19988 180)
			(size 0.4064 0.4064)
			(layers "F.Cu" "F.Mask" "F.Paste")
			(net "GND")
		)
		(pad "AE24" smd circle
			(at 8.400034 9.19988 180)
			(size 0.4064 0.4064)
			(layers "F.Cu" "F.Mask" "F.Paste")
			(net "I3C1_SDA_R")
		)
		(pad "AE25" smd circle
			(at 9.19988 9.19988 180)
			(size 0.4064 0.4064)
			(layers "F.Cu" "F.Mask" "F.Paste")
			(net "I3C4_SCL_R")
		)
		(pad "AE26" smd circle
			(at 9.99998 9.19988 180)
			(size 0.4064 0.4064)
			(layers "F.Cu" "F.Mask" "F.Paste")
			(net "I3C3_SDA_R")
		)
		(pad "AF1" smd circle
			(at -9.99998 9.99998 180)
			(size 0.4064 0.4064)
			(layers "F.Cu" "F.Mask" "F.Paste")
			(net "GND")
		)
		(pad "AF2" smd circle
			(at -9.19988 9.99998 180)
			(size 0.4064 0.4064)
			(layers "F.Cu" "F.Mask" "F.Paste")
			(net "P2E_GPU_TX_DN")
		)
		(pad "AF3" smd circle
			(at -8.400034 9.99998 180)
			(size 0.4064 0.4064)
			(layers "F.Cu" "F.Mask" "F.Paste")
			(net "P2E_GPU_TX_DP")
		)
		(pad "AF4" smd circle
			(at -7.599934 9.99998 180)
			(size 0.4064 0.4064)
			(layers "F.Cu" "F.Mask" "F.Paste")
			(net "GND")
		)
		(pad "AF5" smd circle
			(at -6.800088 9.99998 180)
			(size 0.4064 0.4064)
			(layers "F.Cu" "F.Mask" "F.Paste")
			(net "P2E_PCH_RX_DP")
		)
		(pad "AF6" smd circle
			(at -5.999988 9.99998 180)
			(size 0.4064 0.4064)
			(layers "F.Cu" "F.Mask" "F.Paste")
			(net "P2E_PCH_RX_DN")
		)
		(pad "AF7" smd circle
			(at -5.199888 9.99998 180)
			(size 0.4064 0.4064)
			(layers "F.Cu" "F.Mask" "F.Paste")
			(net "ESPI_HOST_LPC_BMC_LFRAME_N_R")
		)
		(pad "AF8" smd circle
			(at -4.400042 9.99998 180)
			(size 0.4064 0.4064)
			(layers "F.Cu" "F.Mask" "F.Paste")
			(net "SPI_BMC_BIOS_ROM_CLK")
		)
		(pad "AF9" smd circle
			(at -3.599942 9.99998 180)
			(size 0.4064 0.4064)
			(layers "F.Cu" "F.Mask" "F.Paste")
			(net "SPI_BMC_BIOS_ROM_IO2")
		)
		(pad "AF10" smd circle
			(at -2.800096 9.99998 180)
			(size 0.4064 0.4064)
			(layers "F.Cu" "F.Mask" "F.Paste")
			(net "CLK_GEN2_BMC_RC_OE_N")
		)
		(pad "AF11" smd circle
			(at -1.999996 9.99998 180)
			(size 0.4064 0.4064)
			(layers "F.Cu" "F.Mask" "F.Paste")
			(net "RST_BMC_SELF_HW_R1")
		)
		(pad "AF12" smd circle
			(at -1.199896 9.99998 180)
			(size 0.4064 0.4064)
			(layers "F.Cu" "F.Mask" "F.Paste")
			(net "SPI_BMC_IO3_R")
		)
		(pad "AF13" smd circle
			(at -0.40005 9.99998 180)
			(size 0.4064 0.4064)
			(layers "F.Cu" "F.Mask" "F.Paste")
			(net "SPI_BMC_CLK_R")
		)
		(pad "AF14" smd circle
			(at 0.40005 9.99998 180)
			(size 0.4064 0.4064)
			(layers "F.Cu" "F.Mask" "F.Paste")
			(net "RST_RSMRST_R_N")
		)
		(pad "AF15" smd circle
			(at 1.199896 9.99998 180)
			(size 0.4064 0.4064)
			(layers "F.Cu" "F.Mask" "F.Paste")
			(net "IRQ_TPM_SPI_N")
		)
		(pad "AF16" smd circle
			(at 1.999996 9.99998 180)
			(size 0.4064 0.4064)
			(layers "F.Cu" "F.Mask" "F.Paste")
			(net "PECI_BMC_R")
		)
		(pad "AF17" smd circle
			(at 2.800096 9.99998 180)
			(size 0.4064 0.4064)
			(layers "F.Cu" "F.Mask" "F.Paste")
			(net "ADCVREFEXT1")
		)
		(pad "AF18" smd circle
			(at 3.599942 9.99998 180)
			(size 0.4064 0.4064)
			(layers "F.Cu" "F.Mask" "F.Paste")
			(net "A_BMC_ADCREXT1")
		)
		(pad "AF19" smd circle
			(at 4.400042 9.99998 180)
			(size 0.4064 0.4064)
			(layers "F.Cu" "F.Mask" "F.Paste")
			(net "ADCVREFEXT0")
		)
		(pad "AF20" smd circle
			(at 5.199888 9.99998 180)
			(size 0.4064 0.4064)
			(layers "F.Cu" "F.Mask" "F.Paste")
			(net "A_BMC_ADCREXT0")
		)
		(pad "AF21" smd circle
			(at 5.999988 9.99998 180)
			(size 0.4064 0.4064)
			(layers "F.Cu" "F.Mask" "F.Paste")
			(net "V_DACR_R")
		)
		(pad "AF22" smd circle
			(at 6.800088 9.99998 180)
			(size 0.4064 0.4064)
			(layers "F.Cu" "F.Mask" "F.Paste")
			(net "I3C2_SCL_R")
		)
		(pad "AF23" smd circle
			(at 7.599934 9.99998 180)
			(size 0.4064 0.4064)
			(layers "F.Cu" "F.Mask" "F.Paste")
			(net "I3C1_SCL_R")
		)
		(pad "AF24" smd circle
			(at 8.400034 9.99998 180)
			(size 0.4064 0.4064)
			(layers "F.Cu" "F.Mask" "F.Paste")
			(net "I3C4_SDA_R")
		)
		(pad "AF25" smd circle
			(at 9.19988 9.99998 180)
			(size 0.4064 0.4064)
			(layers "F.Cu" "F.Mask" "F.Paste")
			(net "I3C3_SCL_R")
		)
		(pad "AF26" smd circle
			(at 9.99998 9.99998 180)
			(size 0.4064 0.4064)
			(layers "F.Cu" "F.Mask" "F.Paste")
			(net "GND")
		)
		(pad "B1" smd circle
			(at -9.99998 -9.19988 180)
			(size 0.4064 0.4064)
			(layers "F.Cu" "F.Mask" "F.Paste")
			(net "Net_55")
		)
		(pad "B2" smd circle
			(at -9.19988 -9.19988 180)
			(size 0.4064 0.4064)
			(layers "F.Cu" "F.Mask" "F.Paste")
			(net "Net_56")
		)
		(pad "B3" smd circle
			(at -8.400034 -9.19988 180)
			(size 0.4064 0.4064)
			(layers "F.Cu" "F.Mask" "F.Paste")
			(net "Net_36")
		)
		(pad "B4" smd circle
			(at -7.599934 -9.19988 180)
			(size 0.4064 0.4064)
			(layers "F.Cu" "F.Mask" "F.Paste")
			(net "USB_HOST_BMC_A_R_DN")
		)
		(pad "B5" smd circle
			(at -6.800088 -9.19988 180)
			(size 0.4064 0.4064)
			(layers "F.Cu" "F.Mask" "F.Paste")
			(net "GND")
		)
		(pad "B6" smd circle
			(at -5.999988 -9.19988 180)
			(size 0.4064 0.4064)
			(layers "F.Cu" "F.Mask" "F.Paste")
			(net "USB_HOST_BMC_B_R_DN")
		)
		(pad "B7" smd circle
			(at -5.199888 -9.19988 180)
			(size 0.4064 0.4064)
			(layers "F.Cu" "F.Mask" "F.Paste")
			(net "RST_SPI_FLASH_N")
		)
		(pad "B8" smd circle
			(at -4.400042 -9.19988 180)
			(size 0.4064 0.4064)
			(layers "F.Cu" "F.Mask" "F.Paste")
			(net "V_BMC_DDC_SCL")
		)
		(pad "B9" smd circle
			(at -3.599942 -9.19988 180)
			(size 0.4064 0.4064)
			(layers "F.Cu" "F.Mask" "F.Paste")
			(net "JTAG_SCM_TCK")
		)
		(pad "B10" smd circle
			(at -2.800096 -9.19988 180)
			(size 0.4064 0.4064)
			(layers "F.Cu" "F.Mask" "F.Paste")
			(net "RST_EXTRST_N")
		)
		(pad "B11" smd circle
			(at -1.999996 -9.19988 180)
			(size 0.4064 0.4064)
			(layers "F.Cu" "F.Mask" "F.Paste")
			(net "GND")
		)
		(pad "B12" smd circle
			(at -1.199896 -9.19988 180)
			(size 0.4064 0.4064)
			(layers "F.Cu" "F.Mask" "F.Paste")
			(net "PWRGD_SYS_PWROK_BMC")
		)
		(pad "B13" smd circle
			(at -0.40005 -9.19988 180)
			(size 0.4064 0.4064)
			(layers "F.Cu" "F.Mask" "F.Paste")
			(net "FM_VIRTUAL_RESEAT_BMC")
		)
		(pad "B14" smd circle
			(at 0.40005 -9.19988 180)
			(size 0.4064 0.4064)
			(layers "F.Cu" "F.Mask" "F.Paste")
			(net "V_VGAHS_R")
		)
		(pad "B15" smd circle
			(at 1.199896 -9.19988 180)
			(size 0.4064 0.4064)
			(layers "F.Cu" "F.Mask" "F.Paste")
			(net "GND")
		)
		(pad "B16" smd circle
			(at 1.999996 -9.19988 180)
			(size 0.4064 0.4064)
			(layers "F.Cu" "F.Mask" "F.Paste")
			(net "FM_THROTTLE_N")
		)
		(pad "B17" smd circle
			(at 2.800096 -9.19988 180)
			(size 0.4064 0.4064)
			(layers "F.Cu" "F.Mask" "F.Paste")
			(net "SMB_BMC_MM15_R_SDA")
		)
		(pad "B18" smd circle
			(at 3.599942 -9.19988 180)
			(size 0.4064 0.4064)
			(layers "F.Cu" "F.Mask" "F.Paste")
			(net "SGPIO_BMC_M1_LD")
		)
		(pad "B19" smd circle
			(at 4.400042 -9.19988 180)
			(size 0.4064 0.4064)
			(layers "F.Cu" "F.Mask" "F.Paste")
			(net "GND")
		)
		(pad "B20" smd circle
			(at 5.199888 -9.19988 180)
			(size 0.4064 0.4064)
			(layers "F.Cu" "F.Mask" "F.Paste")
			(net "SMB_BMC_MM1_R_SCL")
		)
		(pad "B21" smd circle
			(at 5.999988 -9.19988 180)
			(size 0.4064 0.4064)
			(layers "F.Cu" "F.Mask" "F.Paste")
			(net "FM_BMC_DBP_PRESENT_R_N")
		)
		(pad "B22" smd circle
			(at 6.800088 -9.19988 180)
			(size 0.4064 0.4064)
			(layers "F.Cu" "F.Mask" "F.Paste")
			(net "UART_6_BMC_R_RXD")
		)
		(pad "B23" smd circle
			(at 7.599934 -9.19988 180)
			(size 0.4064 0.4064)
			(layers "F.Cu" "F.Mask" "F.Paste")
			(net "GND")
		)
		(pad "B24" smd circle
			(at 8.400034 -9.19988 180)
			(size 0.4064 0.4064)
			(layers "F.Cu" "F.Mask" "F.Paste")
			(net "RMII_RXER")
		)
		(pad "B25" smd circle
			(at 9.19988 -9.19988 180)
			(size 0.4064 0.4064)
			(layers "F.Cu" "F.Mask" "F.Paste")
			(net "RMII_CSRDV")
		)
		(pad "B26" smd circle
			(at 9.99998 -9.19988 180)
			(size 0.4064 0.4064)
			(layers "F.Cu" "F.Mask" "F.Paste")
			(net "RMII_RXD1")
		)
		(pad "C1" smd circle
			(at -9.99998 -8.400034 180)
			(size 0.4064 0.4064)
			(layers "F.Cu" "F.Mask" "F.Paste")
			(net "Net_41")
		)
		(pad "C2" smd circle
			(at -9.19988 -8.400034 180)
			(size 0.4064 0.4064)
			(layers "F.Cu" "F.Mask" "F.Paste")
			(net "Net_163")
		)
		(pad "C3" smd circle
			(at -8.400034 -8.400034 180)
			(size 0.4064 0.4064)
			(layers "F.Cu" "F.Mask" "F.Paste")
			(net "GND")
		)
		(pad "C4" smd circle
			(at -7.599934 -8.400034 180)
			(size 0.4064 0.4064)
			(layers "F.Cu" "F.Mask" "F.Paste")
			(net "Net_54")
		)
		(pad "C5" smd circle
			(at -6.800088 -8.400034 180)
			(size 0.4064 0.4064)
			(layers "F.Cu" "F.Mask" "F.Paste")
			(net "Net_167")
		)
		(pad "C6" smd circle
			(at -5.999988 -8.400034 180)
			(size 0.4064 0.4064)
			(layers "F.Cu" "F.Mask" "F.Paste")
			(net "AC_PWR_BMC_BTN_R_N")
		)
		(pad "C7" smd circle
			(at -5.199888 -8.400034 180)
			(size 0.4064 0.4064)
			(layers "F.Cu" "F.Mask" "F.Paste")
			(net "DP_BMC_HPD_3V3_BUF")
		)
		(pad "C8" smd circle
			(at -4.400042 -8.400034 180)
			(size 0.4064 0.4064)
			(layers "F.Cu" "F.Mask" "F.Paste")
			(net "UART_BMC_5_TXD")
		)
		(pad "C9" smd circle
			(at -3.599942 -8.400034 180)
			(size 0.4064 0.4064)
			(layers "F.Cu" "F.Mask" "F.Paste")
			(net "JTAG_SCM_TDO")
		)
		(pad "C10" smd circle
			(at -2.800096 -8.400034 180)
			(size 0.4064 0.4064)
			(layers "F.Cu" "F.Mask" "F.Paste")
			(net "PD_SP_ENTEST")
		)
		(pad "C11" smd circle
			(at -1.999996 -8.400034 180)
			(size 0.4064 0.4064)
			(layers "F.Cu" "F.Mask" "F.Paste")
			(net "SMB_BMC_MM5_R_SDA")
		)
		(pad "C12" smd circle
			(at -1.199896 -8.400034 180)
			(size 0.4064 0.4064)
			(layers "F.Cu" "F.Mask" "F.Paste")
			(net "FM_DBP_BMC_PRDY_R_N")
		)
		(pad "C13" smd circle
			(at -0.40005 -8.400034 180)
			(size 0.4064 0.4064)
			(layers "F.Cu" "F.Mask" "F.Paste")
			(net "UART_BMC_1_TXD")
		)
		(pad "C14" smd circle
			(at 0.40005 -8.400034 180)
			(size 0.4064 0.4064)
			(layers "F.Cu" "F.Mask" "F.Paste")
			(net "V_VGAVS_R")
		)
		(pad "C15" smd circle
			(at 1.199896 -8.400034 180)
			(size 0.4064 0.4064)
			(layers "F.Cu" "F.Mask" "F.Paste")
			(net "FM_DBP_CPU_PREQ_GF_N")
		)
		(pad "C16" smd circle
			(at 1.999996 -8.400034 180)
			(size 0.4064 0.4064)
			(layers "F.Cu" "F.Mask" "F.Paste")
			(net "JTAG_1_BMC_TDO")
		)
		(pad "C17" smd circle
			(at 2.800096 -8.400034 180)
			(size 0.4064 0.4064)
			(layers "F.Cu" "F.Mask" "F.Paste")
			(net "SMB_BMC_MM16_R_SCL")
		)
		(pad "C18" smd circle
			(at 3.599942 -8.400034 180)
			(size 0.4064 0.4064)
			(layers "F.Cu" "F.Mask" "F.Paste")
			(net "SGPIO_BMC_M1_DO")
		)
		(pad "C19" smd circle
			(at 4.400042 -8.400034 180)
			(size 0.4064 0.4064)
			(layers "F.Cu" "F.Mask" "F.Paste")
			(net "SMB_BMC_MM3_R_SCL")
		)
		(pad "C20" smd circle
			(at 5.199888 -8.400034 180)
			(size 0.4064 0.4064)
			(layers "F.Cu" "F.Mask" "F.Paste")
			(net "SMB_BMC_MM4_R_SCL")
		)
		(pad "C21" smd circle
			(at 5.999988 -8.400034 180)
			(size 0.4064 0.4064)
			(layers "F.Cu" "F.Mask" "F.Paste")
			(net "BMC_EMMC_DT4")
		)
		(pad "C22" smd circle
			(at 6.800088 -8.400034 180)
			(size 0.4064 0.4064)
			(layers "F.Cu" "F.Mask" "F.Paste")
			(net "BMC_EMMC_DT2")
		)
		(pad "C23" smd circle
			(at 7.599934 -8.400034 180)
			(size 0.4064 0.4064)
			(layers "F.Cu" "F.Mask" "F.Paste")
			(net "BMC_EMMC_DT1")
		)
		(pad "C24" smd circle
			(at 8.400034 -8.400034 180)
			(size 0.4064 0.4064)
			(layers "F.Cu" "F.Mask" "F.Paste")
			(net "RMII_RXD0")
		)
		(pad "C25" smd circle
			(at 9.19988 -8.400034 180)
			(size 0.4064 0.4064)
			(layers "F.Cu" "F.Mask" "F.Paste")
			(net "RMII_OCP_RCLKI_R_ISO")
		)
		(pad "C26" smd circle
			(at 9.99998 -8.400034 180)
			(size 0.4064 0.4064)
			(layers "F.Cu" "F.Mask" "F.Paste")
			(net "FM_PLT_BMC_THERMTRIP_N_R")
		)
		(pad "D1" smd circle
			(at -9.99998 -7.599934 180)
			(size 0.4064 0.4064)
			(layers "F.Cu" "F.Mask" "F.Paste")
			(net "Net_50")
		)
		(pad "D2" smd circle
			(at -9.19988 -7.599934 180)
			(size 0.4064 0.4064)
			(layers "F.Cu" "F.Mask" "F.Paste")
			(net "Net_52")
		)
		(pad "D3" smd circle
			(at -8.400034 -7.599934 180)
			(size 0.4064 0.4064)
			(layers "F.Cu" "F.Mask" "F.Paste")
			(net "FM_BOARD_BMC_REV_ID0")
		)
		(pad "D4" smd circle
			(at -7.599934 -7.599934 180)
			(size 0.4064 0.4064)
			(layers "F.Cu" "F.Mask" "F.Paste")
			(net "Net_164")
		)
		(pad "D5" smd circle
			(at -6.800088 -7.599934 180)
			(size 0.4064 0.4064)
			(layers "F.Cu" "F.Mask" "F.Paste")
			(net "Net_43")
		)
		(pad "D6" smd circle
			(at -5.999988 -7.599934 180)
			(size 0.4064 0.4064)
			(layers "F.Cu" "F.Mask" "F.Paste")
			(net "Net_44")
		)
		(pad "D7" smd circle
			(at -5.199888 -7.599934 180)
			(size 0.4064 0.4064)
			(layers "F.Cu" "F.Mask" "F.Paste")
			(net "FM_BMC_SSPRST_N")
		)
		(pad "D8" smd circle
			(at -4.400042 -7.599934 180)
			(size 0.4064 0.4064)
			(layers "F.Cu" "F.Mask" "F.Paste")
			(net "UART_BMC_5_RXD")
		)
		(pad "D9" smd circle
			(at -3.599942 -7.599934 180)
			(size 0.4064 0.4064)
			(layers "F.Cu" "F.Mask" "F.Paste")
			(net "JTAG_SCM_TDI")
		)
		(pad "D10" smd circle
			(at -2.800096 -7.599934 180)
			(size 0.4064 0.4064)
			(layers "F.Cu" "F.Mask" "F.Paste")
			(net "BMC_CLK_25M")
		)
		(pad "D11" smd circle
			(at -1.999996 -7.599934 180)
			(size 0.4064 0.4064)
			(layers "F.Cu" "F.Mask" "F.Paste")
			(net "SMB_BMC_MM7_R_SCL")
		)
		(pad "D12" smd circle
			(at -1.199896 -7.599934 180)
			(size 0.4064 0.4064)
			(layers "F.Cu" "F.Mask" "F.Paste")
			(net "SMB_BMC_MM6_R_SCL")
		)
		(pad "D13" smd circle
			(at -0.40005 -7.599934 180)
			(size 0.4064 0.4064)
			(layers "F.Cu" "F.Mask" "F.Paste")
			(net "UART_BMC_1_RXD")
		)
		(pad "D14" smd circle
			(at 0.40005 -7.599934 180)
			(size 0.4064 0.4064)
			(layers "F.Cu" "F.Mask" "F.Paste")
			(net "H_CPU0_PROCHOT_LVC1_N")
		)
		(pad "D15" smd circle
			(at 1.199896 -7.599934 180)
			(size 0.4064 0.4064)
			(layers "F.Cu" "F.Mask" "F.Paste")
			(net "SMB_BMC_MM9_R_SCL")
		)
		(pad "D16" smd circle
			(at 1.999996 -7.599934 180)
			(size 0.4064 0.4064)
			(layers "F.Cu" "F.Mask" "F.Paste")
			(net "JTAG_1_BMC_TMS_R")
		)
		(pad "D17" smd circle
			(at 2.800096 -7.599934 180)
			(size 0.4064 0.4064)
			(layers "F.Cu" "F.Mask" "F.Paste")
			(net "JTAG_1_BMC_TRST_R")
		)
		(pad "D18" smd circle
			(at 3.599942 -7.599934 180)
			(size 0.4064 0.4064)
			(layers "F.Cu" "F.Mask" "F.Paste")
			(net "SMB_BMC_MM15_R_SCL")
		)
		(pad "D19" smd circle
			(at 4.400042 -7.599934 180)
			(size 0.4064 0.4064)
			(layers "F.Cu" "F.Mask" "F.Paste")
			(net "SMB_BMC_MM4_R_SDA")
		)
		(pad "D20" smd circle
			(at 5.199888 -7.599934 180)
			(size 0.4064 0.4064)
			(layers "F.Cu" "F.Mask" "F.Paste")
			(net "SMB_BMC_MM2_R_SDA")
		)
		(pad "D21" smd circle
			(at 5.999988 -7.599934 180)
			(size 0.4064 0.4064)
			(layers "F.Cu" "F.Mask" "F.Paste")
			(net "SMB_BMC_ALERT15_N")
		)
		(pad "D22" smd circle
			(at 6.800088 -7.599934 180)
			(size 0.4064 0.4064)
			(layers "F.Cu" "F.Mask" "F.Paste")
			(net "BMC_EMMC_CLK")
		)
		(pad "D23" smd circle
			(at 7.599934 -7.599934 180)
			(size 0.4064 0.4064)
			(layers "F.Cu" "F.Mask" "F.Paste")
			(net "BMC_EMMC_DT0")
		)
		(pad "D24" smd circle
			(at 8.400034 -7.599934 180)
			(size 0.4064 0.4064)
			(layers "F.Cu" "F.Mask" "F.Paste")
			(net "FM_BIOS_DEBUG_EN_R_N")
		)
		(pad "D25" smd circle
			(at 9.19988 -7.599934 180)
			(size 0.4064 0.4064)
			(layers "F.Cu" "F.Mask" "F.Paste")
			(net "GND")
		)
		(pad "D26" smd circle
			(at 9.99998 -7.599934 180)
			(size 0.4064 0.4064)
			(layers "F.Cu" "F.Mask" "F.Paste")
			(net "PD_BIOS_MUX_EN_R_N")
		)
		(pad "E1" smd circle
			(at -9.99998 -6.800088 180)
			(size 0.4064 0.4064)
			(layers "F.Cu" "F.Mask" "F.Paste")
			(net "Net_165")
		)
		(pad "E2" smd circle
			(at -9.19988 -6.800088 180)
			(size 0.4064 0.4064)
			(layers "F.Cu" "F.Mask" "F.Paste")
			(net "Net_48")
		)
		(pad "E3" smd circle
			(at -8.400034 -6.800088 180)
			(size 0.4064 0.4064)
			(layers "F.Cu" "F.Mask" "F.Paste")
			(net "Net_51")
		)
		(pad "E4" smd circle
			(at -7.599934 -6.800088 180)
			(size 0.4064 0.4064)
			(layers "F.Cu" "F.Mask" "F.Paste")
			(net "FM_BOARD_BMC_REV_ID1")
		)
		(pad "E5" smd circle
			(at -6.800088 -6.800088 180)
			(size 0.4064 0.4064)
			(layers "F.Cu" "F.Mask" "F.Paste")
			(net "Net_53")
		)
		(pad "E6" smd circle
			(at -5.999988 -6.800088 180)
			(size 0.4064 0.4064)
			(layers "F.Cu" "F.Mask" "F.Paste")
			(net "Net_166")
		)
		(pad "E7" smd circle
			(at -5.199888 -6.800088 180)
			(size 0.4064 0.4064)
			(layers "F.Cu" "F.Mask" "F.Paste")
			(net "P1V0_STBY_PLAVDD")
		)
		(pad "E8" smd circle
			(at -4.400042 -6.800088 180)
			(size 0.4064 0.4064)
			(layers "F.Cu" "F.Mask" "F.Paste")
			(net "GND")
		)
		(pad "E9" smd circle
			(at -3.599942 -6.800088 180)
			(size 0.4064 0.4064)
			(layers "F.Cu" "F.Mask" "F.Paste")
			(net "P1V0_STBY_PLAVDD")
		)
		(pad "E10" smd circle
			(at -2.800096 -6.800088 180)
			(size 0.4064 0.4064)
			(layers "F.Cu" "F.Mask" "F.Paste")
			(net "RST_BMC_SRST_N")
		)
		(pad "E11" smd circle
			(at -1.999996 -6.800088 180)
			(size 0.4064 0.4064)
			(layers "F.Cu" "F.Mask" "F.Paste")
			(net "SMB_BMC_MM7_R_SDA")
		)
		(pad "E12" smd circle
			(at -1.199896 -6.800088 180)
			(size 0.4064 0.4064)
			(layers "F.Cu" "F.Mask" "F.Paste")
			(net "SMB_BMC_MM8_R_SDA")
		)
		(pad "E13" smd circle
			(at -0.40005 -6.800088 180)
			(size 0.4064 0.4064)
			(layers "F.Cu" "F.Mask" "F.Paste")
			(net "SMB_BMC_MM6_R_SDA")
		)
		(pad "E14" smd circle
			(at 0.40005 -6.800088 180)
			(size 0.4064 0.4064)
			(layers "F.Cu" "F.Mask" "F.Paste")
			(net "FM_PECI_SEL_R_N")
		)
		(pad "E15" smd circle
			(at 1.199896 -6.800088 180)
			(size 0.4064 0.4064)
			(layers "F.Cu" "F.Mask" "F.Paste")
			(net "SMB_BMC_MM10_R_SCL")
		)
		(pad "E16" smd circle
			(at 1.999996 -6.800088 180)
			(size 0.4064 0.4064)
			(layers "F.Cu" "F.Mask" "F.Paste")
			(net "FLASH_WP_STATUS_R1")
		)
		(pad "E17" smd circle
			(at 2.800096 -6.800088 180)
			(size 0.4064 0.4064)
			(layers "F.Cu" "F.Mask" "F.Paste")
			(net "JTAG_1_BMC_TCK_R")
		)
		(pad "E18" smd circle
			(at 3.599942 -6.800088 180)
			(size 0.4064 0.4064)
			(layers "F.Cu" "F.Mask" "F.Paste")
			(net "SMB_BMC_MM16_R_SDA")
		)
		(pad "E19" smd circle
			(at 4.400042 -6.800088 180)
			(size 0.4064 0.4064)
			(layers "F.Cu" "F.Mask" "F.Paste")
			(net "SMB_BMC_MM2_R_SCL")
		)
		(pad "E20" smd circle
			(at 5.199888 -6.800088 180)
			(size 0.4064 0.4064)
			(layers "F.Cu" "F.Mask" "F.Paste")
			(net "BMC_EMMC_DT7")
		)
		(pad "E21" smd circle
			(at 5.999988 -6.800088 180)
			(size 0.4064 0.4064)
			(layers "F.Cu" "F.Mask" "F.Paste")
			(net "UART_6_BMC_R_TXD")
		)
		(pad "E22" smd circle
			(at 6.800088 -6.800088 180)
			(size 0.4064 0.4064)
			(layers "F.Cu" "F.Mask" "F.Paste")
			(net "BMC_EMMC_CMD")
		)
		(pad "E23" smd circle
			(at 7.599934 -6.800088 180)
			(size 0.4064 0.4064)
			(layers "F.Cu" "F.Mask" "F.Paste")
			(net "RMII_TXEN_R")
		)
		(pad "E24" smd circle
			(at 8.400034 -6.800088 180)
			(size 0.4064 0.4064)
			(layers "F.Cu" "F.Mask" "F.Paste")
			(net "RMII_TXD0_R")
		)
		(pad "E25" smd circle
			(at 9.19988 -6.800088 180)
			(size 0.4064 0.4064)
			(layers "F.Cu" "F.Mask" "F.Paste")
			(net "RMII_TXD1_R")
		)
		(pad "E26" smd circle
			(at 9.99998 -6.800088 180)
			(size 0.4064 0.4064)
			(layers "F.Cu" "F.Mask" "F.Paste")
			(net "FM_BMC_CRASHLOG_TRIG_R1_N")
		)
		(pad "F1" smd circle
			(at -9.99998 -5.999988 180)
			(size 0.4064 0.4064)
			(layers "F.Cu" "F.Mask" "F.Paste")
			(net "M_BMC_DDR4_MA<2>")
		)
		(pad "F2" smd circle
			(at -9.19988 -5.999988 180)
			(size 0.4064 0.4064)
			(layers "F.Cu" "F.Mask" "F.Paste")
			(net "M_BMC_DDR4_MA<10>")
		)
		(pad "F3" smd circle
			(at -8.400034 -5.999988 180)
			(size 0.4064 0.4064)
			(layers "F.Cu" "F.Mask" "F.Paste")
			(net "M_BMC_DDR4_MA<0>")
		)
		(pad "F4" smd circle
			(at -7.599934 -5.999988 180)
			(size 0.4064 0.4064)
			(layers "F.Cu" "F.Mask" "F.Paste")
			(net "Net_49")
		)
		(pad "F5" smd circle
			(at -6.800088 -5.999988 180)
			(size 0.4064 0.4064)
			(layers "F.Cu" "F.Mask" "F.Paste")
			(net "FM_BOARD_BMC_REV_ID2")
		)
		(pad "F6" smd circle
			(at -5.999988 -5.999988 180)
			(size 0.4064 0.4064)
			(layers "F.Cu" "F.Mask" "F.Paste")
			(net "GND")
		)
		(pad "F7" smd circle
			(at -5.199888 -5.999988 180)
			(size 0.4064 0.4064)
			(layers "F.Cu" "F.Mask" "F.Paste")
			(net "P1V0_STBY_PLAVDD")
		)
		(pad "F8" smd circle
			(at -4.400042 -5.999988 180)
			(size 0.4064 0.4064)
			(layers "F.Cu" "F.Mask" "F.Paste")
			(net "GND")
		)
		(pad "F9" smd circle
			(at -3.599942 -5.999988 180)
			(size 0.4064 0.4064)
			(layers "F.Cu" "F.Mask" "F.Paste")
			(net "P1V0_STBY_PLAVDD")
		)
		(pad "F10" smd circle
			(at -2.800096 -5.999988 180)
			(size 0.4064 0.4064)
			(layers "F.Cu" "F.Mask" "F.Paste")
			(net "GND")
		)
		(pad "F11" smd circle
			(at -1.999996 -5.999988 180)
			(size 0.4064 0.4064)
			(layers "F.Cu" "F.Mask" "F.Paste")
			(net "JTAG_SCM_NTRST")
		)
		(pad "F12" smd circle
			(at -1.199896 -5.999988 180)
			(size 0.4064 0.4064)
			(layers "F.Cu" "F.Mask" "F.Paste")
			(net "GND")
		)
		(pad "F13" smd circle
			(at -0.40005 -5.999988 180)
			(size 0.4064 0.4064)
			(layers "F.Cu" "F.Mask" "F.Paste")
			(net "SMB_BMC_MM8_R_SCL")
		)
		(pad "F14" smd circle
			(at 0.40005 -5.999988 180)
			(size 0.4064 0.4064)
			(layers "F.Cu" "F.Mask" "F.Paste")
			(net "GND")
		)
		(pad "F15" smd circle
			(at 1.199896 -5.999988 180)
			(size 0.4064 0.4064)
			(layers "F.Cu" "F.Mask" "F.Paste")
			(net "FM_JTAG_TCK_MUX_BMC_SEL_R1")
		)
		(pad "F16" smd circle
			(at 1.999996 -5.999988 180)
			(size 0.4064 0.4064)
			(layers "F.Cu" "F.Mask" "F.Paste")
			(net "GND")
		)
		(pad "F17" smd circle
			(at 2.800096 -5.999988 180)
			(size 0.4064 0.4064)
			(layers "F.Cu" "F.Mask" "F.Paste")
			(net "GND")
		)
		(pad "F18" smd circle
			(at 3.599942 -5.999988 180)
			(size 0.4064 0.4064)
			(layers "F.Cu" "F.Mask" "F.Paste")
			(net "GND")
		)
		(pad "F19" smd circle
			(at 4.400042 -5.999988 180)
			(size 0.4064 0.4064)
			(layers "F.Cu" "F.Mask" "F.Paste")
			(net "P3V3_P1V8_I2C_I3C")
		)
		(pad "F20" smd circle
			(at 5.199888 -5.999988 180)
			(size 0.4064 0.4064)
			(layers "F.Cu" "F.Mask" "F.Paste")
			(net "P3V3_P1V8_I2C_I3C")
		)
		(pad "F21" smd circle
			(at 5.999988 -5.999988 180)
			(size 0.4064 0.4064)
			(layers "F.Cu" "F.Mask" "F.Paste")
			(net "GND")
		)
		(pad "F22" smd circle
			(at 6.800088 -5.999988 180)
			(size 0.4064 0.4064)
			(layers "F.Cu" "F.Mask" "F.Paste")
			(net "H_CPU_CATERR_LVC2_R2_N")
		)
		(pad "F23" smd circle
			(at 7.599934 -5.999988 180)
			(size 0.4064 0.4064)
			(layers "F.Cu" "F.Mask" "F.Paste")
			(net "GPU_FPGA_RST_N")
		)
		(pad "F24" smd circle
			(at 8.400034 -5.999988 180)
			(size 0.4064 0.4064)
			(layers "F.Cu" "F.Mask" "F.Paste")
			(net "IRQ_SML0_ALERT_R_N")
		)
		(pad "F25" smd circle
			(at 9.19988 -5.999988 180)
			(size 0.4064 0.4064)
			(layers "F.Cu" "F.Mask" "F.Paste")
			(net "FM_BIC_DEBUG_SW_N_R")
		)
		(pad "F26" smd circle
			(at 9.99998 -5.999988 180)
			(size 0.4064 0.4064)
			(layers "F.Cu" "F.Mask" "F.Paste")
			(net "CLK_BUF1_GPU_FPGA_OE_R_N")
		)
		(pad "G1" smd circle
			(at -9.99998 -5.199888 180)
			(size 0.4064 0.4064)
			(layers "F.Cu" "F.Mask" "F.Paste")
			(net "M_BMC_DDR4_MA<11>")
		)
		(pad "G2" smd circle
			(at -9.19988 -5.199888 180)
			(size 0.4064 0.4064)
			(layers "F.Cu" "F.Mask" "F.Paste")
			(net "GND")
		)
		(pad "G3" smd circle
			(at -8.400034 -5.199888 180)
			(size 0.4064 0.4064)
			(layers "F.Cu" "F.Mask" "F.Paste")
			(net "M_BMC_DDR4_MBG0")
		)
		(pad "G4" smd circle
			(at -7.599934 -5.199888 180)
			(size 0.4064 0.4064)
			(layers "F.Cu" "F.Mask" "F.Paste")
			(net "M_BMC_DDR4_MBA0")
		)
		(pad "G5" smd circle
			(at -6.800088 -5.199888 180)
			(size 0.4064 0.4064)
			(layers "F.Cu" "F.Mask" "F.Paste")
			(net "M_BMC_DDR4_MWE_N")
		)
		(pad "G6" smd circle
			(at -5.999988 -5.199888 180)
			(size 0.4064 0.4064)
			(layers "F.Cu" "F.Mask" "F.Paste")
			(net "P1V2_AUX")
		)
		(pad "G21" smd circle
			(at 5.999988 -5.199888 180)
			(size 0.4064 0.4064)
			(layers "F.Cu" "F.Mask" "F.Paste")
			(net "P3V3_P1V8_SD1VDD")
		)
		(pad "G22" smd circle
			(at 6.800088 -5.199888 180)
			(size 0.4064 0.4064)
			(layers "F.Cu" "F.Mask" "F.Paste")
			(net "RST_ROT_CPU_R1_N")
		)
		(pad "G23" smd circle
			(at 7.599934 -5.199888 180)
			(size 0.4064 0.4064)
			(layers "F.Cu" "F.Mask" "F.Paste")
			(net "FM_JTAG_SEL")
		)
		(pad "G24" smd circle
			(at 8.400034 -5.199888 180)
			(size 0.4064 0.4064)
			(layers "F.Cu" "F.Mask" "F.Paste")
			(net "IRQ_SGPIO_BMC_N")
		)
		(pad "G25" smd circle
			(at 9.19988 -5.199888 180)
			(size 0.4064 0.4064)
			(layers "F.Cu" "F.Mask" "F.Paste")
			(net "GND")
		)
		(pad "G26" smd circle
			(at 9.99998 -5.199888 180)
			(size 0.4064 0.4064)
			(layers "F.Cu" "F.Mask" "F.Paste")
			(net "FM_ID_LED")
		)
		(pad "H1" smd circle
			(at -9.99998 -4.400042 180)
			(size 0.4064 0.4064)
			(layers "F.Cu" "F.Mask" "F.Paste")
			(net "M_BMC_DDR4_MACT_N")
		)
		(pad "H2" smd circle
			(at -9.19988 -4.400042 180)
			(size 0.4064 0.4064)
			(layers "F.Cu" "F.Mask" "F.Paste")
			(net "M_BMC_DDR4_MCS_N")
		)
		(pad "H3" smd circle
			(at -8.400034 -4.400042 180)
			(size 0.4064 0.4064)
			(layers "F.Cu" "F.Mask" "F.Paste")
			(net "M_BMC_DDR4_MA<3>")
		)
		(pad "H4" smd circle
			(at -7.599934 -4.400042 180)
			(size 0.4064 0.4064)
			(layers "F.Cu" "F.Mask" "F.Paste")
			(net "GND")
		)
		(pad "H5" smd circle
			(at -6.800088 -4.400042 180)
			(size 0.4064 0.4064)
			(layers "F.Cu" "F.Mask" "F.Paste")
			(net "M_BMC_DDR4_MBA1")
		)
		(pad "H6" smd circle
			(at -5.999988 -4.400042 180)
			(size 0.4064 0.4064)
			(layers "F.Cu" "F.Mask" "F.Paste")
			(net "P1V2_AUX")
		)
		(pad "H8" smd circle
			(at -4.400042 -4.400042 180)
			(size 0.4064 0.4064)
			(layers "F.Cu" "F.Mask" "F.Paste")
			(net "P1V8_AUX")
		)
		(pad "H9" smd circle
			(at -3.599942 -4.400042 180)
			(size 0.4064 0.4064)
			(layers "F.Cu" "F.Mask" "F.Paste")
			(net "GND")
		)
		(pad "H10" smd circle
			(at -2.800096 -4.400042 180)
			(size 0.4064 0.4064)
			(layers "F.Cu" "F.Mask" "F.Paste")
			(net "GND")
		)
		(pad "H11" smd circle
			(at -1.999996 -4.400042 180)
			(size 0.4064 0.4064)
			(layers "F.Cu" "F.Mask" "F.Paste")
			(net "GND")
		)
		(pad "H12" smd circle
			(at -1.199896 -4.400042 180)
			(size 0.4064 0.4064)
			(layers "F.Cu" "F.Mask" "F.Paste")
			(net "P1V8_AUX")
		)
		(pad "H13" smd circle
			(at -0.40005 -4.400042 180)
			(size 0.4064 0.4064)
			(layers "F.Cu" "F.Mask" "F.Paste")
			(net "GND")
		)
		(pad "H14" smd circle
			(at 0.40005 -4.400042 180)
			(size 0.4064 0.4064)
			(layers "F.Cu" "F.Mask" "F.Paste")
			(net "P3V3_STBY_PLLAHVDD")
		)
		(pad "H15" smd circle
			(at 1.199896 -4.400042 180)
			(size 0.4064 0.4064)
			(layers "F.Cu" "F.Mask" "F.Paste")
			(net "P3V3_AUX")
		)
		(pad "H16" smd circle
			(at 1.999996 -4.400042 180)
			(size 0.4064 0.4064)
			(layers "F.Cu" "F.Mask" "F.Paste")
			(net "P3V3_AUX")
		)
		(pad "H17" smd circle
			(at 2.800096 -4.400042 180)
			(size 0.4064 0.4064)
			(layers "F.Cu" "F.Mask" "F.Paste")
			(net "P3V3_AUX")
		)
		(pad "H18" smd circle
			(at 3.599942 -4.400042 180)
			(size 0.4064 0.4064)
			(layers "F.Cu" "F.Mask" "F.Paste")
			(net "P3V3_P1V8_SD2VDD")
		)
		(pad "H19" smd circle
			(at 4.400042 -4.400042 180)
			(size 0.4064 0.4064)
			(layers "F.Cu" "F.Mask" "F.Paste")
			(net "P3V3_P1V8_SD2VDD")
		)
		(pad "H21" smd circle
			(at 5.999988 -4.400042 180)
			(size 0.4064 0.4064)
			(layers "F.Cu" "F.Mask" "F.Paste")
			(net "P3V3_P1V8_SD1VDD")
		)
		(pad "H22" smd circle
			(at 6.800088 -4.400042 180)
			(size 0.4064 0.4064)
			(layers "F.Cu" "F.Mask" "F.Paste")
			(net "FM_BMC_CPU_FBRK_OUT_N")
		)
		(pad "H23" smd circle
			(at 7.599934 -4.400042 180)
			(size 0.4064 0.4064)
			(layers "F.Cu" "F.Mask" "F.Paste")
			(net "RST_SGPIO_RESET_BMC_N")
		)
		(pad "H24" smd circle
			(at 8.400034 -4.400042 180)
			(size 0.4064 0.4064)
			(layers "F.Cu" "F.Mask" "F.Paste")
			(net "RST_PLTRST_R_N")
		)
		(pad "H25" smd circle
			(at 9.19988 -4.400042 180)
			(size 0.4064 0.4064)
			(layers "F.Cu" "F.Mask" "F.Paste")
			(net "FM_ESPI_PLD_R1_EN")
		)
		(pad "H26" smd circle
			(at 9.99998 -4.400042 180)
			(size 0.4064 0.4064)
			(layers "F.Cu" "F.Mask" "F.Paste")
			(net "SMB_BMC_ALERT3_R_N")
		)
		(pad "J1" smd circle
			(at -9.99998 -3.599942 180)
			(size 0.4064 0.4064)
			(layers "F.Cu" "F.Mask" "F.Paste")
			(net "M_BMC_DDR4_MODT")
		)
		(pad "J2" smd circle
			(at -9.19988 -3.599942 180)
			(size 0.4064 0.4064)
			(layers "F.Cu" "F.Mask" "F.Paste")
			(net "GND")
		)
		(pad "J3" smd circle
			(at -8.400034 -3.599942 180)
			(size 0.4064 0.4064)
			(layers "F.Cu" "F.Mask" "F.Paste")
			(net "M_BMC_DDR4_MA<4>")
		)
		(pad "J4" smd circle
			(at -7.599934 -3.599942 180)
			(size 0.4064 0.4064)
			(layers "F.Cu" "F.Mask" "F.Paste")
			(net "M_BMC_DDR4_MCAS_N")
		)
		(pad "J5" smd circle
			(at -6.800088 -3.599942 180)
			(size 0.4064 0.4064)
			(layers "F.Cu" "F.Mask" "F.Paste")
			(net "M_BMC_DDR4_MRAS_N")
		)
		(pad "J6" smd circle
			(at -5.999988 -3.599942 180)
			(size 0.4064 0.4064)
			(layers "F.Cu" "F.Mask" "F.Paste")
			(net "P1V2_AUX")
		)
		(pad "J8" smd circle
			(at -4.400042 -3.599942 180)
			(size 0.4064 0.4064)
			(layers "F.Cu" "F.Mask" "F.Paste")
			(net "P1V8_AUX")
		)
		(pad "J9" smd circle
			(at -3.599942 -3.599942 180)
			(size 0.4064 0.4064)
			(layers "F.Cu" "F.Mask" "F.Paste")
			(net "P1V0_STBY_PLAVDD")
		)
		(pad "J10" smd circle
			(at -2.800096 -3.599942 180)
			(size 0.4064 0.4064)
			(layers "F.Cu" "F.Mask" "F.Paste")
			(net "P3V3_BMC_USB2AV33")
		)
		(pad "J11" smd circle
			(at -1.999996 -3.599942 180)
			(size 0.4064 0.4064)
			(layers "F.Cu" "F.Mask" "F.Paste")
			(net "GND")
		)
		(pad "J12" smd circle
			(at -1.199896 -3.599942 180)
			(size 0.4064 0.4064)
			(layers "F.Cu" "F.Mask" "F.Paste")
			(net "P1V8_AUX")
		)
		(pad "J13" smd circle
			(at -0.40005 -3.599942 180)
			(size 0.4064 0.4064)
			(layers "F.Cu" "F.Mask" "F.Paste")
			(net "GND")
		)
		(pad "J14" smd circle
			(at 0.40005 -3.599942 180)
			(size 0.4064 0.4064)
			(layers "F.Cu" "F.Mask" "F.Paste")
			(net "GND")
		)
		(pad "J15" smd circle
			(at 1.199896 -3.599942 180)
			(size 0.4064 0.4064)
			(layers "F.Cu" "F.Mask" "F.Paste")
			(net "GND")
		)
		(pad "J16" smd circle
			(at 1.999996 -3.599942 180)
			(size 0.4064 0.4064)
			(layers "F.Cu" "F.Mask" "F.Paste")
			(net "GND")
		)
		(pad "J17" smd circle
			(at 2.800096 -3.599942 180)
			(size 0.4064 0.4064)
			(layers "F.Cu" "F.Mask" "F.Paste")
			(net "GND")
		)
		(pad "J18" smd circle
			(at 3.599942 -3.599942 180)
			(size 0.4064 0.4064)
			(layers "F.Cu" "F.Mask" "F.Paste")
			(net "GND")
		)
		(pad "J19" smd circle
			(at 4.400042 -3.599942 180)
			(size 0.4064 0.4064)
			(layers "F.Cu" "F.Mask" "F.Paste")
			(net "GND")
		)
		(pad "J21" smd circle
			(at 5.999988 -3.599942 180)
			(size 0.4064 0.4064)
			(layers "F.Cu" "F.Mask" "F.Paste")
			(net "P3V3_P2V5_P1V8_RVDD")
		)
		(pad "J22" smd circle
			(at 6.800088 -3.599942 180)
			(size 0.4064 0.4064)
			(layers "F.Cu" "F.Mask" "F.Paste")
			(net "FM_CPU_RMCA_CATERR_LVT3_R_N")
		)
		(pad "J23" smd circle
			(at 7.599934 -3.599942 180)
			(size 0.4064 0.4064)
			(layers "F.Cu" "F.Mask" "F.Paste")
			(net "FM_BMC_MUX_CS_SPI_SEL_0")
		)
		(pad "J24" smd circle
			(at 8.400034 -3.599942 180)
			(size 0.4064 0.4064)
			(layers "F.Cu" "F.Mask" "F.Paste")
			(net "IRQ_BMC_CPU_NMI")
		)
		(pad "J25" smd circle
			(at 9.19988 -3.599942 180)
			(size 0.4064 0.4064)
			(layers "F.Cu" "F.Mask" "F.Paste")
			(net "SMB_BMC_ALERT4_R_N")
		)
		(pad "J26" smd circle
			(at 9.99998 -3.599942 180)
			(size 0.4064 0.4064)
			(layers "F.Cu" "F.Mask" "F.Paste")
			(net "FM_ME_BT_DONE")
		)
		(pad "K1" smd circle
			(at -9.99998 -2.800096 180)
			(size 0.4064 0.4064)
			(layers "F.Cu" "F.Mask" "F.Paste")
			(net "M_BMC_DDR4_MCLK_DN")
		)
		(pad "K2" smd circle
			(at -9.19988 -2.800096 180)
			(size 0.4064 0.4064)
			(layers "F.Cu" "F.Mask" "F.Paste")
			(net "M_BMC_DDR4_MCLK_DP")
		)
		(pad "K3" smd circle
			(at -8.400034 -2.800096 180)
			(size 0.4064 0.4064)
			(layers "F.Cu" "F.Mask" "F.Paste")
			(net "M_BMC_DDR4_MA<13>")
		)
		(pad "K4" smd circle
			(at -7.599934 -2.800096 180)
			(size 0.4064 0.4064)
			(layers "F.Cu" "F.Mask" "F.Paste")
			(net "GND")
		)
		(pad "K5" smd circle
			(at -6.800088 -2.800096 180)
			(size 0.4064 0.4064)
			(layers "F.Cu" "F.Mask" "F.Paste")
			(net "M_BMC_DDR4_MA<1>")
		)
		(pad "K6" smd circle
			(at -5.999988 -2.800096 180)
			(size 0.4064 0.4064)
			(layers "F.Cu" "F.Mask" "F.Paste")
			(net "P1V2_AUX")
		)
		(pad "K8" smd circle
			(at -4.400042 -2.800096 180)
			(size 0.4064 0.4064)
			(layers "F.Cu" "F.Mask" "F.Paste")
			(net "GND")
		)
		(pad "K9" smd circle
			(at -3.599942 -2.800096 180)
			(size 0.4064 0.4064)
			(layers "F.Cu" "F.Mask" "F.Paste")
			(net "GND")
		)
		(pad "K10" smd circle
			(at -2.800096 -2.800096 180)
			(size 0.4064 0.4064)
			(layers "F.Cu" "F.Mask" "F.Paste")
			(net "P1V8_BMC_USB2AV18")
		)
		(pad "K11" smd circle
			(at -1.999996 -2.800096 180)
			(size 0.4064 0.4064)
			(layers "F.Cu" "F.Mask" "F.Paste")
			(net "P3V3_RGM")
		)
		(pad "K12" smd circle
			(at -1.199896 -2.800096 180)
			(size 0.4064 0.4064)
			(layers "F.Cu" "F.Mask" "F.Paste")
			(net "P3V3_RGM")
		)
		(pad "K13" smd circle
			(at -0.40005 -2.800096 180)
			(size 0.4064 0.4064)
			(layers "F.Cu" "F.Mask" "F.Paste")
			(net "GND")
		)
		(pad "K14" smd circle
			(at 0.40005 -2.800096 180)
			(size 0.4064 0.4064)
			(layers "F.Cu" "F.Mask" "F.Paste")
			(net "GND")
		)
		(pad "K15" smd circle
			(at 1.199896 -2.800096 180)
			(size 0.4064 0.4064)
			(layers "F.Cu" "F.Mask" "F.Paste")
			(net "GND")
		)
		(pad "K16" smd circle
			(at 1.999996 -2.800096 180)
			(size 0.4064 0.4064)
			(layers "F.Cu" "F.Mask" "F.Paste")
			(net "P1V2_AUX")
		)
		(pad "K17" smd circle
			(at 2.800096 -2.800096 180)
			(size 0.4064 0.4064)
			(layers "F.Cu" "F.Mask" "F.Paste")
			(net "P1V2_AUX")
		)
		(pad "K18" smd circle
			(at 3.599942 -2.800096 180)
			(size 0.4064 0.4064)
			(layers "F.Cu" "F.Mask" "F.Paste")
			(net "P1V2_AUX")
		)
		(pad "K19" smd circle
			(at 4.400042 -2.800096 180)
			(size 0.4064 0.4064)
			(layers "F.Cu" "F.Mask" "F.Paste")
			(net "P1V2_AUX")
		)
		(pad "K21" smd circle
			(at 5.999988 -2.800096 180)
			(size 0.4064 0.4064)
			(layers "F.Cu" "F.Mask" "F.Paste")
			(net "P3V3_P2V5_P1V8_RVDD")
		)
		(pad "K22" smd circle
			(at 6.800088 -2.800096 180)
			(size 0.4064 0.4064)
			(layers "F.Cu" "F.Mask" "F.Paste")
			(net "GND")
		)
		(pad "K23" smd circle
			(at 7.599934 -2.800096 180)
			(size 0.4064 0.4064)
			(layers "F.Cu" "F.Mask" "F.Paste")
			(net "VOL_SEN_ALERT_R")
		)
		(pad "K24" smd circle
			(at 8.400034 -2.800096 180)
			(size 0.4064 0.4064)
			(layers "F.Cu" "F.Mask" "F.Paste")
			(net "SMB_BMC_MM12_R_SDA")
		)
		(pad "K25" smd circle
			(at 9.19988 -2.800096 180)
			(size 0.4064 0.4064)
			(layers "F.Cu" "F.Mask" "F.Paste")
			(net "SMB_BMC_MM14_R_SDA")
		)
		(pad "K26" smd circle
			(at 9.99998 -2.800096 180)
			(size 0.4064 0.4064)
			(layers "F.Cu" "F.Mask" "F.Paste")
			(net "SMB_BMC_MM13_R_SCL")
		)
		(pad "L1" smd circle
			(at -9.99998 -1.999996 180)
			(size 0.4064 0.4064)
			(layers "F.Cu" "F.Mask" "F.Paste")
			(net "M_BMC_DDR4_MA<5>")
		)
		(pad "L2" smd circle
			(at -9.19988 -1.999996 180)
			(size 0.4064 0.4064)
			(layers "F.Cu" "F.Mask" "F.Paste")
			(net "GND")
		)
		(pad "L3" smd circle
			(at -8.400034 -1.999996 180)
			(size 0.4064 0.4064)
			(layers "F.Cu" "F.Mask" "F.Paste")
			(net "M_BMC_DDR4_RST_N")
		)
		(pad "L4" smd circle
			(at -7.599934 -1.999996 180)
			(size 0.4064 0.4064)
			(layers "F.Cu" "F.Mask" "F.Paste")
			(net "M_BMC_DDR4_MA<12>")
		)
		(pad "L5" smd circle
			(at -6.800088 -1.999996 180)
			(size 0.4064 0.4064)
			(layers "F.Cu" "F.Mask" "F.Paste")
			(net "M_BMC_DDR4_MCKE")
		)
		(pad "L6" smd circle
			(at -5.999988 -1.999996 180)
			(size 0.4064 0.4064)
			(layers "F.Cu" "F.Mask" "F.Paste")
			(net "P1V2_AUX")
		)
		(pad "L8" smd circle
			(at -4.400042 -1.999996 180)
			(size 0.4064 0.4064)
			(layers "F.Cu" "F.Mask" "F.Paste")
			(net "GND")
		)
		(pad "L9" smd circle
			(at -3.599942 -1.999996 180)
			(size 0.4064 0.4064)
			(layers "F.Cu" "F.Mask" "F.Paste")
			(net "P1V0_AUX")
		)
		(pad "L10" smd circle
			(at -2.800096 -1.999996 180)
			(size 0.4064 0.4064)
			(layers "F.Cu" "F.Mask" "F.Paste")
			(net "P1V0_AUX")
		)
		(pad "L11" smd circle
			(at -1.999996 -1.999996 180)
			(size 0.4064 0.4064)
			(layers "F.Cu" "F.Mask" "F.Paste")
			(net "GND")
		)
		(pad "L12" smd circle
			(at -1.199896 -1.999996 180)
			(size 0.4064 0.4064)
			(layers "F.Cu" "F.Mask" "F.Paste")
			(net "GND")
		)
		(pad "L13" smd circle
			(at -0.40005 -1.999996 180)
			(size 0.4064 0.4064)
			(layers "F.Cu" "F.Mask" "F.Paste")
			(net "P1V8_AUX")
		)
		(pad "L14" smd circle
			(at 0.40005 -1.999996 180)
			(size 0.4064 0.4064)
			(layers "F.Cu" "F.Mask" "F.Paste")
			(net "P1V2_AUX")
		)
		(pad "L15" smd circle
			(at 1.199896 -1.999996 180)
			(size 0.4064 0.4064)
			(layers "F.Cu" "F.Mask" "F.Paste")
			(net "GND")
		)
		(pad "L16" smd circle
			(at 1.999996 -1.999996 180)
			(size 0.4064 0.4064)
			(layers "F.Cu" "F.Mask" "F.Paste")
			(net "GND")
		)
		(pad "L17" smd circle
			(at 2.800096 -1.999996 180)
			(size 0.4064 0.4064)
			(layers "F.Cu" "F.Mask" "F.Paste")
			(net "GND")
		)
		(pad "L18" smd circle
			(at 3.599942 -1.999996 180)
			(size 0.4064 0.4064)
			(layers "F.Cu" "F.Mask" "F.Paste")
			(net "GND")
		)
		(pad "L19" smd circle
			(at 4.400042 -1.999996 180)
			(size 0.4064 0.4064)
			(layers "F.Cu" "F.Mask" "F.Paste")
			(net "GND")
		)
		(pad "L21" smd circle
			(at 5.999988 -1.999996 180)
			(size 0.4064 0.4064)
			(layers "F.Cu" "F.Mask" "F.Paste")
			(net "P1V2_AUX")
		)
		(pad "L22" smd circle
			(at 6.800088 -1.999996 180)
			(size 0.4064 0.4064)
			(layers "F.Cu" "F.Mask" "F.Paste")
			(net "P3V3_P2V5_P1V8_RVDD")
		)
		(pad "L23" smd circle
			(at 7.599934 -1.999996 180)
			(size 0.4064 0.4064)
			(layers "F.Cu" "F.Mask" "F.Paste")
			(net "SMB_BMC_MM14_R_SCL")
		)
		(pad "L24" smd circle
			(at 8.400034 -1.999996 180)
			(size 0.4064 0.4064)
			(layers "F.Cu" "F.Mask" "F.Paste")
			(net "SMB_BMC_MM13_R_SDA")
		)
		(pad "L25" smd circle
			(at 9.19988 -1.999996 180)
			(size 0.4064 0.4064)
			(layers "F.Cu" "F.Mask" "F.Paste")
			(net "GND")
		)
		(pad "L26" smd circle
			(at 9.99998 -1.999996 180)
			(size 0.4064 0.4064)
			(layers "F.Cu" "F.Mask" "F.Paste")
			(net "SMB_BMC_MM12_R_SCL")
		)
		(pad "M1" smd circle
			(at -9.99998 -1.199896 180)
			(size 0.4064 0.4064)
			(layers "F.Cu" "F.Mask" "F.Paste")
			(net "M_BMC_DDR4_MA<8>")
		)
		(pad "M2" smd circle
			(at -9.19988 -1.199896 180)
			(size 0.4064 0.4064)
			(layers "F.Cu" "F.Mask" "F.Paste")
			(net "M_BMC_DDR4_MA<7>")
		)
		(pad "M3" smd circle
			(at -8.400034 -1.199896 180)
			(size 0.4064 0.4064)
			(layers "F.Cu" "F.Mask" "F.Paste")
			(net "M_BMC_DDR4_MBG1")
		)
		(pad "M4" smd circle
			(at -7.599934 -1.199896 180)
			(size 0.4064 0.4064)
			(layers "F.Cu" "F.Mask" "F.Paste")
			(net "GND")
		)
		(pad "M5" smd circle
			(at -6.800088 -1.199896 180)
			(size 0.4064 0.4064)
			(layers "F.Cu" "F.Mask" "F.Paste")
			(net "M_BMC_DDR4_MA<6>")
		)
		(pad "M6" smd circle
			(at -5.999988 -1.199896 180)
			(size 0.4064 0.4064)
			(layers "F.Cu" "F.Mask" "F.Paste")
			(net "P1V2_STBY_MVDD_CK")
		)
		(pad "M8" smd circle
			(at -4.400042 -1.199896 180)
			(size 0.4064 0.4064)
			(layers "F.Cu" "F.Mask" "F.Paste")
			(net "P1V0_AUX")
		)
		(pad "M9" smd circle
			(at -3.599942 -1.199896 180)
			(size 0.4064 0.4064)
			(layers "F.Cu" "F.Mask" "F.Paste")
			(net "GND")
		)
		(pad "M10" smd circle
			(at -2.800096 -1.199896 180)
			(size 0.4064 0.4064)
			(layers "F.Cu" "F.Mask" "F.Paste")
			(net "GND")
		)
		(pad "M11" smd circle
			(at -1.999996 -1.199896 180)
			(size 0.4064 0.4064)
			(layers "F.Cu" "F.Mask" "F.Paste")
			(net "P1V0_AUX")
		)
		(pad "M12" smd circle
			(at -1.199896 -1.199896 180)
			(size 0.4064 0.4064)
			(layers "F.Cu" "F.Mask" "F.Paste")
			(net "GND")
		)
		(pad "M13" smd circle
			(at -0.40005 -1.199896 180)
			(size 0.4064 0.4064)
			(layers "F.Cu" "F.Mask" "F.Paste")
			(net "P1V8_AUX")
		)
		(pad "M14" smd circle
			(at 0.40005 -1.199896 180)
			(size 0.4064 0.4064)
			(layers "F.Cu" "F.Mask" "F.Paste")
			(net "P1V2_AUX")
		)
		(pad "M15" smd circle
			(at 1.199896 -1.199896 180)
			(size 0.4064 0.4064)
			(layers "F.Cu" "F.Mask" "F.Paste")
			(net "GND")
		)
		(pad "M16" smd circle
			(at 1.999996 -1.199896 180)
			(size 0.4064 0.4064)
			(layers "F.Cu" "F.Mask" "F.Paste")
			(net "GND")
		)
		(pad "M17" smd circle
			(at 2.800096 -1.199896 180)
			(size 0.4064 0.4064)
			(layers "F.Cu" "F.Mask" "F.Paste")
			(net "GND")
		)
		(pad "M18" smd circle
			(at 3.599942 -1.199896 180)
			(size 0.4064 0.4064)
			(layers "F.Cu" "F.Mask" "F.Paste")
			(net "GND")
		)
		(pad "M19" smd circle
			(at 4.400042 -1.199896 180)
			(size 0.4064 0.4064)
			(layers "F.Cu" "F.Mask" "F.Paste")
			(net "GND")
		)
		(pad "M21" smd circle
			(at 5.999988 -1.199896 180)
			(size 0.4064 0.4064)
			(layers "F.Cu" "F.Mask" "F.Paste")
			(net "P1V2_AUX")
		)
		(pad "M22" smd circle
			(at 6.800088 -1.199896 180)
			(size 0.4064 0.4064)
			(layers "F.Cu" "F.Mask" "F.Paste")
			(net "P3V3_P2V5_P1V8_RVDD")
		)
		(pad "M23" smd circle
			(at 7.599934 -1.199896 180)
			(size 0.4064 0.4064)
			(layers "F.Cu" "F.Mask" "F.Paste")
			(net "LED_POSTCODE_5")
		)
		(pad "M24" smd circle
			(at 8.400034 -1.199896 180)
			(size 0.4064 0.4064)
			(layers "F.Cu" "F.Mask" "F.Paste")
			(net "FM_PFR_DSW_PWROK_N")
		)
		(pad "M25" smd circle
			(at 9.19988 -1.199896 180)
			(size 0.4064 0.4064)
			(layers "F.Cu" "F.Mask" "F.Paste")
			(net "RST_PFR_OVR_RTC_R")
		)
		(pad "M26" smd circle
			(at 9.99998 -1.199896 180)
			(size 0.4064 0.4064)
			(layers "F.Cu" "F.Mask" "F.Paste")
			(net "LED_POSTCODE_7")
		)
		(pad "N1" smd circle
			(at -9.99998 -0.40005 180)
			(size 0.4064 0.4064)
			(layers "F.Cu" "F.Mask" "F.Paste")
			(net "M_BMC_DDR4_MA<9>")
		)
		(pad "N2" smd circle
			(at -9.19988 -0.40005 180)
			(size 0.4064 0.4064)
			(layers "F.Cu" "F.Mask" "F.Paste")
			(net "GND")
		)
		(pad "N3" smd circle
			(at -8.400034 -0.40005 180)
			(size 0.4064 0.4064)
			(layers "F.Cu" "F.Mask" "F.Paste")
			(net "M_BMC_DDR4_MDM0")
		)
		(pad "N4" smd circle
			(at -7.599934 -0.40005 180)
			(size 0.4064 0.4064)
			(layers "F.Cu" "F.Mask" "F.Paste")
			(net "M_BMC_DDR4_ALERT_N")
		)
		(pad "N5" smd circle
			(at -6.800088 -0.40005 180)
			(size 0.4064 0.4064)
			(layers "F.Cu" "F.Mask" "F.Paste")
			(net "P1V8_STBY_AVDDPLL")
		)
		(pad "N6" smd circle
			(at -5.999988 -0.40005 180)
			(size 0.4064 0.4064)
			(layers "F.Cu" "F.Mask" "F.Paste")
			(net "GND")
		)
		(pad "N8" smd circle
			(at -4.400042 -0.40005 180)
			(size 0.4064 0.4064)
			(layers "F.Cu" "F.Mask" "F.Paste")
			(net "P1V0_AUX")
		)
		(pad "N9" smd circle
			(at -3.599942 -0.40005 180)
			(size 0.4064 0.4064)
			(layers "F.Cu" "F.Mask" "F.Paste")
			(net "GND")
		)
		(pad "N10" smd circle
			(at -2.800096 -0.40005 180)
			(size 0.4064 0.4064)
			(layers "F.Cu" "F.Mask" "F.Paste")
			(net "GND")
		)
		(pad "N11" smd circle
			(at -1.999996 -0.40005 180)
			(size 0.4064 0.4064)
			(layers "F.Cu" "F.Mask" "F.Paste")
			(net "P1V0_AUX")
		)
		(pad "N12" smd circle
			(at -1.199896 -0.40005 180)
			(size 0.4064 0.4064)
			(layers "F.Cu" "F.Mask" "F.Paste")
			(net "P1V8_AUX")
		)
		(pad "N13" smd circle
			(at -0.40005 -0.40005 180)
			(size 0.4064 0.4064)
			(layers "F.Cu" "F.Mask" "F.Paste")
			(net "P1V8_AUX")
		)
		(pad "N14" smd circle
			(at 0.40005 -0.40005 180)
			(size 0.4064 0.4064)
			(layers "F.Cu" "F.Mask" "F.Paste")
			(net "P1V2_AUX")
		)
		(pad "N15" smd circle
			(at 1.199896 -0.40005 180)
			(size 0.4064 0.4064)
			(layers "F.Cu" "F.Mask" "F.Paste")
			(net "GND")
		)
		(pad "N16" smd circle
			(at 1.999996 -0.40005 180)
			(size 0.4064 0.4064)
			(layers "F.Cu" "F.Mask" "F.Paste")
			(net "GND")
		)
		(pad "N17" smd circle
			(at 2.800096 -0.40005 180)
			(size 0.4064 0.4064)
			(layers "F.Cu" "F.Mask" "F.Paste")
			(net "GND")
		)
		(pad "N18" smd circle
			(at 3.599942 -0.40005 180)
			(size 0.4064 0.4064)
			(layers "F.Cu" "F.Mask" "F.Paste")
			(net "GND")
		)
		(pad "N19" smd circle
			(at 4.400042 -0.40005 180)
			(size 0.4064 0.4064)
			(layers "F.Cu" "F.Mask" "F.Paste")
			(net "GND")
		)
		(pad "N21" smd circle
			(at 5.999988 -0.40005 180)
			(size 0.4064 0.4064)
			(layers "F.Cu" "F.Mask" "F.Paste")
			(net "P1V2_AUX")
		)
		(pad "N22" smd circle
			(at 6.800088 -0.40005 180)
			(size 0.4064 0.4064)
			(layers "F.Cu" "F.Mask" "F.Paste")
			(net "P3V3_AUX")
		)
		(pad "N23" smd circle
			(at 7.599934 -0.40005 180)
			(size 0.4064 0.4064)
			(layers "F.Cu" "F.Mask" "F.Paste")
			(net "LED_POSTCODE_1")
		)
		(pad "N24" smd circle
			(at 8.400034 -0.40005 180)
			(size 0.4064 0.4064)
			(layers "F.Cu" "F.Mask" "F.Paste")
			(net "LED_POSTCODE_3")
		)
		(pad "N25" smd circle
			(at 9.19988 -0.40005 180)
			(size 0.4064 0.4064)
			(layers "F.Cu" "F.Mask" "F.Paste")
			(net "LED_POSTCODE_2")
		)
		(pad "N26" smd circle
			(at 9.99998 -0.40005 180)
			(size 0.4064 0.4064)
			(layers "F.Cu" "F.Mask" "F.Paste")
			(net "LED_POSTCODE_6")
		)
		(pad "P1" smd circle
			(at -9.99998 0.40005 180)
			(size 0.4064 0.4064)
			(layers "F.Cu" "F.Mask" "F.Paste")
			(net "M_BMC_DDR4_DQ<5>")
		)
		(pad "P2" smd circle
			(at -9.19988 0.40005 180)
			(size 0.4064 0.4064)
			(layers "F.Cu" "F.Mask" "F.Paste")
			(net "M_BMC_DDR4_DQ<6>")
		)
		(pad "P3" smd circle
			(at -8.400034 0.40005 180)
			(size 0.4064 0.4064)
			(layers "F.Cu" "F.Mask" "F.Paste")
			(net "M_BMC_DDR4_DQ<7>")
		)
		(pad "P4" smd circle
			(at -7.599934 0.40005 180)
			(size 0.4064 0.4064)
			(layers "F.Cu" "F.Mask" "F.Paste")
			(net "GND")
		)
		(pad "P5" smd circle
			(at -6.800088 0.40005 180)
			(size 0.4064 0.4064)
			(layers "F.Cu" "F.Mask" "F.Paste")
			(net "IBMC_MIOZ")
		)
		(pad "P6" smd circle
			(at -5.999988 0.40005 180)
			(size 0.4064 0.4064)
			(layers "F.Cu" "F.Mask" "F.Paste")
			(net "P1V2_AUX")
		)
		(pad "P8" smd circle
			(at -4.400042 0.40005 180)
			(size 0.4064 0.4064)
			(layers "F.Cu" "F.Mask" "F.Paste")
			(net "P1V0_AUX")
		)
		(pad "P9" smd circle
			(at -3.599942 0.40005 180)
			(size 0.4064 0.4064)
			(layers "F.Cu" "F.Mask" "F.Paste")
			(net "GND")
		)
		(pad "P10" smd circle
			(at -2.800096 0.40005 180)
			(size 0.4064 0.4064)
			(layers "F.Cu" "F.Mask" "F.Paste")
			(net "GND")
		)
		(pad "P11" smd circle
			(at -1.999996 0.40005 180)
			(size 0.4064 0.4064)
			(layers "F.Cu" "F.Mask" "F.Paste")
			(net "P1V0_AUX")
		)
		(pad "P12" smd circle
			(at -1.199896 0.40005 180)
			(size 0.4064 0.4064)
			(layers "F.Cu" "F.Mask" "F.Paste")
			(net "P1V8_AUX")
		)
		(pad "P13" smd circle
			(at -0.40005 0.40005 180)
			(size 0.4064 0.4064)
			(layers "F.Cu" "F.Mask" "F.Paste")
			(net "P1V8_AUX")
		)
		(pad "P14" smd circle
			(at 0.40005 0.40005 180)
			(size 0.4064 0.4064)
			(layers "F.Cu" "F.Mask" "F.Paste")
			(net "P1V2_AUX")
		)
		(pad "P15" smd circle
			(at 1.199896 0.40005 180)
			(size 0.4064 0.4064)
			(layers "F.Cu" "F.Mask" "F.Paste")
			(net "GND")
		)
		(pad "P16" smd circle
			(at 1.999996 0.40005 180)
			(size 0.4064 0.4064)
			(layers "F.Cu" "F.Mask" "F.Paste")
			(net "GND")
		)
		(pad "P17" smd circle
			(at 2.800096 0.40005 180)
			(size 0.4064 0.4064)
			(layers "F.Cu" "F.Mask" "F.Paste")
			(net "GND")
		)
		(pad "P18" smd circle
			(at 3.599942 0.40005 180)
			(size 0.4064 0.4064)
			(layers "F.Cu" "F.Mask" "F.Paste")
			(net "GND")
		)
		(pad "P19" smd circle
			(at 4.400042 0.40005 180)
			(size 0.4064 0.4064)
			(layers "F.Cu" "F.Mask" "F.Paste")
			(net "GND")
		)
		(pad "P21" smd circle
			(at 5.999988 0.40005 180)
			(size 0.4064 0.4064)
			(layers "F.Cu" "F.Mask" "F.Paste")
			(net "P1V2_AUX")
		)
		(pad "P22" smd circle
			(at 6.800088 0.40005 180)
			(size 0.4064 0.4064)
			(layers "F.Cu" "F.Mask" "F.Paste")
			(net "P3V3_AUX")
		)
		(pad "P23" smd circle
			(at 7.599934 0.40005 180)
			(size 0.4064 0.4064)
			(layers "F.Cu" "F.Mask" "F.Paste")
			(net "RST_PCA9548_SENSOR_R_N")
		)
		(pad "P24" smd circle
			(at 8.400034 0.40005 180)
			(size 0.4064 0.4064)
			(layers "F.Cu" "F.Mask" "F.Paste")
			(net "H_CPU1_PROCHOT_LVC1_N")
		)
		(pad "P25" smd circle
			(at 9.19988 0.40005 180)
			(size 0.4064 0.4064)
			(layers "F.Cu" "F.Mask" "F.Paste")
			(net "LED_POSTCODE_0")
		)
		(pad "P26" smd circle
			(at 9.99998 0.40005 180)
			(size 0.4064 0.4064)
			(layers "F.Cu" "F.Mask" "F.Paste")
			(net "LED_POSTCODE_4")
		)
		(pad "R1" smd circle
			(at -9.99998 1.199896 180)
			(size 0.4064 0.4064)
			(layers "F.Cu" "F.Mask" "F.Paste")
			(net "M_BMC_DDR4_DQ<4>")
		)
		(pad "R2" smd circle
			(at -9.19988 1.199896 180)
			(size 0.4064 0.4064)
			(layers "F.Cu" "F.Mask" "F.Paste")
			(net "GND")
		)
		(pad "R3" smd circle
			(at -8.400034 1.199896 180)
			(size 0.4064 0.4064)
			(layers "F.Cu" "F.Mask" "F.Paste")
			(net "M_BMC_DDR4_DQ<3>")
		)
		(pad "R4" smd circle
			(at -7.599934 1.199896 180)
			(size 0.4064 0.4064)
			(layers "F.Cu" "F.Mask" "F.Paste")
			(net "M_BMC_DDR4_DQ<1>")
		)
		(pad "R5" smd circle
			(at -6.800088 1.199896 180)
			(size 0.4064 0.4064)
			(layers "F.Cu" "F.Mask" "F.Paste")
			(net "M_BMC_DDR4_MDM1")
		)
		(pad "R6" smd circle
			(at -5.999988 1.199896 180)
			(size 0.4064 0.4064)
			(layers "F.Cu" "F.Mask" "F.Paste")
			(net "P1V2_AUX")
		)
		(pad "R8" smd circle
			(at -4.400042 1.199896 180)
			(size 0.4064 0.4064)
			(layers "F.Cu" "F.Mask" "F.Paste")
			(net "GND")
		)
		(pad "R9" smd circle
			(at -3.599942 1.199896 180)
			(size 0.4064 0.4064)
			(layers "F.Cu" "F.Mask" "F.Paste")
			(net "P1V0_AUX")
		)
		(pad "R10" smd circle
			(at -2.800096 1.199896 180)
			(size 0.4064 0.4064)
			(layers "F.Cu" "F.Mask" "F.Paste")
			(net "P1V0_AUX")
		)
		(pad "R11" smd circle
			(at -1.999996 1.199896 180)
			(size 0.4064 0.4064)
			(layers "F.Cu" "F.Mask" "F.Paste")
			(net "GND")
		)
		(pad "R12" smd circle
			(at -1.199896 1.199896 180)
			(size 0.4064 0.4064)
			(layers "F.Cu" "F.Mask" "F.Paste")
			(net "P1V8_AUX")
		)
		(pad "R13" smd circle
			(at -0.40005 1.199896 180)
			(size 0.4064 0.4064)
			(layers "F.Cu" "F.Mask" "F.Paste")
			(net "P1V8_AUX")
		)
		(pad "R14" smd circle
			(at 0.40005 1.199896 180)
			(size 0.4064 0.4064)
			(layers "F.Cu" "F.Mask" "F.Paste")
			(net "P1V2_AUX")
		)
		(pad "R15" smd circle
			(at 1.199896 1.199896 180)
			(size 0.4064 0.4064)
			(layers "F.Cu" "F.Mask" "F.Paste")
			(net "GND")
		)
		(pad "R16" smd circle
			(at 1.999996 1.199896 180)
			(size 0.4064 0.4064)
			(layers "F.Cu" "F.Mask" "F.Paste")
			(net "GND")
		)
		(pad "R17" smd circle
			(at 2.800096 1.199896 180)
			(size 0.4064 0.4064)
			(layers "F.Cu" "F.Mask" "F.Paste")
			(net "GND")
		)
		(pad "R18" smd circle
			(at 3.599942 1.199896 180)
			(size 0.4064 0.4064)
			(layers "F.Cu" "F.Mask" "F.Paste")
			(net "GND")
		)
		(pad "R19" smd circle
			(at 4.400042 1.199896 180)
			(size 0.4064 0.4064)
			(layers "F.Cu" "F.Mask" "F.Paste")
			(net "GND")
		)
		(pad "R21" smd circle
			(at 5.999988 1.199896 180)
			(size 0.4064 0.4064)
			(layers "F.Cu" "F.Mask" "F.Paste")
			(net "P1V2_AUX")
		)
		(pad "R22" smd circle
			(at 6.800088 1.199896 180)
			(size 0.4064 0.4064)
			(layers "F.Cu" "F.Mask" "F.Paste")
			(net "P3V3_AUX")
		)
		(pad "R23" smd circle
			(at 7.599934 1.199896 180)
			(size 0.4064 0.4064)
			(layers "F.Cu" "F.Mask" "F.Paste")
			(net "IRQ_BMC_PCH_NMI_N")
		)
		(pad "R24" smd circle
			(at 8.400034 1.199896 180)
			(size 0.4064 0.4064)
			(layers "F.Cu" "F.Mask" "F.Paste")
			(net "FM_TPM_PRSNT_1_N")
		)
		(pad "R25" smd circle
			(at 9.19988 1.199896 180)
			(size 0.4064 0.4064)
			(layers "F.Cu" "F.Mask" "F.Paste")
			(net "GND")
		)
		(pad "R26" smd circle
			(at 9.99998 1.199896 180)
			(size 0.4064 0.4064)
			(layers "F.Cu" "F.Mask" "F.Paste")
			(net "FM_BMC_DEBUG_SW_N")
		)
		(pad "T1" smd circle
			(at -9.99998 1.999996 180)
			(size 0.4064 0.4064)
			(layers "F.Cu" "F.Mask" "F.Paste")
			(net "M_BMC_DDR4_DQS0_N")
		)
		(pad "T2" smd circle
			(at -9.19988 1.999996 180)
			(size 0.4064 0.4064)
			(layers "F.Cu" "F.Mask" "F.Paste")
			(net "M_BMC_DDR4_DQS0_P")
		)
		(pad "T3" smd circle
			(at -8.400034 1.999996 180)
			(size 0.4064 0.4064)
			(layers "F.Cu" "F.Mask" "F.Paste")
			(net "M_BMC_DDR4_DQ<0>")
		)
		(pad "T4" smd circle
			(at -7.599934 1.999996 180)
			(size 0.4064 0.4064)
			(layers "F.Cu" "F.Mask" "F.Paste")
			(net "GND")
		)
		(pad "T5" smd circle
			(at -6.800088 1.999996 180)
			(size 0.4064 0.4064)
			(layers "F.Cu" "F.Mask" "F.Paste")
			(net "P0V6_DDR_VREF_AUX")
		)
		(pad "T6" smd circle
			(at -5.999988 1.999996 180)
			(size 0.4064 0.4064)
			(layers "F.Cu" "F.Mask" "F.Paste")
			(net "P1V2_AUX")
		)
		(pad "T8" smd circle
			(at -4.400042 1.999996 180)
			(size 0.4064 0.4064)
			(layers "F.Cu" "F.Mask" "F.Paste")
			(net "P1V0_STBY_DP_VCC10A")
		)
		(pad "T9" smd circle
			(at -3.599942 1.999996 180)
			(size 0.4064 0.4064)
			(layers "F.Cu" "F.Mask" "F.Paste")
			(net "P1V0_STBY_PE_VCC10A")
		)
		(pad "T10" smd circle
			(at -2.800096 1.999996 180)
			(size 0.4064 0.4064)
			(layers "F.Cu" "F.Mask" "F.Paste")
			(net "P1V0_STBY_RC_VCC10A")
		)
		(pad "T11" smd circle
			(at -1.999996 1.999996 180)
			(size 0.4064 0.4064)
			(layers "F.Cu" "F.Mask" "F.Paste")
			(net "GND")
		)
		(pad "T12" smd circle
			(at -1.199896 1.999996 180)
			(size 0.4064 0.4064)
			(layers "F.Cu" "F.Mask" "F.Paste")
			(net "GND")
		)
		(pad "T13" smd circle
			(at -0.40005 1.999996 180)
			(size 0.4064 0.4064)
			(layers "F.Cu" "F.Mask" "F.Paste")
			(net "P1V8_AUX")
		)
		(pad "T14" smd circle
			(at 0.40005 1.999996 180)
			(size 0.4064 0.4064)
			(layers "F.Cu" "F.Mask" "F.Paste")
			(net "P1V2_AUX")
		)
		(pad "T15" smd circle
			(at 1.199896 1.999996 180)
			(size 0.4064 0.4064)
			(layers "F.Cu" "F.Mask" "F.Paste")
			(net "GND")
		)
		(pad "T16" smd circle
			(at 1.999996 1.999996 180)
			(size 0.4064 0.4064)
			(layers "F.Cu" "F.Mask" "F.Paste")
			(net "GND")
		)
		(pad "T17" smd circle
			(at 2.800096 1.999996 180)
			(size 0.4064 0.4064)
			(layers "F.Cu" "F.Mask" "F.Paste")
			(net "GND")
		)
		(pad "T18" smd circle
			(at 3.599942 1.999996 180)
			(size 0.4064 0.4064)
			(layers "F.Cu" "F.Mask" "F.Paste")
			(net "GND")
		)
		(pad "T19" smd circle
			(at 4.400042 1.999996 180)
			(size 0.4064 0.4064)
			(layers "F.Cu" "F.Mask" "F.Paste")
			(net "GND")
		)
		(pad "T21" smd circle
			(at 5.999988 1.999996 180)
			(size 0.4064 0.4064)
			(layers "F.Cu" "F.Mask" "F.Paste")
			(net "P1V2_AUX")
		)
		(pad "T22" smd circle
			(at 6.800088 1.999996 180)
			(size 0.4064 0.4064)
			(layers "F.Cu" "F.Mask" "F.Paste")
			(net "P3V3_AUX")
		)
		(pad "T23" smd circle
			(at 7.599934 1.999996 180)
			(size 0.4064 0.4064)
			(layers "F.Cu" "F.Mask" "F.Paste")
			(net "PWRGD_PCH_PWROK")
		)
		(pad "T24" smd circle
			(at 8.400034 1.999996 180)
			(size 0.4064 0.4064)
			(layers "F.Cu" "F.Mask" "F.Paste")
			(net "BMC_CPLD_GPIO_2_R1")
		)
		(pad "T25" smd circle
			(at 9.19988 1.999996 180)
			(size 0.4064 0.4064)
			(layers "F.Cu" "F.Mask" "F.Paste")
			(net "BMC_MONITER")
		)
		(pad "T26" smd circle
			(at 9.99998 1.999996 180)
			(size 0.4064 0.4064)
			(layers "F.Cu" "F.Mask" "F.Paste")
			(net "FM_THERMTRIP_DLY_LVC1_R_N")
		)
		(pad "U1" smd circle
			(at -9.99998 2.800096 180)
			(size 0.4064 0.4064)
			(layers "F.Cu" "F.Mask" "F.Paste")
			(net "M_BMC_DDR4_DQ<2>")
		)
		(pad "U2" smd circle
			(at -9.19988 2.800096 180)
			(size 0.4064 0.4064)
			(layers "F.Cu" "F.Mask" "F.Paste")
			(net "GND")
		)
		(pad "U3" smd circle
			(at -8.400034 2.800096 180)
			(size 0.4064 0.4064)
			(layers "F.Cu" "F.Mask" "F.Paste")
			(net "M_BMC_DDR4_DQ<15>")
		)
		(pad "U4" smd circle
			(at -7.599934 2.800096 180)
			(size 0.4064 0.4064)
			(layers "F.Cu" "F.Mask" "F.Paste")
			(net "M_BMC_DDR4_DQ<13>")
		)
		(pad "U5" smd circle
			(at -6.800088 2.800096 180)
			(size 0.4064 0.4064)
			(layers "F.Cu" "F.Mask" "F.Paste")
			(net "P0V6_DDR_VREF_AUX")
		)
		(pad "U6" smd circle
			(at -5.999988 2.800096 180)
			(size 0.4064 0.4064)
			(layers "F.Cu" "F.Mask" "F.Paste")
			(net "P1V8_AUX")
		)
		(pad "U8" smd circle
			(at -4.400042 2.800096 180)
			(size 0.4064 0.4064)
			(layers "F.Cu" "F.Mask" "F.Paste")
			(net "GND")
		)
		(pad "U9" smd circle
			(at -3.599942 2.800096 180)
			(size 0.4064 0.4064)
			(layers "F.Cu" "F.Mask" "F.Paste")
			(net "GND")
		)
		(pad "U10" smd circle
			(at -2.800096 2.800096 180)
			(size 0.4064 0.4064)
			(layers "F.Cu" "F.Mask" "F.Paste")
			(net "GND")
		)
		(pad "U11" smd circle
			(at -1.999996 2.800096 180)
			(size 0.4064 0.4064)
			(layers "F.Cu" "F.Mask" "F.Paste")
			(net "GND")
		)
		(pad "U12" smd circle
			(at -1.199896 2.800096 180)
			(size 0.4064 0.4064)
			(layers "F.Cu" "F.Mask" "F.Paste")
			(net "GND")
		)
		(pad "U13" smd circle
			(at -0.40005 2.800096 180)
			(size 0.4064 0.4064)
			(layers "F.Cu" "F.Mask" "F.Paste")
			(net "P1V8_AUX")
		)
		(pad "U14" smd circle
			(at 0.40005 2.800096 180)
			(size 0.4064 0.4064)
			(layers "F.Cu" "F.Mask" "F.Paste")
			(net "GND")
		)
		(pad "U15" smd circle
			(at 1.199896 2.800096 180)
			(size 0.4064 0.4064)
			(layers "F.Cu" "F.Mask" "F.Paste")
			(net "P1V2_AUX")
		)
		(pad "U16" smd circle
			(at 1.999996 2.800096 180)
			(size 0.4064 0.4064)
			(layers "F.Cu" "F.Mask" "F.Paste")
			(net "P1V2_AUX")
		)
		(pad "U17" smd circle
			(at 2.800096 2.800096 180)
			(size 0.4064 0.4064)
			(layers "F.Cu" "F.Mask" "F.Paste")
			(net "P1V2_AUX")
		)
		(pad "U18" smd circle
			(at 3.599942 2.800096 180)
			(size 0.4064 0.4064)
			(layers "F.Cu" "F.Mask" "F.Paste")
			(net "P1V2_AUX")
		)
		(pad "U19" smd circle
			(at 4.400042 2.800096 180)
			(size 0.4064 0.4064)
			(layers "F.Cu" "F.Mask" "F.Paste")
			(net "GND")
		)
		(pad "U21" smd circle
			(at 5.999988 2.800096 180)
			(size 0.4064 0.4064)
			(layers "F.Cu" "F.Mask" "F.Paste")
			(net "P1V2_P1V0_I3C_VDDL2")
		)
		(pad "U22" smd circle
			(at 6.800088 2.800096 180)
			(size 0.4064 0.4064)
			(layers "F.Cu" "F.Mask" "F.Paste")
			(net "GND")
		)
		(pad "U23" smd circle
			(at 7.599934 2.800096 180)
			(size 0.4064 0.4064)
			(layers "F.Cu" "F.Mask" "F.Paste")
			(net "GND")
		)
		(pad "U24" smd circle
			(at 8.400034 2.800096 180)
			(size 0.4064 0.4064)
			(layers "F.Cu" "F.Mask" "F.Paste")
			(net "IRQ_UV_DETECT_N")
		)
		(pad "U25" smd circle
			(at 9.19988 2.800096 180)
			(size 0.4064 0.4064)
			(layers "F.Cu" "F.Mask" "F.Paste")
			(net "IRQ_CPU1_VRHOT_N")
		)
		(pad "U26" smd circle
			(at 9.99998 2.800096 180)
			(size 0.4064 0.4064)
			(layers "F.Cu" "F.Mask" "F.Paste")
			(net "FM_BIOS_POST_CMPLT_BMC_N")
		)
		(pad "V1" smd circle
			(at -9.99998 3.599942 180)
			(size 0.4064 0.4064)
			(layers "F.Cu" "F.Mask" "F.Paste")
			(net "M_BMC_DDR4_DQS1_N")
		)
		(pad "V2" smd circle
			(at -9.19988 3.599942 180)
			(size 0.4064 0.4064)
			(layers "F.Cu" "F.Mask" "F.Paste")
			(net "M_BMC_DDR4_DQS1_P")
		)
		(pad "V3" smd circle
			(at -8.400034 3.599942 180)
			(size 0.4064 0.4064)
			(layers "F.Cu" "F.Mask" "F.Paste")
			(net "M_BMC_DDR4_DQ<9>")
		)
		(pad "V4" smd circle
			(at -7.599934 3.599942 180)
			(size 0.4064 0.4064)
			(layers "F.Cu" "F.Mask" "F.Paste")
			(net "M_BMC_DDR4_DQ<14>")
		)
		(pad "V5" smd circle
			(at -6.800088 3.599942 180)
			(size 0.4064 0.4064)
			(layers "F.Cu" "F.Mask" "F.Paste")
			(net "GND")
		)
		(pad "V6" smd circle
			(at -5.999988 3.599942 180)
			(size 0.4064 0.4064)
			(layers "F.Cu" "F.Mask" "F.Paste")
			(net "P1V8_AUX")
		)
		(pad "V8" smd circle
			(at -4.400042 3.599942 180)
			(size 0.4064 0.4064)
			(layers "F.Cu" "F.Mask" "F.Paste")
			(net "P1V8_STBY_DP_VCC18A")
		)
		(pad "V9" smd circle
			(at -3.599942 3.599942 180)
			(size 0.4064 0.4064)
			(layers "F.Cu" "F.Mask" "F.Paste")
			(net "P1V8_STBY_PE_VCC18A")
		)
		(pad "V10" smd circle
			(at -2.800096 3.599942 180)
			(size 0.4064 0.4064)
			(layers "F.Cu" "F.Mask" "F.Paste")
			(net "P1V8_STBY_RC_VCC18A")
		)
		(pad "V11" smd circle
			(at -1.999996 3.599942 180)
			(size 0.4064 0.4064)
			(layers "F.Cu" "F.Mask" "F.Paste")
			(net "GND")
		)
		(pad "V12" smd circle
			(at -1.199896 3.599942 180)
			(size 0.4064 0.4064)
			(layers "F.Cu" "F.Mask" "F.Paste")
			(net "GND")
		)
		(pad "V13" smd circle
			(at -0.40005 3.599942 180)
			(size 0.4064 0.4064)
			(layers "F.Cu" "F.Mask" "F.Paste")
			(net "P1V8_AUX")
		)
		(pad "V14" smd circle
			(at 0.40005 3.599942 180)
			(size 0.4064 0.4064)
			(layers "F.Cu" "F.Mask" "F.Paste")
			(net "GND")
		)
		(pad "V15" smd circle
			(at 1.199896 3.599942 180)
			(size 0.4064 0.4064)
			(layers "F.Cu" "F.Mask" "F.Paste")
			(net "GND")
		)
		(pad "V16" smd circle
			(at 1.999996 3.599942 180)
			(size 0.4064 0.4064)
			(layers "F.Cu" "F.Mask" "F.Paste")
			(net "GND")
		)
		(pad "V17" smd circle
			(at 2.800096 3.599942 180)
			(size 0.4064 0.4064)
			(layers "F.Cu" "F.Mask" "F.Paste")
			(net "GND")
		)
		(pad "V18" smd circle
			(at 3.599942 3.599942 180)
			(size 0.4064 0.4064)
			(layers "F.Cu" "F.Mask" "F.Paste")
			(net "GND")
		)
		(pad "V19" smd circle
			(at 4.400042 3.599942 180)
			(size 0.4064 0.4064)
			(layers "F.Cu" "F.Mask" "F.Paste")
			(net "GND")
		)
		(pad "V21" smd circle
			(at 5.999988 3.599942 180)
			(size 0.4064 0.4064)
			(layers "F.Cu" "F.Mask" "F.Paste")
			(net "P3V3_STBY_DACAV33")
		)
		(pad "V22" smd circle
			(at 6.800088 3.599942 180)
			(size 0.4064 0.4064)
			(layers "F.Cu" "F.Mask" "F.Paste")
			(net "P1V2_P1V0_I3C_VDDL1")
		)
		(pad "V23" smd circle
			(at 7.599934 3.599942 180)
			(size 0.4064 0.4064)
			(layers "F.Cu" "F.Mask" "F.Paste")
			(net "P3V3_RTC_AUX")
		)
		(pad "V24" smd circle
			(at 8.400034 3.599942 180)
			(size 0.4064 0.4064)
			(layers "F.Cu" "F.Mask" "F.Paste")
			(net "IRQ_OC_DETECT_EN_N")
		)
		(pad "V25" smd circle
			(at 9.19988 3.599942 180)
			(size 0.4064 0.4064)
			(layers "F.Cu" "F.Mask" "F.Paste")
			(net "IRQ_OC_DETECT_N")
		)
		(pad "V26" smd circle
			(at 9.99998 3.599942 180)
			(size 0.4064 0.4064)
			(layers "F.Cu" "F.Mask" "F.Paste")
			(net "IRQ_CPU0_VRHOT_N")
		)
		(pad "W1" smd circle
			(at -9.99998 4.400042 180)
			(size 0.4064 0.4064)
			(layers "F.Cu" "F.Mask" "F.Paste")
			(net "M_BMC_DDR4_DQ<10>")
		)
		(pad "W2" smd circle
			(at -9.19988 4.400042 180)
			(size 0.4064 0.4064)
			(layers "F.Cu" "F.Mask" "F.Paste")
			(net "M_BMC_DDR4_DQ<8>")
		)
		(pad "W3" smd circle
			(at -8.400034 4.400042 180)
			(size 0.4064 0.4064)
			(layers "F.Cu" "F.Mask" "F.Paste")
			(net "M_BMC_DDR4_DQ<11>")
		)
		(pad "W4" smd circle
			(at -7.599934 4.400042 180)
			(size 0.4064 0.4064)
			(layers "F.Cu" "F.Mask" "F.Paste")
			(net "M_BMC_DDR4_DQ<12>")
		)
		(pad "W5" smd circle
			(at -6.800088 4.400042 180)
			(size 0.4064 0.4064)
			(layers "F.Cu" "F.Mask" "F.Paste")
			(net "GND")
		)
		(pad "W6" smd circle
			(at -5.999988 4.400042 180)
			(size 0.4064 0.4064)
			(layers "F.Cu" "F.Mask" "F.Paste")
			(net "GND")
		)
		(pad "W8" smd circle
			(at -4.400042 4.400042 180)
			(size 0.4064 0.4064)
			(layers "F.Cu" "F.Mask" "F.Paste")
			(net "GND")
		)
		(pad "W9" smd circle
			(at -3.599942 4.400042 180)
			(size 0.4064 0.4064)
			(layers "F.Cu" "F.Mask" "F.Paste")
			(net "GND")
		)
		(pad "W10" smd circle
			(at -2.800096 4.400042 180)
			(size 0.4064 0.4064)
			(layers "F.Cu" "F.Mask" "F.Paste")
			(net "GND")
		)
		(pad "W11" smd circle
			(at -1.999996 4.400042 180)
			(size 0.4064 0.4064)
			(layers "F.Cu" "F.Mask" "F.Paste")
			(net "GND")
		)
		(pad "W12" smd circle
			(at -1.199896 4.400042 180)
			(size 0.4064 0.4064)
			(layers "F.Cu" "F.Mask" "F.Paste")
			(net "GND")
		)
		(pad "W13" smd circle
			(at -0.40005 4.400042 180)
			(size 0.4064 0.4064)
			(layers "F.Cu" "F.Mask" "F.Paste")
			(net "P1V8_AUX")
		)
		(pad "W14" smd circle
			(at 0.40005 4.400042 180)
			(size 0.4064 0.4064)
			(layers "F.Cu" "F.Mask" "F.Paste")
			(net "P1V8_AUX")
		)
		(pad "W15" smd circle
			(at 1.199896 4.400042 180)
			(size 0.4064 0.4064)
			(layers "F.Cu" "F.Mask" "F.Paste")
			(net "PGPPA_BMC_AUX")
		)
		(pad "W16" smd circle
			(at 1.999996 4.400042 180)
			(size 0.4064 0.4064)
			(layers "F.Cu" "F.Mask" "F.Paste")
			(net "P3V3_AUX")
		)
		(pad "W17" smd circle
			(at 2.800096 4.400042 180)
			(size 0.4064 0.4064)
			(layers "F.Cu" "F.Mask" "F.Paste")
			(net "P3V3_AUX")
		)
		(pad "W18" smd circle
			(at 3.599942 4.400042 180)
			(size 0.4064 0.4064)
			(layers "F.Cu" "F.Mask" "F.Paste")
			(net "P3V3_AUX")
		)
		(pad "W19" smd circle
			(at 4.400042 4.400042 180)
			(size 0.4064 0.4064)
			(layers "F.Cu" "F.Mask" "F.Paste")
			(net "P3V3_AUX")
		)
		(pad "W21" smd circle
			(at 5.999988 4.400042 180)
			(size 0.4064 0.4064)
			(layers "F.Cu" "F.Mask" "F.Paste")
			(net "P3V3_STBY_DACAV33")
		)
		(pad "W22" smd circle
			(at 6.800088 4.400042 180)
			(size 0.4064 0.4064)
			(layers "F.Cu" "F.Mask" "F.Paste")
			(net "GND")
		)
		(pad "W23" smd circle
			(at 7.599934 4.400042 180)
			(size 0.4064 0.4064)
			(layers "F.Cu" "F.Mask" "F.Paste")
			(net "BMC_PWR_LED")
		)
		(pad "W24" smd circle
			(at 8.400034 4.400042 180)
			(size 0.4064 0.4064)
			(layers "F.Cu" "F.Mask" "F.Paste")
			(net "SYS_BMC_PWRBTN_R1_N")
		)
		(pad "W25" smd circle
			(at 9.19988 4.400042 180)
			(size 0.4064 0.4064)
			(layers "F.Cu" "F.Mask" "F.Paste")
			(net "GND")
		)
		(pad "W26" smd circle
			(at 9.99998 4.400042 180)
			(size 0.4064 0.4064)
			(layers "F.Cu" "F.Mask" "F.Paste")
			(net "PWRGD_CPUPWRGD_LVC1")
		)
		(pad "Y1" smd circle
			(at -9.99998 5.199888 180)
			(size 0.4064 0.4064)
			(layers "F.Cu" "F.Mask" "F.Paste")
			(net "Net_60")
		)
		(pad "Y2" smd circle
			(at -9.19988 5.199888 180)
			(size 0.4064 0.4064)
			(layers "F.Cu" "F.Mask" "F.Paste")
			(net "Net_59")
		)
		(pad "Y3" smd circle
			(at -8.400034 5.199888 180)
			(size 0.4064 0.4064)
			(layers "F.Cu" "F.Mask" "F.Paste")
			(net "Net_58")
		)
		(pad "Y4" smd circle
			(at -7.599934 5.199888 180)
			(size 0.4064 0.4064)
			(layers "F.Cu" "F.Mask" "F.Paste")
			(net "Net_57")
		)
		(pad "Y5" smd circle
			(at -6.800088 5.199888 180)
			(size 0.4064 0.4064)
			(layers "F.Cu" "F.Mask" "F.Paste")
			(net "Net_64")
		)
		(pad "Y6" smd circle
			(at -5.999988 5.199888 180)
			(size 0.4064 0.4064)
			(layers "F.Cu" "F.Mask" "F.Paste")
			(net "GND")
		)
		(pad "Y21" smd circle
			(at 5.999988 5.199888 180)
			(size 0.4064 0.4064)
			(layers "F.Cu" "F.Mask" "F.Paste")
			(net "A_BMC_ADCAV33")
		)
		(pad "Y22" smd circle
			(at 6.800088 5.199888 180)
			(size 0.4064 0.4064)
			(layers "F.Cu" "F.Mask" "F.Paste")
			(net "GND")
		)
		(pad "Y23" smd circle
			(at 7.599934 5.199888 180)
			(size 0.4064 0.4064)
			(layers "F.Cu" "F.Mask" "F.Paste")
			(net "BMC_HEARTBEAT_N")
		)
		(pad "Y24" smd circle
			(at 8.400034 5.199888 180)
			(size 0.4064 0.4064)
			(layers "F.Cu" "F.Mask" "F.Paste")
			(net "GPU_NVS_PWR_BRAKE_R_N")
		)
		(pad "Y25" smd circle
			(at 9.19988 5.199888 180)
			(size 0.4064 0.4064)
			(layers "F.Cu" "F.Mask" "F.Paste")
			(net "FM_PCH_BEEP_LED")
		)
		(pad "Y26" smd circle
			(at 9.99998 5.199888 180)
			(size 0.4064 0.4064)
			(layers "F.Cu" "F.Mask" "F.Paste")
			(net "FM_HDD_LED_N")
		)
		(zone
			(layer "F.Cu")
			(hatch none 0.5)
			(connect_pads
				(clearance 0)
			)
			(min_thickness 0.25)
			(keepout
				(tracks allowed)
				(vias not_allowed)
				(pads allowed)
				(copperpour not_allowed)
				(footprints allowed)
			)
			(placement
				(enabled no)
				(sheetname "")
			)
			(fill
				(thermal_gap 0.5)
				(thermal_bridge_width 0.5)
				(island_removal_mode 0)
			)
			(polygon
				(pts
					(xy 55.041038 -60.38723) (xy 55.041038 -49.5173) (xy 65.910968 -49.5173) (xy 65.910968 -49.2252)
					(xy 55.041038 -49.2252) (xy 55.041038 -38.35527) (xy 54.748938 -38.35527) (xy 54.748938 -49.2252)
					(xy 43.879008 -49.2252) (xy 43.879008 -49.5173) (xy 54.748938 -49.5173) (xy 54.748938 -60.38723)
				)
			)
		)
	)
	(footprint ""
		(layer "F.Cu")
		(at 73.533 -13.843)
		(property "Reference" "U16"
			(at 0.7874 -1.80213 0)
			(unlocked yes)
			(layer "F.SilkS")
			(effects
				(font
					(size 0.7874 0.5842)
					(thickness 0.1524)
				)
				(justify left)
			)
		)
		(property "Value" ""
			(at 0 0 0)
			(layer "F.Fab")
			(effects
				(font
					(size 1.27 1.27)
				)
			)
		)
		(duplicate_pad_numbers_are_jumpers no)
		(fp_line
			(start -1.4986 -1.100074)
			(end 1.4986 -1.100074)
			(stroke
				(width 0.1524)
				(type default)
			)
			(layer "F.SilkS")
		)
		(fp_line
			(start -1.4986 1.100074)
			(end -1.4986 -1.100074)
			(stroke
				(width 0.1524)
				(type default)
			)
			(layer "F.SilkS")
		)
		(fp_line
			(start 1.4986 -1.100074)
			(end 1.4986 1.100074)
			(stroke
				(width 0.1524)
				(type default)
			)
			(layer "F.SilkS")
		)
		(fp_line
			(start 1.4986 1.100074)
			(end -1.4986 1.100074)
			(stroke
				(width 0.1524)
				(type default)
			)
			(layer "F.SilkS")
		)
		(fp_poly
			(pts
				(xy -1.90881 -1.728724) (xy -1.28397 -1.728724) (xy -1.612138 -1.175004)
			)
			(stroke
				(width 0)
				(type default)
			)
			(fill yes)
			(layer "F.SilkS")
		)
		(fp_line
			(start -0.67437 -1.100074)
			(end 0.67437 -1.100074)
			(stroke
				(width 0.1)
				(type default)
			)
			(layer "F.Fab")
		)
		(fp_line
			(start -0.67437 1.100074)
			(end -0.67437 -1.100074)
			(stroke
				(width 0.1)
				(type default)
			)
			(layer "F.Fab")
		)
		(fp_line
			(start 0.67437 -1.100074)
			(end 0.67437 1.100074)
			(stroke
				(width 0.1)
				(type default)
			)
			(layer "F.Fab")
		)
		(fp_line
			(start 0.67437 1.100074)
			(end -0.67437 1.100074)
			(stroke
				(width 0.1)
				(type default)
			)
			(layer "F.Fab")
		)
		(fp_poly
			(pts
				(xy -2.20472 -0.338328) (xy -2.20472 -0.963168) (xy -1.651 -0.635)
			)
			(stroke
				(width 0)
				(type default)
			)
			(fill yes)
			(layer "F.Fab")
		)
		(pad "1" smd rect
			(at -0.889 -0.649986)
			(size 1.016 0.381)
			(layers "F.Cu" "F.Mask" "F.Paste")
			(net "NC_U16_P1")
		)
		(pad "2" smd rect
			(at -0.889 0)
			(size 1.016 0.381)
			(layers "F.Cu" "F.Mask" "F.Paste")
			(net "REAR_AC_PWR_BTN_N")
		)
		(pad "3" smd rect
			(at -0.889 0.649986)
			(size 1.016 0.381)
			(layers "F.Cu" "F.Mask" "F.Paste")
			(net "GND")
		)
		(pad "4" smd rect
			(at 0.889 0.649986)
			(size 1.016 0.381)
			(layers "F.Cu" "F.Mask" "F.Paste")
			(net "AC_PWR_BTN_R1_N")
		)
		(pad "5" smd rect
			(at 0.889 -0.649986)
			(size 1.016 0.381)
			(layers "F.Cu" "F.Mask" "F.Paste")
			(net "P3V3_AUX")
		)
	)
	(footprint ""
		(layer "F.Cu")
		(at 34.417 -51.181 180)
		(property "Reference" "R316"
			(at 0 0 180)
			(layer "F.SilkS")
			(hide yes)
			(effects
				(font
					(size 1.27 1.27)
				)
			)
		)
		(property "Value" ""
			(at 0 0 180)
			(layer "F.Fab")
			(effects
				(font
					(size 1.27 1.27)
				)
			)
		)
		(duplicate_pad_numbers_are_jumpers no)
		(fp_line
			(start 0.7874 0.4064)
			(end -0.7874 0.4064)
			(stroke
				(width 0.1524)
				(type default)
			)
			(layer "F.SilkS")
		)
		(fp_line
			(start 0.7874 -0.4064)
			(end 0.7874 0.4064)
			(stroke
				(width 0.1524)
				(type default)
			)
			(layer "F.SilkS")
		)
		(fp_line
			(start -0.7874 0.4064)
			(end -0.7874 -0.4064)
			(stroke
				(width 0.1524)
				(type default)
			)
			(layer "F.SilkS")
		)
		(fp_line
			(start -0.7874 -0.4064)
			(end 0.7874 -0.4064)
			(stroke
				(width 0.1524)
				(type default)
			)
			(layer "F.SilkS")
		)
		(fp_line
			(start 0.67945 0.3048)
			(end 0.120396 0.3048)
			(stroke
				(width 0.1)
				(type default)
			)
			(layer "F.Fab")
		)
		(fp_line
			(start 0.67945 -0.3048)
			(end 0.67945 0.3048)
			(stroke
				(width 0.1)
				(type default)
			)
			(layer "F.Fab")
		)
		(fp_line
			(start 0.12065 -0.2794)
			(end 0.12065 -0.3048)
			(stroke
				(width 0.1)
				(type default)
			)
			(layer "F.Fab")
		)
		(fp_line
			(start 0.12065 -0.3048)
			(end 0.67945 -0.3048)
			(stroke
				(width 0.1)
				(type default)
			)
			(layer "F.Fab")
		)
		(fp_line
			(start 0.120396 0.3048)
			(end 0.120396 0.2794)
			(stroke
				(width 0.1)
				(type default)
			)
			(layer "F.Fab")
		)
		(fp_line
			(start 0.120396 0.2794)
			(end -0.12065 0.2794)
			(stroke
				(width 0.1)
				(type default)
			)
			(layer "F.Fab")
		)
		(fp_line
			(start -0.12065 0.3048)
			(end -0.67945 0.3048)
			(stroke
				(width 0.1)
				(type default)
			)
			(layer "F.Fab")
		)
		(fp_line
			(start -0.12065 0.2794)
			(end -0.12065 0.3048)
			(stroke
				(width 0.1)
				(type default)
			)
			(layer "F.Fab")
		)
		(fp_line
			(start -0.12065 -0.2794)
			(end 0.12065 -0.2794)
			(stroke
				(width 0.1)
				(type default)
			)
			(layer "F.Fab")
		)
		(fp_line
			(start -0.12065 -0.305054)
			(end -0.12065 -0.2794)
			(stroke
				(width 0.1)
				(type default)
			)
			(layer "F.Fab")
		)
		(fp_line
			(start -0.67945 0.3048)
			(end -0.67945 -0.305054)
			(stroke
				(width 0.1)
				(type default)
			)
			(layer "F.Fab")
		)
		(fp_line
			(start -0.67945 -0.305054)
			(end -0.12065 -0.305054)
			(stroke
				(width 0.1)
				(type default)
			)
			(layer "F.Fab")
		)
		(pad "1" smd circle
			(at -0.40005 0 180)
			(size 0 0)
			(layers "F.Cu" "F.Mask" "F.Paste")
			(net "BMC_PWR_LED")
		)
		(pad "2" smd circle
			(at 0.40005 0 180)
			(size 0 0)
			(layers "F.Cu" "F.Mask" "F.Paste")
			(net "PWR_LED")
		)
	)
	(footprint ""
		(layer "F.Cu")
		(at 84.0486 -81.0006 -90)
		(property "Reference" "C278"
			(at 0 0 270)
			(layer "F.SilkS")
			(hide yes)
			(effects
				(font
					(size 1.27 1.27)
				)
			)
		)
		(property "Value" ""
			(at 0 0 270)
			(layer "F.Fab")
			(effects
				(font
					(size 1.27 1.27)
				)
			)
		)
		(duplicate_pad_numbers_are_jumpers no)
		(fp_line
			(start -0.7874 0.4064)
			(end -0.7874 -0.4064)
			(stroke
				(width 0.1524)
				(type default)
			)
			(layer "F.SilkS")
		)
		(fp_line
			(start 0.7874 0.4064)
			(end -0.7874 0.4064)
			(stroke
				(width 0.1524)
				(type default)
			)
			(layer "F.SilkS")
		)
		(fp_line
			(start -0.7874 -0.4064)
			(end 0.7874 -0.4064)
			(stroke
				(width 0.1524)
				(type default)
			)
			(layer "F.SilkS")
		)
		(fp_line
			(start 0.7874 -0.4064)
			(end 0.7874 0.4064)
			(stroke
				(width 0.1524)
				(type default)
			)
			(layer "F.SilkS")
		)
		(fp_line
			(start -0.67945 0.3048)
			(end -0.67945 -0.305054)
			(stroke
				(width 0.1)
				(type default)
			)
			(layer "F.Fab")
		)
		(fp_line
			(start -0.12065 0.3048)
			(end -0.67945 0.3048)
			(stroke
				(width 0.1)
				(type default)
			)
			(layer "F.Fab")
		)
		(fp_line
			(start 0.120396 0.3048)
			(end 0.120396 0.2794)
			(stroke
				(width 0.1)
				(type default)
			)
			(layer "F.Fab")
		)
		(fp_line
			(start 0.67945 0.3048)
			(end 0.120396 0.3048)
			(stroke
				(width 0.1)
				(type default)
			)
			(layer "F.Fab")
		)
		(fp_line
			(start -0.12065 0.2794)
			(end -0.12065 0.3048)
			(stroke
				(width 0.1)
				(type default)
			)
			(layer "F.Fab")
		)
		(fp_line
			(start 0.120396 0.2794)
			(end -0.12065 0.2794)
			(stroke
				(width 0.1)
				(type default)
			)
			(layer "F.Fab")
		)
		(fp_line
			(start -0.12065 -0.2794)
			(end 0.12065 -0.2794)
			(stroke
				(width 0.1)
				(type default)
			)
			(layer "F.Fab")
		)
		(fp_line
			(start 0.12065 -0.2794)
			(end 0.12065 -0.3048)
			(stroke
				(width 0.1)
				(type default)
			)
			(layer "F.Fab")
		)
		(fp_line
			(start 0.12065 -0.3048)
			(end 0.67945 -0.3048)
			(stroke
				(width 0.1)
				(type default)
			)
			(layer "F.Fab")
		)
		(fp_line
			(start 0.67945 -0.3048)
			(end 0.67945 0.3048)
			(stroke
				(width 0.1)
				(type default)
			)
			(layer "F.Fab")
		)
		(fp_line
			(start -0.67945 -0.305054)
			(end -0.12065 -0.305054)
			(stroke
				(width 0.1)
				(type default)
			)
			(layer "F.Fab")
		)
		(fp_line
			(start -0.12065 -0.305054)
			(end -0.12065 -0.2794)
			(stroke
				(width 0.1)
				(type default)
			)
			(layer "F.Fab")
		)
		(pad "1" smd circle
			(at -0.40005 0 270)
			(size 0 0)
			(layers "F.Cu" "F.Mask" "F.Paste")
			(net "P12V_AUX")
		)
		(pad "2" smd circle
			(at 0.40005 0 270)
			(size 0 0)
			(layers "F.Cu" "F.Mask" "F.Paste")
			(net "GND")
		)
	)
	(footprint ""
		(layer "F.Cu")
		(at 7.999984 -2.94005)
		(property "Reference" "SW6"
			(at -1.015238 -5.161534 0)
			(unlocked yes)
			(layer "F.SilkS")
			(effects
				(font
					(size 0.7874 0.5842)
					(thickness 0.1524)
				)
				(justify left)
			)
		)
		(property "Value" ""
			(at 0 0 0)
			(layer "F.Fab")
			(effects
				(font
					(size 1.27 1.27)
				)
			)
		)
		(duplicate_pad_numbers_are_jumpers no)
		(fp_line
			(start -3.700018 -4.549902)
			(end -3.700018 -2.51206)
			(stroke
				(width 0.1524)
				(type default)
			)
			(layer "F.SilkS")
		)
		(fp_line
			(start -3.700018 -0.98806)
			(end -3.700018 -0.88646)
			(stroke
				(width 0.1524)
				(type default)
			)
			(layer "F.SilkS")
		)
		(fp_line
			(start -3.700018 1.39954)
			(end -3.700018 1.549908)
			(stroke
				(width 0.1524)
				(type default)
			)
			(layer "F.SilkS")
		)
		(fp_line
			(start -3.700018 1.549908)
			(end -1.75006 1.549908)
			(stroke
				(width 0.1524)
				(type default)
			)
			(layer "F.SilkS")
		)
		(fp_line
			(start -3.1496 -4.549902)
			(end -3.700018 -4.549902)
			(stroke
				(width 0.1524)
				(type default)
			)
			(layer "F.SilkS")
		)
		(fp_line
			(start -1.75006 1.549908)
			(end -1.75006 4.549902)
			(stroke
				(width 0.1524)
				(type default)
			)
			(layer "F.SilkS")
		)
		(fp_line
			(start -1.75006 4.549902)
			(end 1.75006 4.549902)
			(stroke
				(width 0.1524)
				(type default)
			)
			(layer "F.SilkS")
		)
		(fp_line
			(start 1.3716 -4.549902)
			(end -1.3716 -4.549902)
			(stroke
				(width 0.1524)
				(type default)
			)
			(layer "F.SilkS")
		)
		(fp_line
			(start 1.75006 1.549908)
			(end 3.700018 1.549908)
			(stroke
				(width 0.1524)
				(type default)
			)
			(layer "F.SilkS")
		)
		(fp_line
			(start 1.75006 4.549902)
			(end 1.75006 1.549908)
			(stroke
				(width 0.1524)
				(type default)
			)
			(layer "F.SilkS")
		)
		(fp_line
			(start 3.700018 -4.549902)
			(end 3.1496 -4.549902)
			(stroke
				(width 0.1524)
				(type default)
			)
			(layer "F.SilkS")
		)
		(fp_line
			(start 3.700018 -2.51206)
			(end 3.700018 -4.549902)
			(stroke
				(width 0.1524)
				(type default)
			)
			(layer "F.SilkS")
		)
		(fp_line
			(start 3.700018 -0.88646)
			(end 3.700018 -0.98806)
			(stroke
				(width 0.1524)
				(type default)
			)
			(layer "F.SilkS")
		)
		(fp_line
			(start 3.700018 1.549908)
			(end 3.700018 1.39954)
			(stroke
				(width 0.1524)
				(type default)
			)
			(layer "F.SilkS")
		)
		(fp_poly
			(pts
				(xy -3.883914 -4.043934) (xy -5.310886 -3.330448) (xy -5.310886 -4.75742)
			)
			(stroke
				(width 0)
				(type default)
			)
			(fill yes)
			(layer "F.SilkS")
		)
		(fp_line
			(start -3.700018 -4.549902)
			(end -3.700018 1.549908)
			(stroke
				(width 0.1)
				(type default)
			)
			(layer "F.Fab")
		)
		(fp_line
			(start -3.700018 1.549908)
			(end -1.75006 1.549908)
			(stroke
				(width 0.1)
				(type default)
			)
			(layer "F.Fab")
		)
		(fp_line
			(start -1.75006 1.549908)
			(end -1.75006 4.549902)
			(stroke
				(width 0.1)
				(type default)
			)
			(layer "F.Fab")
		)
		(fp_line
			(start -1.75006 4.549902)
			(end 1.75006 4.549902)
			(stroke
				(width 0.1)
				(type default)
			)
			(layer "F.Fab")
		)
		(fp_line
			(start 1.75006 1.549908)
			(end 3.700018 1.549908)
			(stroke
				(width 0.1)
				(type default)
			)
			(layer "F.Fab")
		)
		(fp_line
			(start 1.75006 4.549902)
			(end 1.75006 1.549908)
			(stroke
				(width 0.1)
				(type default)
			)
			(layer "F.Fab")
		)
		(fp_line
			(start 3.700018 -4.549902)
			(end -3.700018 -4.549902)
			(stroke
				(width 0.1)
				(type default)
			)
			(layer "F.Fab")
		)
		(fp_line
			(start 3.700018 1.549908)
			(end 3.700018 -4.549902)
			(stroke
				(width 0.1)
				(type default)
			)
			(layer "F.Fab")
		)
		(fp_poly
			(pts
				(xy -3.883914 -4.043934) (xy -5.310886 -3.330448) (xy -5.310886 -4.75742)
			)
			(stroke
				(width 0)
				(type default)
			)
			(fill yes)
			(layer "F.Fab")
		)
		(pad "" np_thru_hole circle
			(at -3.50012 -1.75006)
			(size 0.9144 0.9144)
			(drill 0.9144)
			(layers "*.Cu" "*.Mask")
			(clearance 0.381)
			(thermal_gap 0.381)
		)
		(pad "" np_thru_hole circle
			(at 3.50012 -1.75006)
			(size 0.9144 0.9144)
			(drill 0.9144)
			(layers "*.Cu" "*.Mask")
			(clearance 0.381)
			(thermal_gap 0.381)
		)
		(pad "1" smd rect
			(at -2.249932 -4.05003)
			(size 1.4986 2.0066)
			(layers "F.Cu" "F.Mask" "F.Paste")
			(net "GND")
		)
		(pad "2" smd rect
			(at 2.249932 -4.05003)
			(size 1.4986 2.0066)
			(layers "F.Cu" "F.Mask" "F.Paste")
			(net "REAR_PWR_BTN_N")
		)
		(pad "3" smd rect
			(at -4.19989 0.249936)
			(size 2.0066 2.0066)
			(layers "F.Cu" "F.Mask" "F.Paste")
			(net "GND")
		)
		(pad "4" smd rect
			(at 4.19989 0.249936)
			(size 2.0066 2.0066)
			(layers "F.Cu" "F.Mask" "F.Paste")
			(net "GND")
		)
		(zone
			(layers "F.Cu" "B.Cu" "In1.Cu" "In2.Cu" "In3.Cu" "In4.Cu" "In5.Cu" "In6.Cu"
				"In7.Cu" "In8.Cu" "In9.Cu" "In10.Cu"
			)
			(hatch none 0.5)
			(connect_pads
				(clearance 0)
			)
			(min_thickness 0.25)
			(keepout
				(tracks not_allowed)
				(vias allowed)
				(pads allowed)
				(copperpour not_allowed)
				(footprints allowed)
			)
			(placement
				(enabled no)
				(sheetname "")
			)
			(fill
				(thermal_gap 0.5)
				(thermal_bridge_width 0.5)
				(island_removal_mode 0)
			)
			(polygon
				(pts
					(arc
						(start 5.363718 -4.69011)
						(mid 3.63601 -4.69011)
						(end 5.363718 -4.69011)
					)
				)
			)
		)
		(zone
			(layers "F.Cu" "B.Cu" "In1.Cu" "In2.Cu" "In3.Cu" "In4.Cu" "In5.Cu" "In6.Cu"
				"In7.Cu" "In8.Cu" "In9.Cu" "In10.Cu"
			)
			(hatch none 0.5)
			(connect_pads
				(clearance 0)
			)
			(min_thickness 0.25)
			(keepout
				(tracks not_allowed)
				(vias allowed)
				(pads allowed)
				(copperpour not_allowed)
				(footprints allowed)
			)
			(placement
				(enabled no)
				(sheetname "")
			)
			(fill
				(thermal_gap 0.5)
				(thermal_bridge_width 0.5)
				(island_removal_mode 0)
			)
			(polygon
				(pts
					(arc
						(start 12.363704 -4.69011)
						(mid 10.636504 -4.69011)
						(end 12.363704 -4.69011)
					)
				)
			)
		)
	)
	(footprint ""
		(layer "F.Cu")
		(at 23.749 -66.167 90)
		(property "Reference" "C19"
			(at 0 0 90)
			(layer "F.SilkS")
			(hide yes)
			(effects
				(font
					(size 1.27 1.27)
				)
			)
		)
		(property "Value" ""
			(at 0 0 90)
			(layer "F.Fab")
			(effects
				(font
					(size 1.27 1.27)
				)
			)
		)
		(duplicate_pad_numbers_are_jumpers no)
		(fp_line
			(start 0.7874 -0.4064)
			(end 0.7874 0.4064)
			(stroke
				(width 0.1524)
				(type default)
			)
			(layer "F.SilkS")
		)
		(fp_line
			(start -0.7874 -0.4064)
			(end 0.7874 -0.4064)
			(stroke
				(width 0.1524)
				(type default)
			)
			(layer "F.SilkS")
		)
		(fp_line
			(start 0.7874 0.4064)
			(end -0.7874 0.4064)
			(stroke
				(width 0.1524)
				(type default)
			)
			(layer "F.SilkS")
		)
		(fp_line
			(start -0.7874 0.4064)
			(end -0.7874 -0.4064)
			(stroke
				(width 0.1524)
				(type default)
			)
			(layer "F.SilkS")
		)
		(fp_line
			(start -0.12065 -0.305054)
			(end -0.12065 -0.2794)
			(stroke
				(width 0.1)
				(type default)
			)
			(layer "F.Fab")
		)
		(fp_line
			(start -0.67945 -0.305054)
			(end -0.12065 -0.305054)
			(stroke
				(width 0.1)
				(type default)
			)
			(layer "F.Fab")
		)
		(fp_line
			(start 0.67945 -0.3048)
			(end 0.67945 0.3048)
			(stroke
				(width 0.1)
				(type default)
			)
			(layer "F.Fab")
		)
		(fp_line
			(start 0.12065 -0.3048)
			(end 0.67945 -0.3048)
			(stroke
				(width 0.1)
				(type default)
			)
			(layer "F.Fab")
		)
		(fp_line
			(start 0.12065 -0.2794)
			(end 0.12065 -0.3048)
			(stroke
				(width 0.1)
				(type default)
			)
			(layer "F.Fab")
		)
		(fp_line
			(start -0.12065 -0.2794)
			(end 0.12065 -0.2794)
			(stroke
				(width 0.1)
				(type default)
			)
			(layer "F.Fab")
		)
		(fp_line
			(start 0.120396 0.2794)
			(end -0.12065 0.2794)
			(stroke
				(width 0.1)
				(type default)
			)
			(layer "F.Fab")
		)
		(fp_line
			(start -0.12065 0.2794)
			(end -0.12065 0.3048)
			(stroke
				(width 0.1)
				(type default)
			)
			(layer "F.Fab")
		)
		(fp_line
			(start 0.67945 0.3048)
			(end 0.120396 0.3048)
			(stroke
				(width 0.1)
				(type default)
			)
			(layer "F.Fab")
		)
		(fp_line
			(start 0.120396 0.3048)
			(end 0.120396 0.2794)
			(stroke
				(width 0.1)
				(type default)
			)
			(layer "F.Fab")
		)
		(fp_line
			(start -0.12065 0.3048)
			(end -0.67945 0.3048)
			(stroke
				(width 0.1)
				(type default)
			)
			(layer "F.Fab")
		)
		(fp_line
			(start -0.67945 0.3048)
			(end -0.67945 -0.305054)
			(stroke
				(width 0.1)
				(type default)
			)
			(layer "F.Fab")
		)
		(pad "1" smd circle
			(at -0.40005 0 90)
			(size 0 0)
			(layers "F.Cu" "F.Mask" "F.Paste")
			(net "P3V3_AUX")
		)
		(pad "2" smd circle
			(at 0.40005 0 90)
			(size 0 0)
			(layers "F.Cu" "F.Mask" "F.Paste")
			(net "GND")
		)
	)
	(footprint ""
		(layer "F.Cu")
		(at 10.287 -101.854 90)
		(property "Reference" "R517"
			(at 0 0 90)
			(layer "F.SilkS")
			(hide yes)
			(effects
				(font
					(size 1.27 1.27)
				)
			)
		)
		(property "Value" ""
			(at 0 0 90)
			(layer "F.Fab")
			(effects
				(font
					(size 1.27 1.27)
				)
			)
		)
		(duplicate_pad_numbers_are_jumpers no)
		(fp_line
			(start 0.7874 -0.4064)
			(end 0.7874 0.4064)
			(stroke
				(width 0.1524)
				(type default)
			)
			(layer "F.SilkS")
		)
		(fp_line
			(start -0.7874 -0.4064)
			(end 0.7874 -0.4064)
			(stroke
				(width 0.1524)
				(type default)
			)
			(layer "F.SilkS")
		)
		(fp_line
			(start 0.7874 0.4064)
			(end -0.7874 0.4064)
			(stroke
				(width 0.1524)
				(type default)
			)
			(layer "F.SilkS")
		)
		(fp_line
			(start -0.7874 0.4064)
			(end -0.7874 -0.4064)
			(stroke
				(width 0.1524)
				(type default)
			)
			(layer "F.SilkS")
		)
		(fp_line
			(start -0.12065 -0.305054)
			(end -0.12065 -0.2794)
			(stroke
				(width 0.1)
				(type default)
			)
			(layer "F.Fab")
		)
		(fp_line
			(start -0.67945 -0.305054)
			(end -0.12065 -0.305054)
			(stroke
				(width 0.1)
				(type default)
			)
			(layer "F.Fab")
		)
		(fp_line
			(start 0.67945 -0.3048)
			(end 0.67945 0.3048)
			(stroke
				(width 0.1)
				(type default)
			)
			(layer "F.Fab")
		)
		(fp_line
			(start 0.12065 -0.3048)
			(end 0.67945 -0.3048)
			(stroke
				(width 0.1)
				(type default)
			)
			(layer "F.Fab")
		)
		(fp_line
			(start 0.12065 -0.2794)
			(end 0.12065 -0.3048)
			(stroke
				(width 0.1)
				(type default)
			)
			(layer "F.Fab")
		)
		(fp_line
			(start -0.12065 -0.2794)
			(end 0.12065 -0.2794)
			(stroke
				(width 0.1)
				(type default)
			)
			(layer "F.Fab")
		)
		(fp_line
			(start 0.120396 0.2794)
			(end -0.12065 0.2794)
			(stroke
				(width 0.1)
				(type default)
			)
			(layer "F.Fab")
		)
		(fp_line
			(start -0.12065 0.2794)
			(end -0.12065 0.3048)
			(stroke
				(width 0.1)
				(type default)
			)
			(layer "F.Fab")
		)
		(fp_line
			(start 0.67945 0.3048)
			(end 0.120396 0.3048)
			(stroke
				(width 0.1)
				(type default)
			)
			(layer "F.Fab")
		)
		(fp_line
			(start 0.120396 0.3048)
			(end 0.120396 0.2794)
			(stroke
				(width 0.1)
				(type default)
			)
			(layer "F.Fab")
		)
		(fp_line
			(start -0.12065 0.3048)
			(end -0.67945 0.3048)
			(stroke
				(width 0.1)
				(type default)
			)
			(layer "F.Fab")
		)
		(fp_line
			(start -0.67945 0.3048)
			(end -0.67945 -0.305054)
			(stroke
				(width 0.1)
				(type default)
			)
			(layer "F.Fab")
		)
		(pad "1" smd circle
			(at -0.40005 0 90)
			(size 0 0)
			(layers "F.Cu" "F.Mask" "F.Paste")
			(net "JTAG_SCM_PLD_TDO")
		)
		(pad "2" smd circle
			(at 0.40005 0 90)
			(size 0 0)
			(layers "F.Cu" "F.Mask" "F.Paste")
			(net "JTAG_SCM_CONN_TDO")
		)
	)
	(footprint ""
		(layer "F.Cu")
		(at 49.2252 -28.2702)
		(property "Reference" "R433"
			(at 0 0 0)
			(layer "F.SilkS")
			(hide yes)
			(effects
				(font
					(size 1.27 1.27)
				)
			)
		)
		(property "Value" ""
			(at 0 0 0)
			(layer "F.Fab")
			(effects
				(font
					(size 1.27 1.27)
				)
			)
		)
		(duplicate_pad_numbers_are_jumpers no)
		(fp_line
			(start -0.7874 -0.4064)
			(end 0.7874 -0.4064)
			(stroke
				(width 0.1524)
				(type default)
			)
			(layer "F.SilkS")
		)
		(fp_line
			(start -0.7874 0.4064)
			(end -0.7874 -0.4064)
			(stroke
				(width 0.1524)
				(type default)
			)
			(layer "F.SilkS")
		)
		(fp_line
			(start 0.7874 -0.4064)
			(end 0.7874 0.4064)
			(stroke
				(width 0.1524)
				(type default)
			)
			(layer "F.SilkS")
		)
		(fp_line
			(start 0.7874 0.4064)
			(end -0.7874 0.4064)
			(stroke
				(width 0.1524)
				(type default)
			)
			(layer "F.SilkS")
		)
		(fp_line
			(start -0.67945 -0.305054)
			(end -0.12065 -0.305054)
			(stroke
				(width 0.1)
				(type default)
			)
			(layer "F.Fab")
		)
		(fp_line
			(start -0.67945 0.3048)
			(end -0.67945 -0.305054)
			(stroke
				(width 0.1)
				(type default)
			)
			(layer "F.Fab")
		)
		(fp_line
			(start -0.12065 -0.305054)
			(end -0.12065 -0.2794)
			(stroke
				(width 0.1)
				(type default)
			)
			(layer "F.Fab")
		)
		(fp_line
			(start -0.12065 -0.2794)
			(end 0.12065 -0.2794)
			(stroke
				(width 0.1)
				(type default)
			)
			(layer "F.Fab")
		)
		(fp_line
			(start -0.12065 0.2794)
			(end -0.12065 0.3048)
			(stroke
				(width 0.1)
				(type default)
			)
			(layer "F.Fab")
		)
		(fp_line
			(start -0.12065 0.3048)
			(end -0.67945 0.3048)
			(stroke
				(width 0.1)
				(type default)
			)
			(layer "F.Fab")
		)
		(fp_line
			(start 0.120396 0.2794)
			(end -0.12065 0.2794)
			(stroke
				(width 0.1)
				(type default)
			)
			(layer "F.Fab")
		)
		(fp_line
			(start 0.120396 0.3048)
			(end 0.120396 0.2794)
			(stroke
				(width 0.1)
				(type default)
			)
			(layer "F.Fab")
		)
		(fp_line
			(start 0.12065 -0.3048)
			(end 0.67945 -0.3048)
			(stroke
				(width 0.1)
				(type default)
			)
			(layer "F.Fab")
		)
		(fp_line
			(start 0.12065 -0.2794)
			(end 0.12065 -0.3048)
			(stroke
				(width 0.1)
				(type default)
			)
			(layer "F.Fab")
		)
		(fp_line
			(start 0.67945 -0.3048)
			(end 0.67945 0.3048)
			(stroke
				(width 0.1)
				(type default)
			)
			(layer "F.Fab")
		)
		(fp_line
			(start 0.67945 0.3048)
			(end 0.120396 0.3048)
			(stroke
				(width 0.1)
				(type default)
			)
			(layer "F.Fab")
		)
		(pad "1" smd circle
			(at -0.40005 0)
			(size 0 0)
			(layers "F.Cu" "F.Mask" "F.Paste")
			(net "SGPIO_DI_1")
		)
		(pad "2" smd circle
			(at 0.40005 0)
			(size 0 0)
			(layers "F.Cu" "F.Mask" "F.Paste")
			(net "SGPIO_BMC_M1_DI")
		)
	)
	(footprint ""
		(layer "F.Cu")
		(at 57.531 -102.9462 -90)
		(property "Reference" "R859"
			(at 0 0 270)
			(layer "F.SilkS")
			(hide yes)
			(effects
				(font
					(size 1.27 1.27)
				)
			)
		)
		(property "Value" ""
			(at 0 0 270)
			(layer "F.Fab")
			(effects
				(font
					(size 1.27 1.27)
				)
			)
		)
		(duplicate_pad_numbers_are_jumpers no)
		(fp_line
			(start -0.7874 0.4064)
			(end -0.7874 -0.4064)
			(stroke
				(width 0.1524)
				(type default)
			)
			(layer "F.SilkS")
		)
		(fp_line
			(start 0.7874 0.4064)
			(end -0.7874 0.4064)
			(stroke
				(width 0.1524)
				(type default)
			)
			(layer "F.SilkS")
		)
		(fp_line
			(start -0.7874 -0.4064)
			(end 0.7874 -0.4064)
			(stroke
				(width 0.1524)
				(type default)
			)
			(layer "F.SilkS")
		)
		(fp_line
			(start 0.7874 -0.4064)
			(end 0.7874 0.4064)
			(stroke
				(width 0.1524)
				(type default)
			)
			(layer "F.SilkS")
		)
		(fp_line
			(start -0.67945 0.3048)
			(end -0.67945 -0.305054)
			(stroke
				(width 0.1)
				(type default)
			)
			(layer "F.Fab")
		)
		(fp_line
			(start -0.12065 0.3048)
			(end -0.67945 0.3048)
			(stroke
				(width 0.1)
				(type default)
			)
			(layer "F.Fab")
		)
		(fp_line
			(start 0.120396 0.3048)
			(end 0.120396 0.2794)
			(stroke
				(width 0.1)
				(type default)
			)
			(layer "F.Fab")
		)
		(fp_line
			(start 0.67945 0.3048)
			(end 0.120396 0.3048)
			(stroke
				(width 0.1)
				(type default)
			)
			(layer "F.Fab")
		)
		(fp_line
			(start -0.12065 0.2794)
			(end -0.12065 0.3048)
			(stroke
				(width 0.1)
				(type default)
			)
			(layer "F.Fab")
		)
		(fp_line
			(start 0.120396 0.2794)
			(end -0.12065 0.2794)
			(stroke
				(width 0.1)
				(type default)
			)
			(layer "F.Fab")
		)
		(fp_line
			(start -0.12065 -0.2794)
			(end 0.12065 -0.2794)
			(stroke
				(width 0.1)
				(type default)
			)
			(layer "F.Fab")
		)
		(fp_line
			(start 0.12065 -0.2794)
			(end 0.12065 -0.3048)
			(stroke
				(width 0.1)
				(type default)
			)
			(layer "F.Fab")
		)
		(fp_line
			(start 0.12065 -0.3048)
			(end 0.67945 -0.3048)
			(stroke
				(width 0.1)
				(type default)
			)
			(layer "F.Fab")
		)
		(fp_line
			(start 0.67945 -0.3048)
			(end 0.67945 0.3048)
			(stroke
				(width 0.1)
				(type default)
			)
			(layer "F.Fab")
		)
		(fp_line
			(start -0.67945 -0.305054)
			(end -0.12065 -0.305054)
			(stroke
				(width 0.1)
				(type default)
			)
			(layer "F.Fab")
		)
		(fp_line
			(start -0.12065 -0.305054)
			(end -0.12065 -0.2794)
			(stroke
				(width 0.1)
				(type default)
			)
			(layer "F.Fab")
		)
		(pad "1" smd circle
			(at -0.40005 0 270)
			(size 0 0)
			(layers "F.Cu" "F.Mask" "F.Paste")
			(net "SPI_SYS_R_CLK")
		)
		(pad "2" smd circle
			(at 0.40005 0 270)
			(size 0 0)
			(layers "F.Cu" "F.Mask" "F.Paste")
			(net "SPI_SYS_MUX_CLK")
		)
	)
	(footprint ""
		(layer "F.Cu")
		(at 84.201 -30.099)
		(property "Reference" "C288"
			(at 0 0 0)
			(layer "F.SilkS")
			(hide yes)
			(effects
				(font
					(size 1.27 1.27)
				)
			)
		)
		(property "Value" ""
			(at 0 0 0)
			(layer "F.Fab")
			(effects
				(font
					(size 1.27 1.27)
				)
			)
		)
		(duplicate_pad_numbers_are_jumpers no)
		(fp_line
			(start -1.651 -0.8382)
			(end 1.651 -0.8382)
			(stroke
				(width 0.1524)
				(type default)
			)
			(layer "F.SilkS")
		)
		(fp_line
			(start -1.651 0.8382)
			(end -1.651 -0.8382)
			(stroke
				(width 0.1524)
				(type default)
			)
			(layer "F.SilkS")
		)
		(fp_line
			(start 0 0.8382)
			(end 0 -0.8382)
			(stroke
				(width 0.1524)
				(type default)
			)
			(layer "F.SilkS")
		)
		(fp_line
			(start 1.651 -0.8382)
			(end 1.651 0.8382)
			(stroke
				(width 0.1524)
				(type default)
			)
			(layer "F.SilkS")
		)
		(fp_line
			(start 1.651 0.8382)
			(end -1.651 0.8382)
			(stroke
				(width 0.1524)
				(type default)
			)
			(layer "F.SilkS")
		)
		(fp_line
			(start -1.55956 -0.7366)
			(end -1.55956 0.7366)
			(stroke
				(width 0.1)
				(type default)
			)
			(layer "F.Fab")
		)
		(fp_line
			(start -1.55956 0.7366)
			(end -1.524 0.7366)
			(stroke
				(width 0.1)
				(type default)
			)
			(layer "F.Fab")
		)
		(fp_line
			(start -1.524 -0.7366)
			(end -1.55956 -0.7366)
			(stroke
				(width 0.1)
				(type default)
			)
			(layer "F.Fab")
		)
		(fp_line
			(start -1.524 0.7366)
			(end 1.524 0.7366)
			(stroke
				(width 0.1)
				(type default)
			)
			(layer "F.Fab")
		)
		(fp_line
			(start 1.524 -0.7366)
			(end -1.524 -0.7366)
			(stroke
				(width 0.1)
				(type default)
			)
			(layer "F.Fab")
		)
		(fp_line
			(start 1.524 0.7366)
			(end 1.55956 0.7366)
			(stroke
				(width 0.1)
				(type default)
			)
			(layer "F.Fab")
		)
		(fp_line
			(start 1.55956 -0.7366)
			(end 1.524 -0.7366)
			(stroke
				(width 0.1)
				(type default)
			)
			(layer "F.Fab")
		)
		(fp_line
			(start 1.55956 0.7366)
			(end 1.55956 -0.7366)
			(stroke
				(width 0.1)
				(type default)
			)
			(layer "F.Fab")
		)
		(pad "1" smd rect
			(at -0.94996 0 180)
			(size 1.1176 1.3716)
			(layers "F.Cu" "F.Mask" "F.Paste")
			(net "P3V3_AUX")
		)
		(pad "2" smd rect
			(at 0.94996 0 180)
			(size 1.1176 1.3716)
			(layers "F.Cu" "F.Mask" "F.Paste")
			(net "GND")
		)
	)
	(footprint ""
		(layer "F.Cu")
		(at 50.75174 -63.953644 90)
		(property "Reference" "R216"
			(at 0 0 90)
			(layer "F.SilkS")
			(hide yes)
			(effects
				(font
					(size 1.27 1.27)
				)
			)
		)
		(property "Value" ""
			(at 0 0 90)
			(layer "F.Fab")
			(effects
				(font
					(size 1.27 1.27)
				)
			)
		)
		(duplicate_pad_numbers_are_jumpers no)
		(fp_line
			(start 0.7874 -0.4064)
			(end 0.7874 0.4064)
			(stroke
				(width 0.1524)
				(type default)
			)
			(layer "F.SilkS")
		)
		(fp_line
			(start -0.7874 -0.4064)
			(end 0.7874 -0.4064)
			(stroke
				(width 0.1524)
				(type default)
			)
			(layer "F.SilkS")
		)
		(fp_line
			(start 0.7874 0.4064)
			(end -0.7874 0.4064)
			(stroke
				(width 0.1524)
				(type default)
			)
			(layer "F.SilkS")
		)
		(fp_line
			(start -0.7874 0.4064)
			(end -0.7874 -0.4064)
			(stroke
				(width 0.1524)
				(type default)
			)
			(layer "F.SilkS")
		)
		(fp_line
			(start -0.12065 -0.305054)
			(end -0.12065 -0.2794)
			(stroke
				(width 0.1)
				(type default)
			)
			(layer "F.Fab")
		)
		(fp_line
			(start -0.67945 -0.305054)
			(end -0.12065 -0.305054)
			(stroke
				(width 0.1)
				(type default)
			)
			(layer "F.Fab")
		)
		(fp_line
			(start 0.67945 -0.3048)
			(end 0.67945 0.3048)
			(stroke
				(width 0.1)
				(type default)
			)
			(layer "F.Fab")
		)
		(fp_line
			(start 0.12065 -0.3048)
			(end 0.67945 -0.3048)
			(stroke
				(width 0.1)
				(type default)
			)
			(layer "F.Fab")
		)
		(fp_line
			(start 0.12065 -0.2794)
			(end 0.12065 -0.3048)
			(stroke
				(width 0.1)
				(type default)
			)
			(layer "F.Fab")
		)
		(fp_line
			(start -0.12065 -0.2794)
			(end 0.12065 -0.2794)
			(stroke
				(width 0.1)
				(type default)
			)
			(layer "F.Fab")
		)
		(fp_line
			(start 0.120396 0.2794)
			(end -0.12065 0.2794)
			(stroke
				(width 0.1)
				(type default)
			)
			(layer "F.Fab")
		)
		(fp_line
			(start -0.12065 0.2794)
			(end -0.12065 0.3048)
			(stroke
				(width 0.1)
				(type default)
			)
			(layer "F.Fab")
		)
		(fp_line
			(start 0.67945 0.3048)
			(end 0.120396 0.3048)
			(stroke
				(width 0.1)
				(type default)
			)
			(layer "F.Fab")
		)
		(fp_line
			(start 0.120396 0.3048)
			(end 0.120396 0.2794)
			(stroke
				(width 0.1)
				(type default)
			)
			(layer "F.Fab")
		)
		(fp_line
			(start -0.12065 0.3048)
			(end -0.67945 0.3048)
			(stroke
				(width 0.1)
				(type default)
			)
			(layer "F.Fab")
		)
		(fp_line
			(start -0.67945 0.3048)
			(end -0.67945 -0.305054)
			(stroke
				(width 0.1)
				(type default)
			)
			(layer "F.Fab")
		)
		(pad "1" smd circle
			(at -0.40005 0 90)
			(size 0 0)
			(layers "F.Cu" "F.Mask" "F.Paste")
			(net "PECI_BMC_R")
		)
		(pad "2" smd circle
			(at 0.40005 0 90)
			(size 0 0)
			(layers "F.Cu" "F.Mask" "F.Paste")
			(net "PECI_BMC")
		)
	)
	(footprint ""
		(layer "F.Cu")
		(at 38.123876 -46.378876 180)
		(property "Reference" "R423"
			(at 0 0 180)
			(layer "F.SilkS")
			(hide yes)
			(effects
				(font
					(size 1.27 1.27)
				)
			)
		)
		(property "Value" ""
			(at 0 0 180)
			(layer "F.Fab")
			(effects
				(font
					(size 1.27 1.27)
				)
			)
		)
		(duplicate_pad_numbers_are_jumpers no)
		(fp_line
			(start 0.7874 0.4064)
			(end -0.7874 0.4064)
			(stroke
				(width 0.1524)
				(type default)
			)
			(layer "F.SilkS")
		)
		(fp_line
			(start 0.7874 -0.4064)
			(end 0.7874 0.4064)
			(stroke
				(width 0.1524)
				(type default)
			)
			(layer "F.SilkS")
		)
		(fp_line
			(start -0.7874 0.4064)
			(end -0.7874 -0.4064)
			(stroke
				(width 0.1524)
				(type default)
			)
			(layer "F.SilkS")
		)
		(fp_line
			(start -0.7874 -0.4064)
			(end 0.7874 -0.4064)
			(stroke
				(width 0.1524)
				(type default)
			)
			(layer "F.SilkS")
		)
		(fp_line
			(start 0.67945 0.3048)
			(end 0.120396 0.3048)
			(stroke
				(width 0.1)
				(type default)
			)
			(layer "F.Fab")
		)
		(fp_line
			(start 0.67945 -0.3048)
			(end 0.67945 0.3048)
			(stroke
				(width 0.1)
				(type default)
			)
			(layer "F.Fab")
		)
		(fp_line
			(start 0.12065 -0.2794)
			(end 0.12065 -0.3048)
			(stroke
				(width 0.1)
				(type default)
			)
			(layer "F.Fab")
		)
		(fp_line
			(start 0.12065 -0.3048)
			(end 0.67945 -0.3048)
			(stroke
				(width 0.1)
				(type default)
			)
			(layer "F.Fab")
		)
		(fp_line
			(start 0.120396 0.3048)
			(end 0.120396 0.2794)
			(stroke
				(width 0.1)
				(type default)
			)
			(layer "F.Fab")
		)
		(fp_line
			(start 0.120396 0.2794)
			(end -0.12065 0.2794)
			(stroke
				(width 0.1)
				(type default)
			)
			(layer "F.Fab")
		)
		(fp_line
			(start -0.12065 0.3048)
			(end -0.67945 0.3048)
			(stroke
				(width 0.1)
				(type default)
			)
			(layer "F.Fab")
		)
		(fp_line
			(start -0.12065 0.2794)
			(end -0.12065 0.3048)
			(stroke
				(width 0.1)
				(type default)
			)
			(layer "F.Fab")
		)
		(fp_line
			(start -0.12065 -0.2794)
			(end 0.12065 -0.2794)
			(stroke
				(width 0.1)
				(type default)
			)
			(layer "F.Fab")
		)
		(fp_line
			(start -0.12065 -0.305054)
			(end -0.12065 -0.2794)
			(stroke
				(width 0.1)
				(type default)
			)
			(layer "F.Fab")
		)
		(fp_line
			(start -0.67945 0.3048)
			(end -0.67945 -0.305054)
			(stroke
				(width 0.1)
				(type default)
			)
			(layer "F.Fab")
		)
		(fp_line
			(start -0.67945 -0.305054)
			(end -0.12065 -0.305054)
			(stroke
				(width 0.1)
				(type default)
			)
			(layer "F.Fab")
		)
		(pad "1" smd circle
			(at -0.40005 0 180)
			(size 0 0)
			(layers "F.Cu" "F.Mask" "F.Paste")
			(net "SMB_BMC_MM13_R_SCL")
		)
		(pad "2" smd circle
			(at 0.40005 0 180)
			(size 0 0)
			(layers "F.Cu" "F.Mask" "F.Paste")
			(net "SMB_BMC_MM13_SCL")
		)
	)
	(footprint ""
		(layer "F.Cu")
		(at 40.767 -51.8414 90)
		(property "Reference" "R853"
			(at 0 0 90)
			(layer "F.SilkS")
			(hide yes)
			(effects
				(font
					(size 1.27 1.27)
				)
			)
		)
		(property "Value" ""
			(at 0 0 90)
			(layer "F.Fab")
			(effects
				(font
					(size 1.27 1.27)
				)
			)
		)
		(duplicate_pad_numbers_are_jumpers no)
		(fp_line
			(start 0.7874 -0.4064)
			(end 0.7874 0.4064)
			(stroke
				(width 0.1524)
				(type default)
			)
			(layer "F.SilkS")
		)
		(fp_line
			(start -0.7874 -0.4064)
			(end 0.7874 -0.4064)
			(stroke
				(width 0.1524)
				(type default)
			)
			(layer "F.SilkS")
		)
		(fp_line
			(start 0.7874 0.4064)
			(end -0.7874 0.4064)
			(stroke
				(width 0.1524)
				(type default)
			)
			(layer "F.SilkS")
		)
		(fp_line
			(start -0.7874 0.4064)
			(end -0.7874 -0.4064)
			(stroke
				(width 0.1524)
				(type default)
			)
			(layer "F.SilkS")
		)
		(fp_line
			(start -0.12065 -0.305054)
			(end -0.12065 -0.2794)
			(stroke
				(width 0.1)
				(type default)
			)
			(layer "F.Fab")
		)
		(fp_line
			(start -0.67945 -0.305054)
			(end -0.12065 -0.305054)
			(stroke
				(width 0.1)
				(type default)
			)
			(layer "F.Fab")
		)
		(fp_line
			(start 0.67945 -0.3048)
			(end 0.67945 0.3048)
			(stroke
				(width 0.1)
				(type default)
			)
			(layer "F.Fab")
		)
		(fp_line
			(start 0.12065 -0.3048)
			(end 0.67945 -0.3048)
			(stroke
				(width 0.1)
				(type default)
			)
			(layer "F.Fab")
		)
		(fp_line
			(start 0.12065 -0.2794)
			(end 0.12065 -0.3048)
			(stroke
				(width 0.1)
				(type default)
			)
			(layer "F.Fab")
		)
		(fp_line
			(start -0.12065 -0.2794)
			(end 0.12065 -0.2794)
			(stroke
				(width 0.1)
				(type default)
			)
			(layer "F.Fab")
		)
		(fp_line
			(start 0.120396 0.2794)
			(end -0.12065 0.2794)
			(stroke
				(width 0.1)
				(type default)
			)
			(layer "F.Fab")
		)
		(fp_line
			(start -0.12065 0.2794)
			(end -0.12065 0.3048)
			(stroke
				(width 0.1)
				(type default)
			)
			(layer "F.Fab")
		)
		(fp_line
			(start 0.67945 0.3048)
			(end 0.120396 0.3048)
			(stroke
				(width 0.1)
				(type default)
			)
			(layer "F.Fab")
		)
		(fp_line
			(start 0.120396 0.3048)
			(end 0.120396 0.2794)
			(stroke
				(width 0.1)
				(type default)
			)
			(layer "F.Fab")
		)
		(fp_line
			(start -0.12065 0.3048)
			(end -0.67945 0.3048)
			(stroke
				(width 0.1)
				(type default)
			)
			(layer "F.Fab")
		)
		(fp_line
			(start -0.67945 0.3048)
			(end -0.67945 -0.305054)
			(stroke
				(width 0.1)
				(type default)
			)
			(layer "F.Fab")
		)
		(pad "1" smd circle
			(at -0.40005 0 90)
			(size 0 0)
			(layers "F.Cu" "F.Mask" "F.Paste")
			(net "FM_INTRUDER_R_N")
		)
		(pad "2" smd circle
			(at 0.40005 0 90)
			(size 0 0)
			(layers "F.Cu" "F.Mask" "F.Paste")
			(net "FM_INTRUDER_N")
		)
	)
	(footprint ""
		(layer "F.Cu")
		(at 83.217258 -37.703506)
		(property "Reference" "R830"
			(at 0 0 0)
			(layer "F.SilkS")
			(hide yes)
			(effects
				(font
					(size 1.27 1.27)
				)
			)
		)
		(property "Value" ""
			(at 0 0 0)
			(layer "F.Fab")
			(effects
				(font
					(size 1.27 1.27)
				)
			)
		)
		(duplicate_pad_numbers_are_jumpers no)
		(fp_line
			(start -0.7874 -0.4064)
			(end 0.7874 -0.4064)
			(stroke
				(width 0.1524)
				(type default)
			)
			(layer "F.SilkS")
		)
		(fp_line
			(start -0.7874 0.4064)
			(end -0.7874 -0.4064)
			(stroke
				(width 0.1524)
				(type default)
			)
			(layer "F.SilkS")
		)
		(fp_line
			(start 0.7874 -0.4064)
			(end 0.7874 0.4064)
			(stroke
				(width 0.1524)
				(type default)
			)
			(layer "F.SilkS")
		)
		(fp_line
			(start 0.7874 0.4064)
			(end -0.7874 0.4064)
			(stroke
				(width 0.1524)
				(type default)
			)
			(layer "F.SilkS")
		)
		(fp_line
			(start -0.67945 -0.305054)
			(end -0.12065 -0.305054)
			(stroke
				(width 0.1)
				(type default)
			)
			(layer "F.Fab")
		)
		(fp_line
			(start -0.67945 0.3048)
			(end -0.67945 -0.305054)
			(stroke
				(width 0.1)
				(type default)
			)
			(layer "F.Fab")
		)
		(fp_line
			(start -0.12065 -0.305054)
			(end -0.12065 -0.2794)
			(stroke
				(width 0.1)
				(type default)
			)
			(layer "F.Fab")
		)
		(fp_line
			(start -0.12065 -0.2794)
			(end 0.12065 -0.2794)
			(stroke
				(width 0.1)
				(type default)
			)
			(layer "F.Fab")
		)
		(fp_line
			(start -0.12065 0.2794)
			(end -0.12065 0.3048)
			(stroke
				(width 0.1)
				(type default)
			)
			(layer "F.Fab")
		)
		(fp_line
			(start -0.12065 0.3048)
			(end -0.67945 0.3048)
			(stroke
				(width 0.1)
				(type default)
			)
			(layer "F.Fab")
		)
		(fp_line
			(start 0.120396 0.2794)
			(end -0.12065 0.2794)
			(stroke
				(width 0.1)
				(type default)
			)
			(layer "F.Fab")
		)
		(fp_line
			(start 0.120396 0.3048)
			(end 0.120396 0.2794)
			(stroke
				(width 0.1)
				(type default)
			)
			(layer "F.Fab")
		)
		(fp_line
			(start 0.12065 -0.3048)
			(end 0.67945 -0.3048)
			(stroke
				(width 0.1)
				(type default)
			)
			(layer "F.Fab")
		)
		(fp_line
			(start 0.12065 -0.2794)
			(end 0.12065 -0.3048)
			(stroke
				(width 0.1)
				(type default)
			)
			(layer "F.Fab")
		)
		(fp_line
			(start 0.67945 -0.3048)
			(end 0.67945 0.3048)
			(stroke
				(width 0.1)
				(type default)
			)
			(layer "F.Fab")
		)
		(fp_line
			(start 0.67945 0.3048)
			(end 0.120396 0.3048)
			(stroke
				(width 0.1)
				(type default)
			)
			(layer "F.Fab")
		)
		(pad "1" smd circle
			(at -0.40005 0)
			(size 0 0)
			(layers "F.Cu" "F.Mask" "F.Paste")
			(net "U39_ADJ")
		)
		(pad "2" smd circle
			(at 0.40005 0)
			(size 0 0)
			(layers "F.Cu" "F.Mask" "F.Paste")
			(net "GND")
		)
	)
	(footprint ""
		(layer "F.Cu")
		(at 15.1638 -51.1048 -90)
		(property "Reference" "U18"
			(at 0.8636 -1.83007 90)
			(unlocked yes)
			(layer "F.SilkS")
			(effects
				(font
					(size 0.7874 0.5842)
					(thickness 0.1524)
				)
			)
		)
		(property "Value" ""
			(at 0 0 270)
			(layer "F.Fab")
			(effects
				(font
					(size 1.27 1.27)
				)
			)
		)
		(duplicate_pad_numbers_are_jumpers no)
		(fp_line
			(start -1.7018 1.1176)
			(end -1.7018 -1.1176)
			(stroke
				(width 0.1524)
				(type default)
			)
			(layer "F.SilkS")
		)
		(fp_line
			(start 1.7018 1.1176)
			(end -1.7018 1.1176)
			(stroke
				(width 0.1524)
				(type default)
			)
			(layer "F.SilkS")
		)
		(fp_line
			(start 0 -0.7112)
			(end -0.254 -1.1176)
			(stroke
				(width 0.1524)
				(type default)
			)
			(layer "F.SilkS")
		)
		(fp_line
			(start -0.254 -1.1176)
			(end -1.7018 -1.1176)
			(stroke
				(width 0.1524)
				(type default)
			)
			(layer "F.SilkS")
		)
		(fp_line
			(start 0.254 -1.1176)
			(end 0 -0.7112)
			(stroke
				(width 0.1524)
				(type default)
			)
			(layer "F.SilkS")
		)
		(fp_line
			(start 1.7018 -1.1176)
			(end 1.7018 1.1176)
			(stroke
				(width 0.1524)
				(type default)
			)
			(layer "F.SilkS")
		)
		(fp_line
			(start 1.7018 -1.1176)
			(end 0.254 -1.1176)
			(stroke
				(width 0.1524)
				(type default)
			)
			(layer "F.SilkS")
		)
		(fp_poly
			(pts
				(xy -1.559814 -1.3589) (xy -1.788414 -1.9431) (xy -1.356614 -1.9431)
			)
			(stroke
				(width 0)
				(type default)
			)
			(fill yes)
			(layer "F.SilkS")
		)
		(fp_line
			(start -1.5494 1.1176)
			(end -1.5494 -1.1176)
			(stroke
				(width 0.1)
				(type default)
			)
			(layer "F.Fab")
		)
		(fp_line
			(start 1.5494 1.1176)
			(end -1.5494 1.1176)
			(stroke
				(width 0.1)
				(type default)
			)
			(layer "F.Fab")
		)
		(fp_line
			(start -0.254 -1.1176)
			(end -1.5494 -1.1176)
			(stroke
				(width 0.1)
				(type default)
			)
			(layer "F.Fab")
		)
		(fp_line
			(start 0.254 -1.1176)
			(end -0.254 -1.1176)
			(stroke
				(width 0.1)
				(type default)
			)
			(layer "F.Fab")
		)
		(fp_line
			(start 1.5494 -1.1176)
			(end 1.5494 1.1176)
			(stroke
				(width 0.1)
				(type default)
			)
			(layer "F.Fab")
		)
		(fp_line
			(start 1.5494 -1.1176)
			(end 0.254 -1.1176)
			(stroke
				(width 0.1)
				(type default)
			)
			(layer "F.Fab")
		)
		(fp_poly
			(pts
				(xy -1.8161 -0.675386) (xy -2.4003 -0.446786) (xy -2.4003 -0.878586)
			)
			(stroke
				(width 0)
				(type default)
			)
			(fill yes)
			(layer "F.Fab")
		)
		(pad "1" smd rect
			(at -0.962406 -0.649986 180)
			(size 0.3302 1.1684)
			(layers "F.Cu" "F.Mask" "F.Paste")
			(net "PWRGD_P5V_AUX")
		)
		(pad "2" smd rect
			(at -0.962406 0 180)
			(size 0.3302 1.1684)
			(layers "F.Cu" "F.Mask" "F.Paste")
			(net "PWRGD_P1V8_AUX_R2")
		)
		(pad "3" smd rect
			(at -0.962406 0.649986 180)
			(size 0.3302 1.1684)
			(layers "F.Cu" "F.Mask" "F.Paste")
			(net "GND")
		)
		(pad "4" smd rect
			(at 0.962406 0.649986 180)
			(size 0.3302 1.1684)
			(layers "F.Cu" "F.Mask" "F.Paste")
			(net "EN_P3V3_RGM")
		)
		(pad "5" smd rect
			(at 0.962406 -0.649986 180)
			(size 0.3302 1.1684)
			(layers "F.Cu" "F.Mask" "F.Paste")
			(net "P3V3_LDO")
		)
	)
	(footprint ""
		(layer "F.Cu")
		(at 24.4856 -33.909 90)
		(property "Reference" "C156"
			(at 0 0 90)
			(layer "F.SilkS")
			(hide yes)
			(effects
				(font
					(size 1.27 1.27)
				)
			)
		)
		(property "Value" ""
			(at 0 0 90)
			(layer "F.Fab")
			(effects
				(font
					(size 1.27 1.27)
				)
			)
		)
		(duplicate_pad_numbers_are_jumpers no)
		(fp_line
			(start 0.7874 -0.4064)
			(end 0.7874 0.4064)
			(stroke
				(width 0.1524)
				(type default)
			)
			(layer "F.SilkS")
		)
		(fp_line
			(start -0.7874 -0.4064)
			(end 0.7874 -0.4064)
			(stroke
				(width 0.1524)
				(type default)
			)
			(layer "F.SilkS")
		)
		(fp_line
			(start 0.7874 0.4064)
			(end -0.7874 0.4064)
			(stroke
				(width 0.1524)
				(type default)
			)
			(layer "F.SilkS")
		)
		(fp_line
			(start -0.7874 0.4064)
			(end -0.7874 -0.4064)
			(stroke
				(width 0.1524)
				(type default)
			)
			(layer "F.SilkS")
		)
		(fp_line
			(start -0.12065 -0.305054)
			(end -0.12065 -0.2794)
			(stroke
				(width 0.1)
				(type default)
			)
			(layer "F.Fab")
		)
		(fp_line
			(start -0.67945 -0.305054)
			(end -0.12065 -0.305054)
			(stroke
				(width 0.1)
				(type default)
			)
			(layer "F.Fab")
		)
		(fp_line
			(start 0.67945 -0.3048)
			(end 0.67945 0.3048)
			(stroke
				(width 0.1)
				(type default)
			)
			(layer "F.Fab")
		)
		(fp_line
			(start 0.12065 -0.3048)
			(end 0.67945 -0.3048)
			(stroke
				(width 0.1)
				(type default)
			)
			(layer "F.Fab")
		)
		(fp_line
			(start 0.12065 -0.2794)
			(end 0.12065 -0.3048)
			(stroke
				(width 0.1)
				(type default)
			)
			(layer "F.Fab")
		)
		(fp_line
			(start -0.12065 -0.2794)
			(end 0.12065 -0.2794)
			(stroke
				(width 0.1)
				(type default)
			)
			(layer "F.Fab")
		)
		(fp_line
			(start 0.120396 0.2794)
			(end -0.12065 0.2794)
			(stroke
				(width 0.1)
				(type default)
			)
			(layer "F.Fab")
		)
		(fp_line
			(start -0.12065 0.2794)
			(end -0.12065 0.3048)
			(stroke
				(width 0.1)
				(type default)
			)
			(layer "F.Fab")
		)
		(fp_line
			(start 0.67945 0.3048)
			(end 0.120396 0.3048)
			(stroke
				(width 0.1)
				(type default)
			)
			(layer "F.Fab")
		)
		(fp_line
			(start 0.120396 0.3048)
			(end 0.120396 0.2794)
			(stroke
				(width 0.1)
				(type default)
			)
			(layer "F.Fab")
		)
		(fp_line
			(start -0.12065 0.3048)
			(end -0.67945 0.3048)
			(stroke
				(width 0.1)
				(type default)
			)
			(layer "F.Fab")
		)
		(fp_line
			(start -0.67945 0.3048)
			(end -0.67945 -0.305054)
			(stroke
				(width 0.1)
				(type default)
			)
			(layer "F.Fab")
		)
		(pad "1" smd circle
			(at -0.40005 0 90)
			(size 0 0)
			(layers "F.Cu" "F.Mask" "F.Paste")
			(net "PWRGD_P1V0_AUX_R")
		)
		(pad "2" smd circle
			(at 0.40005 0 90)
			(size 0 0)
			(layers "F.Cu" "F.Mask" "F.Paste")
			(net "GND")
		)
	)
	(footprint ""
		(layer "F.Cu")
		(at 50.3174 -68.2498)
		(property "Reference" "R774"
			(at 0 0 0)
			(layer "F.SilkS")
			(hide yes)
			(effects
				(font
					(size 1.27 1.27)
				)
			)
		)
		(property "Value" ""
			(at 0 0 0)
			(layer "F.Fab")
			(effects
				(font
					(size 1.27 1.27)
				)
			)
		)
		(duplicate_pad_numbers_are_jumpers no)
		(fp_line
			(start -0.7874 -0.4064)
			(end 0.7874 -0.4064)
			(stroke
				(width 0.1524)
				(type default)
			)
			(layer "F.SilkS")
		)
		(fp_line
			(start -0.7874 0.4064)
			(end -0.7874 -0.4064)
			(stroke
				(width 0.1524)
				(type default)
			)
			(layer "F.SilkS")
		)
		(fp_line
			(start 0.7874 -0.4064)
			(end 0.7874 0.4064)
			(stroke
				(width 0.1524)
				(type default)
			)
			(layer "F.SilkS")
		)
		(fp_line
			(start 0.7874 0.4064)
			(end -0.7874 0.4064)
			(stroke
				(width 0.1524)
				(type default)
			)
			(layer "F.SilkS")
		)
		(fp_line
			(start -0.67945 -0.305054)
			(end -0.12065 -0.305054)
			(stroke
				(width 0.1)
				(type default)
			)
			(layer "F.Fab")
		)
		(fp_line
			(start -0.67945 0.3048)
			(end -0.67945 -0.305054)
			(stroke
				(width 0.1)
				(type default)
			)
			(layer "F.Fab")
		)
		(fp_line
			(start -0.12065 -0.305054)
			(end -0.12065 -0.2794)
			(stroke
				(width 0.1)
				(type default)
			)
			(layer "F.Fab")
		)
		(fp_line
			(start -0.12065 -0.2794)
			(end 0.12065 -0.2794)
			(stroke
				(width 0.1)
				(type default)
			)
			(layer "F.Fab")
		)
		(fp_line
			(start -0.12065 0.2794)
			(end -0.12065 0.3048)
			(stroke
				(width 0.1)
				(type default)
			)
			(layer "F.Fab")
		)
		(fp_line
			(start -0.12065 0.3048)
			(end -0.67945 0.3048)
			(stroke
				(width 0.1)
				(type default)
			)
			(layer "F.Fab")
		)
		(fp_line
			(start 0.120396 0.2794)
			(end -0.12065 0.2794)
			(stroke
				(width 0.1)
				(type default)
			)
			(layer "F.Fab")
		)
		(fp_line
			(start 0.120396 0.3048)
			(end 0.120396 0.2794)
			(stroke
				(width 0.1)
				(type default)
			)
			(layer "F.Fab")
		)
		(fp_line
			(start 0.12065 -0.3048)
			(end 0.67945 -0.3048)
			(stroke
				(width 0.1)
				(type default)
			)
			(layer "F.Fab")
		)
		(fp_line
			(start 0.12065 -0.2794)
			(end 0.12065 -0.3048)
			(stroke
				(width 0.1)
				(type default)
			)
			(layer "F.Fab")
		)
		(fp_line
			(start 0.67945 -0.3048)
			(end 0.67945 0.3048)
			(stroke
				(width 0.1)
				(type default)
			)
			(layer "F.Fab")
		)
		(fp_line
			(start 0.67945 0.3048)
			(end 0.120396 0.3048)
			(stroke
				(width 0.1)
				(type default)
			)
			(layer "F.Fab")
		)
		(pad "1" smd circle
			(at -0.40005 0)
			(size 0 0)
			(layers "F.Cu" "F.Mask" "F.Paste")
			(net "P3V3_AUX")
		)
		(pad "2" smd circle
			(at 0.40005 0)
			(size 0 0)
			(layers "F.Cu" "F.Mask" "F.Paste")
			(net "FM_SLPS3_GF_N")
		)
	)
	(footprint ""
		(layer "F.Cu")
		(at 50.8 -30.861 90)
		(property "Reference" "R150"
			(at 0 0 90)
			(layer "F.SilkS")
			(hide yes)
			(effects
				(font
					(size 1.27 1.27)
				)
			)
		)
		(property "Value" ""
			(at 0 0 90)
			(layer "F.Fab")
			(effects
				(font
					(size 1.27 1.27)
				)
			)
		)
		(duplicate_pad_numbers_are_jumpers no)
		(fp_line
			(start 0.7874 -0.4064)
			(end 0.7874 0.4064)
			(stroke
				(width 0.1524)
				(type default)
			)
			(layer "F.SilkS")
		)
		(fp_line
			(start -0.7874 -0.4064)
			(end 0.7874 -0.4064)
			(stroke
				(width 0.1524)
				(type default)
			)
			(layer "F.SilkS")
		)
		(fp_line
			(start 0.7874 0.4064)
			(end -0.7874 0.4064)
			(stroke
				(width 0.1524)
				(type default)
			)
			(layer "F.SilkS")
		)
		(fp_line
			(start -0.7874 0.4064)
			(end -0.7874 -0.4064)
			(stroke
				(width 0.1524)
				(type default)
			)
			(layer "F.SilkS")
		)
		(fp_line
			(start -0.12065 -0.305054)
			(end -0.12065 -0.2794)
			(stroke
				(width 0.1)
				(type default)
			)
			(layer "F.Fab")
		)
		(fp_line
			(start -0.67945 -0.305054)
			(end -0.12065 -0.305054)
			(stroke
				(width 0.1)
				(type default)
			)
			(layer "F.Fab")
		)
		(fp_line
			(start 0.67945 -0.3048)
			(end 0.67945 0.3048)
			(stroke
				(width 0.1)
				(type default)
			)
			(layer "F.Fab")
		)
		(fp_line
			(start 0.12065 -0.3048)
			(end 0.67945 -0.3048)
			(stroke
				(width 0.1)
				(type default)
			)
			(layer "F.Fab")
		)
		(fp_line
			(start 0.12065 -0.2794)
			(end 0.12065 -0.3048)
			(stroke
				(width 0.1)
				(type default)
			)
			(layer "F.Fab")
		)
		(fp_line
			(start -0.12065 -0.2794)
			(end 0.12065 -0.2794)
			(stroke
				(width 0.1)
				(type default)
			)
			(layer "F.Fab")
		)
		(fp_line
			(start 0.120396 0.2794)
			(end -0.12065 0.2794)
			(stroke
				(width 0.1)
				(type default)
			)
			(layer "F.Fab")
		)
		(fp_line
			(start -0.12065 0.2794)
			(end -0.12065 0.3048)
			(stroke
				(width 0.1)
				(type default)
			)
			(layer "F.Fab")
		)
		(fp_line
			(start 0.67945 0.3048)
			(end 0.120396 0.3048)
			(stroke
				(width 0.1)
				(type default)
			)
			(layer "F.Fab")
		)
		(fp_line
			(start 0.120396 0.3048)
			(end 0.120396 0.2794)
			(stroke
				(width 0.1)
				(type default)
			)
			(layer "F.Fab")
		)
		(fp_line
			(start -0.12065 0.3048)
			(end -0.67945 0.3048)
			(stroke
				(width 0.1)
				(type default)
			)
			(layer "F.Fab")
		)
		(fp_line
			(start -0.67945 0.3048)
			(end -0.67945 -0.305054)
			(stroke
				(width 0.1)
				(type default)
			)
			(layer "F.Fab")
		)
		(pad "1" smd circle
			(at -0.40005 0 90)
			(size 0 0)
			(layers "F.Cu" "F.Mask" "F.Paste")
			(net "SGPIO_LD_1")
		)
		(pad "2" smd circle
			(at 0.40005 0 90)
			(size 0 0)
			(layers "F.Cu" "F.Mask" "F.Paste")
			(net "SGPIO_BMC_M1_LD")
		)
	)
	(footprint ""
		(layer "F.Cu")
		(at 103.8225 18.001488 90)
		(property "Reference" "J25"
			(at -6.128512 1.48717 90)
			(unlocked yes)
			(layer "F.SilkS")
			(effects
				(font
					(size 0.7874 0.5842)
					(thickness 0.1524)
				)
				(justify left)
			)
		)
		(property "Value" ""
			(at 0 0 90)
			(layer "F.Fab")
			(effects
				(font
					(size 1.27 1.27)
				)
			)
		)
		(duplicate_pad_numbers_are_jumpers no)
		(fp_line
			(start 1.2192 -2.1082)
			(end 1.2192 -0.458978)
			(stroke
				(width 0.1524)
				(type default)
			)
			(layer "F.SilkS")
		)
		(fp_line
			(start -1.2192 -2.1082)
			(end 1.2192 -2.1082)
			(stroke
				(width 0.1524)
				(type default)
			)
			(layer "F.SilkS")
		)
		(fp_line
			(start 1.2192 0.452882)
			(end 1.2192 2.1082)
			(stroke
				(width 0.1524)
				(type default)
			)
			(layer "F.SilkS")
		)
		(fp_line
			(start 1.2192 2.1082)
			(end -1.2192 2.1082)
			(stroke
				(width 0.1524)
				(type default)
			)
			(layer "F.SilkS")
		)
		(fp_line
			(start -1.2192 2.1082)
			(end -1.2192 -2.1082)
			(stroke
				(width 0.1524)
				(type default)
			)
			(layer "F.SilkS")
		)
		(pad "" np_thru_hole circle
			(at -2.8829 -1.27)
			(size 1.0414 1.0414)
			(drill 1.0414)
			(layers "*.Cu" "*.Mask")
			(clearance 0.381)
			(thermal_gap 0.381)
		)
		(pad "" np_thru_hole circle
			(at -2.8829 1.27)
			(size 1.0414 1.0414)
			(drill 1.0414)
			(layers "*.Cu" "*.Mask")
			(clearance 0.381)
			(thermal_gap 0.381)
		)
		(pad "" np_thru_hole circle
			(at 3.4671 -1.27)
			(size 1.0414 1.0414)
			(drill 1.0414)
			(layers "*.Cu" "*.Mask")
			(clearance 0.381)
			(thermal_gap 0.381)
		)
		(pad "" np_thru_hole circle
			(at 3.4671 1.27)
			(size 1.0414 1.0414)
			(drill 1.0414)
			(layers "*.Cu" "*.Mask")
			(clearance 0.381)
			(thermal_gap 0.381)
		)
		(pad "1" smd rect
			(at 0.8255 -0.249936)
			(size 0.3048 0.508)
			(layers "F.Cu" "F.Mask" "F.Paste")
			(net "85_10INCH_TOP_DN")
		)
		(pad "2" smd rect
			(at 0.8255 0.249936)
			(size 0.3048 0.508)
			(layers "F.Cu" "F.Mask" "F.Paste")
			(net "85_10INCH_TOP_DP")
		)
		(pad "3" smd circle
			(at 0 0 90)
			(size 0 0)
			(layers "F.Cu" "F.Mask" "F.Paste")
			(net "GND_P1")
		)
		(zone
			(layer "F.Cu")
			(hatch none 0.5)
			(connect_pads
				(clearance 0)
			)
			(min_thickness 0.25)
			(keepout
				(tracks not_allowed)
				(vias allowed)
				(pads allowed)
				(copperpour not_allowed)
				(footprints allowed)
			)
			(placement
				(enabled no)
				(sheetname "")
			)
			(fill
				(thermal_gap 0.5)
				(thermal_bridge_width 0.5)
				(island_removal_mode 0)
			)
			(polygon
				(pts
					(xy 103.27386 16.883888) (xy 103.369364 16.883888) (xy 103.369364 17.480788) (xy 103.775764 17.480788)
					(xy 103.775764 16.883888) (xy 103.869236 16.883888) (xy 103.869236 17.480788) (xy 104.275636 17.480788)
					(xy 104.275636 16.883888) (xy 104.37114 16.883888) (xy 104.37114 17.582388) (xy 103.27386 17.582388)
				)
			)
		)
		(zone
			(layers "F.Cu" "B.Cu" "In1.Cu" "In2.Cu" "In3.Cu" "In4.Cu" "In5.Cu" "In6.Cu"
				"In7.Cu" "In8.Cu" "In9.Cu" "In10.Cu"
			)
			(hatch none 0.5)
			(connect_pads
				(clearance 0)
			)
			(min_thickness 0.25)
			(keepout
				(tracks not_allowed)
				(vias allowed)
				(pads allowed)
				(copperpour not_allowed)
				(footprints allowed)
			)
			(placement
				(enabled no)
				(sheetname "")
			)
			(fill
				(thermal_gap 0.5)
				(thermal_bridge_width 0.5)
				(island_removal_mode 0)
			)
			(polygon
				(pts
					(arc
						(start 103.4796 14.534388)
						(mid 101.6254 14.534388)
						(end 103.4796 14.534388)
					)
				)
			)
		)
		(zone
			(layers "F.Cu" "B.Cu" "In1.Cu" "In2.Cu" "In3.Cu" "In4.Cu" "In5.Cu" "In6.Cu"
				"In7.Cu" "In8.Cu" "In9.Cu" "In10.Cu"
			)
			(hatch none 0.5)
			(connect_pads
				(clearance 0)
			)
			(min_thickness 0.25)
			(keepout
				(tracks not_allowed)
				(vias allowed)
				(pads allowed)
				(copperpour not_allowed)
				(footprints allowed)
			)
			(placement
				(enabled no)
				(sheetname "")
			)
			(fill
				(thermal_gap 0.5)
				(thermal_bridge_width 0.5)
				(island_removal_mode 0)
			)
			(polygon
				(pts
					(arc
						(start 103.4796 20.884388)
						(mid 101.6254 20.884388)
						(end 103.4796 20.884388)
					)
				)
			)
		)
		(zone
			(layers "F.Cu" "B.Cu" "In1.Cu" "In2.Cu" "In3.Cu" "In4.Cu" "In5.Cu" "In6.Cu"
				"In7.Cu" "In8.Cu" "In9.Cu" "In10.Cu"
			)
			(hatch none 0.5)
			(connect_pads
				(clearance 0)
			)
			(min_thickness 0.25)
			(keepout
				(tracks not_allowed)
				(vias allowed)
				(pads allowed)
				(copperpour not_allowed)
				(footprints allowed)
			)
			(placement
				(enabled no)
				(sheetname "")
			)
			(fill
				(thermal_gap 0.5)
				(thermal_bridge_width 0.5)
				(island_removal_mode 0)
			)
			(polygon
				(pts
					(arc
						(start 106.0196 14.534388)
						(mid 104.1654 14.534388)
						(end 106.0196 14.534388)
					)
				)
			)
		)
		(zone
			(layers "F.Cu" "B.Cu" "In1.Cu" "In2.Cu" "In3.Cu" "In4.Cu" "In5.Cu" "In6.Cu"
				"In7.Cu" "In8.Cu" "In9.Cu" "In10.Cu"
			)
			(hatch none 0.5)
			(connect_pads
				(clearance 0)
			)
			(min_thickness 0.25)
			(keepout
				(tracks not_allowed)
				(vias allowed)
				(pads allowed)
				(copperpour not_allowed)
				(footprints allowed)
			)
			(placement
				(enabled no)
				(sheetname "")
			)
			(fill
				(thermal_gap 0.5)
				(thermal_bridge_width 0.5)
				(island_removal_mode 0)
			)
			(polygon
				(pts
					(arc
						(start 106.0196 20.884388)
						(mid 104.1654 20.884388)
						(end 106.0196 20.884388)
					)
				)
			)
		)
	)
	(footprint ""
		(layer "F.Cu")
		(at 85.2932 -16.764)
		(property "Reference" "R733"
			(at 0 0 0)
			(layer "F.SilkS")
			(hide yes)
			(effects
				(font
					(size 1.27 1.27)
				)
			)
		)
		(property "Value" ""
			(at 0 0 0)
			(layer "F.Fab")
			(effects
				(font
					(size 1.27 1.27)
				)
			)
		)
		(duplicate_pad_numbers_are_jumpers no)
		(fp_line
			(start -0.7874 -0.4064)
			(end 0.7874 -0.4064)
			(stroke
				(width 0.1524)
				(type default)
			)
			(layer "F.SilkS")
		)
		(fp_line
			(start -0.7874 0.4064)
			(end -0.7874 -0.4064)
			(stroke
				(width 0.1524)
				(type default)
			)
			(layer "F.SilkS")
		)
		(fp_line
			(start 0.7874 -0.4064)
			(end 0.7874 0.4064)
			(stroke
				(width 0.1524)
				(type default)
			)
			(layer "F.SilkS")
		)
		(fp_line
			(start 0.7874 0.4064)
			(end -0.7874 0.4064)
			(stroke
				(width 0.1524)
				(type default)
			)
			(layer "F.SilkS")
		)
		(fp_line
			(start -0.67945 -0.305054)
			(end -0.12065 -0.305054)
			(stroke
				(width 0.1)
				(type default)
			)
			(layer "F.Fab")
		)
		(fp_line
			(start -0.67945 0.3048)
			(end -0.67945 -0.305054)
			(stroke
				(width 0.1)
				(type default)
			)
			(layer "F.Fab")
		)
		(fp_line
			(start -0.12065 -0.305054)
			(end -0.12065 -0.2794)
			(stroke
				(width 0.1)
				(type default)
			)
			(layer "F.Fab")
		)
		(fp_line
			(start -0.12065 -0.2794)
			(end 0.12065 -0.2794)
			(stroke
				(width 0.1)
				(type default)
			)
			(layer "F.Fab")
		)
		(fp_line
			(start -0.12065 0.2794)
			(end -0.12065 0.3048)
			(stroke
				(width 0.1)
				(type default)
			)
			(layer "F.Fab")
		)
		(fp_line
			(start -0.12065 0.3048)
			(end -0.67945 0.3048)
			(stroke
				(width 0.1)
				(type default)
			)
			(layer "F.Fab")
		)
		(fp_line
			(start 0.120396 0.2794)
			(end -0.12065 0.2794)
			(stroke
				(width 0.1)
				(type default)
			)
			(layer "F.Fab")
		)
		(fp_line
			(start 0.120396 0.3048)
			(end 0.120396 0.2794)
			(stroke
				(width 0.1)
				(type default)
			)
			(layer "F.Fab")
		)
		(fp_line
			(start 0.12065 -0.3048)
			(end 0.67945 -0.3048)
			(stroke
				(width 0.1)
				(type default)
			)
			(layer "F.Fab")
		)
		(fp_line
			(start 0.12065 -0.2794)
			(end 0.12065 -0.3048)
			(stroke
				(width 0.1)
				(type default)
			)
			(layer "F.Fab")
		)
		(fp_line
			(start 0.67945 -0.3048)
			(end 0.67945 0.3048)
			(stroke
				(width 0.1)
				(type default)
			)
			(layer "F.Fab")
		)
		(fp_line
			(start 0.67945 0.3048)
			(end 0.120396 0.3048)
			(stroke
				(width 0.1)
				(type default)
			)
			(layer "F.Fab")
		)
		(pad "1" smd circle
			(at -0.40005 0)
			(size 0 0)
			(layers "F.Cu" "F.Mask" "F.Paste")
			(net "REAR_ID_RST_BTN_N")
		)
		(pad "2" smd circle
			(at 0.40005 0)
			(size 0 0)
			(layers "F.Cu" "F.Mask" "F.Paste")
			(net "FM_DEBUG_RST_BTN_N")
		)
	)
	(footprint ""
		(layer "F.Cu")
		(at 47.752 -81.1276 90)
		(property "Reference" "R592"
			(at 0 0 90)
			(layer "F.SilkS")
			(hide yes)
			(effects
				(font
					(size 1.27 1.27)
				)
			)
		)
		(property "Value" ""
			(at 0 0 90)
			(layer "F.Fab")
			(effects
				(font
					(size 1.27 1.27)
				)
			)
		)
		(duplicate_pad_numbers_are_jumpers no)
		(fp_line
			(start 0.7874 -0.4064)
			(end 0.7874 0.4064)
			(stroke
				(width 0.1524)
				(type default)
			)
			(layer "F.SilkS")
		)
		(fp_line
			(start -0.7874 -0.4064)
			(end 0.7874 -0.4064)
			(stroke
				(width 0.1524)
				(type default)
			)
			(layer "F.SilkS")
		)
		(fp_line
			(start 0.7874 0.4064)
			(end -0.7874 0.4064)
			(stroke
				(width 0.1524)
				(type default)
			)
			(layer "F.SilkS")
		)
		(fp_line
			(start -0.7874 0.4064)
			(end -0.7874 -0.4064)
			(stroke
				(width 0.1524)
				(type default)
			)
			(layer "F.SilkS")
		)
		(fp_line
			(start -0.12065 -0.305054)
			(end -0.12065 -0.2794)
			(stroke
				(width 0.1)
				(type default)
			)
			(layer "F.Fab")
		)
		(fp_line
			(start -0.67945 -0.305054)
			(end -0.12065 -0.305054)
			(stroke
				(width 0.1)
				(type default)
			)
			(layer "F.Fab")
		)
		(fp_line
			(start 0.67945 -0.3048)
			(end 0.67945 0.3048)
			(stroke
				(width 0.1)
				(type default)
			)
			(layer "F.Fab")
		)
		(fp_line
			(start 0.12065 -0.3048)
			(end 0.67945 -0.3048)
			(stroke
				(width 0.1)
				(type default)
			)
			(layer "F.Fab")
		)
		(fp_line
			(start 0.12065 -0.2794)
			(end 0.12065 -0.3048)
			(stroke
				(width 0.1)
				(type default)
			)
			(layer "F.Fab")
		)
		(fp_line
			(start -0.12065 -0.2794)
			(end 0.12065 -0.2794)
			(stroke
				(width 0.1)
				(type default)
			)
			(layer "F.Fab")
		)
		(fp_line
			(start 0.120396 0.2794)
			(end -0.12065 0.2794)
			(stroke
				(width 0.1)
				(type default)
			)
			(layer "F.Fab")
		)
		(fp_line
			(start -0.12065 0.2794)
			(end -0.12065 0.3048)
			(stroke
				(width 0.1)
				(type default)
			)
			(layer "F.Fab")
		)
		(fp_line
			(start 0.67945 0.3048)
			(end 0.120396 0.3048)
			(stroke
				(width 0.1)
				(type default)
			)
			(layer "F.Fab")
		)
		(fp_line
			(start 0.120396 0.3048)
			(end 0.120396 0.2794)
			(stroke
				(width 0.1)
				(type default)
			)
			(layer "F.Fab")
		)
		(fp_line
			(start -0.12065 0.3048)
			(end -0.67945 0.3048)
			(stroke
				(width 0.1)
				(type default)
			)
			(layer "F.Fab")
		)
		(fp_line
			(start -0.67945 0.3048)
			(end -0.67945 -0.305054)
			(stroke
				(width 0.1)
				(type default)
			)
			(layer "F.Fab")
		)
		(pad "1" smd circle
			(at -0.40005 0 90)
			(size 0 0)
			(layers "F.Cu" "F.Mask" "F.Paste")
			(net "P3V3_AUX")
		)
		(pad "2" smd circle
			(at 0.40005 0 90)
			(size 0 0)
			(layers "F.Cu" "F.Mask" "F.Paste")
			(net "PU_J1_P1")
		)
	)
	(footprint ""
		(layer "F.Cu")
		(at 9.1694 -104.6226)
		(property "Reference" "C217"
			(at 0 0 0)
			(layer "F.SilkS")
			(hide yes)
			(effects
				(font
					(size 1.27 1.27)
				)
			)
		)
		(property "Value" ""
			(at 0 0 0)
			(layer "F.Fab")
			(effects
				(font
					(size 1.27 1.27)
				)
			)
		)
		(duplicate_pad_numbers_are_jumpers no)
		(fp_line
			(start -0.7874 -0.4064)
			(end 0.7874 -0.4064)
			(stroke
				(width 0.1524)
				(type default)
			)
			(layer "F.SilkS")
		)
		(fp_line
			(start -0.7874 0.4064)
			(end -0.7874 -0.4064)
			(stroke
				(width 0.1524)
				(type default)
			)
			(layer "F.SilkS")
		)
		(fp_line
			(start 0.7874 -0.4064)
			(end 0.7874 0.4064)
			(stroke
				(width 0.1524)
				(type default)
			)
			(layer "F.SilkS")
		)
		(fp_line
			(start 0.7874 0.4064)
			(end -0.7874 0.4064)
			(stroke
				(width 0.1524)
				(type default)
			)
			(layer "F.SilkS")
		)
		(fp_line
			(start -0.67945 -0.305054)
			(end -0.12065 -0.305054)
			(stroke
				(width 0.1)
				(type default)
			)
			(layer "F.Fab")
		)
		(fp_line
			(start -0.67945 0.3048)
			(end -0.67945 -0.305054)
			(stroke
				(width 0.1)
				(type default)
			)
			(layer "F.Fab")
		)
		(fp_line
			(start -0.12065 -0.305054)
			(end -0.12065 -0.2794)
			(stroke
				(width 0.1)
				(type default)
			)
			(layer "F.Fab")
		)
		(fp_line
			(start -0.12065 -0.2794)
			(end 0.12065 -0.2794)
			(stroke
				(width 0.1)
				(type default)
			)
			(layer "F.Fab")
		)
		(fp_line
			(start -0.12065 0.2794)
			(end -0.12065 0.3048)
			(stroke
				(width 0.1)
				(type default)
			)
			(layer "F.Fab")
		)
		(fp_line
			(start -0.12065 0.3048)
			(end -0.67945 0.3048)
			(stroke
				(width 0.1)
				(type default)
			)
			(layer "F.Fab")
		)
		(fp_line
			(start 0.120396 0.2794)
			(end -0.12065 0.2794)
			(stroke
				(width 0.1)
				(type default)
			)
			(layer "F.Fab")
		)
		(fp_line
			(start 0.120396 0.3048)
			(end 0.120396 0.2794)
			(stroke
				(width 0.1)
				(type default)
			)
			(layer "F.Fab")
		)
		(fp_line
			(start 0.12065 -0.3048)
			(end 0.67945 -0.3048)
			(stroke
				(width 0.1)
				(type default)
			)
			(layer "F.Fab")
		)
		(fp_line
			(start 0.12065 -0.2794)
			(end 0.12065 -0.3048)
			(stroke
				(width 0.1)
				(type default)
			)
			(layer "F.Fab")
		)
		(fp_line
			(start 0.67945 -0.3048)
			(end 0.67945 0.3048)
			(stroke
				(width 0.1)
				(type default)
			)
			(layer "F.Fab")
		)
		(fp_line
			(start 0.67945 0.3048)
			(end 0.120396 0.3048)
			(stroke
				(width 0.1)
				(type default)
			)
			(layer "F.Fab")
		)
		(pad "1" smd circle
			(at -0.40005 0)
			(size 0 0)
			(layers "F.Cu" "F.Mask" "F.Paste")
			(net "J7_P1")
		)
		(pad "2" smd circle
			(at 0.40005 0)
			(size 0 0)
			(layers "F.Cu" "F.Mask" "F.Paste")
			(net "GND")
		)
	)
	(footprint ""
		(layer "F.Cu")
		(at 6.096 -53.594 180)
		(property "Reference" "PC207"
			(at 0 0 180)
			(layer "F.SilkS")
			(hide yes)
			(effects
				(font
					(size 1.27 1.27)
				)
			)
		)
		(property "Value" ""
			(at 0 0 180)
			(layer "F.Fab")
			(effects
				(font
					(size 1.27 1.27)
				)
			)
		)
		(duplicate_pad_numbers_are_jumpers no)
		(fp_line
			(start 1.524 0.762)
			(end -1.524 0.762)
			(stroke
				(width 0.1524)
				(type default)
			)
			(layer "F.SilkS")
		)
		(fp_line
			(start 1.524 -0.762)
			(end 1.524 0.762)
			(stroke
				(width 0.1524)
				(type default)
			)
			(layer "F.SilkS")
		)
		(fp_line
			(start -1.524 0.762)
			(end -1.524 -0.762)
			(stroke
				(width 0.1524)
				(type default)
			)
			(layer "F.SilkS")
		)
		(fp_line
			(start -1.524 -0.762)
			(end 1.524 -0.762)
			(stroke
				(width 0.1524)
				(type default)
			)
			(layer "F.SilkS")
		)
		(fp_line
			(start 1.1049 0.724916)
			(end 1.1049 -0.724916)
			(stroke
				(width 0.1)
				(type default)
			)
			(layer "F.Fab")
		)
		(fp_line
			(start 1.1049 -0.724916)
			(end -1.1049 -0.724916)
			(stroke
				(width 0.1)
				(type default)
			)
			(layer "F.Fab")
		)
		(fp_line
			(start -1.1049 0.724916)
			(end 1.1049 0.724916)
			(stroke
				(width 0.1)
				(type default)
			)
			(layer "F.Fab")
		)
		(fp_line
			(start -1.1049 -0.724916)
			(end -1.1049 0.724916)
			(stroke
				(width 0.1)
				(type default)
			)
			(layer "F.Fab")
		)
		(pad "1" smd rect
			(at -0.889 0)
			(size 1.016 1.27)
			(layers "F.Cu" "F.Mask" "F.Paste")
			(net "SW_P5V_AUX_FLT")
		)
		(pad "2" smd rect
			(at 0.889 0)
			(size 1.016 1.27)
			(layers "F.Cu" "F.Mask" "F.Paste")
			(net "GND")
		)
	)
	(footprint ""
		(layer "F.Cu")
		(at -4.251198 -136.217152)
		(property "Reference" "DM1"
			(at -0.3937 -0.588518 0)
			(unlocked yes)
			(layer "F.SilkS")
			(effects
				(font
					(size 0.254 0.127)
					(thickness 0.000001)
				)
				(justify left)
			)
		)
		(property "Value" ""
			(at 0 0 0)
			(layer "F.Fab")
			(effects
				(font
					(size 1.27 1.27)
				)
			)
		)
		(duplicate_pad_numbers_are_jumpers no)
		(pad "1" smd circle
			(at 0 0)
			(size 0.762 0.762)
			(layers "F.Cu" "F.Mask" "F.Paste")
			(net "Net_28")
		)
	)
	(footprint ""
		(layer "F.Cu")
		(at 70.023736 -37.288216 -90)
		(property "Reference" "C56"
			(at 0 0 270)
			(layer "F.SilkS")
			(hide yes)
			(effects
				(font
					(size 1.27 1.27)
				)
			)
		)
		(property "Value" ""
			(at 0 0 270)
			(layer "F.Fab")
			(effects
				(font
					(size 1.27 1.27)
				)
			)
		)
		(duplicate_pad_numbers_are_jumpers no)
		(fp_line
			(start -0.7874 0.4064)
			(end -0.7874 -0.4064)
			(stroke
				(width 0.1524)
				(type default)
			)
			(layer "F.SilkS")
		)
		(fp_line
			(start 0.7874 0.4064)
			(end -0.7874 0.4064)
			(stroke
				(width 0.1524)
				(type default)
			)
			(layer "F.SilkS")
		)
		(fp_line
			(start -0.7874 -0.4064)
			(end 0.7874 -0.4064)
			(stroke
				(width 0.1524)
				(type default)
			)
			(layer "F.SilkS")
		)
		(fp_line
			(start 0.7874 -0.4064)
			(end 0.7874 0.4064)
			(stroke
				(width 0.1524)
				(type default)
			)
			(layer "F.SilkS")
		)
		(fp_line
			(start -0.67945 0.3048)
			(end -0.67945 -0.305054)
			(stroke
				(width 0.1)
				(type default)
			)
			(layer "F.Fab")
		)
		(fp_line
			(start -0.12065 0.3048)
			(end -0.67945 0.3048)
			(stroke
				(width 0.1)
				(type default)
			)
			(layer "F.Fab")
		)
		(fp_line
			(start 0.120396 0.3048)
			(end 0.120396 0.2794)
			(stroke
				(width 0.1)
				(type default)
			)
			(layer "F.Fab")
		)
		(fp_line
			(start 0.67945 0.3048)
			(end 0.120396 0.3048)
			(stroke
				(width 0.1)
				(type default)
			)
			(layer "F.Fab")
		)
		(fp_line
			(start -0.12065 0.2794)
			(end -0.12065 0.3048)
			(stroke
				(width 0.1)
				(type default)
			)
			(layer "F.Fab")
		)
		(fp_line
			(start 0.120396 0.2794)
			(end -0.12065 0.2794)
			(stroke
				(width 0.1)
				(type default)
			)
			(layer "F.Fab")
		)
		(fp_line
			(start -0.12065 -0.2794)
			(end 0.12065 -0.2794)
			(stroke
				(width 0.1)
				(type default)
			)
			(layer "F.Fab")
		)
		(fp_line
			(start 0.12065 -0.2794)
			(end 0.12065 -0.3048)
			(stroke
				(width 0.1)
				(type default)
			)
			(layer "F.Fab")
		)
		(fp_line
			(start 0.12065 -0.3048)
			(end 0.67945 -0.3048)
			(stroke
				(width 0.1)
				(type default)
			)
			(layer "F.Fab")
		)
		(fp_line
			(start 0.67945 -0.3048)
			(end 0.67945 0.3048)
			(stroke
				(width 0.1)
				(type default)
			)
			(layer "F.Fab")
		)
		(fp_line
			(start -0.67945 -0.305054)
			(end -0.12065 -0.305054)
			(stroke
				(width 0.1)
				(type default)
			)
			(layer "F.Fab")
		)
		(fp_line
			(start -0.12065 -0.305054)
			(end -0.12065 -0.2794)
			(stroke
				(width 0.1)
				(type default)
			)
			(layer "F.Fab")
		)
		(pad "1" smd circle
			(at -0.40005 0 270)
			(size 0 0)
			(layers "F.Cu" "F.Mask" "F.Paste")
			(net "P1V0_STBY_PLAVDD")
		)
		(pad "2" smd circle
			(at 0.40005 0 270)
			(size 0 0)
			(layers "F.Cu" "F.Mask" "F.Paste")
			(net "GND")
		)
	)
	(footprint ""
		(layer "F.Cu")
		(at 32.8422 -108.585 -90)
		(property "Reference" "C174"
			(at 0 0 270)
			(layer "F.SilkS")
			(hide yes)
			(effects
				(font
					(size 1.27 1.27)
				)
			)
		)
		(property "Value" ""
			(at 0 0 270)
			(layer "F.Fab")
			(effects
				(font
					(size 1.27 1.27)
				)
			)
		)
		(duplicate_pad_numbers_are_jumpers no)
		(fp_line
			(start -0.7874 0.4064)
			(end -0.7874 -0.4064)
			(stroke
				(width 0.1524)
				(type default)
			)
			(layer "F.SilkS")
		)
		(fp_line
			(start 0.7874 0.4064)
			(end -0.7874 0.4064)
			(stroke
				(width 0.1524)
				(type default)
			)
			(layer "F.SilkS")
		)
		(fp_line
			(start -0.7874 -0.4064)
			(end 0.7874 -0.4064)
			(stroke
				(width 0.1524)
				(type default)
			)
			(layer "F.SilkS")
		)
		(fp_line
			(start 0.7874 -0.4064)
			(end 0.7874 0.4064)
			(stroke
				(width 0.1524)
				(type default)
			)
			(layer "F.SilkS")
		)
		(fp_line
			(start -0.67945 0.3048)
			(end -0.67945 -0.305054)
			(stroke
				(width 0.1)
				(type default)
			)
			(layer "F.Fab")
		)
		(fp_line
			(start -0.12065 0.3048)
			(end -0.67945 0.3048)
			(stroke
				(width 0.1)
				(type default)
			)
			(layer "F.Fab")
		)
		(fp_line
			(start 0.120396 0.3048)
			(end 0.120396 0.2794)
			(stroke
				(width 0.1)
				(type default)
			)
			(layer "F.Fab")
		)
		(fp_line
			(start 0.67945 0.3048)
			(end 0.120396 0.3048)
			(stroke
				(width 0.1)
				(type default)
			)
			(layer "F.Fab")
		)
		(fp_line
			(start -0.12065 0.2794)
			(end -0.12065 0.3048)
			(stroke
				(width 0.1)
				(type default)
			)
			(layer "F.Fab")
		)
		(fp_line
			(start 0.120396 0.2794)
			(end -0.12065 0.2794)
			(stroke
				(width 0.1)
				(type default)
			)
			(layer "F.Fab")
		)
		(fp_line
			(start -0.12065 -0.2794)
			(end 0.12065 -0.2794)
			(stroke
				(width 0.1)
				(type default)
			)
			(layer "F.Fab")
		)
		(fp_line
			(start 0.12065 -0.2794)
			(end 0.12065 -0.3048)
			(stroke
				(width 0.1)
				(type default)
			)
			(layer "F.Fab")
		)
		(fp_line
			(start 0.12065 -0.3048)
			(end 0.67945 -0.3048)
			(stroke
				(width 0.1)
				(type default)
			)
			(layer "F.Fab")
		)
		(fp_line
			(start 0.67945 -0.3048)
			(end 0.67945 0.3048)
			(stroke
				(width 0.1)
				(type default)
			)
			(layer "F.Fab")
		)
		(fp_line
			(start -0.67945 -0.305054)
			(end -0.12065 -0.305054)
			(stroke
				(width 0.1)
				(type default)
			)
			(layer "F.Fab")
		)
		(fp_line
			(start -0.12065 -0.305054)
			(end -0.12065 -0.2794)
			(stroke
				(width 0.1)
				(type default)
			)
			(layer "F.Fab")
		)
		(pad "1" smd circle
			(at -0.40005 0 270)
			(size 0 0)
			(layers "F.Cu" "F.Mask" "F.Paste")
			(net "P3V_BAT_R")
		)
		(pad "2" smd circle
			(at 0.40005 0 270)
			(size 0 0)
			(layers "F.Cu" "F.Mask" "F.Paste")
			(net "GND")
		)
	)
	(footprint ""
		(layer "F.Cu")
		(at 72.46493 -33.011618 90)
		(property "Reference" "R598"
			(at 0 0 90)
			(layer "F.SilkS")
			(hide yes)
			(effects
				(font
					(size 1.27 1.27)
				)
			)
		)
		(property "Value" ""
			(at 0 0 90)
			(layer "F.Fab")
			(effects
				(font
					(size 1.27 1.27)
				)
			)
		)
		(duplicate_pad_numbers_are_jumpers no)
		(fp_line
			(start 0.7874 -0.4064)
			(end 0.7874 0.4064)
			(stroke
				(width 0.1524)
				(type default)
			)
			(layer "F.SilkS")
		)
		(fp_line
			(start -0.7874 -0.4064)
			(end 0.7874 -0.4064)
			(stroke
				(width 0.1524)
				(type default)
			)
			(layer "F.SilkS")
		)
		(fp_line
			(start 0.7874 0.4064)
			(end -0.7874 0.4064)
			(stroke
				(width 0.1524)
				(type default)
			)
			(layer "F.SilkS")
		)
		(fp_line
			(start -0.7874 0.4064)
			(end -0.7874 -0.4064)
			(stroke
				(width 0.1524)
				(type default)
			)
			(layer "F.SilkS")
		)
		(fp_line
			(start -0.12065 -0.305054)
			(end -0.12065 -0.2794)
			(stroke
				(width 0.1)
				(type default)
			)
			(layer "F.Fab")
		)
		(fp_line
			(start -0.67945 -0.305054)
			(end -0.12065 -0.305054)
			(stroke
				(width 0.1)
				(type default)
			)
			(layer "F.Fab")
		)
		(fp_line
			(start 0.67945 -0.3048)
			(end 0.67945 0.3048)
			(stroke
				(width 0.1)
				(type default)
			)
			(layer "F.Fab")
		)
		(fp_line
			(start 0.12065 -0.3048)
			(end 0.67945 -0.3048)
			(stroke
				(width 0.1)
				(type default)
			)
			(layer "F.Fab")
		)
		(fp_line
			(start 0.12065 -0.2794)
			(end 0.12065 -0.3048)
			(stroke
				(width 0.1)
				(type default)
			)
			(layer "F.Fab")
		)
		(fp_line
			(start -0.12065 -0.2794)
			(end 0.12065 -0.2794)
			(stroke
				(width 0.1)
				(type default)
			)
			(layer "F.Fab")
		)
		(fp_line
			(start 0.120396 0.2794)
			(end -0.12065 0.2794)
			(stroke
				(width 0.1)
				(type default)
			)
			(layer "F.Fab")
		)
		(fp_line
			(start -0.12065 0.2794)
			(end -0.12065 0.3048)
			(stroke
				(width 0.1)
				(type default)
			)
			(layer "F.Fab")
		)
		(fp_line
			(start 0.67945 0.3048)
			(end 0.120396 0.3048)
			(stroke
				(width 0.1)
				(type default)
			)
			(layer "F.Fab")
		)
		(fp_line
			(start 0.120396 0.3048)
			(end 0.120396 0.2794)
			(stroke
				(width 0.1)
				(type default)
			)
			(layer "F.Fab")
		)
		(fp_line
			(start -0.12065 0.3048)
			(end -0.67945 0.3048)
			(stroke
				(width 0.1)
				(type default)
			)
			(layer "F.Fab")
		)
		(fp_line
			(start -0.67945 0.3048)
			(end -0.67945 -0.305054)
			(stroke
				(width 0.1)
				(type default)
			)
			(layer "F.Fab")
		)
		(pad "1" smd circle
			(at -0.40005 0 90)
			(size 0 0)
			(layers "F.Cu" "F.Mask" "F.Paste")
			(net "LED_POSTCODE_6")
		)
		(pad "2" smd circle
			(at 0.40005 0 90)
			(size 0 0)
			(layers "F.Cu" "F.Mask" "F.Paste")
			(net "LED_POSTCODE_6_R")
		)
	)
	(footprint ""
		(layer "F.Cu")
		(at 9.649968 -62.513464 180)
		(property "Reference" "PR276"
			(at 0 0 180)
			(layer "F.SilkS")
			(hide yes)
			(effects
				(font
					(size 1.27 1.27)
				)
			)
		)
		(property "Value" ""
			(at 0 0 180)
			(layer "F.Fab")
			(effects
				(font
					(size 1.27 1.27)
				)
			)
		)
		(duplicate_pad_numbers_are_jumpers no)
		(fp_line
			(start 0.7874 0.4064)
			(end -0.7874 0.4064)
			(stroke
				(width 0.1524)
				(type default)
			)
			(layer "F.SilkS")
		)
		(fp_line
			(start 0.7874 -0.4064)
			(end 0.7874 0.4064)
			(stroke
				(width 0.1524)
				(type default)
			)
			(layer "F.SilkS")
		)
		(fp_line
			(start -0.7874 0.4064)
			(end -0.7874 -0.4064)
			(stroke
				(width 0.1524)
				(type default)
			)
			(layer "F.SilkS")
		)
		(fp_line
			(start -0.7874 -0.4064)
			(end 0.7874 -0.4064)
			(stroke
				(width 0.1524)
				(type default)
			)
			(layer "F.SilkS")
		)
		(fp_line
			(start 0.67945 0.3048)
			(end 0.120396 0.3048)
			(stroke
				(width 0.1)
				(type default)
			)
			(layer "F.Fab")
		)
		(fp_line
			(start 0.67945 -0.3048)
			(end 0.67945 0.3048)
			(stroke
				(width 0.1)
				(type default)
			)
			(layer "F.Fab")
		)
		(fp_line
			(start 0.12065 -0.2794)
			(end 0.12065 -0.3048)
			(stroke
				(width 0.1)
				(type default)
			)
			(layer "F.Fab")
		)
		(fp_line
			(start 0.12065 -0.3048)
			(end 0.67945 -0.3048)
			(stroke
				(width 0.1)
				(type default)
			)
			(layer "F.Fab")
		)
		(fp_line
			(start 0.120396 0.3048)
			(end 0.120396 0.2794)
			(stroke
				(width 0.1)
				(type default)
			)
			(layer "F.Fab")
		)
		(fp_line
			(start 0.120396 0.2794)
			(end -0.12065 0.2794)
			(stroke
				(width 0.1)
				(type default)
			)
			(layer "F.Fab")
		)
		(fp_line
			(start -0.12065 0.3048)
			(end -0.67945 0.3048)
			(stroke
				(width 0.1)
				(type default)
			)
			(layer "F.Fab")
		)
		(fp_line
			(start -0.12065 0.2794)
			(end -0.12065 0.3048)
			(stroke
				(width 0.1)
				(type default)
			)
			(layer "F.Fab")
		)
		(fp_line
			(start -0.12065 -0.2794)
			(end 0.12065 -0.2794)
			(stroke
				(width 0.1)
				(type default)
			)
			(layer "F.Fab")
		)
		(fp_line
			(start -0.12065 -0.305054)
			(end -0.12065 -0.2794)
			(stroke
				(width 0.1)
				(type default)
			)
			(layer "F.Fab")
		)
		(fp_line
			(start -0.67945 0.3048)
			(end -0.67945 -0.305054)
			(stroke
				(width 0.1)
				(type default)
			)
			(layer "F.Fab")
		)
		(fp_line
			(start -0.67945 -0.305054)
			(end -0.12065 -0.305054)
			(stroke
				(width 0.1)
				(type default)
			)
			(layer "F.Fab")
		)
		(pad "1" smd circle
			(at -0.40005 0 180)
			(size 0 0)
			(layers "F.Cu" "F.Mask" "F.Paste")
			(net "GND")
		)
		(pad "2" smd circle
			(at 0.40005 0 180)
			(size 0 0)
			(layers "F.Cu" "F.Mask" "F.Paste")
			(net "P3V3_AUX_CS")
		)
	)
	(footprint ""
		(layer "F.Cu")
		(at 81.501488 -30.150308 90)
		(property "Reference" "R382"
			(at 0 0 90)
			(layer "F.SilkS")
			(hide yes)
			(effects
				(font
					(size 1.27 1.27)
				)
			)
		)
		(property "Value" ""
			(at 0 0 90)
			(layer "F.Fab")
			(effects
				(font
					(size 1.27 1.27)
				)
			)
		)
		(duplicate_pad_numbers_are_jumpers no)
		(fp_line
			(start 0.7874 -0.4064)
			(end 0.7874 0.4064)
			(stroke
				(width 0.1524)
				(type default)
			)
			(layer "F.SilkS")
		)
		(fp_line
			(start -0.7874 -0.4064)
			(end 0.7874 -0.4064)
			(stroke
				(width 0.1524)
				(type default)
			)
			(layer "F.SilkS")
		)
		(fp_line
			(start 0.7874 0.4064)
			(end -0.7874 0.4064)
			(stroke
				(width 0.1524)
				(type default)
			)
			(layer "F.SilkS")
		)
		(fp_line
			(start -0.7874 0.4064)
			(end -0.7874 -0.4064)
			(stroke
				(width 0.1524)
				(type default)
			)
			(layer "F.SilkS")
		)
		(fp_line
			(start -0.12065 -0.305054)
			(end -0.12065 -0.2794)
			(stroke
				(width 0.1)
				(type default)
			)
			(layer "F.Fab")
		)
		(fp_line
			(start -0.67945 -0.305054)
			(end -0.12065 -0.305054)
			(stroke
				(width 0.1)
				(type default)
			)
			(layer "F.Fab")
		)
		(fp_line
			(start 0.67945 -0.3048)
			(end 0.67945 0.3048)
			(stroke
				(width 0.1)
				(type default)
			)
			(layer "F.Fab")
		)
		(fp_line
			(start 0.12065 -0.3048)
			(end 0.67945 -0.3048)
			(stroke
				(width 0.1)
				(type default)
			)
			(layer "F.Fab")
		)
		(fp_line
			(start 0.12065 -0.2794)
			(end 0.12065 -0.3048)
			(stroke
				(width 0.1)
				(type default)
			)
			(layer "F.Fab")
		)
		(fp_line
			(start -0.12065 -0.2794)
			(end 0.12065 -0.2794)
			(stroke
				(width 0.1)
				(type default)
			)
			(layer "F.Fab")
		)
		(fp_line
			(start 0.120396 0.2794)
			(end -0.12065 0.2794)
			(stroke
				(width 0.1)
				(type default)
			)
			(layer "F.Fab")
		)
		(fp_line
			(start -0.12065 0.2794)
			(end -0.12065 0.3048)
			(stroke
				(width 0.1)
				(type default)
			)
			(layer "F.Fab")
		)
		(fp_line
			(start 0.67945 0.3048)
			(end 0.120396 0.3048)
			(stroke
				(width 0.1)
				(type default)
			)
			(layer "F.Fab")
		)
		(fp_line
			(start 0.120396 0.3048)
			(end 0.120396 0.2794)
			(stroke
				(width 0.1)
				(type default)
			)
			(layer "F.Fab")
		)
		(fp_line
			(start -0.12065 0.3048)
			(end -0.67945 0.3048)
			(stroke
				(width 0.1)
				(type default)
			)
			(layer "F.Fab")
		)
		(fp_line
			(start -0.67945 0.3048)
			(end -0.67945 -0.305054)
			(stroke
				(width 0.1)
				(type default)
			)
			(layer "F.Fab")
		)
		(pad "1" smd circle
			(at -0.40005 0 90)
			(size 0 0)
			(layers "F.Cu" "F.Mask" "F.Paste")
			(net "PWRGD_P3V3_AUX")
		)
		(pad "2" smd circle
			(at 0.40005 0 90)
			(size 0 0)
			(layers "F.Cu" "F.Mask" "F.Paste")
			(net "PWRGD_P3V3_AUX_R2")
		)
	)
	(footprint ""
		(layer "F.Cu")
		(at 43.966638 -22.15642 -90)
		(property "Reference" "R668"
			(at 0 0 270)
			(layer "F.SilkS")
			(hide yes)
			(effects
				(font
					(size 1.27 1.27)
				)
			)
		)
		(property "Value" ""
			(at 0 0 270)
			(layer "F.Fab")
			(effects
				(font
					(size 1.27 1.27)
				)
			)
		)
		(duplicate_pad_numbers_are_jumpers no)
		(fp_line
			(start 0.7874 0.4064)
			(end -0.7874 0.4064)
			(stroke
				(width 0.1524)
				(type default)
			)
			(layer "F.SilkS")
		)
		(fp_line
			(start -0.7874 -0.4064)
			(end 0.7874 -0.4064)
			(stroke
				(width 0.1524)
				(type default)
			)
			(layer "F.SilkS")
		)
		(fp_line
			(start -0.67945 0.3048)
			(end -0.67945 -0.305054)
			(stroke
				(width 0.1)
				(type default)
			)
			(layer "F.Fab")
		)
		(fp_line
			(start -0.12065 0.3048)
			(end -0.67945 0.3048)
			(stroke
				(width 0.1)
				(type default)
			)
			(layer "F.Fab")
		)
		(fp_line
			(start 0.120396 0.3048)
			(end 0.120396 0.2794)
			(stroke
				(width 0.1)
				(type default)
			)
			(layer "F.Fab")
		)
		(fp_line
			(start 0.67945 0.3048)
			(end 0.120396 0.3048)
			(stroke
				(width 0.1)
				(type default)
			)
			(layer "F.Fab")
		)
		(fp_line
			(start -0.12065 0.2794)
			(end -0.12065 0.3048)
			(stroke
				(width 0.1)
				(type default)
			)
			(layer "F.Fab")
		)
		(fp_line
			(start 0.120396 0.2794)
			(end -0.12065 0.2794)
			(stroke
				(width 0.1)
				(type default)
			)
			(layer "F.Fab")
		)
		(fp_line
			(start -0.12065 -0.2794)
			(end 0.12065 -0.2794)
			(stroke
				(width 0.1)
				(type default)
			)
			(layer "F.Fab")
		)
		(fp_line
			(start 0.12065 -0.2794)
			(end 0.12065 -0.3048)
			(stroke
				(width 0.1)
				(type default)
			)
			(layer "F.Fab")
		)
		(fp_line
			(start 0.12065 -0.3048)
			(end 0.67945 -0.3048)
			(stroke
				(width 0.1)
				(type default)
			)
			(layer "F.Fab")
		)
		(fp_line
			(start 0.67945 -0.3048)
			(end 0.67945 0.3048)
			(stroke
				(width 0.1)
				(type default)
			)
			(layer "F.Fab")
		)
		(fp_line
			(start -0.67945 -0.305054)
			(end -0.12065 -0.305054)
			(stroke
				(width 0.1)
				(type default)
			)
			(layer "F.Fab")
		)
		(fp_line
			(start -0.12065 -0.305054)
			(end -0.12065 -0.2794)
			(stroke
				(width 0.1)
				(type default)
			)
			(layer "F.Fab")
		)
		(pad "1" smd circle
			(at -0.40005 0 270)
			(size 0 0)
			(layers "F.Cu" "F.Mask" "F.Paste")
			(net "USB3_01_MUX_FB_RXN")
		)
		(pad "2" smd circle
			(at 0.40005 0 270)
			(size 0 0)
			(layers "F.Cu" "F.Mask" "F.Paste")
			(net "USB3_01_FB_RXN")
		)
	)
	(footprint ""
		(layer "F.Cu")
		(at 12.4206 -101.9429)
		(property "Reference" "R463"
			(at 0 0 0)
			(layer "F.SilkS")
			(hide yes)
			(effects
				(font
					(size 1.27 1.27)
				)
			)
		)
		(property "Value" ""
			(at 0 0 0)
			(layer "F.Fab")
			(effects
				(font
					(size 1.27 1.27)
				)
			)
		)
		(duplicate_pad_numbers_are_jumpers no)
		(fp_line
			(start -0.7874 -0.4064)
			(end 0.7874 -0.4064)
			(stroke
				(width 0.1524)
				(type default)
			)
			(layer "F.SilkS")
		)
		(fp_line
			(start -0.7874 0.4064)
			(end -0.7874 -0.4064)
			(stroke
				(width 0.1524)
				(type default)
			)
			(layer "F.SilkS")
		)
		(fp_line
			(start 0.7874 -0.4064)
			(end 0.7874 0.4064)
			(stroke
				(width 0.1524)
				(type default)
			)
			(layer "F.SilkS")
		)
		(fp_line
			(start 0.7874 0.4064)
			(end -0.7874 0.4064)
			(stroke
				(width 0.1524)
				(type default)
			)
			(layer "F.SilkS")
		)
		(fp_line
			(start -0.67945 -0.305054)
			(end -0.12065 -0.305054)
			(stroke
				(width 0.1)
				(type default)
			)
			(layer "F.Fab")
		)
		(fp_line
			(start -0.67945 0.3048)
			(end -0.67945 -0.305054)
			(stroke
				(width 0.1)
				(type default)
			)
			(layer "F.Fab")
		)
		(fp_line
			(start -0.12065 -0.305054)
			(end -0.12065 -0.2794)
			(stroke
				(width 0.1)
				(type default)
			)
			(layer "F.Fab")
		)
		(fp_line
			(start -0.12065 -0.2794)
			(end 0.12065 -0.2794)
			(stroke
				(width 0.1)
				(type default)
			)
			(layer "F.Fab")
		)
		(fp_line
			(start -0.12065 0.2794)
			(end -0.12065 0.3048)
			(stroke
				(width 0.1)
				(type default)
			)
			(layer "F.Fab")
		)
		(fp_line
			(start -0.12065 0.3048)
			(end -0.67945 0.3048)
			(stroke
				(width 0.1)
				(type default)
			)
			(layer "F.Fab")
		)
		(fp_line
			(start 0.120396 0.2794)
			(end -0.12065 0.2794)
			(stroke
				(width 0.1)
				(type default)
			)
			(layer "F.Fab")
		)
		(fp_line
			(start 0.120396 0.3048)
			(end 0.120396 0.2794)
			(stroke
				(width 0.1)
				(type default)
			)
			(layer "F.Fab")
		)
		(fp_line
			(start 0.12065 -0.3048)
			(end 0.67945 -0.3048)
			(stroke
				(width 0.1)
				(type default)
			)
			(layer "F.Fab")
		)
		(fp_line
			(start 0.12065 -0.2794)
			(end 0.12065 -0.3048)
			(stroke
				(width 0.1)
				(type default)
			)
			(layer "F.Fab")
		)
		(fp_line
			(start 0.67945 -0.3048)
			(end 0.67945 0.3048)
			(stroke
				(width 0.1)
				(type default)
			)
			(layer "F.Fab")
		)
		(fp_line
			(start 0.67945 0.3048)
			(end 0.120396 0.3048)
			(stroke
				(width 0.1)
				(type default)
			)
			(layer "F.Fab")
		)
		(pad "1" smd circle
			(at -0.40005 0)
			(size 0 0)
			(layers "F.Cu" "F.Mask" "F.Paste")
			(net "AC_PWR_BTN_R1_N")
		)
		(pad "2" smd circle
			(at 0.40005 0)
			(size 0 0)
			(layers "F.Cu" "F.Mask" "F.Paste")
			(net "AC_PWR_BTN_R2_N")
		)
	)
	(footprint ""
		(layer "F.Cu")
		(at 51.562 -18.034)
		(property "Reference" "C327"
			(at 0 0 0)
			(layer "F.SilkS")
			(hide yes)
			(effects
				(font
					(size 1.27 1.27)
				)
			)
		)
		(property "Value" ""
			(at 0 0 0)
			(layer "F.Fab")
			(effects
				(font
					(size 1.27 1.27)
				)
			)
		)
		(duplicate_pad_numbers_are_jumpers no)
		(fp_line
			(start -2.2098 -0.9398)
			(end 2.2098 -0.9398)
			(stroke
				(width 0.1524)
				(type default)
			)
			(layer "F.SilkS")
		)
		(fp_line
			(start -2.2098 0.9398)
			(end -2.2098 -0.9398)
			(stroke
				(width 0.1524)
				(type default)
			)
			(layer "F.SilkS")
		)
		(fp_line
			(start 2.2098 -0.9398)
			(end 2.2098 0.9398)
			(stroke
				(width 0.1524)
				(type default)
			)
			(layer "F.SilkS")
		)
		(fp_line
			(start 2.2098 0.9398)
			(end -2.2098 0.9398)
			(stroke
				(width 0.1524)
				(type default)
			)
			(layer "F.SilkS")
		)
		(fp_line
			(start -1.700022 -0.899922)
			(end 1.700022 -0.899922)
			(stroke
				(width 0.1)
				(type default)
			)
			(layer "F.Fab")
		)
		(fp_line
			(start -1.700022 0.899922)
			(end -1.700022 -0.899922)
			(stroke
				(width 0.1)
				(type default)
			)
			(layer "F.Fab")
		)
		(fp_line
			(start 1.700022 -0.899922)
			(end 1.700022 0.899922)
			(stroke
				(width 0.1)
				(type default)
			)
			(layer "F.Fab")
		)
		(fp_line
			(start 1.700022 0.899922)
			(end -1.700022 0.899922)
			(stroke
				(width 0.1)
				(type default)
			)
			(layer "F.Fab")
		)
		(pad "1" smd rect
			(at -1.4732 0 180)
			(size 1.1684 1.5748)
			(layers "F.Cu" "F.Mask" "F.Paste")
			(net "P5V_USB_REAR")
		)
		(pad "2" smd rect
			(at 1.4732 0 180)
			(size 1.1684 1.5748)
			(layers "F.Cu" "F.Mask" "F.Paste")
			(net "GND")
		)
	)
	(footprint ""
		(layer "F.Cu")
		(at 84.792312 -72.333358 90)
		(property "Reference" "PC250"
			(at 0 0 90)
			(layer "F.SilkS")
			(hide yes)
			(effects
				(font
					(size 1.27 1.27)
				)
			)
		)
		(property "Value" ""
			(at 0 0 90)
			(layer "F.Fab")
			(effects
				(font
					(size 1.27 1.27)
				)
			)
		)
		(duplicate_pad_numbers_are_jumpers no)
		(fp_line
			(start 0.7874 -0.4064)
			(end 0.7874 0.4064)
			(stroke
				(width 0.1524)
				(type default)
			)
			(layer "F.SilkS")
		)
		(fp_line
			(start -0.7874 -0.4064)
			(end 0.7874 -0.4064)
			(stroke
				(width 0.1524)
				(type default)
			)
			(layer "F.SilkS")
		)
		(fp_line
			(start 0.7874 0.4064)
			(end -0.7874 0.4064)
			(stroke
				(width 0.1524)
				(type default)
			)
			(layer "F.SilkS")
		)
		(fp_line
			(start -0.7874 0.4064)
			(end -0.7874 -0.4064)
			(stroke
				(width 0.1524)
				(type default)
			)
			(layer "F.SilkS")
		)
		(fp_line
			(start -0.12065 -0.305054)
			(end -0.12065 -0.2794)
			(stroke
				(width 0.1)
				(type default)
			)
			(layer "F.Fab")
		)
		(fp_line
			(start -0.67945 -0.305054)
			(end -0.12065 -0.305054)
			(stroke
				(width 0.1)
				(type default)
			)
			(layer "F.Fab")
		)
		(fp_line
			(start 0.67945 -0.3048)
			(end 0.67945 0.3048)
			(stroke
				(width 0.1)
				(type default)
			)
			(layer "F.Fab")
		)
		(fp_line
			(start 0.12065 -0.3048)
			(end 0.67945 -0.3048)
			(stroke
				(width 0.1)
				(type default)
			)
			(layer "F.Fab")
		)
		(fp_line
			(start 0.12065 -0.2794)
			(end 0.12065 -0.3048)
			(stroke
				(width 0.1)
				(type default)
			)
			(layer "F.Fab")
		)
		(fp_line
			(start -0.12065 -0.2794)
			(end 0.12065 -0.2794)
			(stroke
				(width 0.1)
				(type default)
			)
			(layer "F.Fab")
		)
		(fp_line
			(start 0.120396 0.2794)
			(end -0.12065 0.2794)
			(stroke
				(width 0.1)
				(type default)
			)
			(layer "F.Fab")
		)
		(fp_line
			(start -0.12065 0.2794)
			(end -0.12065 0.3048)
			(stroke
				(width 0.1)
				(type default)
			)
			(layer "F.Fab")
		)
		(fp_line
			(start 0.67945 0.3048)
			(end 0.120396 0.3048)
			(stroke
				(width 0.1)
				(type default)
			)
			(layer "F.Fab")
		)
		(fp_line
			(start 0.120396 0.3048)
			(end 0.120396 0.2794)
			(stroke
				(width 0.1)
				(type default)
			)
			(layer "F.Fab")
		)
		(fp_line
			(start -0.12065 0.3048)
			(end -0.67945 0.3048)
			(stroke
				(width 0.1)
				(type default)
			)
			(layer "F.Fab")
		)
		(fp_line
			(start -0.67945 0.3048)
			(end -0.67945 -0.305054)
			(stroke
				(width 0.1)
				(type default)
			)
			(layer "F.Fab")
		)
		(pad "1" smd circle
			(at -0.40005 0 90)
			(size 0 0)
			(layers "F.Cu" "F.Mask" "F.Paste")
			(net "P1V2_AUX_VCC")
		)
		(pad "2" smd circle
			(at 0.40005 0 90)
			(size 0 0)
			(layers "F.Cu" "F.Mask" "F.Paste")
			(net "GND")
		)
	)
	(footprint ""
		(layer "F.Cu")
		(at 103.8225 -54.403752 -90)
		(property "Reference" "J22"
			(at -4.016248 -1.48717 90)
			(unlocked yes)
			(layer "F.SilkS")
			(effects
				(font
					(size 0.7874 0.5842)
					(thickness 0.1524)
				)
				(justify left)
			)
		)
		(property "Value" ""
			(at 0 0 270)
			(layer "F.Fab")
			(effects
				(font
					(size 1.27 1.27)
				)
			)
		)
		(duplicate_pad_numbers_are_jumpers no)
		(fp_line
			(start -1.2192 2.1082)
			(end -1.2192 -2.1082)
			(stroke
				(width 0.1524)
				(type default)
			)
			(layer "F.SilkS")
		)
		(fp_line
			(start 1.2192 2.1082)
			(end -1.2192 2.1082)
			(stroke
				(width 0.1524)
				(type default)
			)
			(layer "F.SilkS")
		)
		(fp_line
			(start 1.2192 0.456692)
			(end 1.2192 2.1082)
			(stroke
				(width 0.1524)
				(type default)
			)
			(layer "F.SilkS")
		)
		(fp_line
			(start -1.2192 -2.1082)
			(end 1.2192 -2.1082)
			(stroke
				(width 0.1524)
				(type default)
			)
			(layer "F.SilkS")
		)
		(fp_line
			(start 1.2192 -2.1082)
			(end 1.2192 -0.450596)
			(stroke
				(width 0.1524)
				(type default)
			)
			(layer "F.SilkS")
		)
		(pad "" np_thru_hole circle
			(at -2.8829 -1.27 180)
			(size 1.0414 1.0414)
			(drill 1.0414)
			(layers "*.Cu" "*.Mask")
			(clearance 0.381)
			(thermal_gap 0.381)
		)
		(pad "" np_thru_hole circle
			(at -2.8829 1.27 180)
			(size 1.0414 1.0414)
			(drill 1.0414)
			(layers "*.Cu" "*.Mask")
			(clearance 0.381)
			(thermal_gap 0.381)
		)
		(pad "" np_thru_hole circle
			(at 3.4671 -1.27 180)
			(size 1.0414 1.0414)
			(drill 1.0414)
			(layers "*.Cu" "*.Mask")
			(clearance 0.381)
			(thermal_gap 0.381)
		)
		(pad "" np_thru_hole circle
			(at 3.4671 1.27 180)
			(size 1.0414 1.0414)
			(drill 1.0414)
			(layers "*.Cu" "*.Mask")
			(clearance 0.381)
			(thermal_gap 0.381)
		)
		(pad "1" smd rect
			(at 0.8255 -0.249936 180)
			(size 0.3048 0.508)
			(layers "F.Cu" "F.Mask" "F.Paste")
			(net "85_10INCH_TOP_DP")
		)
		(pad "2" smd rect
			(at 0.8255 0.249936 180)
			(size 0.3048 0.508)
			(layers "F.Cu" "F.Mask" "F.Paste")
			(net "85_10INCH_TOP_DN")
		)
		(pad "3" smd circle
			(at 0 0 270)
			(size 0 0)
			(layers "F.Cu" "F.Mask" "F.Paste")
			(net "GND_P1")
		)
		(zone
			(layer "F.Cu")
			(hatch none 0.5)
			(connect_pads
				(clearance 0)
			)
			(min_thickness 0.25)
			(keepout
				(tracks not_allowed)
				(vias allowed)
				(pads allowed)
				(copperpour not_allowed)
				(footprints allowed)
			)
			(placement
				(enabled no)
				(sheetname "")
			)
			(fill
				(thermal_gap 0.5)
				(thermal_bridge_width 0.5)
				(island_removal_mode 0)
			)
			(polygon
				(pts
					(xy 104.37114 -53.286152) (xy 104.275636 -53.286152) (xy 104.275636 -53.883052) (xy 103.869236 -53.883052)
					(xy 103.869236 -53.286152) (xy 103.775764 -53.286152) (xy 103.775764 -53.883052) (xy 103.369364 -53.883052)
					(xy 103.369364 -53.286152) (xy 103.27386 -53.286152) (xy 103.27386 -53.984652) (xy 104.37114 -53.984652)
				)
			)
		)
		(zone
			(layers "F.Cu" "B.Cu" "In1.Cu" "In2.Cu" "In3.Cu" "In4.Cu" "In5.Cu" "In6.Cu"
				"In7.Cu" "In8.Cu" "In9.Cu" "In10.Cu"
			)
			(hatch none 0.5)
			(connect_pads
				(clearance 0)
			)
			(min_thickness 0.25)
			(keepout
				(tracks not_allowed)
				(vias allowed)
				(pads allowed)
				(copperpour not_allowed)
				(footprints allowed)
			)
			(placement
				(enabled no)
				(sheetname "")
			)
			(fill
				(thermal_gap 0.5)
				(thermal_bridge_width 0.5)
				(island_removal_mode 0)
			)
			(polygon
				(pts
					(arc
						(start 103.4796 -57.286652)
						(mid 101.6254 -57.286652)
						(end 103.4796 -57.286652)
					)
				)
			)
		)
		(zone
			(layers "F.Cu" "B.Cu" "In1.Cu" "In2.Cu" "In3.Cu" "In4.Cu" "In5.Cu" "In6.Cu"
				"In7.Cu" "In8.Cu" "In9.Cu" "In10.Cu"
			)
			(hatch none 0.5)
			(connect_pads
				(clearance 0)
			)
			(min_thickness 0.25)
			(keepout
				(tracks not_allowed)
				(vias allowed)
				(pads allowed)
				(copperpour not_allowed)
				(footprints allowed)
			)
			(placement
				(enabled no)
				(sheetname "")
			)
			(fill
				(thermal_gap 0.5)
				(thermal_bridge_width 0.5)
				(island_removal_mode 0)
			)
			(polygon
				(pts
					(arc
						(start 103.4796 -50.936652)
						(mid 101.6254 -50.936652)
						(end 103.4796 -50.936652)
					)
				)
			)
		)
		(zone
			(layers "F.Cu" "B.Cu" "In1.Cu" "In2.Cu" "In3.Cu" "In4.Cu" "In5.Cu" "In6.Cu"
				"In7.Cu" "In8.Cu" "In9.Cu" "In10.Cu"
			)
			(hatch none 0.5)
			(connect_pads
				(clearance 0)
			)
			(min_thickness 0.25)
			(keepout
				(tracks not_allowed)
				(vias allowed)
				(pads allowed)
				(copperpour not_allowed)
				(footprints allowed)
			)
			(placement
				(enabled no)
				(sheetname "")
			)
			(fill
				(thermal_gap 0.5)
				(thermal_bridge_width 0.5)
				(island_removal_mode 0)
			)
			(polygon
				(pts
					(arc
						(start 106.0196 -57.286652)
						(mid 104.1654 -57.286652)
						(end 106.0196 -57.286652)
					)
				)
			)
		)
		(zone
			(layers "F.Cu" "B.Cu" "In1.Cu" "In2.Cu" "In3.Cu" "In4.Cu" "In5.Cu" "In6.Cu"
				"In7.Cu" "In8.Cu" "In9.Cu" "In10.Cu"
			)
			(hatch none 0.5)
			(connect_pads
				(clearance 0)
			)
			(min_thickness 0.25)
			(keepout
				(tracks not_allowed)
				(vias allowed)
				(pads allowed)
				(copperpour not_allowed)
				(footprints allowed)
			)
			(placement
				(enabled no)
				(sheetname "")
			)
			(fill
				(thermal_gap 0.5)
				(thermal_bridge_width 0.5)
				(island_removal_mode 0)
			)
			(polygon
				(pts
					(arc
						(start 106.0196 -50.936652)
						(mid 104.1654 -50.936652)
						(end 106.0196 -50.936652)
					)
				)
			)
		)
	)
	(footprint ""
		(layer "F.Cu")
		(at 9.842246 -46.814994)
		(property "Reference" "PC216"
			(at 0 0 0)
			(layer "F.SilkS")
			(hide yes)
			(effects
				(font
					(size 1.27 1.27)
				)
			)
		)
		(property "Value" ""
			(at 0 0 0)
			(layer "F.Fab")
			(effects
				(font
					(size 1.27 1.27)
				)
			)
		)
		(duplicate_pad_numbers_are_jumpers no)
		(fp_line
			(start -0.7874 -0.4064)
			(end 0.7874 -0.4064)
			(stroke
				(width 0.1524)
				(type default)
			)
			(layer "F.SilkS")
		)
		(fp_line
			(start -0.7874 0.4064)
			(end -0.7874 -0.4064)
			(stroke
				(width 0.1524)
				(type default)
			)
			(layer "F.SilkS")
		)
		(fp_line
			(start 0.7874 -0.4064)
			(end 0.7874 0.4064)
			(stroke
				(width 0.1524)
				(type default)
			)
			(layer "F.SilkS")
		)
		(fp_line
			(start 0.7874 0.4064)
			(end -0.7874 0.4064)
			(stroke
				(width 0.1524)
				(type default)
			)
			(layer "F.SilkS")
		)
		(fp_line
			(start -0.67945 -0.305054)
			(end -0.12065 -0.305054)
			(stroke
				(width 0.1)
				(type default)
			)
			(layer "F.Fab")
		)
		(fp_line
			(start -0.67945 0.3048)
			(end -0.67945 -0.305054)
			(stroke
				(width 0.1)
				(type default)
			)
			(layer "F.Fab")
		)
		(fp_line
			(start -0.12065 -0.305054)
			(end -0.12065 -0.2794)
			(stroke
				(width 0.1)
				(type default)
			)
			(layer "F.Fab")
		)
		(fp_line
			(start -0.12065 -0.2794)
			(end 0.12065 -0.2794)
			(stroke
				(width 0.1)
				(type default)
			)
			(layer "F.Fab")
		)
		(fp_line
			(start -0.12065 0.2794)
			(end -0.12065 0.3048)
			(stroke
				(width 0.1)
				(type default)
			)
			(layer "F.Fab")
		)
		(fp_line
			(start -0.12065 0.3048)
			(end -0.67945 0.3048)
			(stroke
				(width 0.1)
				(type default)
			)
			(layer "F.Fab")
		)
		(fp_line
			(start 0.120396 0.2794)
			(end -0.12065 0.2794)
			(stroke
				(width 0.1)
				(type default)
			)
			(layer "F.Fab")
		)
		(fp_line
			(start 0.120396 0.3048)
			(end 0.120396 0.2794)
			(stroke
				(width 0.1)
				(type default)
			)
			(layer "F.Fab")
		)
		(fp_line
			(start 0.12065 -0.3048)
			(end 0.67945 -0.3048)
			(stroke
				(width 0.1)
				(type default)
			)
			(layer "F.Fab")
		)
		(fp_line
			(start 0.12065 -0.2794)
			(end 0.12065 -0.3048)
			(stroke
				(width 0.1)
				(type default)
			)
			(layer "F.Fab")
		)
		(fp_line
			(start 0.67945 -0.3048)
			(end 0.67945 0.3048)
			(stroke
				(width 0.1)
				(type default)
			)
			(layer "F.Fab")
		)
		(fp_line
			(start 0.67945 0.3048)
			(end 0.120396 0.3048)
			(stroke
				(width 0.1)
				(type default)
			)
			(layer "F.Fab")
		)
		(pad "1" smd circle
			(at -0.40005 0)
			(size 0 0)
			(layers "F.Cu" "F.Mask" "F.Paste")
			(net "SW_P5V_AUX_BST")
		)
		(pad "2" smd circle
			(at 0.40005 0)
			(size 0 0)
			(layers "F.Cu" "F.Mask" "F.Paste")
			(net "SW_P5V_AUX_SW")
		)
	)
	(footprint ""
		(layer "F.Cu")
		(at 15.494 -83.693 -90)
		(property "Reference" "R810"
			(at 0 0 270)
			(layer "F.SilkS")
			(hide yes)
			(effects
				(font
					(size 1.27 1.27)
				)
			)
		)
		(property "Value" ""
			(at 0 0 270)
			(layer "F.Fab")
			(effects
				(font
					(size 1.27 1.27)
				)
			)
		)
		(duplicate_pad_numbers_are_jumpers no)
		(fp_line
			(start -0.7874 0.4064)
			(end -0.7874 -0.4064)
			(stroke
				(width 0.1524)
				(type default)
			)
			(layer "F.SilkS")
		)
		(fp_line
			(start 0.7874 0.4064)
			(end -0.7874 0.4064)
			(stroke
				(width 0.1524)
				(type default)
			)
			(layer "F.SilkS")
		)
		(fp_line
			(start -0.7874 -0.4064)
			(end 0.7874 -0.4064)
			(stroke
				(width 0.1524)
				(type default)
			)
			(layer "F.SilkS")
		)
		(fp_line
			(start 0.7874 -0.4064)
			(end 0.7874 0.4064)
			(stroke
				(width 0.1524)
				(type default)
			)
			(layer "F.SilkS")
		)
		(fp_line
			(start -0.67945 0.3048)
			(end -0.67945 -0.305054)
			(stroke
				(width 0.1)
				(type default)
			)
			(layer "F.Fab")
		)
		(fp_line
			(start -0.12065 0.3048)
			(end -0.67945 0.3048)
			(stroke
				(width 0.1)
				(type default)
			)
			(layer "F.Fab")
		)
		(fp_line
			(start 0.120396 0.3048)
			(end 0.120396 0.2794)
			(stroke
				(width 0.1)
				(type default)
			)
			(layer "F.Fab")
		)
		(fp_line
			(start 0.67945 0.3048)
			(end 0.120396 0.3048)
			(stroke
				(width 0.1)
				(type default)
			)
			(layer "F.Fab")
		)
		(fp_line
			(start -0.12065 0.2794)
			(end -0.12065 0.3048)
			(stroke
				(width 0.1)
				(type default)
			)
			(layer "F.Fab")
		)
		(fp_line
			(start 0.120396 0.2794)
			(end -0.12065 0.2794)
			(stroke
				(width 0.1)
				(type default)
			)
			(layer "F.Fab")
		)
		(fp_line
			(start -0.12065 -0.2794)
			(end 0.12065 -0.2794)
			(stroke
				(width 0.1)
				(type default)
			)
			(layer "F.Fab")
		)
		(fp_line
			(start 0.12065 -0.2794)
			(end 0.12065 -0.3048)
			(stroke
				(width 0.1)
				(type default)
			)
			(layer "F.Fab")
		)
		(fp_line
			(start 0.12065 -0.3048)
			(end 0.67945 -0.3048)
			(stroke
				(width 0.1)
				(type default)
			)
			(layer "F.Fab")
		)
		(fp_line
			(start 0.67945 -0.3048)
			(end 0.67945 0.3048)
			(stroke
				(width 0.1)
				(type default)
			)
			(layer "F.Fab")
		)
		(fp_line
			(start -0.67945 -0.305054)
			(end -0.12065 -0.305054)
			(stroke
				(width 0.1)
				(type default)
			)
			(layer "F.Fab")
		)
		(fp_line
			(start -0.12065 -0.305054)
			(end -0.12065 -0.2794)
			(stroke
				(width 0.1)
				(type default)
			)
			(layer "F.Fab")
		)
		(pad "1" smd circle
			(at -0.40005 0 270)
			(size 0 0)
			(layers "F.Cu" "F.Mask" "F.Paste")
			(net "PU_FPGA_NSTATUS")
		)
		(pad "2" smd circle
			(at 0.40005 0 270)
			(size 0 0)
			(layers "F.Cu" "F.Mask" "F.Paste")
			(net "PVCCIO_AUX_PLD")
		)
	)
	(footprint ""
		(layer "F.Cu")
		(at 6.050026 -103.925116)
		(property "Reference" "J7"
			(at -4.703826 -0.048514 0)
			(unlocked yes)
			(layer "F.SilkS")
			(effects
				(font
					(size 0.7874 0.5842)
					(thickness 0.1524)
				)
				(justify left)
			)
		)
		(property "Value" ""
			(at 0 0 0)
			(layer "F.Fab")
			(effects
				(font
					(size 1.27 1.27)
				)
			)
		)
		(duplicate_pad_numbers_are_jumpers no)
		(fp_line
			(start -1.249934 -1.320038)
			(end 1.249934 -1.320038)
			(stroke
				(width 0.1524)
				(type default)
			)
			(layer "F.SilkS")
		)
		(fp_line
			(start -1.249934 19.100038)
			(end -1.249934 -1.320038)
			(stroke
				(width 0.1524)
				(type default)
			)
			(layer "F.SilkS")
		)
		(fp_line
			(start 1.249934 -1.320038)
			(end 1.249934 19.100038)
			(stroke
				(width 0.1524)
				(type default)
			)
			(layer "F.SilkS")
		)
		(fp_line
			(start 1.249934 19.100038)
			(end -1.249934 19.100038)
			(stroke
				(width 0.1524)
				(type default)
			)
			(layer "F.SilkS")
		)
		(fp_poly
			(pts
				(xy -2.7432 0.63881) (xy -2.7432 -0.63881) (xy -1.465834 0)
			)
			(stroke
				(width 0)
				(type default)
			)
			(fill yes)
			(layer "F.SilkS")
		)
		(fp_line
			(start -1.249934 -1.320038)
			(end 1.249934 -1.320038)
			(stroke
				(width 0.1)
				(type default)
			)
			(layer "F.Fab")
		)
		(fp_line
			(start -1.249934 19.100038)
			(end -1.249934 -1.320038)
			(stroke
				(width 0.1)
				(type default)
			)
			(layer "F.Fab")
		)
		(fp_line
			(start 1.249934 -1.320038)
			(end 1.249934 19.100038)
			(stroke
				(width 0.1)
				(type default)
			)
			(layer "F.Fab")
		)
		(fp_line
			(start 1.249934 19.100038)
			(end -1.249934 19.100038)
			(stroke
				(width 0.1)
				(type default)
			)
			(layer "F.Fab")
		)
		(fp_poly
			(pts
				(xy -2.7432 0.63881) (xy -2.7432 -0.63881) (xy -1.465834 0)
			)
			(stroke
				(width 0)
				(type default)
			)
			(fill yes)
			(layer "F.Fab")
		)
		(fp_text user "8"
			(at -1.7526 17.80667 0)
			(unlocked yes)
			(layer "F.SilkS")
			(effects
				(font
					(size 0.7874 0.5842)
					(thickness 0.1524)
				)
			)
		)
		(fp_text user "1"
			(at -1.401826 -0.340614 0)
			(unlocked yes)
			(layer "B.SilkS")
			(effects
				(font
					(size 0.7874 0.5842)
					(thickness 0.1524)
				)
				(justify mirror)
			)
		)
		(fp_text user "8"
			(at -1.1938 17.80667 0)
			(unlocked yes)
			(layer "B.SilkS")
			(effects
				(font
					(size 0.7874 0.5842)
					(thickness 0.1524)
				)
				(justify mirror)
			)
		)
		(fp_text user "8"
			(at -1.1938 17.80667 0)
			(unlocked yes)
			(layer "B.Fab")
			(effects
				(font
					(size 0.7874 0.5842)
					(thickness 0.1524)
				)
				(justify mirror)
			)
		)
		(fp_text user "1"
			(at -1.1176 -0.02413 0)
			(unlocked yes)
			(layer "B.Fab")
			(effects
				(font
					(size 0.7874 0.5842)
					(thickness 0.1524)
				)
				(justify mirror)
			)
		)
		(fp_text user "8"
			(at -1.7526 17.80667 0)
			(unlocked yes)
			(layer "F.Fab")
			(effects
				(font
					(size 0.7874 0.5842)
					(thickness 0.1524)
				)
			)
		)
		(pad "1" thru_hole rect
			(at 0 0)
			(size 1.5494 1.5494)
			(drill 1.0414)
			(layers "*.Cu" "*.Mask")
			(remove_unused_layers no)
			(net "J7_P1")
			(clearance 0)
			(padstack
				(mode front_inner_back)
				(layer "Inner"
					(shape circle)
					(size 1.5494 1.5494)
					(clearance 0)
				)
				(layer "B.Cu"
					(shape rect)
					(size 1.5494 1.5494)
					(clearance 0)
				)
			)
		)
		(pad "2" thru_hole circle
			(at 0 2.54)
			(size 1.5494 1.5494)
			(drill 1.0414)
			(layers "*.Cu" "*.Mask")
			(remove_unused_layers no)
			(net "JTAG_SCM_CONN_TDO")
			(clearance 0)
		)
		(pad "3" thru_hole circle
			(at 0 5.08)
			(size 1.5494 1.5494)
			(drill 1.0414)
			(layers "*.Cu" "*.Mask")
			(remove_unused_layers no)
			(net "JTAG_SCM_CONN_TDI")
			(clearance 0)
		)
		(pad "4" thru_hole circle
			(at 0 7.62)
			(size 1.5494 1.5494)
			(drill 1.0414)
			(layers "*.Cu" "*.Mask")
			(remove_unused_layers no)
			(net "JTAG_SCM_PLD_R1_JTAGEN")
			(clearance 0)
		)
		(pad "5" thru_hole circle
			(at 0 10.16)
			(size 1.5494 1.5494)
			(drill 1.0414)
			(layers "*.Cu" "*.Mask")
			(remove_unused_layers no)
			(net "TP_PLD_CONN_P5")
			(clearance 0)
		)
		(pad "6" thru_hole circle
			(at 0 12.7)
			(size 1.5494 1.5494)
			(drill 1.0414)
			(layers "*.Cu" "*.Mask")
			(remove_unused_layers no)
			(net "JTAG_SCM_CONN_TMS")
			(clearance 0)
		)
		(pad "7" thru_hole circle
			(at 0 15.24)
			(size 1.5494 1.5494)
			(drill 1.0414)
			(layers "*.Cu" "*.Mask")
			(remove_unused_layers no)
			(net "GND")
			(clearance 0)
		)
		(pad "8" thru_hole circle
			(at 0 17.78)
			(size 1.5494 1.5494)
			(drill 1.0414)
			(layers "*.Cu" "*.Mask")
			(remove_unused_layers no)
			(net "JTAG_SCM_CONN_TCK")
			(clearance 0)
		)
	)
	(footprint ""
		(layer "F.Cu")
		(at 39.4462 -26.1112 90)
		(property "Reference" "R392"
			(at 0 0 90)
			(layer "F.SilkS")
			(hide yes)
			(effects
				(font
					(size 1.27 1.27)
				)
			)
		)
		(property "Value" ""
			(at 0 0 90)
			(layer "F.Fab")
			(effects
				(font
					(size 1.27 1.27)
				)
			)
		)
		(duplicate_pad_numbers_are_jumpers no)
		(fp_line
			(start 0.7874 -0.4064)
			(end 0.7874 0.4064)
			(stroke
				(width 0.1524)
				(type default)
			)
			(layer "F.SilkS")
		)
		(fp_line
			(start -0.7874 -0.4064)
			(end 0.7874 -0.4064)
			(stroke
				(width 0.1524)
				(type default)
			)
			(layer "F.SilkS")
		)
		(fp_line
			(start 0.7874 0.4064)
			(end -0.7874 0.4064)
			(stroke
				(width 0.1524)
				(type default)
			)
			(layer "F.SilkS")
		)
		(fp_line
			(start -0.7874 0.4064)
			(end -0.7874 -0.4064)
			(stroke
				(width 0.1524)
				(type default)
			)
			(layer "F.SilkS")
		)
		(fp_line
			(start -0.12065 -0.305054)
			(end -0.12065 -0.2794)
			(stroke
				(width 0.1)
				(type default)
			)
			(layer "F.Fab")
		)
		(fp_line
			(start -0.67945 -0.305054)
			(end -0.12065 -0.305054)
			(stroke
				(width 0.1)
				(type default)
			)
			(layer "F.Fab")
		)
		(fp_line
			(start 0.67945 -0.3048)
			(end 0.67945 0.3048)
			(stroke
				(width 0.1)
				(type default)
			)
			(layer "F.Fab")
		)
		(fp_line
			(start 0.12065 -0.3048)
			(end 0.67945 -0.3048)
			(stroke
				(width 0.1)
				(type default)
			)
			(layer "F.Fab")
		)
		(fp_line
			(start 0.12065 -0.2794)
			(end 0.12065 -0.3048)
			(stroke
				(width 0.1)
				(type default)
			)
			(layer "F.Fab")
		)
		(fp_line
			(start -0.12065 -0.2794)
			(end 0.12065 -0.2794)
			(stroke
				(width 0.1)
				(type default)
			)
			(layer "F.Fab")
		)
		(fp_line
			(start 0.120396 0.2794)
			(end -0.12065 0.2794)
			(stroke
				(width 0.1)
				(type default)
			)
			(layer "F.Fab")
		)
		(fp_line
			(start -0.12065 0.2794)
			(end -0.12065 0.3048)
			(stroke
				(width 0.1)
				(type default)
			)
			(layer "F.Fab")
		)
		(fp_line
			(start 0.67945 0.3048)
			(end 0.120396 0.3048)
			(stroke
				(width 0.1)
				(type default)
			)
			(layer "F.Fab")
		)
		(fp_line
			(start 0.120396 0.3048)
			(end 0.120396 0.2794)
			(stroke
				(width 0.1)
				(type default)
			)
			(layer "F.Fab")
		)
		(fp_line
			(start -0.12065 0.3048)
			(end -0.67945 0.3048)
			(stroke
				(width 0.1)
				(type default)
			)
			(layer "F.Fab")
		)
		(fp_line
			(start -0.67945 0.3048)
			(end -0.67945 -0.305054)
			(stroke
				(width 0.1)
				(type default)
			)
			(layer "F.Fab")
		)
		(pad "1" smd circle
			(at -0.40005 0 90)
			(size 0 0)
			(layers "F.Cu" "F.Mask" "F.Paste")
			(net "RMII_OCP_RCLKI_ISO")
		)
		(pad "2" smd circle
			(at 0.40005 0 90)
			(size 0 0)
			(layers "F.Cu" "F.Mask" "F.Paste")
			(net "RMII_OCP_RCLKI_R_ISO")
		)
	)
	(footprint ""
		(layer "F.Cu")
		(at 21.459444 -93.587062 180)
		(property "Reference" "U25"
			(at -10.595356 -8.218932 0)
			(unlocked yes)
			(layer "F.SilkS")
			(effects
				(font
					(size 0.7874 0.5842)
					(thickness 0.1524)
				)
				(justify left)
			)
		)
		(property "Value" ""
			(at 0 0 180)
			(layer "F.Fab")
			(effects
				(font
					(size 1.27 1.27)
				)
			)
		)
		(duplicate_pad_numbers_are_jumpers no)
		(fp_line
			(start 9.99998 9.99998)
			(end 9.99998 -9.99998)
			(stroke
				(width 0.1524)
				(type default)
			)
			(layer "F.SilkS")
		)
		(fp_line
			(start 9.99998 -9.99998)
			(end 9.826244 -9.99998)
			(stroke
				(width 0.1524)
				(type default)
			)
			(layer "F.SilkS")
		)
		(fp_line
			(start 6.999986 6.999986)
			(end 6.999986 -6.999986)
			(stroke
				(width 0.1524)
				(type default)
			)
			(layer "F.SilkS")
		)
		(fp_line
			(start 6.999986 -6.999986)
			(end -6.999986 -6.999986)
			(stroke
				(width 0.1524)
				(type default)
			)
			(layer "F.SilkS")
		)
		(fp_line
			(start 0.377444 -9.99998)
			(end -0.740156 -9.99998)
			(stroke
				(width 0.1524)
				(type default)
			)
			(layer "F.SilkS")
		)
		(fp_line
			(start -6.999986 6.999986)
			(end 6.999986 6.999986)
			(stroke
				(width 0.1524)
				(type default)
			)
			(layer "F.SilkS")
		)
		(fp_line
			(start -6.999986 -6.999986)
			(end -6.999986 6.999986)
			(stroke
				(width 0.1524)
				(type default)
			)
			(layer "F.SilkS")
		)
		(fp_line
			(start -9.99998 9.99998)
			(end 9.99998 9.99998)
			(stroke
				(width 0.1524)
				(type default)
			)
			(layer "F.SilkS")
		)
		(fp_line
			(start -9.99998 -9.99998)
			(end -9.99998 9.99998)
			(stroke
				(width 0.1524)
				(type default)
			)
			(layer "F.SilkS")
		)
		(fp_poly
			(pts
				(xy -9.99998 -6.571488) (xy -8.78078 -7.81558) (xy -7.25678 -6.18998) (xy -6.16458 -7.28218) (xy -7.58698 -8.85698)
				(xy -7.330948 -9.092184) (xy -9.99998 -9.092184)
			)
			(stroke
				(width 0)
				(type default)
			)
			(fill yes)
			(layer "F.SilkS")
		)
		(fp_line
			(start 6.999986 6.999986)
			(end 6.999986 -6.999986)
			(stroke
				(width 0.1)
				(type default)
			)
			(layer "F.Fab")
		)
		(fp_line
			(start 6.999986 -6.999986)
			(end -6.999986 -6.999986)
			(stroke
				(width 0.1)
				(type default)
			)
			(layer "F.Fab")
		)
		(fp_line
			(start -6.999986 6.999986)
			(end 6.999986 6.999986)
			(stroke
				(width 0.1)
				(type default)
			)
			(layer "F.Fab")
		)
		(fp_line
			(start -6.999986 -6.999986)
			(end -6.999986 6.999986)
			(stroke
				(width 0.1)
				(type default)
			)
			(layer "F.Fab")
		)
		(fp_text user "16"
			(at 6.025388 -8.597138 180)
			(unlocked yes)
			(layer "F.SilkS")
			(effects
				(font
					(size 0.635 0.4064)
					(thickness 0.1524)
				)
			)
		)
		(fp_text user "15"
			(at 5.199888 -7.809738 180)
			(unlocked yes)
			(layer "F.SilkS")
			(effects
				(font
					(size 0.635 0.4064)
					(thickness 0.1524)
				)
			)
		)
		(fp_text user "14"
			(at 4.425442 -8.597138 180)
			(unlocked yes)
			(layer "F.SilkS")
			(effects
				(font
					(size 0.635 0.4064)
					(thickness 0.1524)
				)
			)
		)
		(fp_text user "13"
			(at 3.599942 -7.809738 180)
			(unlocked yes)
			(layer "F.SilkS")
			(effects
				(font
					(size 0.635 0.4064)
					(thickness 0.1524)
				)
			)
		)
		(fp_text user "12"
			(at 2.825496 -8.597138 180)
			(unlocked yes)
			(layer "F.SilkS")
			(effects
				(font
					(size 0.635 0.4064)
					(thickness 0.1524)
				)
			)
		)
		(fp_text user "11"
			(at 1.999996 -7.809738 180)
			(unlocked yes)
			(layer "F.SilkS")
			(effects
				(font
					(size 0.635 0.4064)
					(thickness 0.1524)
				)
			)
		)
		(fp_text user "10"
			(at 1.225296 -8.597138 180)
			(unlocked yes)
			(layer "F.SilkS")
			(effects
				(font
					(size 0.635 0.4064)
					(thickness 0.1524)
				)
			)
		)
		(fp_text user "9"
			(at 0.40005 -7.809738 180)
			(unlocked yes)
			(layer "F.SilkS")
			(effects
				(font
					(size 0.635 0.4064)
					(thickness 0.1524)
				)
			)
		)
		(fp_text user "8"
			(at -0.40005 -8.952738 180)
			(unlocked yes)
			(layer "F.SilkS")
			(effects
				(font
					(size 0.635 0.4064)
					(thickness 0.1524)
				)
			)
		)
		(fp_text user "7"
			(at -1.199896 -7.809738 180)
			(unlocked yes)
			(layer "F.SilkS")
			(effects
				(font
					(size 0.635 0.4064)
					(thickness 0.1524)
				)
			)
		)
		(fp_text user "6"
			(at -2.416556 -8.909812 180)
			(unlocked yes)
			(layer "F.SilkS")
			(effects
				(font
					(size 0.635 0.4064)
					(thickness 0.1524)
				)
			)
		)
		(fp_text user "5"
			(at -2.800096 -7.809738 180)
			(unlocked yes)
			(layer "F.SilkS")
			(effects
				(font
					(size 0.635 0.4064)
					(thickness 0.1524)
				)
			)
		)
		(fp_text user "4"
			(at -3.574542 -8.597138 180)
			(unlocked yes)
			(layer "F.SilkS")
			(effects
				(font
					(size 0.635 0.4064)
					(thickness 0.1524)
				)
			)
		)
		(fp_text user "3"
			(at -4.400042 -7.809738 180)
			(unlocked yes)
			(layer "F.SilkS")
			(effects
				(font
					(size 0.635 0.4064)
					(thickness 0.1524)
				)
			)
		)
		(fp_text user "2"
			(at -5.464556 -9.036812 180)
			(unlocked yes)
			(layer "F.SilkS")
			(effects
				(font
					(size 0.635 0.4064)
					(thickness 0.1524)
				)
			)
		)
		(fp_text user "1"
			(at -5.999988 -7.809738 180)
			(unlocked yes)
			(layer "F.SilkS")
			(effects
				(font
					(size 0.635 0.4064)
					(thickness 0.1524)
				)
			)
		)
		(fp_text user "E"
			(at -7.371588 -2.730246 180)
			(unlocked yes)
			(layer "F.SilkS")
			(effects
				(font
					(size 0.635 0.4064)
					(thickness 0.1524)
				)
			)
		)
		(fp_text user "C"
			(at -7.371588 -4.330192 180)
			(unlocked yes)
			(layer "F.SilkS")
			(effects
				(font
					(size 0.635 0.4064)
					(thickness 0.1524)
				)
			)
		)
		(fp_text user "A"
			(at -7.371588 -5.930138 180)
			(unlocked yes)
			(layer "F.SilkS")
			(effects
				(font
					(size 0.635 0.4064)
					(thickness 0.1524)
				)
			)
		)
		(fp_text user "D"
			(at -7.981188 -3.479292 180)
			(unlocked yes)
			(layer "F.SilkS")
			(effects
				(font
					(size 0.635 0.4064)
					(thickness 0.1524)
				)
			)
		)
		(fp_text user "B"
			(at -7.981188 -5.079238 180)
			(unlocked yes)
			(layer "F.SilkS")
			(effects
				(font
					(size 0.635 0.4064)
					(thickness 0.1524)
				)
			)
		)
		(fp_text user "R"
			(at -8.082788 5.193538 180)
			(unlocked yes)
			(layer "F.SilkS")
			(effects
				(font
					(size 0.635 0.4064)
					(thickness 0.1524)
				)
			)
		)
		(fp_text user "N"
			(at -8.082788 3.593592 180)
			(unlocked yes)
			(layer "F.SilkS")
			(effects
				(font
					(size 0.635 0.4064)
					(thickness 0.1524)
				)
			)
		)
		(fp_text user "L"
			(at -8.082788 1.993646 180)
			(unlocked yes)
			(layer "F.SilkS")
			(effects
				(font
					(size 0.635 0.4064)
					(thickness 0.1524)
				)
			)
		)
		(fp_text user "J"
			(at -8.082788 0.3937 180)
			(unlocked yes)
			(layer "F.SilkS")
			(effects
				(font
					(size 0.635 0.4064)
					(thickness 0.1524)
				)
			)
		)
		(fp_text user "G"
			(at -8.082788 -1.206246 180)
			(unlocked yes)
			(layer "F.SilkS")
			(effects
				(font
					(size 0.635 0.4064)
					(thickness 0.1524)
				)
			)
		)
		(fp_text user "T"
			(at -9.098788 5.993638 180)
			(unlocked yes)
			(layer "F.SilkS")
			(effects
				(font
					(size 0.635 0.4064)
					(thickness 0.1524)
				)
			)
		)
		(fp_text user "P"
			(at -9.098788 4.393692 180)
			(unlocked yes)
			(layer "F.SilkS")
			(effects
				(font
					(size 0.635 0.4064)
					(thickness 0.1524)
				)
			)
		)
		(fp_text user "M"
			(at -9.098788 2.793746 180)
			(unlocked yes)
			(layer "F.SilkS")
			(effects
				(font
					(size 0.635 0.4064)
					(thickness 0.1524)
				)
			)
		)
		(fp_text user "K"
			(at -9.098788 1.193546 180)
			(unlocked yes)
			(layer "F.SilkS")
			(effects
				(font
					(size 0.635 0.4064)
					(thickness 0.1524)
				)
			)
		)
		(fp_text user "H"
			(at -9.098788 -0.4064 180)
			(unlocked yes)
			(layer "F.SilkS")
			(effects
				(font
					(size 0.635 0.4064)
					(thickness 0.1524)
				)
			)
		)
		(fp_text user "F"
			(at -9.098788 -2.006346 180)
			(unlocked yes)
			(layer "F.SilkS")
			(effects
				(font
					(size 0.635 0.4064)
					(thickness 0.1524)
				)
			)
		)
		(fp_text user "16"
			(at 5.999988 -8.952738 180)
			(unlocked yes)
			(layer "F.Fab")
			(effects
				(font
					(size 0.635 0.4064)
					(thickness 0.1524)
				)
			)
		)
		(fp_text user "1"
			(at -5.999988 -7.809738 180)
			(unlocked yes)
			(layer "F.Fab")
			(effects
				(font
					(size 0.635 0.4064)
					(thickness 0.1524)
				)
			)
		)
		(fp_text user "A"
			(at -8.082788 -6.006338 180)
			(unlocked yes)
			(layer "F.Fab")
			(effects
				(font
					(size 0.635 0.4064)
					(thickness 0.1524)
				)
			)
		)
		(fp_text user "T"
			(at -9.098788 5.993638 180)
			(unlocked yes)
			(layer "F.Fab")
			(effects
				(font
					(size 0.635 0.4064)
					(thickness 0.1524)
				)
			)
		)
		(pad "A1" smd circle
			(at -5.999988 -5.999988 180)
			(size 0.4064 0.4064)
			(layers "F.Cu" "F.Mask" "F.Paste")
			(net "PVCCA_AUX_PLD")
		)
		(pad "A2" smd circle
			(at -5.199888 -5.999988 180)
			(size 0.4064 0.4064)
			(layers "F.Cu" "F.Mask" "F.Paste")
			(net "Net_316")
		)
		(pad "A3" smd circle
			(at -4.400042 -5.999988 180)
			(size 0.4064 0.4064)
			(layers "F.Cu" "F.Mask" "F.Paste")
			(net "BSM_PRSNT_R1_N")
		)
		(pad "A4" smd circle
			(at -3.599942 -5.999988 180)
			(size 0.4064 0.4064)
			(layers "F.Cu" "F.Mask" "F.Paste")
			(net "RST_PLTRST_R1_N")
		)
		(pad "A5" smd circle
			(at -2.800096 -5.999988 180)
			(size 0.4064 0.4064)
			(layers "F.Cu" "F.Mask" "F.Paste")
			(net "RST_RSMRST_N")
		)
		(pad "A6" smd circle
			(at -1.999996 -5.999988 180)
			(size 0.4064 0.4064)
			(layers "F.Cu" "F.Mask" "F.Paste")
			(net "JTAG_SCM_PLD_TDI")
		)
		(pad "A7" smd circle
			(at -1.199896 -5.999988 180)
			(size 0.4064 0.4064)
			(layers "F.Cu" "F.Mask" "F.Paste")
			(net "JTAG_SCM_PLD_TCK")
		)
		(pad "A8" smd circle
			(at -0.40005 -5.999988 180)
			(size 0.4064 0.4064)
			(layers "F.Cu" "F.Mask" "F.Paste")
			(net "IRQ_BMC_PCH_NMI_R_N")
		)
		(pad "A9" smd circle
			(at 0.40005 -5.999988 180)
			(size 0.4064 0.4064)
			(layers "F.Cu" "F.Mask" "F.Paste")
			(net "SMB_BMC_MM16_R3_SCL")
		)
		(pad "A10" smd circle
			(at 1.199896 -5.999988 180)
			(size 0.4064 0.4064)
			(layers "F.Cu" "F.Mask" "F.Paste")
			(net "Net_75")
		)
		(pad "A11" smd circle
			(at 1.999996 -5.999988 180)
			(size 0.4064 0.4064)
			(layers "F.Cu" "F.Mask" "F.Paste")
			(net "RST_EXTRST_R_N")
		)
		(pad "A12" smd circle
			(at 2.800096 -5.999988 180)
			(size 0.4064 0.4064)
			(layers "F.Cu" "F.Mask" "F.Paste")
			(net "FM_ADR_COMPLETE")
		)
		(pad "A13" smd circle
			(at 3.599942 -5.999988 180)
			(size 0.4064 0.4064)
			(layers "F.Cu" "F.Mask" "F.Paste")
			(net "PU_FPGA_NSTATUS")
		)
		(pad "A14" smd circle
			(at 4.400042 -5.999988 180)
			(size 0.4064 0.4064)
			(layers "F.Cu" "F.Mask" "F.Paste")
			(net "SGPIO_CLK_PLD_0")
		)
		(pad "A15" smd circle
			(at 5.199888 -5.999988 180)
			(size 0.4064 0.4064)
			(layers "F.Cu" "F.Mask" "F.Paste")
			(net "FM_THERMTRIP_DLY_LVC1_R_N")
		)
		(pad "A16" smd circle
			(at 5.999988 -5.999988 180)
			(size 0.4064 0.4064)
			(layers "F.Cu" "F.Mask" "F.Paste")
			(net "PVCCA_AUX_PLD")
		)
		(pad "B1" smd circle
			(at -5.999988 -5.199888 180)
			(size 0.4064 0.4064)
			(layers "F.Cu" "F.Mask" "F.Paste")
			(net "Net_298")
		)
		(pad "B2" smd circle
			(at -5.199888 -5.199888 180)
			(size 0.4064 0.4064)
			(layers "F.Cu" "F.Mask" "F.Paste")
			(net "GND")
		)
		(pad "B3" smd circle
			(at -4.400042 -5.199888 180)
			(size 0.4064 0.4064)
			(layers "F.Cu" "F.Mask" "F.Paste")
			(net "IRQ_BMC_CPU_NMI_R")
		)
		(pad "B4" smd circle
			(at -3.599942 -5.199888 180)
			(size 0.4064 0.4064)
			(layers "F.Cu" "F.Mask" "F.Paste")
			(net "RST_PCA9548_SENSOR_N")
		)
		(pad "B5" smd circle
			(at -2.800096 -5.199888 180)
			(size 0.4064 0.4064)
			(layers "F.Cu" "F.Mask" "F.Paste")
			(net "FM_TPM_PRSNT_1_R_N")
		)
		(pad "B6" smd circle
			(at -1.999996 -5.199888 180)
			(size 0.4064 0.4064)
			(layers "F.Cu" "F.Mask" "F.Paste")
			(net "FM_JTAG_BMC_MUX_SEL_R2")
		)
		(pad "B7" smd circle
			(at -1.199896 -5.199888 180)
			(size 0.4064 0.4064)
			(layers "F.Cu" "F.Mask" "F.Paste")
			(net "IRQ_UV_DETECT_N")
		)
		(pad "B8" smd circle
			(at -0.40005 -5.199888 180)
			(size 0.4064 0.4064)
			(layers "F.Cu" "F.Mask" "F.Paste")
			(net "JTAG_SCM_PLD_TMS")
		)
		(pad "B9" smd circle
			(at 0.40005 -5.199888 180)
			(size 0.4064 0.4064)
			(layers "F.Cu" "F.Mask" "F.Paste")
			(net "IRQ_PCH_SCI_WHEA_N")
		)
		(pad "B10" smd circle
			(at 1.199896 -5.199888 180)
			(size 0.4064 0.4064)
			(layers "F.Cu" "F.Mask" "F.Paste")
			(net "PU_PT20D")
		)
		(pad "B11" smd circle
			(at 1.999996 -5.199888 180)
			(size 0.4064 0.4064)
			(layers "F.Cu" "F.Mask" "F.Paste")
			(net "IRQ_OC_DETECT_N")
		)
		(pad "B12" smd circle
			(at 2.800096 -5.199888 180)
			(size 0.4064 0.4064)
			(layers "F.Cu" "F.Mask" "F.Paste")
			(net "SGPIO_PLD_LD_0")
		)
		(pad "B13" smd circle
			(at 3.599942 -5.199888 180)
			(size 0.4064 0.4064)
			(layers "F.Cu" "F.Mask" "F.Paste")
			(net "IRQ_OC_DETECT_EN_N")
		)
		(pad "B14" smd circle
			(at 4.400042 -5.199888 180)
			(size 0.4064 0.4064)
			(layers "F.Cu" "F.Mask" "F.Paste")
			(net "SGPIO_PLD_DI_0")
		)
		(pad "B15" smd circle
			(at 5.199888 -5.199888 180)
			(size 0.4064 0.4064)
			(layers "F.Cu" "F.Mask" "F.Paste")
			(net "GND")
		)
		(pad "B16" smd circle
			(at 5.999988 -5.199888 180)
			(size 0.4064 0.4064)
			(layers "F.Cu" "F.Mask" "F.Paste")
			(net "FM_PECI_SEL_N")
		)
		(pad "C1" smd circle
			(at -5.999988 -4.400042 180)
			(size 0.4064 0.4064)
			(layers "F.Cu" "F.Mask" "F.Paste")
			(net "Net_302")
		)
		(pad "C2" smd circle
			(at -5.199888 -4.400042 180)
			(size 0.4064 0.4064)
			(layers "F.Cu" "F.Mask" "F.Paste")
			(net "Net_299")
		)
		(pad "C3" smd circle
			(at -4.400042 -4.400042 180)
			(size 0.4064 0.4064)
			(layers "F.Cu" "F.Mask" "F.Paste")
			(net "GND")
		)
		(pad "C4" smd circle
			(at -3.599942 -4.400042 180)
			(size 0.4064 0.4064)
			(layers "F.Cu" "F.Mask" "F.Paste")
			(net "FM_TPM_PRSNT_0_R_N")
		)
		(pad "C5" smd circle
			(at -2.800096 -4.400042 180)
			(size 0.4064 0.4064)
			(layers "F.Cu" "F.Mask" "F.Paste")
			(net "PWRGD_PSU_AC_PWROK_PLD")
		)
		(pad "C6" smd circle
			(at -1.999996 -4.400042 180)
			(size 0.4064 0.4064)
			(layers "F.Cu" "F.Mask" "F.Paste")
			(net "JTAG_SCM_PLD_TDO")
		)
		(pad "C7" smd circle
			(at -1.199896 -4.400042 180)
			(size 0.4064 0.4064)
			(layers "F.Cu" "F.Mask" "F.Paste")
			(net "RST_BMC_RSTBTN_OUT_N")
		)
		(pad "C8" smd circle
			(at -0.40005 -4.400042 180)
			(size 0.4064 0.4064)
			(layers "F.Cu" "F.Mask" "F.Paste")
			(net "CLK_25M_OSC_FPGA")
		)
		(pad "C9" smd circle
			(at 0.40005 -4.400042 180)
			(size 0.4064 0.4064)
			(layers "F.Cu" "F.Mask" "F.Paste")
			(net "SMB_BMC_MM16_R3_SDA")
		)
		(pad "C10" smd circle
			(at 1.199896 -4.400042 180)
			(size 0.4064 0.4064)
			(layers "F.Cu" "F.Mask" "F.Paste")
			(net "JTAG_SCM_PLD_R_JTAGEN")
		)
		(pad "C11" smd circle
			(at 1.999996 -4.400042 180)
			(size 0.4064 0.4064)
			(layers "F.Cu" "F.Mask" "F.Paste")
			(net "PWRGD_CPUPWRGD_LVC1")
		)
		(pad "C12" smd circle
			(at 2.800096 -4.400042 180)
			(size 0.4064 0.4064)
			(layers "F.Cu" "F.Mask" "F.Paste")
			(net "SGPIO_PLD_DO_0")
		)
		(pad "C13" smd circle
			(at 3.599942 -4.400042 180)
			(size 0.4064 0.4064)
			(layers "F.Cu" "F.Mask" "F.Paste")
			(net "PU_FPGA_CONFIG_DONE")
		)
		(pad "C14" smd circle
			(at 4.400042 -4.400042 180)
			(size 0.4064 0.4064)
			(layers "F.Cu" "F.Mask" "F.Paste")
			(net "GND")
		)
		(pad "C15" smd circle
			(at 5.199888 -4.400042 180)
			(size 0.4064 0.4064)
			(layers "F.Cu" "F.Mask" "F.Paste")
			(net "VOL_SEN_ALERT_R")
		)
		(pad "C16" smd circle
			(at 5.999988 -4.400042 180)
			(size 0.4064 0.4064)
			(layers "F.Cu" "F.Mask" "F.Paste")
			(net "SMB_BMC_ALERT3_R1_N")
		)
		(pad "D1" smd circle
			(at -5.999988 -3.599942 180)
			(size 0.4064 0.4064)
			(layers "F.Cu" "F.Mask" "F.Paste")
			(net "Net_297")
		)
		(pad "D2" smd circle
			(at -5.199888 -3.599942 180)
			(size 0.4064 0.4064)
			(layers "F.Cu" "F.Mask" "F.Paste")
			(net "Net_303")
		)
		(pad "D3" smd circle
			(at -4.400042 -3.599942 180)
			(size 0.4064 0.4064)
			(layers "F.Cu" "F.Mask" "F.Paste")
			(net "Net_296")
		)
		(pad "D4" smd circle
			(at -3.599942 -3.599942 180)
			(size 0.4064 0.4064)
			(layers "F.Cu" "F.Mask" "F.Paste")
			(net "GND")
		)
		(pad "D5" smd circle
			(at -2.800096 -3.599942 180)
			(size 0.4064 0.4064)
			(layers "F.Cu" "F.Mask" "F.Paste")
			(net "VCCIO0")
		)
		(pad "D6" smd circle
			(at -1.999996 -3.599942 180)
			(size 0.4064 0.4064)
			(layers "F.Cu" "F.Mask" "F.Paste")
			(net "FM_BMC_DBP_PRESENT_N")
		)
		(pad "D7" smd circle
			(at -1.199896 -3.599942 180)
			(size 0.4064 0.4064)
			(layers "F.Cu" "F.Mask" "F.Paste")
			(net "FM_ME_BT_DONE")
		)
		(pad "D8" smd circle
			(at -0.40005 -3.599942 180)
			(size 0.4064 0.4064)
			(layers "F.Cu" "F.Mask" "F.Paste")
			(net "FM_PCH_BMC_THERMTRIP_N")
		)
		(pad "D9" smd circle
			(at 0.40005 -3.599942 180)
			(size 0.4064 0.4064)
			(layers "F.Cu" "F.Mask" "F.Paste")
			(net "Net_246")
		)
		(pad "D10" smd circle
			(at 1.199896 -3.599942 180)
			(size 0.4064 0.4064)
			(layers "F.Cu" "F.Mask" "F.Paste")
			(net "Net_11")
		)
		(pad "D11" smd circle
			(at 1.999996 -3.599942 180)
			(size 0.4064 0.4064)
			(layers "F.Cu" "F.Mask" "F.Paste")
			(net "IRQ_CPU1_VRHOT_N")
		)
		(pad "D12" smd circle
			(at 2.800096 -3.599942 180)
			(size 0.4064 0.4064)
			(layers "F.Cu" "F.Mask" "F.Paste")
			(net "VCCIO0")
		)
		(pad "D13" smd circle
			(at 3.599942 -3.599942 180)
			(size 0.4064 0.4064)
			(layers "F.Cu" "F.Mask" "F.Paste")
			(net "GND")
		)
		(pad "D14" smd circle
			(at 4.400042 -3.599942 180)
			(size 0.4064 0.4064)
			(layers "F.Cu" "F.Mask" "F.Paste")
			(net "H_CPU0_MEMTRIP_LVC1_N")
		)
		(pad "D15" smd circle
			(at 5.199888 -3.599942 180)
			(size 0.4064 0.4064)
			(layers "F.Cu" "F.Mask" "F.Paste")
			(net "SMB_BMC_ALERT4_R1_N")
		)
		(pad "D16" smd circle
			(at 5.999988 -3.599942 180)
			(size 0.4064 0.4064)
			(layers "F.Cu" "F.Mask" "F.Paste")
			(net "H_CPU1_MEMTRIP_LVC1_N")
		)
		(pad "E1" smd circle
			(at -5.999988 -2.800096 180)
			(size 0.4064 0.4064)
			(layers "F.Cu" "F.Mask" "F.Paste")
			(net "Net_304")
		)
		(pad "E2" smd circle
			(at -5.199888 -2.800096 180)
			(size 0.4064 0.4064)
			(layers "F.Cu" "F.Mask" "F.Paste")
			(net "Net_300")
		)
		(pad "E3" smd circle
			(at -4.400042 -2.800096 180)
			(size 0.4064 0.4064)
			(layers "F.Cu" "F.Mask" "F.Paste")
			(net "Net_301")
		)
		(pad "E4" smd circle
			(at -3.599942 -2.800096 180)
			(size 0.4064 0.4064)
			(layers "F.Cu" "F.Mask" "F.Paste")
			(net "VCCIO5")
		)
		(pad "E5" smd circle
			(at -2.800096 -2.800096 180)
			(size 0.4064 0.4064)
			(layers "F.Cu" "F.Mask" "F.Paste")
			(net "GND")
		)
		(pad "E6" smd circle
			(at -1.999996 -2.800096 180)
			(size 0.4064 0.4064)
			(layers "F.Cu" "F.Mask" "F.Paste")
			(net "BMC_CPLD_GPIO_2_R2")
		)
		(pad "E7" smd circle
			(at -1.199896 -2.800096 180)
			(size 0.4064 0.4064)
			(layers "F.Cu" "F.Mask" "F.Paste")
			(net "PWRGD_PCH_PWROK")
		)
		(pad "E8" smd circle
			(at -0.40005 -2.800096 180)
			(size 0.4064 0.4064)
			(layers "F.Cu" "F.Mask" "F.Paste")
			(net "FM_BIOS_POST_CMPLT_BMC_N")
		)
		(pad "E9" smd circle
			(at 0.40005 -2.800096 180)
			(size 0.4064 0.4064)
			(layers "F.Cu" "F.Mask" "F.Paste")
			(net "H_CPU1_PROCHOT_LVC1_R_N")
		)
		(pad "E10" smd circle
			(at 1.199896 -2.800096 180)
			(size 0.4064 0.4064)
			(layers "F.Cu" "F.Mask" "F.Paste")
			(net "FM_CPU_MSMI_CATERR_LVT3_PLD_N")
		)
		(pad "E11" smd circle
			(at 1.999996 -2.800096 180)
			(size 0.4064 0.4064)
			(layers "F.Cu" "F.Mask" "F.Paste")
			(net "TP_PLD_19D")
		)
		(pad "E12" smd circle
			(at 2.800096 -2.800096 180)
			(size 0.4064 0.4064)
			(layers "F.Cu" "F.Mask" "F.Paste")
			(net "GND")
		)
		(pad "E13" smd circle
			(at 3.599942 -2.800096 180)
			(size 0.4064 0.4064)
			(layers "F.Cu" "F.Mask" "F.Paste")
			(net "VCCIO1")
		)
		(pad "E14" smd circle
			(at 4.400042 -2.800096 180)
			(size 0.4064 0.4064)
			(layers "F.Cu" "F.Mask" "F.Paste")
			(net "IRQ_SGPIO_R_N")
		)
		(pad "E15" smd circle
			(at 5.199888 -2.800096 180)
			(size 0.4064 0.4064)
			(layers "F.Cu" "F.Mask" "F.Paste")
			(net "FM_SPD_REMOTE_EN_R")
		)
		(pad "E16" smd circle
			(at 5.999988 -2.800096 180)
			(size 0.4064 0.4064)
			(layers "F.Cu" "F.Mask" "F.Paste")
			(net "RST_SGPIO_RESET_R_N")
		)
		(pad "F1" smd circle
			(at -5.999988 -1.999996 180)
			(size 0.4064 0.4064)
			(layers "F.Cu" "F.Mask" "F.Paste")
			(net "Net_309")
		)
		(pad "F2" smd circle
			(at -5.199888 -1.999996 180)
			(size 0.4064 0.4064)
			(layers "F.Cu" "F.Mask" "F.Paste")
			(net "Net_305")
		)
		(pad "F3" smd circle
			(at -4.400042 -1.999996 180)
			(size 0.4064 0.4064)
			(layers "F.Cu" "F.Mask" "F.Paste")
			(net "Net_308")
		)
		(pad "F4" smd circle
			(at -3.599942 -1.999996 180)
			(size 0.4064 0.4064)
			(layers "F.Cu" "F.Mask" "F.Paste")
			(net "Net_306")
		)
		(pad "F5" smd circle
			(at -2.800096 -1.999996 180)
			(size 0.4064 0.4064)
			(layers "F.Cu" "F.Mask" "F.Paste")
			(net "Net_314")
		)
		(pad "F6" smd circle
			(at -1.999996 -1.999996 180)
			(size 0.4064 0.4064)
			(layers "F.Cu" "F.Mask" "F.Paste")
			(net "GND")
		)
		(pad "F7" smd circle
			(at -1.199896 -1.999996 180)
			(size 0.4064 0.4064)
			(layers "F.Cu" "F.Mask" "F.Paste")
			(net "FM_PCIE_M2_SSD0_PRSNT_N")
		)
		(pad "F8" smd circle
			(at -0.40005 -1.999996 180)
			(size 0.4064 0.4064)
			(layers "F.Cu" "F.Mask" "F.Paste")
			(net "RST_SRST_PLD_BMC_R2_N")
		)
		(pad "F9" smd circle
			(at 0.40005 -1.999996 180)
			(size 0.4064 0.4064)
			(layers "F.Cu" "F.Mask" "F.Paste")
			(net "Net_76")
		)
		(pad "F10" smd circle
			(at 1.199896 -1.999996 180)
			(size 0.4064 0.4064)
			(layers "F.Cu" "F.Mask" "F.Paste")
			(net "IRQ_CPU0_VRHOT_N")
		)
		(pad "F11" smd circle
			(at 1.999996 -1.999996 180)
			(size 0.4064 0.4064)
			(layers "F.Cu" "F.Mask" "F.Paste")
			(net "GND")
		)
		(pad "F12" smd circle
			(at 2.800096 -1.999996 180)
			(size 0.4064 0.4064)
			(layers "F.Cu" "F.Mask" "F.Paste")
			(net "TP_PLD_L3")
		)
		(pad "F13" smd circle
			(at 3.599942 -1.999996 180)
			(size 0.4064 0.4064)
			(layers "F.Cu" "F.Mask" "F.Paste")
			(net "SMB_BMC_ALERT9_R1_N")
		)
		(pad "F14" smd circle
			(at 4.400042 -1.999996 180)
			(size 0.4064 0.4064)
			(layers "F.Cu" "F.Mask" "F.Paste")
			(net "BMC_CPLD_GPIO_8_R2")
		)
		(pad "F15" smd circle
			(at 5.199888 -1.999996 180)
			(size 0.4064 0.4064)
			(layers "F.Cu" "F.Mask" "F.Paste")
			(net "BMC_CPLD_GPIO_7_R2")
		)
		(pad "F16" smd circle
			(at 5.999988 -1.999996 180)
			(size 0.4064 0.4064)
			(layers "F.Cu" "F.Mask" "F.Paste")
			(net "Net_77")
		)
		(pad "G1" smd circle
			(at -5.999988 -1.199896 180)
			(size 0.4064 0.4064)
			(layers "F.Cu" "F.Mask" "F.Paste")
			(net "Net_284")
		)
		(pad "G2" smd circle
			(at -5.199888 -1.199896 180)
			(size 0.4064 0.4064)
			(layers "F.Cu" "F.Mask" "F.Paste")
			(net "Net_312")
		)
		(pad "G3" smd circle
			(at -4.400042 -1.199896 180)
			(size 0.4064 0.4064)
			(layers "F.Cu" "F.Mask" "F.Paste")
			(net "Net_313")
		)
		(pad "G4" smd circle
			(at -3.599942 -1.199896 180)
			(size 0.4064 0.4064)
			(layers "F.Cu" "F.Mask" "F.Paste")
			(net "Net_311")
		)
		(pad "G5" smd circle
			(at -2.800096 -1.199896 180)
			(size 0.4064 0.4064)
			(layers "F.Cu" "F.Mask" "F.Paste")
			(net "Net_310")
		)
		(pad "G6" smd circle
			(at -1.999996 -1.199896 180)
			(size 0.4064 0.4064)
			(layers "F.Cu" "F.Mask" "F.Paste")
			(net "Net_307")
		)
		(pad "G7" smd circle
			(at -1.199896 -1.199896 180)
			(size 0.4064 0.4064)
			(layers "F.Cu" "F.Mask" "F.Paste")
			(net "PVCCA_AUX_PLD")
		)
		(pad "G8" smd circle
			(at -0.40005 -1.199896 180)
			(size 0.4064 0.4064)
			(layers "F.Cu" "F.Mask" "F.Paste")
			(net "VCCIO0")
		)
		(pad "G9" smd circle
			(at 0.40005 -1.199896 180)
			(size 0.4064 0.4064)
			(layers "F.Cu" "F.Mask" "F.Paste")
			(net "VCCIO0")
		)
		(pad "G10" smd circle
			(at 1.199896 -1.199896 180)
			(size 0.4064 0.4064)
			(layers "F.Cu" "F.Mask" "F.Paste")
			(net "PVCCA_AUX_PLD")
		)
		(pad "G11" smd circle
			(at 1.999996 -1.199896 180)
			(size 0.4064 0.4064)
			(layers "F.Cu" "F.Mask" "F.Paste")
			(net "FM_SLPS3_GF_R_N")
		)
		(pad "G12" smd circle
			(at 2.800096 -1.199896 180)
			(size 0.4064 0.4064)
			(layers "F.Cu" "F.Mask" "F.Paste")
			(net "SMB_BMC_ALERT10_R1_N")
		)
		(pad "G13" smd circle
			(at 3.599942 -1.199896 180)
			(size 0.4064 0.4064)
			(layers "F.Cu" "F.Mask" "F.Paste")
			(net "RST_BMC_SELF_HW_R2")
		)
		(pad "G14" smd circle
			(at 4.400042 -1.199896 180)
			(size 0.4064 0.4064)
			(layers "F.Cu" "F.Mask" "F.Paste")
			(net "Net_70")
		)
		(pad "G15" smd circle
			(at 5.199888 -1.199896 180)
			(size 0.4064 0.4064)
			(layers "F.Cu" "F.Mask" "F.Paste")
			(net "Net_69")
		)
		(pad "G16" smd circle
			(at 5.999988 -1.199896 180)
			(size 0.4064 0.4064)
			(layers "F.Cu" "F.Mask" "F.Paste")
			(net "BMC_CPLD_GPIO_12_R2")
		)
		(pad "H1" smd circle
			(at -5.999988 -0.40005 180)
			(size 0.4064 0.4064)
			(layers "F.Cu" "F.Mask" "F.Paste")
			(net "Net_289")
		)
		(pad "H2" smd circle
			(at -5.199888 -0.40005 180)
			(size 0.4064 0.4064)
			(layers "F.Cu" "F.Mask" "F.Paste")
			(net "Net_285")
		)
		(pad "H3" smd circle
			(at -4.400042 -0.40005 180)
			(size 0.4064 0.4064)
			(layers "F.Cu" "F.Mask" "F.Paste")
			(net "Net_288")
		)
		(pad "H4" smd circle
			(at -3.599942 -0.40005 180)
			(size 0.4064 0.4064)
			(layers "F.Cu" "F.Mask" "F.Paste")
			(net "Net_286")
		)
		(pad "H5" smd circle
			(at -2.800096 -0.40005 180)
			(size 0.4064 0.4064)
			(layers "F.Cu" "F.Mask" "F.Paste")
			(net "Net_294")
		)
		(pad "H6" smd circle
			(at -1.999996 -0.40005 180)
			(size 0.4064 0.4064)
			(layers "F.Cu" "F.Mask" "F.Paste")
			(net "Net_315")
		)
		(pad "H7" smd circle
			(at -1.199896 -0.40005 180)
			(size 0.4064 0.4064)
			(layers "F.Cu" "F.Mask" "F.Paste")
			(net "VCCIO4")
		)
		(pad "H8" smd circle
			(at -0.40005 -0.40005 180)
			(size 0.4064 0.4064)
			(layers "F.Cu" "F.Mask" "F.Paste")
			(net "GND")
		)
		(pad "H9" smd circle
			(at 0.40005 -0.40005 180)
			(size 0.4064 0.4064)
			(layers "F.Cu" "F.Mask" "F.Paste")
			(net "GND")
		)
		(pad "H10" smd circle
			(at 1.199896 -0.40005 180)
			(size 0.4064 0.4064)
			(layers "F.Cu" "F.Mask" "F.Paste")
			(net "VCCIO1")
		)
		(pad "H11" smd circle
			(at 1.999996 -0.40005 180)
			(size 0.4064 0.4064)
			(layers "F.Cu" "F.Mask" "F.Paste")
			(net "RST_MB_STBY_R_N")
		)
		(pad "H12" smd circle
			(at 2.800096 -0.40005 180)
			(size 0.4064 0.4064)
			(layers "F.Cu" "F.Mask" "F.Paste")
			(net "RST_ROT_CPU_R_N")
		)
		(pad "H13" smd circle
			(at 3.599942 -0.40005 180)
			(size 0.4064 0.4064)
			(layers "F.Cu" "F.Mask" "F.Paste")
			(net "FM_ESPI_PLD_R_EN")
		)
		(pad "H14" smd circle
			(at 4.400042 -0.40005 180)
			(size 0.4064 0.4064)
			(layers "F.Cu" "F.Mask" "F.Paste")
			(net "Net_71")
		)
		(pad "H15" smd circle
			(at 5.199888 -0.40005 180)
			(size 0.4064 0.4064)
			(layers "F.Cu" "F.Mask" "F.Paste")
			(net "BMC_CPLD_GPIO_13_R2")
		)
		(pad "H16" smd circle
			(at 5.999988 -0.40005 180)
			(size 0.4064 0.4064)
			(layers "F.Cu" "F.Mask" "F.Paste")
			(net "Net_72")
		)
		(pad "J1" smd circle
			(at -5.999988 0.40005 180)
			(size 0.4064 0.4064)
			(layers "F.Cu" "F.Mask" "F.Paste")
			(net "Net_290")
		)
		(pad "J2" smd circle
			(at -5.199888 0.40005 180)
			(size 0.4064 0.4064)
			(layers "F.Cu" "F.Mask" "F.Paste")
			(net "Net_292")
		)
		(pad "J3" smd circle
			(at -4.400042 0.40005 180)
			(size 0.4064 0.4064)
			(layers "F.Cu" "F.Mask" "F.Paste")
			(net "Net_291")
		)
		(pad "J4" smd circle
			(at -3.599942 0.40005 180)
			(size 0.4064 0.4064)
			(layers "F.Cu" "F.Mask" "F.Paste")
			(net "Net_295")
		)
		(pad "J5" smd circle
			(at -2.800096 0.40005 180)
			(size 0.4064 0.4064)
			(layers "F.Cu" "F.Mask" "F.Paste")
			(net "Net_282")
		)
		(pad "J6" smd circle
			(at -1.999996 0.40005 180)
			(size 0.4064 0.4064)
			(layers "F.Cu" "F.Mask" "F.Paste")
			(net "Net_287")
		)
		(pad "J7" smd circle
			(at -1.199896 0.40005 180)
			(size 0.4064 0.4064)
			(layers "F.Cu" "F.Mask" "F.Paste")
			(net "VCCIO4")
		)
		(pad "J8" smd circle
			(at -0.40005 0.40005 180)
			(size 0.4064 0.4064)
			(layers "F.Cu" "F.Mask" "F.Paste")
			(net "GND")
		)
		(pad "J9" smd circle
			(at 0.40005 0.40005 180)
			(size 0.4064 0.4064)
			(layers "F.Cu" "F.Mask" "F.Paste")
			(net "GND")
		)
		(pad "J10" smd circle
			(at 1.199896 0.40005 180)
			(size 0.4064 0.4064)
			(layers "F.Cu" "F.Mask" "F.Paste")
			(net "VCCIO1")
		)
		(pad "J11" smd circle
			(at 1.999996 0.40005 180)
			(size 0.4064 0.4064)
			(layers "F.Cu" "F.Mask" "F.Paste")
			(net "Net_37")
		)
		(pad "J12" smd circle
			(at 2.800096 0.40005 180)
			(size 0.4064 0.4064)
			(layers "F.Cu" "F.Mask" "F.Paste")
			(net "FM_THROTTLE_R_N")
		)
		(pad "J13" smd circle
			(at 3.599942 0.40005 180)
			(size 0.4064 0.4064)
			(layers "F.Cu" "F.Mask" "F.Paste")
			(net "FM_ADR_TRIGGER_N")
		)
		(pad "J14" smd circle
			(at 4.400042 0.40005 180)
			(size 0.4064 0.4064)
			(layers "F.Cu" "F.Mask" "F.Paste")
			(net "H_CPU0_PROCHOT_LVC1_R_N")
		)
		(pad "J15" smd circle
			(at 5.199888 0.40005 180)
			(size 0.4064 0.4064)
			(layers "F.Cu" "F.Mask" "F.Paste")
			(net "RST_BMC_HW_R")
		)
		(pad "J16" smd circle
			(at 5.999988 0.40005 180)
			(size 0.4064 0.4064)
			(layers "F.Cu" "F.Mask" "F.Paste")
			(net "FM_PMBUS_ALERT_EN")
		)
		(pad "K1" smd circle
			(at -5.999988 1.199896 180)
			(size 0.4064 0.4064)
			(layers "F.Cu" "F.Mask" "F.Paste")
			(net "Net_293")
		)
		(pad "K2" smd circle
			(at -5.199888 1.199896 180)
			(size 0.4064 0.4064)
			(layers "F.Cu" "F.Mask" "F.Paste")
			(net "Net_281")
		)
		(pad "K3" smd circle
			(at -4.400042 1.199896 180)
			(size 0.4064 0.4064)
			(layers "F.Cu" "F.Mask" "F.Paste")
			(net "Net_280")
		)
		(pad "K4" smd circle
			(at -3.599942 1.199896 180)
			(size 0.4064 0.4064)
			(layers "F.Cu" "F.Mask" "F.Paste")
			(net "Net_266")
		)
		(pad "K5" smd circle
			(at -2.800096 1.199896 180)
			(size 0.4064 0.4064)
			(layers "F.Cu" "F.Mask" "F.Paste")
			(net "Net_270")
		)
		(pad "K6" smd circle
			(at -1.999996 1.199896 180)
			(size 0.4064 0.4064)
			(layers "F.Cu" "F.Mask" "F.Paste")
			(net "Net_283")
		)
		(pad "K7" smd circle
			(at -1.199896 1.199896 180)
			(size 0.4064 0.4064)
			(layers "F.Cu" "F.Mask" "F.Paste")
			(net "PVCCA_AUX_PLD")
		)
		(pad "K8" smd circle
			(at -0.40005 1.199896 180)
			(size 0.4064 0.4064)
			(layers "F.Cu" "F.Mask" "F.Paste")
			(net "VCCIO2")
		)
		(pad "K9" smd circle
			(at 0.40005 1.199896 180)
			(size 0.4064 0.4064)
			(layers "F.Cu" "F.Mask" "F.Paste")
			(net "VCCIO2")
		)
		(pad "K10" smd circle
			(at 1.199896 1.199896 180)
			(size 0.4064 0.4064)
			(layers "F.Cu" "F.Mask" "F.Paste")
			(net "PVCCA_AUX_PLD")
		)
		(pad "K11" smd circle
			(at 1.999996 1.199896 180)
			(size 0.4064 0.4064)
			(layers "F.Cu" "F.Mask" "F.Paste")
			(net "FM_PCHHOT_R_N")
		)
		(pad "K12" smd circle
			(at 2.800096 1.199896 180)
			(size 0.4064 0.4064)
			(layers "F.Cu" "F.Mask" "F.Paste")
			(net "FM_BIOS_DEBUG_EN_N")
		)
		(pad "K13" smd circle
			(at 3.599942 1.199896 180)
			(size 0.4064 0.4064)
			(layers "F.Cu" "F.Mask" "F.Paste")
			(net "FM_BMC_READY_PLD_N")
		)
		(pad "K14" smd circle
			(at 4.400042 1.199896 180)
			(size 0.4064 0.4064)
			(layers "F.Cu" "F.Mask" "F.Paste")
			(net "FM_PWR_R_BTN")
		)
		(pad "K15" smd circle
			(at 5.199888 1.199896 180)
			(size 0.4064 0.4064)
			(layers "F.Cu" "F.Mask" "F.Paste")
			(net "PWRGD_SYS_PWROK_PLD")
		)
		(pad "K16" smd circle
			(at 5.999988 1.199896 180)
			(size 0.4064 0.4064)
			(layers "F.Cu" "F.Mask" "F.Paste")
			(net "Net_247")
		)
		(pad "L1" smd circle
			(at -5.999988 1.999996 180)
			(size 0.4064 0.4064)
			(layers "F.Cu" "F.Mask" "F.Paste")
			(net "Net_264")
		)
		(pad "L2" smd circle
			(at -5.199888 1.999996 180)
			(size 0.4064 0.4064)
			(layers "F.Cu" "F.Mask" "F.Paste")
			(net "Net_268")
		)
		(pad "L3" smd circle
			(at -4.400042 1.999996 180)
			(size 0.4064 0.4064)
			(layers "F.Cu" "F.Mask" "F.Paste")
			(net "Net_265")
		)
		(pad "L4" smd circle
			(at -3.599942 1.999996 180)
			(size 0.4064 0.4064)
			(layers "F.Cu" "F.Mask" "F.Paste")
			(net "Net_271")
		)
		(pad "L5" smd circle
			(at -2.800096 1.999996 180)
			(size 0.4064 0.4064)
			(layers "F.Cu" "F.Mask" "F.Paste")
			(net "Net_267")
		)
		(pad "L6" smd circle
			(at -1.999996 1.999996 180)
			(size 0.4064 0.4064)
			(layers "F.Cu" "F.Mask" "F.Paste")
			(net "GND")
		)
		(pad "L7" smd circle
			(at -1.199896 1.999996 180)
			(size 0.4064 0.4064)
			(layers "F.Cu" "F.Mask" "F.Paste")
			(net "NC_FM_PFR_NO_SERVICE_ACT_N")
		)
		(pad "L8" smd circle
			(at -0.40005 1.999996 180)
			(size 0.4064 0.4064)
			(layers "F.Cu" "F.Mask" "F.Paste")
			(net "FM_PFR_DSW_PWROK_N")
		)
		(pad "L9" smd circle
			(at 0.40005 1.999996 180)
			(size 0.4064 0.4064)
			(layers "F.Cu" "F.Mask" "F.Paste")
			(net "FM_BMC_CPU_FBRK_OUT_R_N")
		)
		(pad "L10" smd circle
			(at 1.199896 1.999996 180)
			(size 0.4064 0.4064)
			(layers "F.Cu" "F.Mask" "F.Paste")
			(net "FM_UARTSW_MSB_R_N")
		)
		(pad "L11" smd circle
			(at 1.999996 1.999996 180)
			(size 0.4064 0.4064)
			(layers "F.Cu" "F.Mask" "F.Paste")
			(net "GND")
		)
		(pad "L12" smd circle
			(at 2.800096 1.999996 180)
			(size 0.4064 0.4064)
			(layers "F.Cu" "F.Mask" "F.Paste")
			(net "FM_BMC_EN_DET_R")
		)
		(pad "L13" smd circle
			(at 3.599942 1.999996 180)
			(size 0.4064 0.4064)
			(layers "F.Cu" "F.Mask" "F.Paste")
			(net "FM_BMC_ONCTL_R_N")
		)
		(pad "L14" smd circle
			(at 4.400042 1.999996 180)
			(size 0.4064 0.4064)
			(layers "F.Cu" "F.Mask" "F.Paste")
			(net "SMB_BMC_ALERT12_N")
		)
		(pad "L15" smd circle
			(at 5.199888 1.999996 180)
			(size 0.4064 0.4064)
			(layers "F.Cu" "F.Mask" "F.Paste")
			(net "Net_78")
		)
		(pad "L16" smd circle
			(at 5.999988 1.999996 180)
			(size 0.4064 0.4064)
			(layers "F.Cu" "F.Mask" "F.Paste")
			(net "USB_OC0_REAR_R_N")
		)
		(pad "M1" smd circle
			(at -5.999988 2.800096 180)
			(size 0.4064 0.4064)
			(layers "F.Cu" "F.Mask" "F.Paste")
			(net "Net_269")
		)
		(pad "M2" smd circle
			(at -5.199888 2.800096 180)
			(size 0.4064 0.4064)
			(layers "F.Cu" "F.Mask" "F.Paste")
			(net "Net_276")
		)
		(pad "M3" smd circle
			(at -4.400042 2.800096 180)
			(size 0.4064 0.4064)
			(layers "F.Cu" "F.Mask" "F.Paste")
			(net "Net_272")
		)
		(pad "M4" smd circle
			(at -3.599942 2.800096 180)
			(size 0.4064 0.4064)
			(layers "F.Cu" "F.Mask" "F.Paste")
			(net "VCCIO3")
		)
		(pad "M5" smd circle
			(at -2.800096 2.800096 180)
			(size 0.4064 0.4064)
			(layers "F.Cu" "F.Mask" "F.Paste")
			(net "GND")
		)
		(pad "M6" smd circle
			(at -1.999996 2.800096 180)
			(size 0.4064 0.4064)
			(layers "F.Cu" "F.Mask" "F.Paste")
			(net "BMC_MONITER")
		)
		(pad "M7" smd circle
			(at -1.199896 2.800096 180)
			(size 0.4064 0.4064)
			(layers "F.Cu" "F.Mask" "F.Paste")
			(net "CLK_GEN2_BMC_RC_OE_N")
		)
		(pad "M8" smd circle
			(at -0.40005 2.800096 180)
			(size 0.4064 0.4064)
			(layers "F.Cu" "F.Mask" "F.Paste")
			(net "PWRGD_P1V8_AUX_R1")
		)
		(pad "M9" smd circle
			(at 0.40005 2.800096 180)
			(size 0.4064 0.4064)
			(layers "F.Cu" "F.Mask" "F.Paste")
			(net "FM_UARTSW_LSB_R_N")
		)
		(pad "M10" smd circle
			(at 1.199896 2.800096 180)
			(size 0.4064 0.4064)
			(layers "F.Cu" "F.Mask" "F.Paste")
			(net "PU_FPGA_NCONFIG")
		)
		(pad "M11" smd circle
			(at 1.999996 2.800096 180)
			(size 0.4064 0.4064)
			(layers "F.Cu" "F.Mask" "F.Paste")
			(net "Net_253")
		)
		(pad "M12" smd circle
			(at 2.800096 2.800096 180)
			(size 0.4064 0.4064)
			(layers "F.Cu" "F.Mask" "F.Paste")
			(net "GND")
		)
		(pad "M13" smd circle
			(at 3.599942 2.800096 180)
			(size 0.4064 0.4064)
			(layers "F.Cu" "F.Mask" "F.Paste")
			(net "VCCIO1")
		)
		(pad "M14" smd circle
			(at 4.400042 2.800096 180)
			(size 0.4064 0.4064)
			(layers "F.Cu" "F.Mask" "F.Paste")
			(net "PWR_LED_CPLD")
		)
		(pad "M15" smd circle
			(at 5.199888 2.800096 180)
			(size 0.4064 0.4064)
			(layers "F.Cu" "F.Mask" "F.Paste")
			(net "PWRGD_P5V_AUX_R1")
		)
		(pad "M16" smd circle
			(at 5.999988 2.800096 180)
			(size 0.4064 0.4064)
			(layers "F.Cu" "F.Mask" "F.Paste")
			(net "Net_79")
		)
		(pad "N1" smd circle
			(at -5.999988 3.599942 180)
			(size 0.4064 0.4064)
			(layers "F.Cu" "F.Mask" "F.Paste")
			(net "Net_273")
		)
		(pad "N2" smd circle
			(at -5.199888 3.599942 180)
			(size 0.4064 0.4064)
			(layers "F.Cu" "F.Mask" "F.Paste")
			(net "Net_274")
		)
		(pad "N3" smd circle
			(at -4.400042 3.599942 180)
			(size 0.4064 0.4064)
			(layers "F.Cu" "F.Mask" "F.Paste")
			(net "Net_277")
		)
		(pad "N4" smd circle
			(at -3.599942 3.599942 180)
			(size 0.4064 0.4064)
			(layers "F.Cu" "F.Mask" "F.Paste")
			(net "GND")
		)
		(pad "N5" smd circle
			(at -2.800096 3.599942 180)
			(size 0.4064 0.4064)
			(layers "F.Cu" "F.Mask" "F.Paste")
			(net "VCCIO2")
		)
		(pad "N6" smd circle
			(at -1.999996 3.599942 180)
			(size 0.4064 0.4064)
			(layers "F.Cu" "F.Mask" "F.Paste")
			(net "FM_BMC_DEBUG_SW_R2_N")
		)
		(pad "N7" smd circle
			(at -1.199896 3.599942 180)
			(size 0.4064 0.4064)
			(layers "F.Cu" "F.Mask" "F.Paste")
			(net "IRQ_SML0_ALERT_R_N")
		)
		(pad "N8" smd circle
			(at -0.40005 3.599942 180)
			(size 0.4064 0.4064)
			(layers "F.Cu" "F.Mask" "F.Paste")
			(net "CLK_BUF1_GPU_FPGA_OE_R_N")
		)
		(pad "N9" smd circle
			(at 0.40005 3.599942 180)
			(size 0.4064 0.4064)
			(layers "F.Cu" "F.Mask" "F.Paste")
			(net "PWRGD_P3V3_RGM_R1")
		)
		(pad "N10" smd circle
			(at 1.199896 3.599942 180)
			(size 0.4064 0.4064)
			(layers "F.Cu" "F.Mask" "F.Paste")
			(net "Net_252")
		)
		(pad "N11" smd circle
			(at 1.999996 3.599942 180)
			(size 0.4064 0.4064)
			(layers "F.Cu" "F.Mask" "F.Paste")
			(net "Net_256")
		)
		(pad "N12" smd circle
			(at 2.800096 3.599942 180)
			(size 0.4064 0.4064)
			(layers "F.Cu" "F.Mask" "F.Paste")
			(net "VCCIO2")
		)
		(pad "N13" smd circle
			(at 3.599942 3.599942 180)
			(size 0.4064 0.4064)
			(layers "F.Cu" "F.Mask" "F.Paste")
			(net "GND")
		)
		(pad "N14" smd circle
			(at 4.400042 3.599942 180)
			(size 0.4064 0.4064)
			(layers "F.Cu" "F.Mask" "F.Paste")
			(net "PWRGD_P2V5_AUX_R1")
		)
		(pad "N15" smd circle
			(at 5.199888 3.599942 180)
			(size 0.4064 0.4064)
			(layers "F.Cu" "F.Mask" "F.Paste")
			(net "AC_PWR_BTN_R2_N")
		)
		(pad "N16" smd circle
			(at 5.999988 3.599942 180)
			(size 0.4064 0.4064)
			(layers "F.Cu" "F.Mask" "F.Paste")
			(net "PWRGD_P3V3_AUX_R1")
		)
		(pad "P1" smd circle
			(at -5.999988 4.400042 180)
			(size 0.4064 0.4064)
			(layers "F.Cu" "F.Mask" "F.Paste")
			(net "Net_275")
		)
		(pad "P2" smd circle
			(at -5.199888 4.400042 180)
			(size 0.4064 0.4064)
			(layers "F.Cu" "F.Mask" "F.Paste")
			(net "Net_279")
		)
		(pad "P3" smd circle
			(at -4.400042 4.400042 180)
			(size 0.4064 0.4064)
			(layers "F.Cu" "F.Mask" "F.Paste")
			(net "GND")
		)
		(pad "P4" smd circle
			(at -3.599942 4.400042 180)
			(size 0.4064 0.4064)
			(layers "F.Cu" "F.Mask" "F.Paste")
			(net "FM_P12V_HSC_ENABLE_R2")
		)
		(pad "P5" smd circle
			(at -2.800096 4.400042 180)
			(size 0.4064 0.4064)
			(layers "F.Cu" "F.Mask" "F.Paste")
			(net "TP_PLD_C13")
		)
		(pad "P6" smd circle
			(at -1.999996 4.400042 180)
			(size 0.4064 0.4064)
			(layers "F.Cu" "F.Mask" "F.Paste")
			(net "FM_HDD_LED_N")
		)
		(pad "P7" smd circle
			(at -1.199896 4.400042 180)
			(size 0.4064 0.4064)
			(layers "F.Cu" "F.Mask" "F.Paste")
			(net "GPU_WP_HW_CTRL_R_N")
		)
		(pad "P8" smd circle
			(at -0.40005 4.400042 180)
			(size 0.4064 0.4064)
			(layers "F.Cu" "F.Mask" "F.Paste")
			(net "GPU_FPGA_RST_N")
		)
		(pad "P9" smd circle
			(at 0.40005 4.400042 180)
			(size 0.4064 0.4064)
			(layers "F.Cu" "F.Mask" "F.Paste")
			(net "PWRGD_P1V0_AUX_R1")
		)
		(pad "P10" smd circle
			(at 1.199896 4.400042 180)
			(size 0.4064 0.4064)
			(layers "F.Cu" "F.Mask" "F.Paste")
			(net "Net_250")
		)
		(pad "P11" smd circle
			(at 1.999996 4.400042 180)
			(size 0.4064 0.4064)
			(layers "F.Cu" "F.Mask" "F.Paste")
			(net "Net_255")
		)
		(pad "P12" smd circle
			(at 2.800096 4.400042 180)
			(size 0.4064 0.4064)
			(layers "F.Cu" "F.Mask" "F.Paste")
			(net "Net_261")
		)
		(pad "P13" smd circle
			(at 3.599942 4.400042 180)
			(size 0.4064 0.4064)
			(layers "F.Cu" "F.Mask" "F.Paste")
			(net "Net_263")
		)
		(pad "P14" smd circle
			(at 4.400042 4.400042 180)
			(size 0.4064 0.4064)
			(layers "F.Cu" "F.Mask" "F.Paste")
			(net "GND")
		)
		(pad "P15" smd circle
			(at 5.199888 4.400042 180)
			(size 0.4064 0.4064)
			(layers "F.Cu" "F.Mask" "F.Paste")
			(net "Net_74")
		)
		(pad "P16" smd circle
			(at 5.999988 4.400042 180)
			(size 0.4064 0.4064)
			(layers "F.Cu" "F.Mask" "F.Paste")
			(net "Net_73")
		)
		(pad "R1" smd circle
			(at -5.999988 5.199888 180)
			(size 0.4064 0.4064)
			(layers "F.Cu" "F.Mask" "F.Paste")
			(net "Net_278")
		)
		(pad "R2" smd circle
			(at -5.199888 5.199888 180)
			(size 0.4064 0.4064)
			(layers "F.Cu" "F.Mask" "F.Paste")
			(net "GND")
		)
		(pad "R3" smd circle
			(at -4.400042 5.199888 180)
			(size 0.4064 0.4064)
			(layers "F.Cu" "F.Mask" "F.Paste")
			(net "PWRGD_DSW_PWROK_R2")
		)
		(pad "R4" smd circle
			(at -3.599942 5.199888 180)
			(size 0.4064 0.4064)
			(layers "F.Cu" "F.Mask" "F.Paste")
			(net "FM_BMC_SUSACK_R2_N")
		)
		(pad "R5" smd circle
			(at -2.800096 5.199888 180)
			(size 0.4064 0.4064)
			(layers "F.Cu" "F.Mask" "F.Paste")
			(net "FM_DEBUG_PORT_R2_PRSNT_N")
		)
		(pad "R6" smd circle
			(at -1.999996 5.199888 180)
			(size 0.4064 0.4064)
			(layers "F.Cu" "F.Mask" "F.Paste")
			(net "FM_BMC_CRASHLOG_TRIG_R2_N")
		)
		(pad "R7" smd circle
			(at -1.199896 5.199888 180)
			(size 0.4064 0.4064)
			(layers "F.Cu" "F.Mask" "F.Paste")
			(net "GPU_NVS_PWR_BRAKE_R_N")
		)
		(pad "R8" smd circle
			(at -0.40005 5.199888 180)
			(size 0.4064 0.4064)
			(layers "F.Cu" "F.Mask" "F.Paste")
			(net "NC_FM_PFR_UPDATE_N")
		)
		(pad "R9" smd circle
			(at 0.40005 5.199888 180)
			(size 0.4064 0.4064)
			(layers "F.Cu" "F.Mask" "F.Paste")
			(net "Net_248")
		)
		(pad "R10" smd circle
			(at 1.199896 5.199888 180)
			(size 0.4064 0.4064)
			(layers "F.Cu" "F.Mask" "F.Paste")
			(net "Net_251")
		)
		(pad "R11" smd circle
			(at 1.999996 5.199888 180)
			(size 0.4064 0.4064)
			(layers "F.Cu" "F.Mask" "F.Paste")
			(net "Net_257")
		)
		(pad "R12" smd circle
			(at 2.800096 5.199888 180)
			(size 0.4064 0.4064)
			(layers "F.Cu" "F.Mask" "F.Paste")
			(net "PU_PB25A")
		)
		(pad "R13" smd circle
			(at 3.599942 5.199888 180)
			(size 0.4064 0.4064)
			(layers "F.Cu" "F.Mask" "F.Paste")
			(net "Net_259")
		)
		(pad "R14" smd circle
			(at 4.400042 5.199888 180)
			(size 0.4064 0.4064)
			(layers "F.Cu" "F.Mask" "F.Paste")
			(net "SMB_BMC_MM16_R4_SDA")
		)
		(pad "R15" smd circle
			(at 5.199888 5.199888 180)
			(size 0.4064 0.4064)
			(layers "F.Cu" "F.Mask" "F.Paste")
			(net "GND")
		)
		(pad "R16" smd circle
			(at 5.999988 5.199888 180)
			(size 0.4064 0.4064)
			(layers "F.Cu" "F.Mask" "F.Paste")
			(net "SMB_BMC_ALERT16_R2_N")
		)
		(pad "T1" smd circle
			(at -5.999988 5.999988 180)
			(size 0.4064 0.4064)
			(layers "F.Cu" "F.Mask" "F.Paste")
			(net "PVCCA_AUX_PLD")
		)
		(pad "T2" smd circle
			(at -5.199888 5.999988 180)
			(size 0.4064 0.4064)
			(layers "F.Cu" "F.Mask" "F.Paste")
			(net "FM_SOL_UART_CH_SEL_R2")
		)
		(pad "T3" smd circle
			(at -4.400042 5.999988 180)
			(size 0.4064 0.4064)
			(layers "F.Cu" "F.Mask" "F.Paste")
			(net "RST_WDTRST_PLD_R2_N")
		)
		(pad "T4" smd circle
			(at -3.599942 5.999988 180)
			(size 0.4064 0.4064)
			(layers "F.Cu" "F.Mask" "F.Paste")
			(net "Net_45")
		)
		(pad "T5" smd circle
			(at -2.800096 5.999988 180)
			(size 0.4064 0.4064)
			(layers "F.Cu" "F.Mask" "F.Paste")
			(net "IRQ_PCH_TPM_SPI_R2_N")
		)
		(pad "T6" smd circle
			(at -1.999996 5.999988 180)
			(size 0.4064 0.4064)
			(layers "F.Cu" "F.Mask" "F.Paste")
			(net "FM_PCH_BEEP_LED")
		)
		(pad "T7" smd circle
			(at -1.199896 5.999988 180)
			(size 0.4064 0.4064)
			(layers "F.Cu" "F.Mask" "F.Paste")
			(net "RST_PFR_OVR_RTC_R")
		)
		(pad "T8" smd circle
			(at -0.40005 5.999988 180)
			(size 0.4064 0.4064)
			(layers "F.Cu" "F.Mask" "F.Paste")
			(net "FM_JTAG_TCK_MUX_BMC_SEL")
		)
		(pad "T9" smd circle
			(at 0.40005 5.999988 180)
			(size 0.4064 0.4064)
			(layers "F.Cu" "F.Mask" "F.Paste")
			(net "PWRGD_P1V2_AUX_R1")
		)
		(pad "T10" smd circle
			(at 1.199896 5.999988 180)
			(size 0.4064 0.4064)
			(layers "F.Cu" "F.Mask" "F.Paste")
			(net "Net_249")
		)
		(pad "T11" smd circle
			(at 1.999996 5.999988 180)
			(size 0.4064 0.4064)
			(layers "F.Cu" "F.Mask" "F.Paste")
			(net "Net_254")
		)
		(pad "T12" smd circle
			(at 2.800096 5.999988 180)
			(size 0.4064 0.4064)
			(layers "F.Cu" "F.Mask" "F.Paste")
			(net "Net_258")
		)
		(pad "T13" smd circle
			(at 3.599942 5.999988 180)
			(size 0.4064 0.4064)
			(layers "F.Cu" "F.Mask" "F.Paste")
			(net "Net_262")
		)
		(pad "T14" smd circle
			(at 4.400042 5.999988 180)
			(size 0.4064 0.4064)
			(layers "F.Cu" "F.Mask" "F.Paste")
			(net "Net_260")
		)
		(pad "T15" smd circle
			(at 5.199888 5.999988 180)
			(size 0.4064 0.4064)
			(layers "F.Cu" "F.Mask" "F.Paste")
			(net "SMB_BMC_MM16_R4_SCL")
		)
		(pad "T16" smd circle
			(at 5.999988 5.999988 180)
			(size 0.4064 0.4064)
			(layers "F.Cu" "F.Mask" "F.Paste")
			(net "PVCCA_AUX_PLD")
		)
		(zone
			(layer "F.Cu")
			(hatch none 0.5)
			(connect_pads
				(clearance 0)
			)
			(min_thickness 0.25)
			(keepout
				(tracks allowed)
				(vias not_allowed)
				(pads allowed)
				(copperpour not_allowed)
				(footprints allowed)
			)
			(placement
				(enabled no)
				(sheetname "")
			)
			(fill
				(thermal_gap 0.5)
				(thermal_bridge_width 0.5)
				(island_removal_mode 0)
			)
			(polygon
				(pts
					(xy 21.605494 -100.60305) (xy 21.605494 -93.733112) (xy 28.475432 -93.733112) (xy 28.475432 -93.441012)
					(xy 21.605494 -93.441012) (xy 21.605494 -86.571074) (xy 21.313394 -86.571074) (xy 21.313394 -93.441012)
					(xy 14.443456 -93.441012) (xy 14.443456 -93.733112) (xy 21.313394 -93.733112) (xy 21.313394 -100.60305)
				)
			)
		)
	)
	(footprint ""
		(layer "F.Cu")
		(at 19.4056 -62.3316 90)
		(property "Reference" "U3"
			(at -1.8288 -1.61163 90)
			(unlocked yes)
			(layer "F.SilkS")
			(effects
				(font
					(size 0.7874 0.5842)
					(thickness 0.1524)
				)
				(justify left)
			)
		)
		(property "Value" ""
			(at 0 0 90)
			(layer "F.Fab")
			(effects
				(font
					(size 1.27 1.27)
				)
			)
		)
		(duplicate_pad_numbers_are_jumpers no)
		(fp_line
			(start 0.8636 -1.050036)
			(end 0.542036 -1.050036)
			(stroke
				(width 0.1524)
				(type default)
			)
			(layer "F.SilkS")
		)
		(fp_line
			(start 0.542036 -1.050036)
			(end 0 -0.508)
			(stroke
				(width 0.1524)
				(type default)
			)
			(layer "F.SilkS")
		)
		(fp_line
			(start -0.542036 -1.050036)
			(end -0.8636 -1.050036)
			(stroke
				(width 0.1524)
				(type default)
			)
			(layer "F.SilkS")
		)
		(fp_line
			(start -0.8636 -1.050036)
			(end -0.8636 1.050036)
			(stroke
				(width 0.1524)
				(type default)
			)
			(layer "F.SilkS")
		)
		(fp_line
			(start 0 -0.508)
			(end -0.542036 -1.050036)
			(stroke
				(width 0.1524)
				(type default)
			)
			(layer "F.SilkS")
		)
		(fp_line
			(start 0.8636 1.050036)
			(end 0.8636 -1.050036)
			(stroke
				(width 0.1524)
				(type default)
			)
			(layer "F.SilkS")
		)
		(fp_line
			(start -0.8636 1.050036)
			(end 0.8636 1.050036)
			(stroke
				(width 0.1524)
				(type default)
			)
			(layer "F.SilkS")
		)
		(fp_poly
			(pts
				(xy -2.201672 -1.857248) (xy -2.919984 -1.138936) (xy -1.842262 -0.77978)
			)
			(stroke
				(width 0)
				(type default)
			)
			(fill yes)
			(layer "F.SilkS")
		)
		(fp_line
			(start 1.199896 -1.050036)
			(end -1.199896 -1.050036)
			(stroke
				(width 0.1)
				(type default)
			)
			(layer "F.Fab")
		)
		(fp_line
			(start -1.199896 -1.050036)
			(end -1.199896 1.050036)
			(stroke
				(width 0.1)
				(type default)
			)
			(layer "F.Fab")
		)
		(fp_line
			(start 1.199896 1.050036)
			(end 1.199896 -1.050036)
			(stroke
				(width 0.1)
				(type default)
			)
			(layer "F.Fab")
		)
		(fp_line
			(start -1.199896 1.050036)
			(end 1.199896 1.050036)
			(stroke
				(width 0.1)
				(type default)
			)
			(layer "F.Fab")
		)
		(fp_poly
			(pts
				(xy -2.794 -1.258062) (xy -2.794 -0.242062) (xy -1.778 -0.750062)
			)
			(stroke
				(width 0)
				(type default)
			)
			(fill yes)
			(layer "F.Fab")
		)
		(pad "1" smd rect
			(at -1.35001 -0.750062)
			(size 0.2794 0.7112)
			(layers "F.Cu" "F.Mask" "F.Paste")
			(net "UART_BIC_DBG_RX")
		)
		(pad "2" smd rect
			(at -1.35001 -0.249936)
			(size 0.2794 0.7112)
			(layers "F.Cu" "F.Mask" "F.Paste")
			(net "UART_BMC_5_RXD_BUF1_SW")
		)
		(pad "3" smd rect
			(at -1.35001 0.249936)
			(size 0.2794 0.7112)
			(layers "F.Cu" "F.Mask" "F.Paste")
			(net "UART_BMC_1_RXD_R")
		)
		(pad "4" smd rect
			(at -1.35001 0.750062)
			(size 0.2794 0.7112)
			(layers "F.Cu" "F.Mask" "F.Paste")
			(net "GND")
		)
		(pad "5" smd rect
			(at 1.35001 0.750062)
			(size 0.2794 0.7112)
			(layers "F.Cu" "F.Mask" "F.Paste")
			(net "FM_UARTSW_LSB_N")
		)
		(pad "6" smd rect
			(at 1.35001 0.249936)
			(size 0.2794 0.7112)
			(layers "F.Cu" "F.Mask" "F.Paste")
			(net "FM_UARTSW_MSB_N")
		)
		(pad "7" smd rect
			(at 1.35001 -0.249936)
			(size 0.2794 0.7112)
			(layers "F.Cu" "F.Mask" "F.Paste")
			(net "SPA_SIN_SW_BUF")
		)
		(pad "8" smd rect
			(at 1.35001 -0.750062)
			(size 0.2794 0.7112)
			(layers "F.Cu" "F.Mask" "F.Paste")
			(net "P3V3_AUX")
		)
	)
	(footprint ""
		(layer "F.Cu")
		(at 30.41904 -70.536054 90)
		(property "Reference" "R651"
			(at 0 0 90)
			(layer "F.SilkS")
			(hide yes)
			(effects
				(font
					(size 1.27 1.27)
				)
			)
		)
		(property "Value" ""
			(at 0 0 90)
			(layer "F.Fab")
			(effects
				(font
					(size 1.27 1.27)
				)
			)
		)
		(duplicate_pad_numbers_are_jumpers no)
		(fp_line
			(start 0.7874 -0.4064)
			(end 0.7874 0.4064)
			(stroke
				(width 0.1524)
				(type default)
			)
			(layer "F.SilkS")
		)
		(fp_line
			(start -0.7874 -0.4064)
			(end 0.7874 -0.4064)
			(stroke
				(width 0.1524)
				(type default)
			)
			(layer "F.SilkS")
		)
		(fp_line
			(start 0.7874 0.4064)
			(end -0.7874 0.4064)
			(stroke
				(width 0.1524)
				(type default)
			)
			(layer "F.SilkS")
		)
		(fp_line
			(start -0.7874 0.4064)
			(end -0.7874 -0.4064)
			(stroke
				(width 0.1524)
				(type default)
			)
			(layer "F.SilkS")
		)
		(fp_line
			(start -0.12065 -0.305054)
			(end -0.12065 -0.2794)
			(stroke
				(width 0.1)
				(type default)
			)
			(layer "F.Fab")
		)
		(fp_line
			(start -0.67945 -0.305054)
			(end -0.12065 -0.305054)
			(stroke
				(width 0.1)
				(type default)
			)
			(layer "F.Fab")
		)
		(fp_line
			(start 0.67945 -0.3048)
			(end 0.67945 0.3048)
			(stroke
				(width 0.1)
				(type default)
			)
			(layer "F.Fab")
		)
		(fp_line
			(start 0.12065 -0.3048)
			(end 0.67945 -0.3048)
			(stroke
				(width 0.1)
				(type default)
			)
			(layer "F.Fab")
		)
		(fp_line
			(start 0.12065 -0.2794)
			(end 0.12065 -0.3048)
			(stroke
				(width 0.1)
				(type default)
			)
			(layer "F.Fab")
		)
		(fp_line
			(start -0.12065 -0.2794)
			(end 0.12065 -0.2794)
			(stroke
				(width 0.1)
				(type default)
			)
			(layer "F.Fab")
		)
		(fp_line
			(start 0.120396 0.2794)
			(end -0.12065 0.2794)
			(stroke
				(width 0.1)
				(type default)
			)
			(layer "F.Fab")
		)
		(fp_line
			(start -0.12065 0.2794)
			(end -0.12065 0.3048)
			(stroke
				(width 0.1)
				(type default)
			)
			(layer "F.Fab")
		)
		(fp_line
			(start 0.67945 0.3048)
			(end 0.120396 0.3048)
			(stroke
				(width 0.1)
				(type default)
			)
			(layer "F.Fab")
		)
		(fp_line
			(start 0.120396 0.3048)
			(end 0.120396 0.2794)
			(stroke
				(width 0.1)
				(type default)
			)
			(layer "F.Fab")
		)
		(fp_line
			(start -0.12065 0.3048)
			(end -0.67945 0.3048)
			(stroke
				(width 0.1)
				(type default)
			)
			(layer "F.Fab")
		)
		(fp_line
			(start -0.67945 0.3048)
			(end -0.67945 -0.305054)
			(stroke
				(width 0.1)
				(type default)
			)
			(layer "F.Fab")
		)
		(pad "1" smd circle
			(at -0.40005 0 90)
			(size 0 0)
			(layers "F.Cu" "F.Mask" "F.Paste")
			(net "BMC_EMMC_DT6")
		)
		(pad "2" smd circle
			(at 0.40005 0 90)
			(size 0 0)
			(layers "F.Cu" "F.Mask" "F.Paste")
			(net "EMMC_DT6_R")
		)
	)
	(footprint ""
		(layer "F.Cu")
		(at 85.7504 -70.4596 -90)
		(property "Reference" "PR275"
			(at 0 0 270)
			(layer "F.SilkS")
			(hide yes)
			(effects
				(font
					(size 1.27 1.27)
				)
			)
		)
		(property "Value" ""
			(at 0 0 270)
			(layer "F.Fab")
			(effects
				(font
					(size 1.27 1.27)
				)
			)
		)
		(duplicate_pad_numbers_are_jumpers no)
		(fp_line
			(start -0.7874 0.4064)
			(end -0.7874 -0.4064)
			(stroke
				(width 0.1524)
				(type default)
			)
			(layer "F.SilkS")
		)
		(fp_line
			(start 0.7874 0.4064)
			(end -0.7874 0.4064)
			(stroke
				(width 0.1524)
				(type default)
			)
			(layer "F.SilkS")
		)
		(fp_line
			(start -0.7874 -0.4064)
			(end 0.7874 -0.4064)
			(stroke
				(width 0.1524)
				(type default)
			)
			(layer "F.SilkS")
		)
		(fp_line
			(start 0.7874 -0.4064)
			(end 0.7874 0.4064)
			(stroke
				(width 0.1524)
				(type default)
			)
			(layer "F.SilkS")
		)
		(fp_line
			(start -0.67945 0.3048)
			(end -0.67945 -0.305054)
			(stroke
				(width 0.1)
				(type default)
			)
			(layer "F.Fab")
		)
		(fp_line
			(start -0.12065 0.3048)
			(end -0.67945 0.3048)
			(stroke
				(width 0.1)
				(type default)
			)
			(layer "F.Fab")
		)
		(fp_line
			(start 0.120396 0.3048)
			(end 0.120396 0.2794)
			(stroke
				(width 0.1)
				(type default)
			)
			(layer "F.Fab")
		)
		(fp_line
			(start 0.67945 0.3048)
			(end 0.120396 0.3048)
			(stroke
				(width 0.1)
				(type default)
			)
			(layer "F.Fab")
		)
		(fp_line
			(start -0.12065 0.2794)
			(end -0.12065 0.3048)
			(stroke
				(width 0.1)
				(type default)
			)
			(layer "F.Fab")
		)
		(fp_line
			(start 0.120396 0.2794)
			(end -0.12065 0.2794)
			(stroke
				(width 0.1)
				(type default)
			)
			(layer "F.Fab")
		)
		(fp_line
			(start -0.12065 -0.2794)
			(end 0.12065 -0.2794)
			(stroke
				(width 0.1)
				(type default)
			)
			(layer "F.Fab")
		)
		(fp_line
			(start 0.12065 -0.2794)
			(end 0.12065 -0.3048)
			(stroke
				(width 0.1)
				(type default)
			)
			(layer "F.Fab")
		)
		(fp_line
			(start 0.12065 -0.3048)
			(end 0.67945 -0.3048)
			(stroke
				(width 0.1)
				(type default)
			)
			(layer "F.Fab")
		)
		(fp_line
			(start 0.67945 -0.3048)
			(end 0.67945 0.3048)
			(stroke
				(width 0.1)
				(type default)
			)
			(layer "F.Fab")
		)
		(fp_line
			(start -0.67945 -0.305054)
			(end -0.12065 -0.305054)
			(stroke
				(width 0.1)
				(type default)
			)
			(layer "F.Fab")
		)
		(fp_line
			(start -0.12065 -0.305054)
			(end -0.12065 -0.2794)
			(stroke
				(width 0.1)
				(type default)
			)
			(layer "F.Fab")
		)
		(pad "1" smd circle
			(at -0.40005 0 270)
			(size 0 0)
			(layers "F.Cu" "F.Mask" "F.Paste")
			(net "P5V_AUX")
		)
		(pad "2" smd circle
			(at 0.40005 0 270)
			(size 0 0)
			(layers "F.Cu" "F.Mask" "F.Paste")
			(net "PVCC1_AUX")
		)
	)
	(footprint ""
		(layer "F.Cu")
		(at 39.932864 -45.384466 180)
		(property "Reference" "R820"
			(at 0 0 180)
			(layer "F.SilkS")
			(hide yes)
			(effects
				(font
					(size 1.27 1.27)
				)
			)
		)
		(property "Value" ""
			(at 0 0 180)
			(layer "F.Fab")
			(effects
				(font
					(size 1.27 1.27)
				)
			)
		)
		(duplicate_pad_numbers_are_jumpers no)
		(fp_line
			(start 0.7874 0.4064)
			(end -0.7874 0.4064)
			(stroke
				(width 0.1524)
				(type default)
			)
			(layer "F.SilkS")
		)
		(fp_line
			(start 0.7874 -0.4064)
			(end 0.7874 0.4064)
			(stroke
				(width 0.1524)
				(type default)
			)
			(layer "F.SilkS")
		)
		(fp_line
			(start -0.7874 0.4064)
			(end -0.7874 -0.4064)
			(stroke
				(width 0.1524)
				(type default)
			)
			(layer "F.SilkS")
		)
		(fp_line
			(start -0.7874 -0.4064)
			(end 0.7874 -0.4064)
			(stroke
				(width 0.1524)
				(type default)
			)
			(layer "F.SilkS")
		)
		(fp_line
			(start 0.67945 0.3048)
			(end 0.120396 0.3048)
			(stroke
				(width 0.1)
				(type default)
			)
			(layer "F.Fab")
		)
		(fp_line
			(start 0.67945 -0.3048)
			(end 0.67945 0.3048)
			(stroke
				(width 0.1)
				(type default)
			)
			(layer "F.Fab")
		)
		(fp_line
			(start 0.12065 -0.2794)
			(end 0.12065 -0.3048)
			(stroke
				(width 0.1)
				(type default)
			)
			(layer "F.Fab")
		)
		(fp_line
			(start 0.12065 -0.3048)
			(end 0.67945 -0.3048)
			(stroke
				(width 0.1)
				(type default)
			)
			(layer "F.Fab")
		)
		(fp_line
			(start 0.120396 0.3048)
			(end 0.120396 0.2794)
			(stroke
				(width 0.1)
				(type default)
			)
			(layer "F.Fab")
		)
		(fp_line
			(start 0.120396 0.2794)
			(end -0.12065 0.2794)
			(stroke
				(width 0.1)
				(type default)
			)
			(layer "F.Fab")
		)
		(fp_line
			(start -0.12065 0.3048)
			(end -0.67945 0.3048)
			(stroke
				(width 0.1)
				(type default)
			)
			(layer "F.Fab")
		)
		(fp_line
			(start -0.12065 0.2794)
			(end -0.12065 0.3048)
			(stroke
				(width 0.1)
				(type default)
			)
			(layer "F.Fab")
		)
		(fp_line
			(start -0.12065 -0.2794)
			(end 0.12065 -0.2794)
			(stroke
				(width 0.1)
				(type default)
			)
			(layer "F.Fab")
		)
		(fp_line
			(start -0.12065 -0.305054)
			(end -0.12065 -0.2794)
			(stroke
				(width 0.1)
				(type default)
			)
			(layer "F.Fab")
		)
		(fp_line
			(start -0.67945 0.3048)
			(end -0.67945 -0.305054)
			(stroke
				(width 0.1)
				(type default)
			)
			(layer "F.Fab")
		)
		(fp_line
			(start -0.67945 -0.305054)
			(end -0.12065 -0.305054)
			(stroke
				(width 0.1)
				(type default)
			)
			(layer "F.Fab")
		)
		(pad "1" smd circle
			(at -0.40005 0 180)
			(size 0 0)
			(layers "F.Cu" "F.Mask" "F.Paste")
			(net "SMB_BMC_MM14_R_SDA")
		)
		(pad "2" smd circle
			(at 0.40005 0 180)
			(size 0 0)
			(layers "F.Cu" "F.Mask" "F.Paste")
			(net "GND")
		)
	)
	(footprint ""
		(layer "F.Cu")
		(at 9.7536 -80.5434)
		(property "Reference" "R108"
			(at 0 0 0)
			(layer "F.SilkS")
			(hide yes)
			(effects
				(font
					(size 1.27 1.27)
				)
			)
		)
		(property "Value" ""
			(at 0 0 0)
			(layer "F.Fab")
			(effects
				(font
					(size 1.27 1.27)
				)
			)
		)
		(duplicate_pad_numbers_are_jumpers no)
		(fp_line
			(start -0.7874 -0.4064)
			(end 0.7874 -0.4064)
			(stroke
				(width 0.1524)
				(type default)
			)
			(layer "F.SilkS")
		)
		(fp_line
			(start -0.7874 0.4064)
			(end -0.7874 -0.4064)
			(stroke
				(width 0.1524)
				(type default)
			)
			(layer "F.SilkS")
		)
		(fp_line
			(start 0.7874 -0.4064)
			(end 0.7874 0.4064)
			(stroke
				(width 0.1524)
				(type default)
			)
			(layer "F.SilkS")
		)
		(fp_line
			(start 0.7874 0.4064)
			(end -0.7874 0.4064)
			(stroke
				(width 0.1524)
				(type default)
			)
			(layer "F.SilkS")
		)
		(fp_line
			(start -0.67945 -0.305054)
			(end -0.12065 -0.305054)
			(stroke
				(width 0.1)
				(type default)
			)
			(layer "F.Fab")
		)
		(fp_line
			(start -0.67945 0.3048)
			(end -0.67945 -0.305054)
			(stroke
				(width 0.1)
				(type default)
			)
			(layer "F.Fab")
		)
		(fp_line
			(start -0.12065 -0.305054)
			(end -0.12065 -0.2794)
			(stroke
				(width 0.1)
				(type default)
			)
			(layer "F.Fab")
		)
		(fp_line
			(start -0.12065 -0.2794)
			(end 0.12065 -0.2794)
			(stroke
				(width 0.1)
				(type default)
			)
			(layer "F.Fab")
		)
		(fp_line
			(start -0.12065 0.2794)
			(end -0.12065 0.3048)
			(stroke
				(width 0.1)
				(type default)
			)
			(layer "F.Fab")
		)
		(fp_line
			(start -0.12065 0.3048)
			(end -0.67945 0.3048)
			(stroke
				(width 0.1)
				(type default)
			)
			(layer "F.Fab")
		)
		(fp_line
			(start 0.120396 0.2794)
			(end -0.12065 0.2794)
			(stroke
				(width 0.1)
				(type default)
			)
			(layer "F.Fab")
		)
		(fp_line
			(start 0.120396 0.3048)
			(end 0.120396 0.2794)
			(stroke
				(width 0.1)
				(type default)
			)
			(layer "F.Fab")
		)
		(fp_line
			(start 0.12065 -0.3048)
			(end 0.67945 -0.3048)
			(stroke
				(width 0.1)
				(type default)
			)
			(layer "F.Fab")
		)
		(fp_line
			(start 0.12065 -0.2794)
			(end 0.12065 -0.3048)
			(stroke
				(width 0.1)
				(type default)
			)
			(layer "F.Fab")
		)
		(fp_line
			(start 0.67945 -0.3048)
			(end 0.67945 0.3048)
			(stroke
				(width 0.1)
				(type default)
			)
			(layer "F.Fab")
		)
		(fp_line
			(start 0.67945 0.3048)
			(end 0.120396 0.3048)
			(stroke
				(width 0.1)
				(type default)
			)
			(layer "F.Fab")
		)
		(pad "1" smd circle
			(at -0.40005 0)
			(size 0 0)
			(layers "F.Cu" "F.Mask" "F.Paste")
			(net "RST_SRST_PLD_BMC_BUF_N")
		)
		(pad "2" smd circle
			(at 0.40005 0)
			(size 0 0)
			(layers "F.Cu" "F.Mask" "F.Paste")
			(net "RST_BMC_SRST_BUF_R_N")
		)
	)
	(footprint ""
		(layer "F.Cu")
		(at 112.014 90.17 90)
		(property "Reference" "X18"
			(at -2.07137 1.0795 0)
			(unlocked yes)
			(layer "F.SilkS")
			(effects
				(font
					(size 0.7874 0.5842)
					(thickness 0.1524)
				)
				(justify left)
			)
		)
		(property "Value" ""
			(at 0 0 90)
			(layer "F.Fab")
			(effects
				(font
					(size 1.27 1.27)
				)
			)
		)
		(property "Device Type" "TP_TDR_4P_FTS_TH-TP_TDR_4P_DIPA"
			(at 1.30175 1.27 180)
			(unlocked yes)
			(layer "F.Fab")
			(hide yes)
			(effects
				(font
					(size 0.635 0.4064)
					(thickness 0.1524)
				)
			)
		)
		(property "User Part Number" "N_A"
			(at 1.30175 1.27 180)
			(unlocked yes)
			(layer "Cmts.User")
			(hide yes)
			(effects
				(font
					(size 0.635 0.4064)
					(thickness 0.1524)
				)
			)
		)
		(duplicate_pad_numbers_are_jumpers no)
		(fp_line
			(start 2.54 -1.27)
			(end 0 -1.27)
			(stroke
				(width 0.1524)
				(type default)
			)
			(layer "F.SilkS")
		)
		(fp_line
			(start 0 -1.27)
			(end 0 -0.635)
			(stroke
				(width 0.1524)
				(type default)
			)
			(layer "F.SilkS")
		)
		(fp_line
			(start 2.54 -1.1303)
			(end 2.54 -1.27)
			(stroke
				(width 0.1524)
				(type default)
			)
			(layer "F.SilkS")
		)
		(fp_line
			(start 0 0.635)
			(end 0 1.905)
			(stroke
				(width 0.1524)
				(type default)
			)
			(layer "F.SilkS")
		)
		(fp_line
			(start 2.54 1.4097)
			(end 2.54 1.1303)
			(stroke
				(width 0.1524)
				(type default)
			)
			(layer "F.SilkS")
		)
		(fp_line
			(start 0 3.175)
			(end 0 3.81)
			(stroke
				(width 0.1524)
				(type default)
			)
			(layer "F.SilkS")
		)
		(fp_line
			(start 2.54 3.81)
			(end 2.54 3.6703)
			(stroke
				(width 0.1524)
				(type default)
			)
			(layer "F.SilkS")
		)
		(fp_line
			(start 0 3.81)
			(end 2.54 3.81)
			(stroke
				(width 0.1524)
				(type default)
			)
			(layer "F.SilkS")
		)
		(fp_poly
			(pts
				(xy -0.761746 0) (xy -2.285746 -0.762) (xy -2.285746 0.762)
			)
			(stroke
				(width 0)
				(type default)
			)
			(fill yes)
			(layer "F.SilkS")
		)
		(fp_line
			(start 2.54 -1.27)
			(end 0 -1.27)
			(stroke
				(width 0.1)
				(type default)
			)
			(layer "F.Fab")
		)
		(fp_line
			(start 0 -1.27)
			(end 0 3.81)
			(stroke
				(width 0.1)
				(type default)
			)
			(layer "F.Fab")
		)
		(fp_line
			(start 2.54 3.81)
			(end 2.54 -1.27)
			(stroke
				(width 0.1)
				(type default)
			)
			(layer "F.Fab")
		)
		(fp_line
			(start 0 3.81)
			(end 2.54 3.81)
			(stroke
				(width 0.1)
				(type default)
			)
			(layer "F.Fab")
		)
		(fp_poly
			(pts
				(xy -0.761746 0) (xy -2.285746 -0.762) (xy -2.285746 0.762)
			)
			(stroke
				(width 0)
				(type default)
			)
			(fill yes)
			(layer "F.Fab")
		)
		(pad "1" thru_hole circle
			(at 0 0 90)
			(size 1.0033 1.0033)
			(drill 0.249936)
			(layers "*.Cu" "*.Mask")
			(remove_unused_layers no)
			(net "TDR_DIFF_100_BOT_DP")
			(clearance 0.10795)
			(thermal_gap 0.10795)
			(padstack
				(mode front_inner_back)
				(layer "Inner"
					(shape circle)
					(size 0.8001 0.8001)
					(clearance 0.1524)
				)
				(layer "B.Cu"
					(shape circle)
					(size 1.0033 1.0033)
					(clearance 0.10795)
				)
			)
		)
		(pad "2" thru_hole circle
			(at 2.54 0 90)
			(size 1.9939 1.9939)
			(drill 0.249936)
			(layers "*.Cu" "*.Mask")
			(remove_unused_layers no)
			(net "GND_P1")
			(clearance 0.10795)
			(thermal_gap 0.10795)
			(padstack
				(mode front_inner_back)
				(layer "Inner"
					(shape circle)
					(size 0.8001 0.8001)
					(clearance 0.1524)
				)
				(layer "B.Cu"
					(shape circle)
					(size 1.9939 1.9939)
					(clearance 0.10795)
				)
			)
		)
		(pad "3" thru_hole circle
			(at 2.54 2.54 90)
			(size 1.9939 1.9939)
			(drill 0.249936)
			(layers "*.Cu" "*.Mask")
			(remove_unused_layers no)
			(net "GND_P1")
			(clearance 0.10795)
			(thermal_gap 0.10795)
			(padstack
				(mode front_inner_back)
				(layer "Inner"
					(shape circle)
					(size 0.8001 0.8001)
					(clearance 0.1524)
				)
				(layer "B.Cu"
					(shape circle)
					(size 1.9939 1.9939)
					(clearance 0.10795)
				)
			)
		)
		(pad "4" thru_hole circle
			(at 0 2.54 90)
			(size 1.0033 1.0033)
			(drill 0.249936)
			(layers "*.Cu" "*.Mask")
			(remove_unused_layers no)
			(net "TDR_DIFF_100_BOT_DN")
			(clearance 0.10795)
			(thermal_gap 0.10795)
			(padstack
				(mode front_inner_back)
				(layer "Inner"
					(shape circle)
					(size 0.8001 0.8001)
					(clearance 0.1524)
				)
				(layer "B.Cu"
					(shape circle)
					(size 1.0033 1.0033)
					(clearance 0.10795)
				)
			)
		)
	)
	(footprint ""
		(layer "F.Cu")
		(at 31.56204 -70.536054 90)
		(property "Reference" "R660"
			(at 0 0 90)
			(layer "F.SilkS")
			(hide yes)
			(effects
				(font
					(size 1.27 1.27)
				)
			)
		)
		(property "Value" ""
			(at 0 0 90)
			(layer "F.Fab")
			(effects
				(font
					(size 1.27 1.27)
				)
			)
		)
		(duplicate_pad_numbers_are_jumpers no)
		(fp_line
			(start 0.7874 -0.4064)
			(end 0.7874 0.4064)
			(stroke
				(width 0.1524)
				(type default)
			)
			(layer "F.SilkS")
		)
		(fp_line
			(start -0.7874 -0.4064)
			(end 0.7874 -0.4064)
			(stroke
				(width 0.1524)
				(type default)
			)
			(layer "F.SilkS")
		)
		(fp_line
			(start 0.7874 0.4064)
			(end -0.7874 0.4064)
			(stroke
				(width 0.1524)
				(type default)
			)
			(layer "F.SilkS")
		)
		(fp_line
			(start -0.7874 0.4064)
			(end -0.7874 -0.4064)
			(stroke
				(width 0.1524)
				(type default)
			)
			(layer "F.SilkS")
		)
		(fp_line
			(start -0.12065 -0.305054)
			(end -0.12065 -0.2794)
			(stroke
				(width 0.1)
				(type default)
			)
			(layer "F.Fab")
		)
		(fp_line
			(start -0.67945 -0.305054)
			(end -0.12065 -0.305054)
			(stroke
				(width 0.1)
				(type default)
			)
			(layer "F.Fab")
		)
		(fp_line
			(start 0.67945 -0.3048)
			(end 0.67945 0.3048)
			(stroke
				(width 0.1)
				(type default)
			)
			(layer "F.Fab")
		)
		(fp_line
			(start 0.12065 -0.3048)
			(end 0.67945 -0.3048)
			(stroke
				(width 0.1)
				(type default)
			)
			(layer "F.Fab")
		)
		(fp_line
			(start 0.12065 -0.2794)
			(end 0.12065 -0.3048)
			(stroke
				(width 0.1)
				(type default)
			)
			(layer "F.Fab")
		)
		(fp_line
			(start -0.12065 -0.2794)
			(end 0.12065 -0.2794)
			(stroke
				(width 0.1)
				(type default)
			)
			(layer "F.Fab")
		)
		(fp_line
			(start 0.120396 0.2794)
			(end -0.12065 0.2794)
			(stroke
				(width 0.1)
				(type default)
			)
			(layer "F.Fab")
		)
		(fp_line
			(start -0.12065 0.2794)
			(end -0.12065 0.3048)
			(stroke
				(width 0.1)
				(type default)
			)
			(layer "F.Fab")
		)
		(fp_line
			(start 0.67945 0.3048)
			(end 0.120396 0.3048)
			(stroke
				(width 0.1)
				(type default)
			)
			(layer "F.Fab")
		)
		(fp_line
			(start 0.120396 0.3048)
			(end 0.120396 0.2794)
			(stroke
				(width 0.1)
				(type default)
			)
			(layer "F.Fab")
		)
		(fp_line
			(start -0.12065 0.3048)
			(end -0.67945 0.3048)
			(stroke
				(width 0.1)
				(type default)
			)
			(layer "F.Fab")
		)
		(fp_line
			(start -0.67945 0.3048)
			(end -0.67945 -0.305054)
			(stroke
				(width 0.1)
				(type default)
			)
			(layer "F.Fab")
		)
		(pad "1" smd circle
			(at -0.40005 0 90)
			(size 0 0)
			(layers "F.Cu" "F.Mask" "F.Paste")
			(net "P3V3_AUX")
		)
		(pad "2" smd circle
			(at 0.40005 0 90)
			(size 0 0)
			(layers "F.Cu" "F.Mask" "F.Paste")
			(net "EMMC_DT5_R")
		)
	)
	(footprint ""
		(layer "F.Cu")
		(at 84.795106 -70.458838 90)
		(property "Reference" "PR539"
			(at 0 0 90)
			(layer "F.SilkS")
			(hide yes)
			(effects
				(font
					(size 1.27 1.27)
				)
			)
		)
		(property "Value" ""
			(at 0 0 90)
			(layer "F.Fab")
			(effects
				(font
					(size 1.27 1.27)
				)
			)
		)
		(duplicate_pad_numbers_are_jumpers no)
		(fp_line
			(start 0.7874 -0.4064)
			(end 0.7874 0.4064)
			(stroke
				(width 0.1524)
				(type default)
			)
			(layer "F.SilkS")
		)
		(fp_line
			(start -0.7874 -0.4064)
			(end 0.7874 -0.4064)
			(stroke
				(width 0.1524)
				(type default)
			)
			(layer "F.SilkS")
		)
		(fp_line
			(start 0.7874 0.4064)
			(end -0.7874 0.4064)
			(stroke
				(width 0.1524)
				(type default)
			)
			(layer "F.SilkS")
		)
		(fp_line
			(start -0.7874 0.4064)
			(end -0.7874 -0.4064)
			(stroke
				(width 0.1524)
				(type default)
			)
			(layer "F.SilkS")
		)
		(fp_line
			(start -0.12065 -0.305054)
			(end -0.12065 -0.2794)
			(stroke
				(width 0.1)
				(type default)
			)
			(layer "F.Fab")
		)
		(fp_line
			(start -0.67945 -0.305054)
			(end -0.12065 -0.305054)
			(stroke
				(width 0.1)
				(type default)
			)
			(layer "F.Fab")
		)
		(fp_line
			(start 0.67945 -0.3048)
			(end 0.67945 0.3048)
			(stroke
				(width 0.1)
				(type default)
			)
			(layer "F.Fab")
		)
		(fp_line
			(start 0.12065 -0.3048)
			(end 0.67945 -0.3048)
			(stroke
				(width 0.1)
				(type default)
			)
			(layer "F.Fab")
		)
		(fp_line
			(start 0.12065 -0.2794)
			(end 0.12065 -0.3048)
			(stroke
				(width 0.1)
				(type default)
			)
			(layer "F.Fab")
		)
		(fp_line
			(start -0.12065 -0.2794)
			(end 0.12065 -0.2794)
			(stroke
				(width 0.1)
				(type default)
			)
			(layer "F.Fab")
		)
		(fp_line
			(start 0.120396 0.2794)
			(end -0.12065 0.2794)
			(stroke
				(width 0.1)
				(type default)
			)
			(layer "F.Fab")
		)
		(fp_line
			(start -0.12065 0.2794)
			(end -0.12065 0.3048)
			(stroke
				(width 0.1)
				(type default)
			)
			(layer "F.Fab")
		)
		(fp_line
			(start 0.67945 0.3048)
			(end 0.120396 0.3048)
			(stroke
				(width 0.1)
				(type default)
			)
			(layer "F.Fab")
		)
		(fp_line
			(start 0.120396 0.3048)
			(end 0.120396 0.2794)
			(stroke
				(width 0.1)
				(type default)
			)
			(layer "F.Fab")
		)
		(fp_line
			(start -0.12065 0.3048)
			(end -0.67945 0.3048)
			(stroke
				(width 0.1)
				(type default)
			)
			(layer "F.Fab")
		)
		(fp_line
			(start -0.67945 0.3048)
			(end -0.67945 -0.305054)
			(stroke
				(width 0.1)
				(type default)
			)
			(layer "F.Fab")
		)
		(pad "1" smd circle
			(at -0.40005 0 90)
			(size 0 0)
			(layers "F.Cu" "F.Mask" "F.Paste")
			(net "PVCC1_AUX")
		)
		(pad "2" smd circle
			(at 0.40005 0 90)
			(size 0 0)
			(layers "F.Cu" "F.Mask" "F.Paste")
			(net "P1V2_AUX_VCC")
		)
	)
	(footprint ""
		(layer "F.Cu")
		(at 64.1096 -70.84314 90)
		(property "Reference" "R96"
			(at 0 0 90)
			(layer "F.SilkS")
			(hide yes)
			(effects
				(font
					(size 1.27 1.27)
				)
			)
		)
		(property "Value" ""
			(at 0 0 90)
			(layer "F.Fab")
			(effects
				(font
					(size 1.27 1.27)
				)
			)
		)
		(duplicate_pad_numbers_are_jumpers no)
		(fp_line
			(start 0.7874 -0.4064)
			(end 0.7874 0.4064)
			(stroke
				(width 0.1524)
				(type default)
			)
			(layer "F.SilkS")
		)
		(fp_line
			(start -0.7874 -0.4064)
			(end 0.7874 -0.4064)
			(stroke
				(width 0.1524)
				(type default)
			)
			(layer "F.SilkS")
		)
		(fp_line
			(start 0.7874 0.4064)
			(end -0.7874 0.4064)
			(stroke
				(width 0.1524)
				(type default)
			)
			(layer "F.SilkS")
		)
		(fp_line
			(start -0.7874 0.4064)
			(end -0.7874 -0.4064)
			(stroke
				(width 0.1524)
				(type default)
			)
			(layer "F.SilkS")
		)
		(fp_line
			(start -0.12065 -0.305054)
			(end -0.12065 -0.2794)
			(stroke
				(width 0.1)
				(type default)
			)
			(layer "F.Fab")
		)
		(fp_line
			(start -0.67945 -0.305054)
			(end -0.12065 -0.305054)
			(stroke
				(width 0.1)
				(type default)
			)
			(layer "F.Fab")
		)
		(fp_line
			(start 0.67945 -0.3048)
			(end 0.67945 0.3048)
			(stroke
				(width 0.1)
				(type default)
			)
			(layer "F.Fab")
		)
		(fp_line
			(start 0.12065 -0.3048)
			(end 0.67945 -0.3048)
			(stroke
				(width 0.1)
				(type default)
			)
			(layer "F.Fab")
		)
		(fp_line
			(start 0.12065 -0.2794)
			(end 0.12065 -0.3048)
			(stroke
				(width 0.1)
				(type default)
			)
			(layer "F.Fab")
		)
		(fp_line
			(start -0.12065 -0.2794)
			(end 0.12065 -0.2794)
			(stroke
				(width 0.1)
				(type default)
			)
			(layer "F.Fab")
		)
		(fp_line
			(start 0.120396 0.2794)
			(end -0.12065 0.2794)
			(stroke
				(width 0.1)
				(type default)
			)
			(layer "F.Fab")
		)
		(fp_line
			(start -0.12065 0.2794)
			(end -0.12065 0.3048)
			(stroke
				(width 0.1)
				(type default)
			)
			(layer "F.Fab")
		)
		(fp_line
			(start 0.67945 0.3048)
			(end 0.120396 0.3048)
			(stroke
				(width 0.1)
				(type default)
			)
			(layer "F.Fab")
		)
		(fp_line
			(start 0.120396 0.3048)
			(end 0.120396 0.2794)
			(stroke
				(width 0.1)
				(type default)
			)
			(layer "F.Fab")
		)
		(fp_line
			(start -0.12065 0.3048)
			(end -0.67945 0.3048)
			(stroke
				(width 0.1)
				(type default)
			)
			(layer "F.Fab")
		)
		(fp_line
			(start -0.67945 0.3048)
			(end -0.67945 -0.305054)
			(stroke
				(width 0.1)
				(type default)
			)
			(layer "F.Fab")
		)
		(pad "1" smd circle
			(at -0.40005 0 90)
			(size 0 0)
			(layers "F.Cu" "F.Mask" "F.Paste")
			(net "BMC_EMMC_RST_R_N")
		)
		(pad "2" smd circle
			(at 0.40005 0 90)
			(size 0 0)
			(layers "F.Cu" "F.Mask" "F.Paste")
			(net "BMC_EMMC_RST_N")
		)
	)
	(footprint ""
		(layer "F.Cu")
		(at 71.80834 -23.68804 180)
		(property "Reference" "R585"
			(at 0 0 180)
			(layer "F.SilkS")
			(hide yes)
			(effects
				(font
					(size 1.27 1.27)
				)
			)
		)
		(property "Value" ""
			(at 0 0 180)
			(layer "F.Fab")
			(effects
				(font
					(size 1.27 1.27)
				)
			)
		)
		(duplicate_pad_numbers_are_jumpers no)
		(fp_line
			(start 0.7874 0.4064)
			(end -0.7874 0.4064)
			(stroke
				(width 0.1524)
				(type default)
			)
			(layer "F.SilkS")
		)
		(fp_line
			(start 0.7874 -0.4064)
			(end 0.7874 0.4064)
			(stroke
				(width 0.1524)
				(type default)
			)
			(layer "F.SilkS")
		)
		(fp_line
			(start -0.7874 0.4064)
			(end -0.7874 -0.4064)
			(stroke
				(width 0.1524)
				(type default)
			)
			(layer "F.SilkS")
		)
		(fp_line
			(start -0.7874 -0.4064)
			(end 0.7874 -0.4064)
			(stroke
				(width 0.1524)
				(type default)
			)
			(layer "F.SilkS")
		)
		(fp_line
			(start 0.67945 0.3048)
			(end 0.120396 0.3048)
			(stroke
				(width 0.1)
				(type default)
			)
			(layer "F.Fab")
		)
		(fp_line
			(start 0.67945 -0.3048)
			(end 0.67945 0.3048)
			(stroke
				(width 0.1)
				(type default)
			)
			(layer "F.Fab")
		)
		(fp_line
			(start 0.12065 -0.2794)
			(end 0.12065 -0.3048)
			(stroke
				(width 0.1)
				(type default)
			)
			(layer "F.Fab")
		)
		(fp_line
			(start 0.12065 -0.3048)
			(end 0.67945 -0.3048)
			(stroke
				(width 0.1)
				(type default)
			)
			(layer "F.Fab")
		)
		(fp_line
			(start 0.120396 0.3048)
			(end 0.120396 0.2794)
			(stroke
				(width 0.1)
				(type default)
			)
			(layer "F.Fab")
		)
		(fp_line
			(start 0.120396 0.2794)
			(end -0.12065 0.2794)
			(stroke
				(width 0.1)
				(type default)
			)
			(layer "F.Fab")
		)
		(fp_line
			(start -0.12065 0.3048)
			(end -0.67945 0.3048)
			(stroke
				(width 0.1)
				(type default)
			)
			(layer "F.Fab")
		)
		(fp_line
			(start -0.12065 0.2794)
			(end -0.12065 0.3048)
			(stroke
				(width 0.1)
				(type default)
			)
			(layer "F.Fab")
		)
		(fp_line
			(start -0.12065 -0.2794)
			(end 0.12065 -0.2794)
			(stroke
				(width 0.1)
				(type default)
			)
			(layer "F.Fab")
		)
		(fp_line
			(start -0.12065 -0.305054)
			(end -0.12065 -0.2794)
			(stroke
				(width 0.1)
				(type default)
			)
			(layer "F.Fab")
		)
		(fp_line
			(start -0.67945 0.3048)
			(end -0.67945 -0.305054)
			(stroke
				(width 0.1)
				(type default)
			)
			(layer "F.Fab")
		)
		(fp_line
			(start -0.67945 -0.305054)
			(end -0.12065 -0.305054)
			(stroke
				(width 0.1)
				(type default)
			)
			(layer "F.Fab")
		)
		(pad "1" smd circle
			(at -0.40005 0 180)
			(size 0 0)
			(layers "F.Cu" "F.Mask" "F.Paste")
			(net "BMC_RSTIND_N")
		)
		(pad "2" smd circle
			(at 0.40005 0 180)
			(size 0 0)
			(layers "F.Cu" "F.Mask" "F.Paste")
			(net "RST_SPI_FLASH_N")
		)
	)
	(footprint ""
		(layer "F.Cu")
		(at 46.9646 -76.2508)
		(property "Reference" "R181"
			(at 0 0 0)
			(layer "F.SilkS")
			(hide yes)
			(effects
				(font
					(size 1.27 1.27)
				)
			)
		)
		(property "Value" ""
			(at 0 0 0)
			(layer "F.Fab")
			(effects
				(font
					(size 1.27 1.27)
				)
			)
		)
		(duplicate_pad_numbers_are_jumpers no)
		(fp_line
			(start -0.7874 -0.4064)
			(end 0.7874 -0.4064)
			(stroke
				(width 0.1524)
				(type default)
			)
			(layer "F.SilkS")
		)
		(fp_line
			(start -0.7874 0.4064)
			(end -0.7874 -0.4064)
			(stroke
				(width 0.1524)
				(type default)
			)
			(layer "F.SilkS")
		)
		(fp_line
			(start 0.7874 -0.4064)
			(end 0.7874 0.4064)
			(stroke
				(width 0.1524)
				(type default)
			)
			(layer "F.SilkS")
		)
		(fp_line
			(start 0.7874 0.4064)
			(end -0.7874 0.4064)
			(stroke
				(width 0.1524)
				(type default)
			)
			(layer "F.SilkS")
		)
		(fp_line
			(start -0.67945 -0.305054)
			(end -0.12065 -0.305054)
			(stroke
				(width 0.1)
				(type default)
			)
			(layer "F.Fab")
		)
		(fp_line
			(start -0.67945 0.3048)
			(end -0.67945 -0.305054)
			(stroke
				(width 0.1)
				(type default)
			)
			(layer "F.Fab")
		)
		(fp_line
			(start -0.12065 -0.305054)
			(end -0.12065 -0.2794)
			(stroke
				(width 0.1)
				(type default)
			)
			(layer "F.Fab")
		)
		(fp_line
			(start -0.12065 -0.2794)
			(end 0.12065 -0.2794)
			(stroke
				(width 0.1)
				(type default)
			)
			(layer "F.Fab")
		)
		(fp_line
			(start -0.12065 0.2794)
			(end -0.12065 0.3048)
			(stroke
				(width 0.1)
				(type default)
			)
			(layer "F.Fab")
		)
		(fp_line
			(start -0.12065 0.3048)
			(end -0.67945 0.3048)
			(stroke
				(width 0.1)
				(type default)
			)
			(layer "F.Fab")
		)
		(fp_line
			(start 0.120396 0.2794)
			(end -0.12065 0.2794)
			(stroke
				(width 0.1)
				(type default)
			)
			(layer "F.Fab")
		)
		(fp_line
			(start 0.120396 0.3048)
			(end 0.120396 0.2794)
			(stroke
				(width 0.1)
				(type default)
			)
			(layer "F.Fab")
		)
		(fp_line
			(start 0.12065 -0.3048)
			(end 0.67945 -0.3048)
			(stroke
				(width 0.1)
				(type default)
			)
			(layer "F.Fab")
		)
		(fp_line
			(start 0.12065 -0.2794)
			(end 0.12065 -0.3048)
			(stroke
				(width 0.1)
				(type default)
			)
			(layer "F.Fab")
		)
		(fp_line
			(start 0.67945 -0.3048)
			(end 0.67945 0.3048)
			(stroke
				(width 0.1)
				(type default)
			)
			(layer "F.Fab")
		)
		(fp_line
			(start 0.67945 0.3048)
			(end 0.120396 0.3048)
			(stroke
				(width 0.1)
				(type default)
			)
			(layer "F.Fab")
		)
		(pad "1" smd circle
			(at -0.40005 0)
			(size 0 0)
			(layers "F.Cu" "F.Mask" "F.Paste")
			(net "P3V3_AUX")
		)
		(pad "2" smd circle
			(at 0.40005 0)
			(size 0 0)
			(layers "F.Cu" "F.Mask" "F.Paste")
			(net "FM_FLASH_LATCH_N")
		)
	)
	(footprint ""
		(layer "F.Cu")
		(at 32.131 -64.8208 90)
		(property "Reference" "C310"
			(at 0 0 90)
			(layer "F.SilkS")
			(hide yes)
			(effects
				(font
					(size 1.27 1.27)
				)
			)
		)
		(property "Value" ""
			(at 0 0 90)
			(layer "F.Fab")
			(effects
				(font
					(size 1.27 1.27)
				)
			)
		)
		(duplicate_pad_numbers_are_jumpers no)
		(fp_line
			(start 0.7874 -0.4064)
			(end 0.7874 0.4064)
			(stroke
				(width 0.1524)
				(type default)
			)
			(layer "F.SilkS")
		)
		(fp_line
			(start -0.7874 -0.4064)
			(end 0.7874 -0.4064)
			(stroke
				(width 0.1524)
				(type default)
			)
			(layer "F.SilkS")
		)
		(fp_line
			(start 0.7874 0.4064)
			(end -0.7874 0.4064)
			(stroke
				(width 0.1524)
				(type default)
			)
			(layer "F.SilkS")
		)
		(fp_line
			(start -0.7874 0.4064)
			(end -0.7874 -0.4064)
			(stroke
				(width 0.1524)
				(type default)
			)
			(layer "F.SilkS")
		)
		(fp_line
			(start -0.12065 -0.305054)
			(end -0.12065 -0.2794)
			(stroke
				(width 0.1)
				(type default)
			)
			(layer "F.Fab")
		)
		(fp_line
			(start -0.67945 -0.305054)
			(end -0.12065 -0.305054)
			(stroke
				(width 0.1)
				(type default)
			)
			(layer "F.Fab")
		)
		(fp_line
			(start 0.67945 -0.3048)
			(end 0.67945 0.3048)
			(stroke
				(width 0.1)
				(type default)
			)
			(layer "F.Fab")
		)
		(fp_line
			(start 0.12065 -0.3048)
			(end 0.67945 -0.3048)
			(stroke
				(width 0.1)
				(type default)
			)
			(layer "F.Fab")
		)
		(fp_line
			(start 0.12065 -0.2794)
			(end 0.12065 -0.3048)
			(stroke
				(width 0.1)
				(type default)
			)
			(layer "F.Fab")
		)
		(fp_line
			(start -0.12065 -0.2794)
			(end 0.12065 -0.2794)
			(stroke
				(width 0.1)
				(type default)
			)
			(layer "F.Fab")
		)
		(fp_line
			(start 0.120396 0.2794)
			(end -0.12065 0.2794)
			(stroke
				(width 0.1)
				(type default)
			)
			(layer "F.Fab")
		)
		(fp_line
			(start -0.12065 0.2794)
			(end -0.12065 0.3048)
			(stroke
				(width 0.1)
				(type default)
			)
			(layer "F.Fab")
		)
		(fp_line
			(start 0.67945 0.3048)
			(end 0.120396 0.3048)
			(stroke
				(width 0.1)
				(type default)
			)
			(layer "F.Fab")
		)
		(fp_line
			(start 0.120396 0.3048)
			(end 0.120396 0.2794)
			(stroke
				(width 0.1)
				(type default)
			)
			(layer "F.Fab")
		)
		(fp_line
			(start -0.12065 0.3048)
			(end -0.67945 0.3048)
			(stroke
				(width 0.1)
				(type default)
			)
			(layer "F.Fab")
		)
		(fp_line
			(start -0.67945 0.3048)
			(end -0.67945 -0.305054)
			(stroke
				(width 0.1)
				(type default)
			)
			(layer "F.Fab")
		)
		(pad "1" smd circle
			(at -0.40005 0 90)
			(size 0 0)
			(layers "F.Cu" "F.Mask" "F.Paste")
			(net "PWRGD_P3V3_RGM_R2")
		)
		(pad "2" smd circle
			(at 0.40005 0 90)
			(size 0 0)
			(layers "F.Cu" "F.Mask" "F.Paste")
			(net "GND")
		)
	)
	(footprint ""
		(layer "F.Cu")
		(at 4.953 -31.837122 -90)
		(property "Reference" "PC215"
			(at 0 0 270)
			(layer "F.SilkS")
			(hide yes)
			(effects
				(font
					(size 1.27 1.27)
				)
			)
		)
		(property "Value" ""
			(at 0 0 270)
			(layer "F.Fab")
			(effects
				(font
					(size 1.27 1.27)
				)
			)
		)
		(duplicate_pad_numbers_are_jumpers no)
		(fp_line
			(start -1.651 0.8382)
			(end -1.651 -0.8382)
			(stroke
				(width 0.1524)
				(type default)
			)
			(layer "F.SilkS")
		)
		(fp_line
			(start 0 0.8382)
			(end 0 -0.8382)
			(stroke
				(width 0.1524)
				(type default)
			)
			(layer "F.SilkS")
		)
		(fp_line
			(start 1.651 0.8382)
			(end -1.651 0.8382)
			(stroke
				(width 0.1524)
				(type default)
			)
			(layer "F.SilkS")
		)
		(fp_line
			(start -1.651 -0.8382)
			(end 1.651 -0.8382)
			(stroke
				(width 0.1524)
				(type default)
			)
			(layer "F.SilkS")
		)
		(fp_line
			(start 1.651 -0.8382)
			(end 1.651 0.8382)
			(stroke
				(width 0.1524)
				(type default)
			)
			(layer "F.SilkS")
		)
		(fp_line
			(start -1.55956 0.7366)
			(end -1.524 0.7366)
			(stroke
				(width 0.1)
				(type default)
			)
			(layer "F.Fab")
		)
		(fp_line
			(start -1.524 0.7366)
			(end 1.524 0.7366)
			(stroke
				(width 0.1)
				(type default)
			)
			(layer "F.Fab")
		)
		(fp_line
			(start 1.524 0.7366)
			(end 1.55956 0.7366)
			(stroke
				(width 0.1)
				(type default)
			)
			(layer "F.Fab")
		)
		(fp_line
			(start 1.55956 0.7366)
			(end 1.55956 -0.7366)
			(stroke
				(width 0.1)
				(type default)
			)
			(layer "F.Fab")
		)
		(fp_line
			(start -1.55956 -0.7366)
			(end -1.55956 0.7366)
			(stroke
				(width 0.1)
				(type default)
			)
			(layer "F.Fab")
		)
		(fp_line
			(start -1.524 -0.7366)
			(end -1.55956 -0.7366)
			(stroke
				(width 0.1)
				(type default)
			)
			(layer "F.Fab")
		)
		(fp_line
			(start 1.524 -0.7366)
			(end -1.524 -0.7366)
			(stroke
				(width 0.1)
				(type default)
			)
			(layer "F.Fab")
		)
		(fp_line
			(start 1.55956 -0.7366)
			(end 1.524 -0.7366)
			(stroke
				(width 0.1)
				(type default)
			)
			(layer "F.Fab")
		)
		(pad "1" smd rect
			(at -0.94996 0 90)
			(size 1.1176 1.3716)
			(layers "F.Cu" "F.Mask" "F.Paste")
			(net "P5V_AUX")
		)
		(pad "2" smd rect
			(at 0.94996 0 90)
			(size 1.1176 1.3716)
			(layers "F.Cu" "F.Mask" "F.Paste")
			(net "GND")
		)
	)
	(footprint ""
		(layer "F.Cu")
		(at 11.147044 -48.64989)
		(property "Reference" "PC271"
			(at 0 0 0)
			(layer "F.SilkS")
			(hide yes)
			(effects
				(font
					(size 1.27 1.27)
				)
			)
		)
		(property "Value" ""
			(at 0 0 0)
			(layer "F.Fab")
			(effects
				(font
					(size 1.27 1.27)
				)
			)
		)
		(duplicate_pad_numbers_are_jumpers no)
		(fp_line
			(start -0.7874 -0.4064)
			(end 0.7874 -0.4064)
			(stroke
				(width 0.1524)
				(type default)
			)
			(layer "F.SilkS")
		)
		(fp_line
			(start -0.7874 0.4064)
			(end -0.7874 -0.4064)
			(stroke
				(width 0.1524)
				(type default)
			)
			(layer "F.SilkS")
		)
		(fp_line
			(start 0.7874 -0.4064)
			(end 0.7874 0.4064)
			(stroke
				(width 0.1524)
				(type default)
			)
			(layer "F.SilkS")
		)
		(fp_line
			(start 0.7874 0.4064)
			(end -0.7874 0.4064)
			(stroke
				(width 0.1524)
				(type default)
			)
			(layer "F.SilkS")
		)
		(fp_line
			(start -0.67945 -0.305054)
			(end -0.12065 -0.305054)
			(stroke
				(width 0.1)
				(type default)
			)
			(layer "F.Fab")
		)
		(fp_line
			(start -0.67945 0.3048)
			(end -0.67945 -0.305054)
			(stroke
				(width 0.1)
				(type default)
			)
			(layer "F.Fab")
		)
		(fp_line
			(start -0.12065 -0.305054)
			(end -0.12065 -0.2794)
			(stroke
				(width 0.1)
				(type default)
			)
			(layer "F.Fab")
		)
		(fp_line
			(start -0.12065 -0.2794)
			(end 0.12065 -0.2794)
			(stroke
				(width 0.1)
				(type default)
			)
			(layer "F.Fab")
		)
		(fp_line
			(start -0.12065 0.2794)
			(end -0.12065 0.3048)
			(stroke
				(width 0.1)
				(type default)
			)
			(layer "F.Fab")
		)
		(fp_line
			(start -0.12065 0.3048)
			(end -0.67945 0.3048)
			(stroke
				(width 0.1)
				(type default)
			)
			(layer "F.Fab")
		)
		(fp_line
			(start 0.120396 0.2794)
			(end -0.12065 0.2794)
			(stroke
				(width 0.1)
				(type default)
			)
			(layer "F.Fab")
		)
		(fp_line
			(start 0.120396 0.3048)
			(end 0.120396 0.2794)
			(stroke
				(width 0.1)
				(type default)
			)
			(layer "F.Fab")
		)
		(fp_line
			(start 0.12065 -0.3048)
			(end 0.67945 -0.3048)
			(stroke
				(width 0.1)
				(type default)
			)
			(layer "F.Fab")
		)
		(fp_line
			(start 0.12065 -0.2794)
			(end 0.12065 -0.3048)
			(stroke
				(width 0.1)
				(type default)
			)
			(layer "F.Fab")
		)
		(fp_line
			(start 0.67945 -0.3048)
			(end 0.67945 0.3048)
			(stroke
				(width 0.1)
				(type default)
			)
			(layer "F.Fab")
		)
		(fp_line
			(start 0.67945 0.3048)
			(end 0.120396 0.3048)
			(stroke
				(width 0.1)
				(type default)
			)
			(layer "F.Fab")
		)
		(pad "1" smd circle
			(at -0.40005 0)
			(size 0 0)
			(layers "F.Cu" "F.Mask" "F.Paste")
			(net "P5V_AUX_REF")
		)
		(pad "2" smd circle
			(at 0.40005 0)
			(size 0 0)
			(layers "F.Cu" "F.Mask" "F.Paste")
			(net "GND")
		)
	)
	(footprint ""
		(layer "F.Cu")
		(at 28.2194 -70.5358 90)
		(property "Reference" "R867"
			(at 0 0 90)
			(layer "F.SilkS")
			(hide yes)
			(effects
				(font
					(size 1.27 1.27)
				)
			)
		)
		(property "Value" ""
			(at 0 0 90)
			(layer "F.Fab")
			(effects
				(font
					(size 1.27 1.27)
				)
			)
		)
		(duplicate_pad_numbers_are_jumpers no)
		(fp_line
			(start 0.7874 -0.4064)
			(end 0.7874 0.4064)
			(stroke
				(width 0.1524)
				(type default)
			)
			(layer "F.SilkS")
		)
		(fp_line
			(start -0.7874 -0.4064)
			(end 0.7874 -0.4064)
			(stroke
				(width 0.1524)
				(type default)
			)
			(layer "F.SilkS")
		)
		(fp_line
			(start 0.7874 0.4064)
			(end -0.7874 0.4064)
			(stroke
				(width 0.1524)
				(type default)
			)
			(layer "F.SilkS")
		)
		(fp_line
			(start -0.7874 0.4064)
			(end -0.7874 -0.4064)
			(stroke
				(width 0.1524)
				(type default)
			)
			(layer "F.SilkS")
		)
		(fp_line
			(start -0.12065 -0.305054)
			(end -0.12065 -0.2794)
			(stroke
				(width 0.1)
				(type default)
			)
			(layer "F.Fab")
		)
		(fp_line
			(start -0.67945 -0.305054)
			(end -0.12065 -0.305054)
			(stroke
				(width 0.1)
				(type default)
			)
			(layer "F.Fab")
		)
		(fp_line
			(start 0.67945 -0.3048)
			(end 0.67945 0.3048)
			(stroke
				(width 0.1)
				(type default)
			)
			(layer "F.Fab")
		)
		(fp_line
			(start 0.12065 -0.3048)
			(end 0.67945 -0.3048)
			(stroke
				(width 0.1)
				(type default)
			)
			(layer "F.Fab")
		)
		(fp_line
			(start 0.12065 -0.2794)
			(end 0.12065 -0.3048)
			(stroke
				(width 0.1)
				(type default)
			)
			(layer "F.Fab")
		)
		(fp_line
			(start -0.12065 -0.2794)
			(end 0.12065 -0.2794)
			(stroke
				(width 0.1)
				(type default)
			)
			(layer "F.Fab")
		)
		(fp_line
			(start 0.120396 0.2794)
			(end -0.12065 0.2794)
			(stroke
				(width 0.1)
				(type default)
			)
			(layer "F.Fab")
		)
		(fp_line
			(start -0.12065 0.2794)
			(end -0.12065 0.3048)
			(stroke
				(width 0.1)
				(type default)
			)
			(layer "F.Fab")
		)
		(fp_line
			(start 0.67945 0.3048)
			(end 0.120396 0.3048)
			(stroke
				(width 0.1)
				(type default)
			)
			(layer "F.Fab")
		)
		(fp_line
			(start 0.120396 0.3048)
			(end 0.120396 0.2794)
			(stroke
				(width 0.1)
				(type default)
			)
			(layer "F.Fab")
		)
		(fp_line
			(start -0.12065 0.3048)
			(end -0.67945 0.3048)
			(stroke
				(width 0.1)
				(type default)
			)
			(layer "F.Fab")
		)
		(fp_line
			(start -0.67945 0.3048)
			(end -0.67945 -0.305054)
			(stroke
				(width 0.1)
				(type default)
			)
			(layer "F.Fab")
		)
		(pad "1" smd circle
			(at -0.40005 0 90)
			(size 0 0)
			(layers "F.Cu" "F.Mask" "F.Paste")
			(net "P3V3_AUX")
		)
		(pad "2" smd circle
			(at 0.40005 0 90)
			(size 0 0)
			(layers "F.Cu" "F.Mask" "F.Paste")
			(net "EMMC_WP")
		)
	)
	(footprint ""
		(layer "F.Cu")
		(at 28.575 -10.287 90)
		(property "Reference" "C324"
			(at 0 0 90)
			(layer "F.SilkS")
			(hide yes)
			(effects
				(font
					(size 1.27 1.27)
				)
			)
		)
		(property "Value" ""
			(at 0 0 90)
			(layer "F.Fab")
			(effects
				(font
					(size 1.27 1.27)
				)
			)
		)
		(duplicate_pad_numbers_are_jumpers no)
		(fp_line
			(start 0.7874 -0.4064)
			(end 0.7874 0.4064)
			(stroke
				(width 0.1524)
				(type default)
			)
			(layer "F.SilkS")
		)
		(fp_line
			(start -0.7874 -0.4064)
			(end 0.7874 -0.4064)
			(stroke
				(width 0.1524)
				(type default)
			)
			(layer "F.SilkS")
		)
		(fp_line
			(start 0.7874 0.4064)
			(end -0.7874 0.4064)
			(stroke
				(width 0.1524)
				(type default)
			)
			(layer "F.SilkS")
		)
		(fp_line
			(start -0.7874 0.4064)
			(end -0.7874 -0.4064)
			(stroke
				(width 0.1524)
				(type default)
			)
			(layer "F.SilkS")
		)
		(fp_line
			(start -0.12065 -0.305054)
			(end -0.12065 -0.2794)
			(stroke
				(width 0.1)
				(type default)
			)
			(layer "F.Fab")
		)
		(fp_line
			(start -0.67945 -0.305054)
			(end -0.12065 -0.305054)
			(stroke
				(width 0.1)
				(type default)
			)
			(layer "F.Fab")
		)
		(fp_line
			(start 0.67945 -0.3048)
			(end 0.67945 0.3048)
			(stroke
				(width 0.1)
				(type default)
			)
			(layer "F.Fab")
		)
		(fp_line
			(start 0.12065 -0.3048)
			(end 0.67945 -0.3048)
			(stroke
				(width 0.1)
				(type default)
			)
			(layer "F.Fab")
		)
		(fp_line
			(start 0.12065 -0.2794)
			(end 0.12065 -0.3048)
			(stroke
				(width 0.1)
				(type default)
			)
			(layer "F.Fab")
		)
		(fp_line
			(start -0.12065 -0.2794)
			(end 0.12065 -0.2794)
			(stroke
				(width 0.1)
				(type default)
			)
			(layer "F.Fab")
		)
		(fp_line
			(start 0.120396 0.2794)
			(end -0.12065 0.2794)
			(stroke
				(width 0.1)
				(type default)
			)
			(layer "F.Fab")
		)
		(fp_line
			(start -0.12065 0.2794)
			(end -0.12065 0.3048)
			(stroke
				(width 0.1)
				(type default)
			)
			(layer "F.Fab")
		)
		(fp_line
			(start 0.67945 0.3048)
			(end 0.120396 0.3048)
			(stroke
				(width 0.1)
				(type default)
			)
			(layer "F.Fab")
		)
		(fp_line
			(start 0.120396 0.3048)
			(end 0.120396 0.2794)
			(stroke
				(width 0.1)
				(type default)
			)
			(layer "F.Fab")
		)
		(fp_line
			(start -0.12065 0.3048)
			(end -0.67945 0.3048)
			(stroke
				(width 0.1)
				(type default)
			)
			(layer "F.Fab")
		)
		(fp_line
			(start -0.67945 0.3048)
			(end -0.67945 -0.305054)
			(stroke
				(width 0.1)
				(type default)
			)
			(layer "F.Fab")
		)
		(pad "1" smd circle
			(at -0.40005 0 90)
			(size 0 0)
			(layers "F.Cu" "F.Mask" "F.Paste")
			(net "HDD_LED_BUF_R")
		)
		(pad "2" smd circle
			(at 0.40005 0 90)
			(size 0 0)
			(layers "F.Cu" "F.Mask" "F.Paste")
			(net "GND")
		)
	)
	(footprint ""
		(layer "F.Cu")
		(at 81.744058 -72.680576 -90)
		(property "Reference" "PU41"
			(at -3.61823 5.860034 0)
			(unlocked yes)
			(layer "F.SilkS")
			(effects
				(font
					(size 0.7874 0.5842)
					(thickness 0.1524)
				)
				(justify left)
			)
		)
		(property "Value" ""
			(at 0 0 270)
			(layer "F.Fab")
			(effects
				(font
					(size 1.27 1.27)
				)
			)
		)
		(duplicate_pad_numbers_are_jumpers no)
		(fp_line
			(start -1.050036 1.549908)
			(end -1.016 1.549908)
			(stroke
				(width 0.1524)
				(type default)
			)
			(layer "F.SilkS")
		)
		(fp_line
			(start 1.016 1.549908)
			(end 1.050036 1.549908)
			(stroke
				(width 0.1524)
				(type default)
			)
			(layer "F.SilkS")
		)
		(fp_line
			(start 1.050036 1.549908)
			(end 1.050036 0.762)
			(stroke
				(width 0.1524)
				(type default)
			)
			(layer "F.SilkS")
		)
		(fp_line
			(start -1.050036 0.762)
			(end -1.050036 1.549908)
			(stroke
				(width 0.1524)
				(type default)
			)
			(layer "F.SilkS")
		)
		(fp_line
			(start -1.050036 -0.2286)
			(end -1.050036 0.2286)
			(stroke
				(width 0.1524)
				(type default)
			)
			(layer "F.SilkS")
		)
		(fp_line
			(start 1.050036 -0.762)
			(end 1.050036 -1.549908)
			(stroke
				(width 0.1524)
				(type default)
			)
			(layer "F.SilkS")
		)
		(fp_line
			(start -1.050036 -1.549908)
			(end -1.050036 -0.762)
			(stroke
				(width 0.1524)
				(type default)
			)
			(layer "F.SilkS")
		)
		(fp_line
			(start -1.016 -1.549908)
			(end -1.050036 -1.549908)
			(stroke
				(width 0.1524)
				(type default)
			)
			(layer "F.SilkS")
		)
		(fp_line
			(start 1.050036 -1.549908)
			(end 1.016 -1.549908)
			(stroke
				(width 0.1524)
				(type default)
			)
			(layer "F.SilkS")
		)
		(fp_poly
			(pts
				(xy -1.851914 -0.720344) (xy -1.411224 -0.499872) (xy -1.851914 -0.279654)
			)
			(stroke
				(width 0)
				(type default)
			)
			(fill yes)
			(layer "F.SilkS")
		)
		(fp_line
			(start -1.050036 1.549908)
			(end 1.050036 1.549908)
			(stroke
				(width 0.1)
				(type default)
			)
			(layer "F.Fab")
		)
		(fp_line
			(start 1.050036 1.549908)
			(end 1.050036 -1.549908)
			(stroke
				(width 0.1)
				(type default)
			)
			(layer "F.Fab")
		)
		(fp_line
			(start -1.050036 -1.549908)
			(end -1.050036 1.549908)
			(stroke
				(width 0.1)
				(type default)
			)
			(layer "F.Fab")
		)
		(fp_line
			(start 1.050036 -1.549908)
			(end -1.050036 -1.549908)
			(stroke
				(width 0.1)
				(type default)
			)
			(layer "F.Fab")
		)
		(fp_poly
			(pts
				(xy -1.851914 -0.720344) (xy -1.411224 -0.499872) (xy -1.851914 -0.279654)
			)
			(stroke
				(width 0)
				(type default)
			)
			(fill yes)
			(layer "F.Fab")
		)
		(pad "1" smd rect
			(at -0.54991 -0.499872)
			(size 0.254 1.4986)
			(layers "F.Cu" "F.Mask" "F.Paste")
			(net "SW_P1V2_AUX_FLT")
		)
		(pad "2" smd rect
			(at -0.54991 0.499872)
			(size 0.254 1.4986)
			(layers "F.Cu" "F.Mask" "F.Paste")
			(net "GND")
		)
		(pad "3" smd rect
			(at -0.750062 1.450086 270)
			(size 0.254 0.7112)
			(layers "F.Cu" "F.Mask" "F.Paste")
			(net "GND")
		)
		(pad "4" smd rect
			(at -0.249936 1.450086 270)
			(size 0.254 0.7112)
			(layers "F.Cu" "F.Mask" "F.Paste")
			(net "GND")
		)
		(pad "5" smd rect
			(at 0.249936 1.450086 270)
			(size 0.254 0.7112)
			(layers "F.Cu" "F.Mask" "F.Paste")
			(net "EN_P1V2_AUX_R")
		)
		(pad "6" smd rect
			(at 0.750062 1.450086 270)
			(size 0.254 0.7112)
			(layers "F.Cu" "F.Mask" "F.Paste")
			(net "P1V2_AUX_VCC")
		)
		(pad "7" smd rect
			(at 0.94996 0.499872)
			(size 0.254 0.7112)
			(layers "F.Cu" "F.Mask" "F.Paste")
			(net "P1V2_AUX_MODE")
		)
		(pad "8" smd rect
			(at 0.54991 0)
			(size 0.254 1.4986)
			(layers "F.Cu" "F.Mask" "F.Paste")
			(net "SW_P1V2_AUX_SW")
		)
		(pad "9" smd rect
			(at 0.94996 -0.499872)
			(size 0.254 0.7112)
			(layers "F.Cu" "F.Mask" "F.Paste")
			(net "SW_P1V2_AUX_BST")
		)
		(pad "10" smd rect
			(at 0.750062 -1.450086 270)
			(size 0.254 0.7112)
			(layers "F.Cu" "F.Mask" "F.Paste")
			(net "P1V2_AUX_VCC")
		)
		(pad "11" smd rect
			(at 0.249936 -1.450086 270)
			(size 0.254 0.7112)
			(layers "F.Cu" "F.Mask" "F.Paste")
			(net "GND")
		)
		(pad "12" smd rect
			(at -0.249936 -1.450086 270)
			(size 0.254 0.7112)
			(layers "F.Cu" "F.Mask" "F.Paste")
			(net "P1V2_AUX")
		)
		(pad "13" smd rect
			(at -0.750062 -1.450086 270)
			(size 0.254 0.7112)
			(layers "F.Cu" "F.Mask" "F.Paste")
			(net "PWRGD_P1V2_AUX_R")
		)
	)
	(footprint ""
		(layer "F.Cu")
		(at 75.032108 -11.061954 90)
		(property "Reference" "D10"
			(at -1.029716 1.187704 90)
			(unlocked yes)
			(layer "F.SilkS")
			(effects
				(font
					(size 0.7874 0.5842)
					(thickness 0.1524)
				)
				(justify left)
			)
		)
		(property "Value" ""
			(at 0 0 90)
			(layer "F.Fab")
			(effects
				(font
					(size 1.27 1.27)
				)
			)
		)
		(duplicate_pad_numbers_are_jumpers no)
		(fp_line
			(start 0.94488 -0.450088)
			(end -0.854964 -0.450088)
			(stroke
				(width 0.1524)
				(type default)
			)
			(layer "F.SilkS")
		)
		(fp_line
			(start -0.854964 -0.450088)
			(end -0.854964 0.450088)
			(stroke
				(width 0.1524)
				(type default)
			)
			(layer "F.SilkS")
		)
		(fp_line
			(start 0.870458 -0.2794)
			(end 0.845058 0.4064)
			(stroke
				(width 0.1524)
				(type default)
			)
			(layer "F.SilkS")
		)
		(fp_line
			(start 0.845058 0.4064)
			(end 0.845058 -0.381)
			(stroke
				(width 0.1524)
				(type default)
			)
			(layer "F.SilkS")
		)
		(fp_line
			(start 0.94488 0.450088)
			(end 0.94488 -0.450088)
			(stroke
				(width 0.1524)
				(type default)
			)
			(layer "F.SilkS")
		)
		(fp_line
			(start -0.854964 0.450088)
			(end 0.925068 0.450088)
			(stroke
				(width 0.1524)
				(type default)
			)
			(layer "F.SilkS")
		)
		(fp_line
			(start 0.54991 -0.350012)
			(end -0.54991 -0.350012)
			(stroke
				(width 0.1)
				(type default)
			)
			(layer "F.Fab")
		)
		(fp_line
			(start -0.54991 -0.350012)
			(end -0.54991 0.350012)
			(stroke
				(width 0.1)
				(type default)
			)
			(layer "F.Fab")
		)
		(fp_line
			(start 0.54991 0.350012)
			(end 0.54991 -0.350012)
			(stroke
				(width 0.1)
				(type default)
			)
			(layer "F.Fab")
		)
		(fp_line
			(start -0.54991 0.350012)
			(end 0.54991 0.350012)
			(stroke
				(width 0.1)
				(type default)
			)
			(layer "F.Fab")
		)
		(fp_text user "+"
			(at -0.808228 0.239014 270)
			(unlocked yes)
			(layer "F.SilkS")
			(effects
				(font
					(size 1.905 1.4224)
					(thickness 0.1524)
				)
				(justify left)
			)
		)
		(fp_text user "-"
			(at 2.196846 0.577342 270)
			(unlocked yes)
			(layer "F.SilkS")
			(effects
				(font
					(size 1.905 1.4224)
					(thickness 0.1524)
				)
				(justify left)
			)
		)
		(fp_text user "-"
			(at 2.48539 0.239014 270)
			(unlocked yes)
			(layer "F.Fab")
			(effects
				(font
					(size 1.905 1.4224)
					(thickness 0.1524)
				)
				(justify left)
			)
		)
		(fp_text user "+"
			(at -0.808228 0.239014 270)
			(unlocked yes)
			(layer "F.Fab")
			(effects
				(font
					(size 1.905 1.4224)
					(thickness 0.1524)
				)
				(justify left)
			)
		)
		(pad "A" smd rect
			(at -0.424942 0 90)
			(size 0.5588 0.6096)
			(layers "F.Cu" "F.Mask" "F.Paste")
			(net "REAR_AC_PWR_BTN")
		)
		(pad "C" smd rect
			(at 0.424942 0 270)
			(size 0.5588 0.6096)
			(layers "F.Cu" "F.Mask" "F.Paste")
			(net "GND")
		)
	)
	(footprint ""
		(layer "F.Cu")
		(at 39.37 -73.914 90)
		(property "Reference" "C26"
			(at 0 0 90)
			(layer "F.SilkS")
			(hide yes)
			(effects
				(font
					(size 1.27 1.27)
				)
			)
		)
		(property "Value" ""
			(at 0 0 90)
			(layer "F.Fab")
			(effects
				(font
					(size 1.27 1.27)
				)
			)
		)
		(duplicate_pad_numbers_are_jumpers no)
		(fp_line
			(start 0.7874 -0.4064)
			(end 0.7874 0.141986)
			(stroke
				(width 0.1524)
				(type default)
			)
			(layer "F.SilkS")
		)
		(fp_line
			(start -0.7874 -0.4064)
			(end 0.7874 -0.4064)
			(stroke
				(width 0.1524)
				(type default)
			)
			(layer "F.SilkS")
		)
		(fp_line
			(start -0.7874 0.070866)
			(end -0.7874 -0.4064)
			(stroke
				(width 0.1524)
				(type default)
			)
			(layer "F.SilkS")
		)
		(fp_line
			(start 0.413004 0.4064)
			(end -0.440436 0.4064)
			(stroke
				(width 0.1524)
				(type default)
			)
			(layer "F.SilkS")
		)
		(fp_line
			(start -0.12065 -0.305054)
			(end -0.12065 -0.2794)
			(stroke
				(width 0.1)
				(type default)
			)
			(layer "F.Fab")
		)
		(fp_line
			(start -0.67945 -0.305054)
			(end -0.12065 -0.305054)
			(stroke
				(width 0.1)
				(type default)
			)
			(layer "F.Fab")
		)
		(fp_line
			(start 0.67945 -0.3048)
			(end 0.67945 0.3048)
			(stroke
				(width 0.1)
				(type default)
			)
			(layer "F.Fab")
		)
		(fp_line
			(start 0.12065 -0.3048)
			(end 0.67945 -0.3048)
			(stroke
				(width 0.1)
				(type default)
			)
			(layer "F.Fab")
		)
		(fp_line
			(start 0.12065 -0.2794)
			(end 0.12065 -0.3048)
			(stroke
				(width 0.1)
				(type default)
			)
			(layer "F.Fab")
		)
		(fp_line
			(start -0.12065 -0.2794)
			(end 0.12065 -0.2794)
			(stroke
				(width 0.1)
				(type default)
			)
			(layer "F.Fab")
		)
		(fp_line
			(start 0.120396 0.2794)
			(end -0.12065 0.2794)
			(stroke
				(width 0.1)
				(type default)
			)
			(layer "F.Fab")
		)
		(fp_line
			(start -0.12065 0.2794)
			(end -0.12065 0.3048)
			(stroke
				(width 0.1)
				(type default)
			)
			(layer "F.Fab")
		)
		(fp_line
			(start 0.67945 0.3048)
			(end 0.120396 0.3048)
			(stroke
				(width 0.1)
				(type default)
			)
			(layer "F.Fab")
		)
		(fp_line
			(start 0.120396 0.3048)
			(end 0.120396 0.2794)
			(stroke
				(width 0.1)
				(type default)
			)
			(layer "F.Fab")
		)
		(fp_line
			(start -0.12065 0.3048)
			(end -0.67945 0.3048)
			(stroke
				(width 0.1)
				(type default)
			)
			(layer "F.Fab")
		)
		(fp_line
			(start -0.67945 0.3048)
			(end -0.67945 -0.305054)
			(stroke
				(width 0.1)
				(type default)
			)
			(layer "F.Fab")
		)
		(pad "1" smd circle
			(at -0.40005 0 90)
			(size 0 0)
			(layers "F.Cu" "F.Mask" "F.Paste")
			(net "P3V3_AUX")
		)
		(pad "2" smd circle
			(at 0.40005 0 90)
			(size 0 0)
			(layers "F.Cu" "F.Mask" "F.Paste")
			(net "GND")
		)
	)
	(footprint ""
		(layer "F.Cu")
		(at 74.01052 -27.738832 90)
		(property "Reference" "D3"
			(at -1.830832 8.94715 90)
			(unlocked yes)
			(layer "F.SilkS")
			(effects
				(font
					(size 0.7874 0.5842)
					(thickness 0.1524)
				)
				(justify left)
			)
		)
		(property "Value" ""
			(at 0 0 90)
			(layer "F.Fab")
			(effects
				(font
					(size 1.27 1.27)
				)
			)
		)
		(duplicate_pad_numbers_are_jumpers no)
		(fp_line
			(start 1.778 -0.5588)
			(end 1.3208 -0.5588)
			(stroke
				(width 0.1524)
				(type default)
			)
			(layer "F.SilkS")
		)
		(fp_line
			(start 1.778 -0.5588)
			(end 1.778 0.5588)
			(stroke
				(width 0.1524)
				(type default)
			)
			(layer "F.SilkS")
		)
		(fp_line
			(start 1.4732 -0.5588)
			(end 1.4732 0.5588)
			(stroke
				(width 0.1524)
				(type default)
			)
			(layer "F.SilkS")
		)
		(fp_line
			(start 1.3208 -0.5588)
			(end 1.3208 0.5588)
			(stroke
				(width 0.1524)
				(type default)
			)
			(layer "F.SilkS")
		)
		(fp_line
			(start -1.3208 -0.5588)
			(end 1.3208 -0.5588)
			(stroke
				(width 0.1524)
				(type default)
			)
			(layer "F.SilkS")
		)
		(fp_line
			(start 1.778 0.5588)
			(end 1.3208 0.5588)
			(stroke
				(width 0.1524)
				(type default)
			)
			(layer "F.SilkS")
		)
		(fp_line
			(start 1.6256 0.5588)
			(end 1.6256 -0.5588)
			(stroke
				(width 0.1524)
				(type default)
			)
			(layer "F.SilkS")
		)
		(fp_line
			(start 1.3208 0.5588)
			(end -1.3208 0.5588)
			(stroke
				(width 0.1524)
				(type default)
			)
			(layer "F.SilkS")
		)
		(fp_line
			(start -1.3208 0.5588)
			(end -1.3208 -0.5588)
			(stroke
				(width 0.1524)
				(type default)
			)
			(layer "F.SilkS")
		)
		(fp_line
			(start 1.236726 -0.508)
			(end 1.1684 -0.508)
			(stroke
				(width 0.1)
				(type default)
			)
			(layer "F.Fab")
		)
		(fp_line
			(start 1.1684 -0.508)
			(end -1.1684 -0.508)
			(stroke
				(width 0.1)
				(type default)
			)
			(layer "F.Fab")
		)
		(fp_line
			(start -1.1684 -0.508)
			(end -1.235964 -0.508)
			(stroke
				(width 0.1)
				(type default)
			)
			(layer "F.Fab")
		)
		(fp_line
			(start -1.235964 -0.508)
			(end -1.235964 0.508)
			(stroke
				(width 0.1)
				(type default)
			)
			(layer "F.Fab")
		)
		(fp_line
			(start 1.236726 0.508)
			(end 1.236726 -0.508)
			(stroke
				(width 0.1)
				(type default)
			)
			(layer "F.Fab")
		)
		(fp_line
			(start 1.1684 0.508)
			(end 1.236726 0.508)
			(stroke
				(width 0.1)
				(type default)
			)
			(layer "F.Fab")
		)
		(fp_line
			(start -1.1684 0.508)
			(end 1.1684 0.508)
			(stroke
				(width 0.1)
				(type default)
			)
			(layer "F.Fab")
		)
		(fp_line
			(start -1.235964 0.508)
			(end -1.1684 0.508)
			(stroke
				(width 0.1)
				(type default)
			)
			(layer "F.Fab")
		)
		(fp_text user "+"
			(at -1.526032 -1.43637 90)
			(unlocked yes)
			(layer "F.SilkS")
			(effects
				(font
					(size 1.905 1.4224)
					(thickness 0.1524)
				)
				(justify left)
			)
		)
		(fp_text user "-"
			(at 0.328168 -1.10617 90)
			(unlocked yes)
			(layer "F.SilkS")
			(effects
				(font
					(size 1.905 1.4224)
					(thickness 0.1524)
				)
				(justify left)
			)
		)
		(fp_text user "-"
			(at 1.524 -0.24765 90)
			(unlocked yes)
			(layer "F.Fab")
			(effects
				(font
					(size 1.905 1.4224)
					(thickness 0.1524)
				)
				(justify left)
			)
		)
		(fp_text user "+"
			(at -2.5654 -0.24765 90)
			(unlocked yes)
			(layer "F.Fab")
			(effects
				(font
					(size 1.905 1.4224)
					(thickness 0.1524)
				)
				(justify left)
			)
		)
		(pad "A" smd rect
			(at -0.750062 0 90)
			(size 0.8128 0.8128)
			(layers "F.Cu" "F.Mask" "F.Paste")
			(net "LED_POSTCODE_3_R")
		)
		(pad "C" smd rect
			(at 0.750062 0 90)
			(size 0.8128 0.8128)
			(layers "F.Cu" "F.Mask" "F.Paste")
			(net "GND")
		)
	)
	(footprint ""
		(layer "F.Cu")
		(at 39.8272 -78.6638 180)
		(property "Reference" "R558"
			(at 0 0 180)
			(layer "F.SilkS")
			(hide yes)
			(effects
				(font
					(size 1.27 1.27)
				)
			)
		)
		(property "Value" ""
			(at 0 0 180)
			(layer "F.Fab")
			(effects
				(font
					(size 1.27 1.27)
				)
			)
		)
		(duplicate_pad_numbers_are_jumpers no)
		(fp_line
			(start 0.7874 0.4064)
			(end -0.7874 0.4064)
			(stroke
				(width 0.1524)
				(type default)
			)
			(layer "F.SilkS")
		)
		(fp_line
			(start 0.7874 -0.4064)
			(end 0.7874 0.4064)
			(stroke
				(width 0.1524)
				(type default)
			)
			(layer "F.SilkS")
		)
		(fp_line
			(start -0.7874 0.4064)
			(end -0.7874 -0.4064)
			(stroke
				(width 0.1524)
				(type default)
			)
			(layer "F.SilkS")
		)
		(fp_line
			(start -0.7874 -0.4064)
			(end 0.7874 -0.4064)
			(stroke
				(width 0.1524)
				(type default)
			)
			(layer "F.SilkS")
		)
		(fp_line
			(start 0.67945 0.3048)
			(end 0.120396 0.3048)
			(stroke
				(width 0.1)
				(type default)
			)
			(layer "F.Fab")
		)
		(fp_line
			(start 0.67945 -0.3048)
			(end 0.67945 0.3048)
			(stroke
				(width 0.1)
				(type default)
			)
			(layer "F.Fab")
		)
		(fp_line
			(start 0.12065 -0.2794)
			(end 0.12065 -0.3048)
			(stroke
				(width 0.1)
				(type default)
			)
			(layer "F.Fab")
		)
		(fp_line
			(start 0.12065 -0.3048)
			(end 0.67945 -0.3048)
			(stroke
				(width 0.1)
				(type default)
			)
			(layer "F.Fab")
		)
		(fp_line
			(start 0.120396 0.3048)
			(end 0.120396 0.2794)
			(stroke
				(width 0.1)
				(type default)
			)
			(layer "F.Fab")
		)
		(fp_line
			(start 0.120396 0.2794)
			(end -0.12065 0.2794)
			(stroke
				(width 0.1)
				(type default)
			)
			(layer "F.Fab")
		)
		(fp_line
			(start -0.12065 0.3048)
			(end -0.67945 0.3048)
			(stroke
				(width 0.1)
				(type default)
			)
			(layer "F.Fab")
		)
		(fp_line
			(start -0.12065 0.2794)
			(end -0.12065 0.3048)
			(stroke
				(width 0.1)
				(type default)
			)
			(layer "F.Fab")
		)
		(fp_line
			(start -0.12065 -0.2794)
			(end 0.12065 -0.2794)
			(stroke
				(width 0.1)
				(type default)
			)
			(layer "F.Fab")
		)
		(fp_line
			(start -0.12065 -0.305054)
			(end -0.12065 -0.2794)
			(stroke
				(width 0.1)
				(type default)
			)
			(layer "F.Fab")
		)
		(fp_line
			(start -0.67945 0.3048)
			(end -0.67945 -0.305054)
			(stroke
				(width 0.1)
				(type default)
			)
			(layer "F.Fab")
		)
		(fp_line
			(start -0.67945 -0.305054)
			(end -0.12065 -0.305054)
			(stroke
				(width 0.1)
				(type default)
			)
			(layer "F.Fab")
		)
		(pad "1" smd circle
			(at -0.40005 0 180)
			(size 0 0)
			(layers "F.Cu" "F.Mask" "F.Paste")
			(net "P3V3_AUX")
		)
		(pad "2" smd circle
			(at 0.40005 0 180)
			(size 0 0)
			(layers "F.Cu" "F.Mask" "F.Paste")
			(net "SPI_BMC_CS1_FLASH_R_N")
		)
	)
	(footprint ""
		(layer "F.Cu")
		(at 85.29955 -40.617394 180)
		(property "Reference" "R327"
			(at 0 0 180)
			(layer "F.SilkS")
			(hide yes)
			(effects
				(font
					(size 1.27 1.27)
				)
			)
		)
		(property "Value" ""
			(at 0 0 180)
			(layer "F.Fab")
			(effects
				(font
					(size 1.27 1.27)
				)
			)
		)
		(duplicate_pad_numbers_are_jumpers no)
		(fp_line
			(start 0.7874 0.4064)
			(end -0.7874 0.4064)
			(stroke
				(width 0.1524)
				(type default)
			)
			(layer "F.SilkS")
		)
		(fp_line
			(start 0.7874 -0.4064)
			(end 0.7874 0.4064)
			(stroke
				(width 0.1524)
				(type default)
			)
			(layer "F.SilkS")
		)
		(fp_line
			(start -0.7874 0.4064)
			(end -0.7874 -0.4064)
			(stroke
				(width 0.1524)
				(type default)
			)
			(layer "F.SilkS")
		)
		(fp_line
			(start -0.7874 -0.4064)
			(end 0.7874 -0.4064)
			(stroke
				(width 0.1524)
				(type default)
			)
			(layer "F.SilkS")
		)
		(fp_line
			(start 0.67945 0.3048)
			(end 0.120396 0.3048)
			(stroke
				(width 0.1)
				(type default)
			)
			(layer "F.Fab")
		)
		(fp_line
			(start 0.67945 -0.3048)
			(end 0.67945 0.3048)
			(stroke
				(width 0.1)
				(type default)
			)
			(layer "F.Fab")
		)
		(fp_line
			(start 0.12065 -0.2794)
			(end 0.12065 -0.3048)
			(stroke
				(width 0.1)
				(type default)
			)
			(layer "F.Fab")
		)
		(fp_line
			(start 0.12065 -0.3048)
			(end 0.67945 -0.3048)
			(stroke
				(width 0.1)
				(type default)
			)
			(layer "F.Fab")
		)
		(fp_line
			(start 0.120396 0.3048)
			(end 0.120396 0.2794)
			(stroke
				(width 0.1)
				(type default)
			)
			(layer "F.Fab")
		)
		(fp_line
			(start 0.120396 0.2794)
			(end -0.12065 0.2794)
			(stroke
				(width 0.1)
				(type default)
			)
			(layer "F.Fab")
		)
		(fp_line
			(start -0.12065 0.3048)
			(end -0.67945 0.3048)
			(stroke
				(width 0.1)
				(type default)
			)
			(layer "F.Fab")
		)
		(fp_line
			(start -0.12065 0.2794)
			(end -0.12065 0.3048)
			(stroke
				(width 0.1)
				(type default)
			)
			(layer "F.Fab")
		)
		(fp_line
			(start -0.12065 -0.2794)
			(end 0.12065 -0.2794)
			(stroke
				(width 0.1)
				(type default)
			)
			(layer "F.Fab")
		)
		(fp_line
			(start -0.12065 -0.305054)
			(end -0.12065 -0.2794)
			(stroke
				(width 0.1)
				(type default)
			)
			(layer "F.Fab")
		)
		(fp_line
			(start -0.67945 0.3048)
			(end -0.67945 -0.305054)
			(stroke
				(width 0.1)
				(type default)
			)
			(layer "F.Fab")
		)
		(fp_line
			(start -0.67945 -0.305054)
			(end -0.12065 -0.305054)
			(stroke
				(width 0.1)
				(type default)
			)
			(layer "F.Fab")
		)
		(pad "1" smd circle
			(at -0.40005 0 180)
			(size 0 0)
			(layers "F.Cu" "F.Mask" "F.Paste")
			(net "GND")
		)
		(pad "2" smd circle
			(at 0.40005 0 180)
			(size 0 0)
			(layers "F.Cu" "F.Mask" "F.Paste")
			(net "M_BMC_DDR4_MA<1>")
		)
	)
	(footprint ""
		(layer "F.Cu")
		(at 40.513 -89.027 180)
		(property "Reference" "R496"
			(at 0 0 180)
			(layer "F.SilkS")
			(hide yes)
			(effects
				(font
					(size 1.27 1.27)
				)
			)
		)
		(property "Value" ""
			(at 0 0 180)
			(layer "F.Fab")
			(effects
				(font
					(size 1.27 1.27)
				)
			)
		)
		(duplicate_pad_numbers_are_jumpers no)
		(fp_line
			(start 0.7874 0.4064)
			(end -0.7874 0.4064)
			(stroke
				(width 0.1524)
				(type default)
			)
			(layer "F.SilkS")
		)
		(fp_line
			(start 0.7874 -0.4064)
			(end 0.7874 0.4064)
			(stroke
				(width 0.1524)
				(type default)
			)
			(layer "F.SilkS")
		)
		(fp_line
			(start -0.7874 0.4064)
			(end -0.7874 -0.4064)
			(stroke
				(width 0.1524)
				(type default)
			)
			(layer "F.SilkS")
		)
		(fp_line
			(start -0.7874 -0.4064)
			(end 0.7874 -0.4064)
			(stroke
				(width 0.1524)
				(type default)
			)
			(layer "F.SilkS")
		)
		(fp_line
			(start 0.67945 0.3048)
			(end 0.120396 0.3048)
			(stroke
				(width 0.1)
				(type default)
			)
			(layer "F.Fab")
		)
		(fp_line
			(start 0.67945 -0.3048)
			(end 0.67945 0.3048)
			(stroke
				(width 0.1)
				(type default)
			)
			(layer "F.Fab")
		)
		(fp_line
			(start 0.12065 -0.2794)
			(end 0.12065 -0.3048)
			(stroke
				(width 0.1)
				(type default)
			)
			(layer "F.Fab")
		)
		(fp_line
			(start 0.12065 -0.3048)
			(end 0.67945 -0.3048)
			(stroke
				(width 0.1)
				(type default)
			)
			(layer "F.Fab")
		)
		(fp_line
			(start 0.120396 0.3048)
			(end 0.120396 0.2794)
			(stroke
				(width 0.1)
				(type default)
			)
			(layer "F.Fab")
		)
		(fp_line
			(start 0.120396 0.2794)
			(end -0.12065 0.2794)
			(stroke
				(width 0.1)
				(type default)
			)
			(layer "F.Fab")
		)
		(fp_line
			(start -0.12065 0.3048)
			(end -0.67945 0.3048)
			(stroke
				(width 0.1)
				(type default)
			)
			(layer "F.Fab")
		)
		(fp_line
			(start -0.12065 0.2794)
			(end -0.12065 0.3048)
			(stroke
				(width 0.1)
				(type default)
			)
			(layer "F.Fab")
		)
		(fp_line
			(start -0.12065 -0.2794)
			(end 0.12065 -0.2794)
			(stroke
				(width 0.1)
				(type default)
			)
			(layer "F.Fab")
		)
		(fp_line
			(start -0.12065 -0.305054)
			(end -0.12065 -0.2794)
			(stroke
				(width 0.1)
				(type default)
			)
			(layer "F.Fab")
		)
		(fp_line
			(start -0.67945 0.3048)
			(end -0.67945 -0.305054)
			(stroke
				(width 0.1)
				(type default)
			)
			(layer "F.Fab")
		)
		(fp_line
			(start -0.67945 -0.305054)
			(end -0.12065 -0.305054)
			(stroke
				(width 0.1)
				(type default)
			)
			(layer "F.Fab")
		)
		(pad "1" smd circle
			(at -0.40005 0 180)
			(size 0 0)
			(layers "F.Cu" "F.Mask" "F.Paste")
			(net "P3V3_AUX")
		)
		(pad "2" smd circle
			(at 0.40005 0 180)
			(size 0 0)
			(layers "F.Cu" "F.Mask" "F.Paste")
			(net "RST_SPI_PCH_FLASH_R1_N")
		)
	)
	(footprint ""
		(layer "F.Cu")
		(at 44.193968 -65.776094 -90)
		(property "Reference" "R186"
			(at 0 0 270)
			(layer "F.SilkS")
			(hide yes)
			(effects
				(font
					(size 1.27 1.27)
				)
			)
		)
		(property "Value" ""
			(at 0 0 270)
			(layer "F.Fab")
			(effects
				(font
					(size 1.27 1.27)
				)
			)
		)
		(duplicate_pad_numbers_are_jumpers no)
		(fp_line
			(start -0.7874 0.4064)
			(end -0.7874 -0.4064)
			(stroke
				(width 0.1524)
				(type default)
			)
			(layer "F.SilkS")
		)
		(fp_line
			(start 0.7874 0.4064)
			(end -0.7874 0.4064)
			(stroke
				(width 0.1524)
				(type default)
			)
			(layer "F.SilkS")
		)
		(fp_line
			(start -0.7874 -0.4064)
			(end 0.7874 -0.4064)
			(stroke
				(width 0.1524)
				(type default)
			)
			(layer "F.SilkS")
		)
		(fp_line
			(start 0.7874 -0.4064)
			(end 0.7874 0.4064)
			(stroke
				(width 0.1524)
				(type default)
			)
			(layer "F.SilkS")
		)
		(fp_line
			(start -0.67945 0.3048)
			(end -0.67945 -0.305054)
			(stroke
				(width 0.1)
				(type default)
			)
			(layer "F.Fab")
		)
		(fp_line
			(start -0.12065 0.3048)
			(end -0.67945 0.3048)
			(stroke
				(width 0.1)
				(type default)
			)
			(layer "F.Fab")
		)
		(fp_line
			(start 0.120396 0.3048)
			(end 0.120396 0.2794)
			(stroke
				(width 0.1)
				(type default)
			)
			(layer "F.Fab")
		)
		(fp_line
			(start 0.67945 0.3048)
			(end 0.120396 0.3048)
			(stroke
				(width 0.1)
				(type default)
			)
			(layer "F.Fab")
		)
		(fp_line
			(start -0.12065 0.2794)
			(end -0.12065 0.3048)
			(stroke
				(width 0.1)
				(type default)
			)
			(layer "F.Fab")
		)
		(fp_line
			(start 0.120396 0.2794)
			(end -0.12065 0.2794)
			(stroke
				(width 0.1)
				(type default)
			)
			(layer "F.Fab")
		)
		(fp_line
			(start -0.12065 -0.2794)
			(end 0.12065 -0.2794)
			(stroke
				(width 0.1)
				(type default)
			)
			(layer "F.Fab")
		)
		(fp_line
			(start 0.12065 -0.2794)
			(end 0.12065 -0.3048)
			(stroke
				(width 0.1)
				(type default)
			)
			(layer "F.Fab")
		)
		(fp_line
			(start 0.12065 -0.3048)
			(end 0.67945 -0.3048)
			(stroke
				(width 0.1)
				(type default)
			)
			(layer "F.Fab")
		)
		(fp_line
			(start 0.67945 -0.3048)
			(end 0.67945 0.3048)
			(stroke
				(width 0.1)
				(type default)
			)
			(layer "F.Fab")
		)
		(fp_line
			(start -0.67945 -0.305054)
			(end -0.12065 -0.305054)
			(stroke
				(width 0.1)
				(type default)
			)
			(layer "F.Fab")
		)
		(fp_line
			(start -0.12065 -0.305054)
			(end -0.12065 -0.2794)
			(stroke
				(width 0.1)
				(type default)
			)
			(layer "F.Fab")
		)
		(pad "1" smd circle
			(at -0.40005 0 270)
			(size 0 0)
			(layers "F.Cu" "F.Mask" "F.Paste")
			(net "I3C2_SPD_SCL")
		)
		(pad "2" smd circle
			(at 0.40005 0 270)
			(size 0 0)
			(layers "F.Cu" "F.Mask" "F.Paste")
			(net "I3C2_SCL_R")
		)
	)
	(footprint ""
		(layer "F.Cu")
		(at 51.832002 -63.953644 -90)
		(property "Reference" "R160"
			(at 0 0 270)
			(layer "F.SilkS")
			(hide yes)
			(effects
				(font
					(size 1.27 1.27)
				)
			)
		)
		(property "Value" ""
			(at 0 0 270)
			(layer "F.Fab")
			(effects
				(font
					(size 1.27 1.27)
				)
			)
		)
		(duplicate_pad_numbers_are_jumpers no)
		(fp_line
			(start -0.7874 0.4064)
			(end -0.7874 -0.4064)
			(stroke
				(width 0.1524)
				(type default)
			)
			(layer "F.SilkS")
		)
		(fp_line
			(start 0.7874 0.4064)
			(end -0.7874 0.4064)
			(stroke
				(width 0.1524)
				(type default)
			)
			(layer "F.SilkS")
		)
		(fp_line
			(start -0.7874 -0.4064)
			(end 0.7874 -0.4064)
			(stroke
				(width 0.1524)
				(type default)
			)
			(layer "F.SilkS")
		)
		(fp_line
			(start 0.7874 -0.4064)
			(end 0.7874 0.4064)
			(stroke
				(width 0.1524)
				(type default)
			)
			(layer "F.SilkS")
		)
		(fp_line
			(start -0.67945 0.3048)
			(end -0.67945 -0.305054)
			(stroke
				(width 0.1)
				(type default)
			)
			(layer "F.Fab")
		)
		(fp_line
			(start -0.12065 0.3048)
			(end -0.67945 0.3048)
			(stroke
				(width 0.1)
				(type default)
			)
			(layer "F.Fab")
		)
		(fp_line
			(start 0.120396 0.3048)
			(end 0.120396 0.2794)
			(stroke
				(width 0.1)
				(type default)
			)
			(layer "F.Fab")
		)
		(fp_line
			(start 0.67945 0.3048)
			(end 0.120396 0.3048)
			(stroke
				(width 0.1)
				(type default)
			)
			(layer "F.Fab")
		)
		(fp_line
			(start -0.12065 0.2794)
			(end -0.12065 0.3048)
			(stroke
				(width 0.1)
				(type default)
			)
			(layer "F.Fab")
		)
		(fp_line
			(start 0.120396 0.2794)
			(end -0.12065 0.2794)
			(stroke
				(width 0.1)
				(type default)
			)
			(layer "F.Fab")
		)
		(fp_line
			(start -0.12065 -0.2794)
			(end 0.12065 -0.2794)
			(stroke
				(width 0.1)
				(type default)
			)
			(layer "F.Fab")
		)
		(fp_line
			(start 0.12065 -0.2794)
			(end 0.12065 -0.3048)
			(stroke
				(width 0.1)
				(type default)
			)
			(layer "F.Fab")
		)
		(fp_line
			(start 0.12065 -0.3048)
			(end 0.67945 -0.3048)
			(stroke
				(width 0.1)
				(type default)
			)
			(layer "F.Fab")
		)
		(fp_line
			(start 0.67945 -0.3048)
			(end 0.67945 0.3048)
			(stroke
				(width 0.1)
				(type default)
			)
			(layer "F.Fab")
		)
		(fp_line
			(start -0.67945 -0.305054)
			(end -0.12065 -0.305054)
			(stroke
				(width 0.1)
				(type default)
			)
			(layer "F.Fab")
		)
		(fp_line
			(start -0.12065 -0.305054)
			(end -0.12065 -0.2794)
			(stroke
				(width 0.1)
				(type default)
			)
			(layer "F.Fab")
		)
		(pad "1" smd circle
			(at -0.40005 0 270)
			(size 0 0)
			(layers "F.Cu" "F.Mask" "F.Paste")
			(net "RST_RSMRST_N")
		)
		(pad "2" smd circle
			(at 0.40005 0 270)
			(size 0 0)
			(layers "F.Cu" "F.Mask" "F.Paste")
			(net "RST_RSMRST_R_N")
		)
	)
	(footprint ""
		(layer "F.Cu")
		(at 17.018 -102.743 90)
		(property "Reference" "R105"
			(at 0 0 90)
			(layer "F.SilkS")
			(hide yes)
			(effects
				(font
					(size 1.27 1.27)
				)
			)
		)
		(property "Value" ""
			(at 0 0 90)
			(layer "F.Fab")
			(effects
				(font
					(size 1.27 1.27)
				)
			)
		)
		(duplicate_pad_numbers_are_jumpers no)
		(fp_line
			(start 0.7874 -0.4064)
			(end 0.7874 0.4064)
			(stroke
				(width 0.1524)
				(type default)
			)
			(layer "F.SilkS")
		)
		(fp_line
			(start -0.7874 -0.4064)
			(end 0.7874 -0.4064)
			(stroke
				(width 0.1524)
				(type default)
			)
			(layer "F.SilkS")
		)
		(fp_line
			(start 0.7874 0.4064)
			(end -0.7874 0.4064)
			(stroke
				(width 0.1524)
				(type default)
			)
			(layer "F.SilkS")
		)
		(fp_line
			(start -0.7874 0.4064)
			(end -0.7874 -0.4064)
			(stroke
				(width 0.1524)
				(type default)
			)
			(layer "F.SilkS")
		)
		(fp_line
			(start -0.12065 -0.305054)
			(end -0.12065 -0.2794)
			(stroke
				(width 0.1)
				(type default)
			)
			(layer "F.Fab")
		)
		(fp_line
			(start -0.67945 -0.305054)
			(end -0.12065 -0.305054)
			(stroke
				(width 0.1)
				(type default)
			)
			(layer "F.Fab")
		)
		(fp_line
			(start 0.67945 -0.3048)
			(end 0.67945 0.3048)
			(stroke
				(width 0.1)
				(type default)
			)
			(layer "F.Fab")
		)
		(fp_line
			(start 0.12065 -0.3048)
			(end 0.67945 -0.3048)
			(stroke
				(width 0.1)
				(type default)
			)
			(layer "F.Fab")
		)
		(fp_line
			(start 0.12065 -0.2794)
			(end 0.12065 -0.3048)
			(stroke
				(width 0.1)
				(type default)
			)
			(layer "F.Fab")
		)
		(fp_line
			(start -0.12065 -0.2794)
			(end 0.12065 -0.2794)
			(stroke
				(width 0.1)
				(type default)
			)
			(layer "F.Fab")
		)
		(fp_line
			(start 0.120396 0.2794)
			(end -0.12065 0.2794)
			(stroke
				(width 0.1)
				(type default)
			)
			(layer "F.Fab")
		)
		(fp_line
			(start -0.12065 0.2794)
			(end -0.12065 0.3048)
			(stroke
				(width 0.1)
				(type default)
			)
			(layer "F.Fab")
		)
		(fp_line
			(start 0.67945 0.3048)
			(end 0.120396 0.3048)
			(stroke
				(width 0.1)
				(type default)
			)
			(layer "F.Fab")
		)
		(fp_line
			(start 0.120396 0.3048)
			(end 0.120396 0.2794)
			(stroke
				(width 0.1)
				(type default)
			)
			(layer "F.Fab")
		)
		(fp_line
			(start -0.12065 0.3048)
			(end -0.67945 0.3048)
			(stroke
				(width 0.1)
				(type default)
			)
			(layer "F.Fab")
		)
		(fp_line
			(start -0.67945 0.3048)
			(end -0.67945 -0.305054)
			(stroke
				(width 0.1)
				(type default)
			)
			(layer "F.Fab")
		)
		(pad "1" smd circle
			(at -0.40005 0 90)
			(size 0 0)
			(layers "F.Cu" "F.Mask" "F.Paste")
			(net "SMB_BMC_MM16_R4_SCL")
		)
		(pad "2" smd circle
			(at 0.40005 0 90)
			(size 0 0)
			(layers "F.Cu" "F.Mask" "F.Paste")
			(net "SMB_BMC_MM16_R5_SCL")
		)
	)
	(footprint ""
		(layer "F.Cu")
		(at 101.2825 -104.76484 -90)
		(property "Reference" "J12"
			(at -3.94716 -1.48717 90)
			(unlocked yes)
			(layer "F.SilkS")
			(effects
				(font
					(size 0.7874 0.5842)
					(thickness 0.1524)
				)
				(justify left)
			)
		)
		(property "Value" ""
			(at 0 0 270)
			(layer "F.Fab")
			(effects
				(font
					(size 1.27 1.27)
				)
			)
		)
		(duplicate_pad_numbers_are_jumpers no)
		(fp_line
			(start -1.2192 2.1082)
			(end -1.2192 -2.1082)
			(stroke
				(width 0.1524)
				(type default)
			)
			(layer "F.SilkS")
		)
		(fp_line
			(start 1.2192 2.1082)
			(end -1.2192 2.1082)
			(stroke
				(width 0.1524)
				(type default)
			)
			(layer "F.SilkS")
		)
		(fp_line
			(start 1.2192 0.466598)
			(end 1.2192 2.1082)
			(stroke
				(width 0.1524)
				(type default)
			)
			(layer "F.SilkS")
		)
		(fp_line
			(start -1.2192 -2.1082)
			(end 1.2192 -2.1082)
			(stroke
				(width 0.1524)
				(type default)
			)
			(layer "F.SilkS")
		)
		(fp_line
			(start 1.2192 -2.1082)
			(end 1.2192 -0.454406)
			(stroke
				(width 0.1524)
				(type default)
			)
			(layer "F.SilkS")
		)
		(pad "" np_thru_hole circle
			(at -2.8829 -1.27 180)
			(size 1.0414 1.0414)
			(drill 1.0414)
			(layers "*.Cu" "*.Mask")
			(clearance 0.381)
			(thermal_gap 0.381)
		)
		(pad "" np_thru_hole circle
			(at -2.8829 1.27 180)
			(size 1.0414 1.0414)
			(drill 1.0414)
			(layers "*.Cu" "*.Mask")
			(clearance 0.381)
			(thermal_gap 0.381)
		)
		(pad "" np_thru_hole circle
			(at 3.4671 -1.27 180)
			(size 1.0414 1.0414)
			(drill 1.0414)
			(layers "*.Cu" "*.Mask")
			(clearance 0.381)
			(thermal_gap 0.381)
		)
		(pad "" np_thru_hole circle
			(at 3.4671 1.27 180)
			(size 1.0414 1.0414)
			(drill 1.0414)
			(layers "*.Cu" "*.Mask")
			(clearance 0.381)
			(thermal_gap 0.381)
		)
		(pad "1" smd rect
			(at 0.8255 -0.249936 180)
			(size 0.3048 0.508)
			(layers "F.Cu" "F.Mask" "F.Paste")
			(net "85_5INCH_TOP_DP")
		)
		(pad "2" smd rect
			(at 0.8255 0.249936 180)
			(size 0.3048 0.508)
			(layers "F.Cu" "F.Mask" "F.Paste")
			(net "85_5INCH_TOP_DN")
		)
		(pad "3" smd circle
			(at 0 0 270)
			(size 0 0)
			(layers "F.Cu" "F.Mask" "F.Paste")
			(net "GND_P1")
		)
		(zone
			(layer "F.Cu")
			(hatch none 0.5)
			(connect_pads
				(clearance 0)
			)
			(min_thickness 0.25)
			(keepout
				(tracks not_allowed)
				(vias allowed)
				(pads allowed)
				(copperpour not_allowed)
				(footprints allowed)
			)
			(placement
				(enabled no)
				(sheetname "")
			)
			(fill
				(thermal_gap 0.5)
				(thermal_bridge_width 0.5)
				(island_removal_mode 0)
			)
			(polygon
				(pts
					(xy 101.83114 -103.64724) (xy 101.735636 -103.64724) (xy 101.735636 -104.24414) (xy 101.329236 -104.24414)
					(xy 101.329236 -103.64724) (xy 101.235764 -103.64724) (xy 101.235764 -104.24414) (xy 100.829364 -104.24414)
					(xy 100.829364 -103.64724) (xy 100.73386 -103.64724) (xy 100.73386 -104.34574) (xy 101.83114 -104.34574)
				)
			)
		)
		(zone
			(layers "F.Cu" "B.Cu" "In1.Cu" "In2.Cu" "In3.Cu" "In4.Cu" "In5.Cu" "In6.Cu"
				"In7.Cu" "In8.Cu" "In9.Cu" "In10.Cu"
			)
			(hatch none 0.5)
			(connect_pads
				(clearance 0)
			)
			(min_thickness 0.25)
			(keepout
				(tracks not_allowed)
				(vias allowed)
				(pads allowed)
				(copperpour not_allowed)
				(footprints allowed)
			)
			(placement
				(enabled no)
				(sheetname "")
			)
			(fill
				(thermal_gap 0.5)
				(thermal_bridge_width 0.5)
				(island_removal_mode 0)
			)
			(polygon
				(pts
					(arc
						(start 100.9396 -107.64774)
						(mid 99.0854 -107.64774)
						(end 100.9396 -107.64774)
					)
				)
			)
		)
		(zone
			(layers "F.Cu" "B.Cu" "In1.Cu" "In2.Cu" "In3.Cu" "In4.Cu" "In5.Cu" "In6.Cu"
				"In7.Cu" "In8.Cu" "In9.Cu" "In10.Cu"
			)
			(hatch none 0.5)
			(connect_pads
				(clearance 0)
			)
			(min_thickness 0.25)
			(keepout
				(tracks not_allowed)
				(vias allowed)
				(pads allowed)
				(copperpour not_allowed)
				(footprints allowed)
			)
			(placement
				(enabled no)
				(sheetname "")
			)
			(fill
				(thermal_gap 0.5)
				(thermal_bridge_width 0.5)
				(island_removal_mode 0)
			)
			(polygon
				(pts
					(arc
						(start 100.9396 -101.29774)
						(mid 99.0854 -101.29774)
						(end 100.9396 -101.29774)
					)
				)
			)
		)
		(zone
			(layers "F.Cu" "B.Cu" "In1.Cu" "In2.Cu" "In3.Cu" "In4.Cu" "In5.Cu" "In6.Cu"
				"In7.Cu" "In8.Cu" "In9.Cu" "In10.Cu"
			)
			(hatch none 0.5)
			(connect_pads
				(clearance 0)
			)
			(min_thickness 0.25)
			(keepout
				(tracks not_allowed)
				(vias allowed)
				(pads allowed)
				(copperpour not_allowed)
				(footprints allowed)
			)
			(placement
				(enabled no)
				(sheetname "")
			)
			(fill
				(thermal_gap 0.5)
				(thermal_bridge_width 0.5)
				(island_removal_mode 0)
			)
			(polygon
				(pts
					(arc
						(start 103.4796 -107.64774)
						(mid 101.6254 -107.64774)
						(end 103.4796 -107.64774)
					)
				)
			)
		)
		(zone
			(layers "F.Cu" "B.Cu" "In1.Cu" "In2.Cu" "In3.Cu" "In4.Cu" "In5.Cu" "In6.Cu"
				"In7.Cu" "In8.Cu" "In9.Cu" "In10.Cu"
			)
			(hatch none 0.5)
			(connect_pads
				(clearance 0)
			)
			(min_thickness 0.25)
			(keepout
				(tracks not_allowed)
				(vias allowed)
				(pads allowed)
				(copperpour not_allowed)
				(footprints allowed)
			)
			(placement
				(enabled no)
				(sheetname "")
			)
			(fill
				(thermal_gap 0.5)
				(thermal_bridge_width 0.5)
				(island_removal_mode 0)
			)
			(polygon
				(pts
					(arc
						(start 103.4796 -101.29774)
						(mid 101.6254 -101.29774)
						(end 103.4796 -101.29774)
					)
				)
			)
		)
	)
	(footprint ""
		(layer "F.Cu")
		(at 74.01052 -31.307786 90)
		(property "Reference" "D7"
			(at -3.672586 8.64235 90)
			(unlocked yes)
			(layer "F.SilkS")
			(effects
				(font
					(size 0.7874 0.5842)
					(thickness 0.1524)
				)
				(justify left)
			)
		)
		(property "Value" ""
			(at 0 0 90)
			(layer "F.Fab")
			(effects
				(font
					(size 1.27 1.27)
				)
			)
		)
		(duplicate_pad_numbers_are_jumpers no)
		(fp_line
			(start 1.778 -0.5588)
			(end 1.3208 -0.5588)
			(stroke
				(width 0.1524)
				(type default)
			)
			(layer "F.SilkS")
		)
		(fp_line
			(start 1.778 -0.5588)
			(end 1.778 0.5588)
			(stroke
				(width 0.1524)
				(type default)
			)
			(layer "F.SilkS")
		)
		(fp_line
			(start 1.4732 -0.5588)
			(end 1.4732 0.5588)
			(stroke
				(width 0.1524)
				(type default)
			)
			(layer "F.SilkS")
		)
		(fp_line
			(start 1.3208 -0.5588)
			(end 1.3208 0.5588)
			(stroke
				(width 0.1524)
				(type default)
			)
			(layer "F.SilkS")
		)
		(fp_line
			(start -1.3208 -0.5588)
			(end 1.3208 -0.5588)
			(stroke
				(width 0.1524)
				(type default)
			)
			(layer "F.SilkS")
		)
		(fp_line
			(start 1.778 0.5588)
			(end 1.3208 0.5588)
			(stroke
				(width 0.1524)
				(type default)
			)
			(layer "F.SilkS")
		)
		(fp_line
			(start 1.6256 0.5588)
			(end 1.6256 -0.5588)
			(stroke
				(width 0.1524)
				(type default)
			)
			(layer "F.SilkS")
		)
		(fp_line
			(start 1.3208 0.5588)
			(end -1.3208 0.5588)
			(stroke
				(width 0.1524)
				(type default)
			)
			(layer "F.SilkS")
		)
		(fp_line
			(start -1.3208 0.5588)
			(end -1.3208 -0.5588)
			(stroke
				(width 0.1524)
				(type default)
			)
			(layer "F.SilkS")
		)
		(fp_line
			(start 0.8001 -0.40005)
			(end 0.8001 0.40005)
			(stroke
				(width 0.1)
				(type default)
			)
			(layer "F.Fab")
		)
		(fp_line
			(start -0.8001 -0.40005)
			(end 0.8001 -0.40005)
			(stroke
				(width 0.1)
				(type default)
			)
			(layer "F.Fab")
		)
		(fp_line
			(start 0.8001 0.40005)
			(end -0.8001 0.40005)
			(stroke
				(width 0.1)
				(type default)
			)
			(layer "F.Fab")
		)
		(fp_line
			(start -0.8001 0.40005)
			(end -0.8001 -0.40005)
			(stroke
				(width 0.1)
				(type default)
			)
			(layer "F.Fab")
		)
		(fp_text user "+"
			(at -0.811276 -0.6985 270)
			(unlocked yes)
			(layer "F.SilkS")
			(effects
				(font
					(size 1.905 1.4224)
					(thickness 0.1524)
				)
				(justify left)
			)
		)
		(fp_text user "-"
			(at 1.6256 -0.22225 90)
			(unlocked yes)
			(layer "F.SilkS")
			(effects
				(font
					(size 1.905 1.4224)
					(thickness 0.1524)
				)
				(justify left)
			)
		)
		(fp_text user "-"
			(at 1.6256 -0.22225 90)
			(unlocked yes)
			(layer "F.Fab")
			(effects
				(font
					(size 1.905 1.4224)
					(thickness 0.1524)
				)
				(justify left)
			)
		)
		(fp_text user "+"
			(at -2.5654 -0.22225 90)
			(unlocked yes)
			(layer "F.Fab")
			(effects
				(font
					(size 1.905 1.4224)
					(thickness 0.1524)
				)
				(justify left)
			)
		)
		(pad "A" smd rect
			(at -0.750062 0 90)
			(size 0.8128 0.8128)
			(layers "F.Cu" "F.Mask" "F.Paste")
			(net "LED_POSTCODE_7_R")
		)
		(pad "C" smd rect
			(at 0.750062 0 90)
			(size 0.8128 0.8128)
			(layers "F.Cu" "F.Mask" "F.Paste")
			(net "GND")
		)
	)
	(footprint ""
		(layer "F.Cu")
		(at 30.41904 -68.504054 90)
		(property "Reference" "R661"
			(at 0 0 90)
			(layer "F.SilkS")
			(hide yes)
			(effects
				(font
					(size 1.27 1.27)
				)
			)
		)
		(property "Value" ""
			(at 0 0 90)
			(layer "F.Fab")
			(effects
				(font
					(size 1.27 1.27)
				)
			)
		)
		(duplicate_pad_numbers_are_jumpers no)
		(fp_line
			(start 0.7874 -0.4064)
			(end 0.7874 0.4064)
			(stroke
				(width 0.1524)
				(type default)
			)
			(layer "F.SilkS")
		)
		(fp_line
			(start -0.7874 -0.4064)
			(end 0.7874 -0.4064)
			(stroke
				(width 0.1524)
				(type default)
			)
			(layer "F.SilkS")
		)
		(fp_line
			(start 0.7874 0.4064)
			(end -0.7874 0.4064)
			(stroke
				(width 0.1524)
				(type default)
			)
			(layer "F.SilkS")
		)
		(fp_line
			(start -0.7874 0.4064)
			(end -0.7874 -0.4064)
			(stroke
				(width 0.1524)
				(type default)
			)
			(layer "F.SilkS")
		)
		(fp_line
			(start -0.12065 -0.305054)
			(end -0.12065 -0.2794)
			(stroke
				(width 0.1)
				(type default)
			)
			(layer "F.Fab")
		)
		(fp_line
			(start -0.67945 -0.305054)
			(end -0.12065 -0.305054)
			(stroke
				(width 0.1)
				(type default)
			)
			(layer "F.Fab")
		)
		(fp_line
			(start 0.67945 -0.3048)
			(end 0.67945 0.3048)
			(stroke
				(width 0.1)
				(type default)
			)
			(layer "F.Fab")
		)
		(fp_line
			(start 0.12065 -0.3048)
			(end 0.67945 -0.3048)
			(stroke
				(width 0.1)
				(type default)
			)
			(layer "F.Fab")
		)
		(fp_line
			(start 0.12065 -0.2794)
			(end 0.12065 -0.3048)
			(stroke
				(width 0.1)
				(type default)
			)
			(layer "F.Fab")
		)
		(fp_line
			(start -0.12065 -0.2794)
			(end 0.12065 -0.2794)
			(stroke
				(width 0.1)
				(type default)
			)
			(layer "F.Fab")
		)
		(fp_line
			(start 0.120396 0.2794)
			(end -0.12065 0.2794)
			(stroke
				(width 0.1)
				(type default)
			)
			(layer "F.Fab")
		)
		(fp_line
			(start -0.12065 0.2794)
			(end -0.12065 0.3048)
			(stroke
				(width 0.1)
				(type default)
			)
			(layer "F.Fab")
		)
		(fp_line
			(start 0.67945 0.3048)
			(end 0.120396 0.3048)
			(stroke
				(width 0.1)
				(type default)
			)
			(layer "F.Fab")
		)
		(fp_line
			(start 0.120396 0.3048)
			(end 0.120396 0.2794)
			(stroke
				(width 0.1)
				(type default)
			)
			(layer "F.Fab")
		)
		(fp_line
			(start -0.12065 0.3048)
			(end -0.67945 0.3048)
			(stroke
				(width 0.1)
				(type default)
			)
			(layer "F.Fab")
		)
		(fp_line
			(start -0.67945 0.3048)
			(end -0.67945 -0.305054)
			(stroke
				(width 0.1)
				(type default)
			)
			(layer "F.Fab")
		)
		(pad "1" smd circle
			(at -0.40005 0 90)
			(size 0 0)
			(layers "F.Cu" "F.Mask" "F.Paste")
			(net "P3V3_AUX")
		)
		(pad "2" smd circle
			(at 0.40005 0 90)
			(size 0 0)
			(layers "F.Cu" "F.Mask" "F.Paste")
			(net "EMMC_DT6_R")
		)
	)
	(footprint ""
		(layer "F.Cu")
		(at 16.230092 -6.290056)
		(property "Reference" "D14"
			(at 1.448308 -2.547874 0)
			(unlocked yes)
			(layer "F.SilkS")
			(effects
				(font
					(size 0.7874 0.5842)
					(thickness 0.1524)
				)
				(justify left)
			)
		)
		(property "Value" ""
			(at 0 0 0)
			(layer "F.Fab")
			(effects
				(font
					(size 1.27 1.27)
				)
			)
		)
		(duplicate_pad_numbers_are_jumpers no)
		(fp_line
			(start -1.080008 -1.999996)
			(end 3.620008 -1.999996)
			(stroke
				(width 0.1524)
				(type default)
			)
			(layer "F.SilkS")
		)
		(fp_line
			(start -1.080008 3.999992)
			(end -1.080008 -1.999996)
			(stroke
				(width 0.1524)
				(type default)
			)
			(layer "F.SilkS")
		)
		(fp_line
			(start -0.230124 3.999992)
			(end -1.080008 3.999992)
			(stroke
				(width 0.1524)
				(type default)
			)
			(layer "F.SilkS")
		)
		(fp_line
			(start -0.230124 5.199888)
			(end -0.230124 3.999992)
			(stroke
				(width 0.1524)
				(type default)
			)
			(layer "F.SilkS")
		)
		(fp_line
			(start 2.770124 3.999992)
			(end 2.770124 5.199888)
			(stroke
				(width 0.1524)
				(type default)
			)
			(layer "F.SilkS")
		)
		(fp_line
			(start 3.620008 -1.999996)
			(end 3.620008 3.999992)
			(stroke
				(width 0.1524)
				(type default)
			)
			(layer "F.SilkS")
		)
		(fp_line
			(start 3.620008 3.999992)
			(end 2.770124 3.999992)
			(stroke
				(width 0.1524)
				(type default)
			)
			(layer "F.SilkS")
		)
		(fp_arc
			(start 1.27 6.700012)
			(mid 0.209252 6.260636)
			(end -0.230124 5.199888)
			(stroke
				(width 0.1524)
				(type default)
			)
			(layer "F.SilkS")
		)
		(fp_arc
			(start 2.770124 5.199888)
			(mid 2.330748 6.260636)
			(end 1.27 6.700012)
			(stroke
				(width 0.1524)
				(type default)
			)
			(layer "F.SilkS")
		)
		(fp_line
			(start -1.080008 -1.999996)
			(end 3.620008 -1.999996)
			(stroke
				(width 0.1)
				(type default)
			)
			(layer "F.Fab")
		)
		(fp_line
			(start -1.080008 3.999992)
			(end -1.080008 -1.999996)
			(stroke
				(width 0.1)
				(type default)
			)
			(layer "F.Fab")
		)
		(fp_line
			(start -0.230124 3.999992)
			(end -1.080008 3.999992)
			(stroke
				(width 0.1)
				(type default)
			)
			(layer "F.Fab")
		)
		(fp_line
			(start -0.230124 5.199888)
			(end -0.230124 3.999992)
			(stroke
				(width 0.1)
				(type default)
			)
			(layer "F.Fab")
		)
		(fp_line
			(start 2.770124 3.999992)
			(end 2.770124 5.199888)
			(stroke
				(width 0.1)
				(type default)
			)
			(layer "F.Fab")
		)
		(fp_line
			(start 3.620008 -1.999996)
			(end 3.620008 3.999992)
			(stroke
				(width 0.1)
				(type default)
			)
			(layer "F.Fab")
		)
		(fp_line
			(start 3.620008 3.999992)
			(end 2.770124 3.999992)
			(stroke
				(width 0.1)
				(type default)
			)
			(layer "F.Fab")
		)
		(fp_arc
			(start 1.27 6.700012)
			(mid 0.209252 6.260636)
			(end -0.230124 5.199888)
			(stroke
				(width 0.1)
				(type default)
			)
			(layer "F.Fab")
		)
		(fp_arc
			(start 2.770124 5.199888)
			(mid 2.330748 6.260636)
			(end 1.27 6.700012)
			(stroke
				(width 0.1)
				(type default)
			)
			(layer "F.Fab")
		)
		(pad "A" thru_hole rect
			(at 0 0)
			(size 1.2192 1.2192)
			(drill 0.8128)
			(layers "*.Cu" "*.Mask")
			(remove_unused_layers no)
			(net "PWR_LED_P5V_AUX")
			(clearance 0.0508)
			(thermal_gap 0.0508)
			(padstack
				(mode front_inner_back)
				(layer "Inner"
					(shape circle)
					(size 1.2192 1.2192)
					(clearance 0.0508)
				)
				(layer "B.Cu"
					(shape rect)
					(size 1.2192 1.2192)
					(clearance 0.0508)
				)
			)
		)
		(pad "C" thru_hole circle
			(at 2.54 0)
			(size 1.2192 1.2192)
			(drill 0.8128)
			(layers "*.Cu" "*.Mask")
			(remove_unused_layers no)
			(net "PWR_LED_BUF_N_R")
			(clearance 0.0508)
			(thermal_gap 0.0508)
		)
	)
	(footprint ""
		(layer "F.Cu")
		(at 26.289 -68.834 90)
		(property "Reference" "R58"
			(at 0 0 90)
			(layer "F.SilkS")
			(hide yes)
			(effects
				(font
					(size 1.27 1.27)
				)
			)
		)
		(property "Value" ""
			(at 0 0 90)
			(layer "F.Fab")
			(effects
				(font
					(size 1.27 1.27)
				)
			)
		)
		(duplicate_pad_numbers_are_jumpers no)
		(fp_line
			(start 0.7874 -0.4064)
			(end 0.7874 0.4064)
			(stroke
				(width 0.1524)
				(type default)
			)
			(layer "F.SilkS")
		)
		(fp_line
			(start -0.7874 -0.4064)
			(end 0.7874 -0.4064)
			(stroke
				(width 0.1524)
				(type default)
			)
			(layer "F.SilkS")
		)
		(fp_line
			(start 0.7874 0.4064)
			(end -0.7874 0.4064)
			(stroke
				(width 0.1524)
				(type default)
			)
			(layer "F.SilkS")
		)
		(fp_line
			(start -0.7874 0.4064)
			(end -0.7874 -0.4064)
			(stroke
				(width 0.1524)
				(type default)
			)
			(layer "F.SilkS")
		)
		(fp_line
			(start -0.12065 -0.305054)
			(end -0.12065 -0.2794)
			(stroke
				(width 0.1)
				(type default)
			)
			(layer "F.Fab")
		)
		(fp_line
			(start -0.67945 -0.305054)
			(end -0.12065 -0.305054)
			(stroke
				(width 0.1)
				(type default)
			)
			(layer "F.Fab")
		)
		(fp_line
			(start 0.67945 -0.3048)
			(end 0.67945 0.3048)
			(stroke
				(width 0.1)
				(type default)
			)
			(layer "F.Fab")
		)
		(fp_line
			(start 0.12065 -0.3048)
			(end 0.67945 -0.3048)
			(stroke
				(width 0.1)
				(type default)
			)
			(layer "F.Fab")
		)
		(fp_line
			(start 0.12065 -0.2794)
			(end 0.12065 -0.3048)
			(stroke
				(width 0.1)
				(type default)
			)
			(layer "F.Fab")
		)
		(fp_line
			(start -0.12065 -0.2794)
			(end 0.12065 -0.2794)
			(stroke
				(width 0.1)
				(type default)
			)
			(layer "F.Fab")
		)
		(fp_line
			(start 0.120396 0.2794)
			(end -0.12065 0.2794)
			(stroke
				(width 0.1)
				(type default)
			)
			(layer "F.Fab")
		)
		(fp_line
			(start -0.12065 0.2794)
			(end -0.12065 0.3048)
			(stroke
				(width 0.1)
				(type default)
			)
			(layer "F.Fab")
		)
		(fp_line
			(start 0.67945 0.3048)
			(end 0.120396 0.3048)
			(stroke
				(width 0.1)
				(type default)
			)
			(layer "F.Fab")
		)
		(fp_line
			(start 0.120396 0.3048)
			(end 0.120396 0.2794)
			(stroke
				(width 0.1)
				(type default)
			)
			(layer "F.Fab")
		)
		(fp_line
			(start -0.12065 0.3048)
			(end -0.67945 0.3048)
			(stroke
				(width 0.1)
				(type default)
			)
			(layer "F.Fab")
		)
		(fp_line
			(start -0.67945 0.3048)
			(end -0.67945 -0.305054)
			(stroke
				(width 0.1)
				(type default)
			)
			(layer "F.Fab")
		)
		(pad "1" smd circle
			(at -0.40005 0 90)
			(size 0 0)
			(layers "F.Cu" "F.Mask" "F.Paste")
			(net "P3V3_AUX")
		)
		(pad "2" smd circle
			(at 0.40005 0 90)
			(size 0 0)
			(layers "F.Cu" "F.Mask" "F.Paste")
			(net "SPI_BMC_HOLD0_N")
		)
	)
	(footprint ""
		(layer "F.Cu")
		(at 73.980294 -99.4664)
		(property "Reference" "R33"
			(at 0 0 0)
			(layer "F.SilkS")
			(hide yes)
			(effects
				(font
					(size 1.27 1.27)
				)
			)
		)
		(property "Value" ""
			(at 0 0 0)
			(layer "F.Fab")
			(effects
				(font
					(size 1.27 1.27)
				)
			)
		)
		(duplicate_pad_numbers_are_jumpers no)
		(fp_line
			(start -0.7874 -0.4064)
			(end 0.7874 -0.4064)
			(stroke
				(width 0.1524)
				(type default)
			)
			(layer "F.SilkS")
		)
		(fp_line
			(start -0.7874 0.4064)
			(end -0.7874 -0.4064)
			(stroke
				(width 0.1524)
				(type default)
			)
			(layer "F.SilkS")
		)
		(fp_line
			(start 0.7874 -0.4064)
			(end 0.7874 0.4064)
			(stroke
				(width 0.1524)
				(type default)
			)
			(layer "F.SilkS")
		)
		(fp_line
			(start 0.7874 0.4064)
			(end -0.7874 0.4064)
			(stroke
				(width 0.1524)
				(type default)
			)
			(layer "F.SilkS")
		)
		(fp_line
			(start -0.67945 -0.305054)
			(end -0.12065 -0.305054)
			(stroke
				(width 0.1)
				(type default)
			)
			(layer "F.Fab")
		)
		(fp_line
			(start -0.67945 0.3048)
			(end -0.67945 -0.305054)
			(stroke
				(width 0.1)
				(type default)
			)
			(layer "F.Fab")
		)
		(fp_line
			(start -0.12065 -0.305054)
			(end -0.12065 -0.2794)
			(stroke
				(width 0.1)
				(type default)
			)
			(layer "F.Fab")
		)
		(fp_line
			(start -0.12065 -0.2794)
			(end 0.12065 -0.2794)
			(stroke
				(width 0.1)
				(type default)
			)
			(layer "F.Fab")
		)
		(fp_line
			(start -0.12065 0.2794)
			(end -0.12065 0.3048)
			(stroke
				(width 0.1)
				(type default)
			)
			(layer "F.Fab")
		)
		(fp_line
			(start -0.12065 0.3048)
			(end -0.67945 0.3048)
			(stroke
				(width 0.1)
				(type default)
			)
			(layer "F.Fab")
		)
		(fp_line
			(start 0.120396 0.2794)
			(end -0.12065 0.2794)
			(stroke
				(width 0.1)
				(type default)
			)
			(layer "F.Fab")
		)
		(fp_line
			(start 0.120396 0.3048)
			(end 0.120396 0.2794)
			(stroke
				(width 0.1)
				(type default)
			)
			(layer "F.Fab")
		)
		(fp_line
			(start 0.12065 -0.3048)
			(end 0.67945 -0.3048)
			(stroke
				(width 0.1)
				(type default)
			)
			(layer "F.Fab")
		)
		(fp_line
			(start 0.12065 -0.2794)
			(end 0.12065 -0.3048)
			(stroke
				(width 0.1)
				(type default)
			)
			(layer "F.Fab")
		)
		(fp_line
			(start 0.67945 -0.3048)
			(end 0.67945 0.3048)
			(stroke
				(width 0.1)
				(type default)
			)
			(layer "F.Fab")
		)
		(fp_line
			(start 0.67945 0.3048)
			(end 0.120396 0.3048)
			(stroke
				(width 0.1)
				(type default)
			)
			(layer "F.Fab")
		)
		(pad "1" smd circle
			(at -0.40005 0)
			(size 0 0)
			(layers "F.Cu" "F.Mask" "F.Paste")
			(net "SMB_BMC_MM16_R5_SDA")
		)
		(pad "2" smd circle
			(at 0.40005 0)
			(size 0 0)
			(layers "F.Cu" "F.Mask" "F.Paste")
			(net "SMB_BMC_TPM_MM16_SDA")
		)
	)
	(footprint ""
		(layer "F.Cu")
		(at 4.6736 -83.4644 180)
		(property "Reference" "R66"
			(at 0 0 180)
			(layer "F.SilkS")
			(hide yes)
			(effects
				(font
					(size 1.27 1.27)
				)
			)
		)
		(property "Value" ""
			(at 0 0 180)
			(layer "F.Fab")
			(effects
				(font
					(size 1.27 1.27)
				)
			)
		)
		(duplicate_pad_numbers_are_jumpers no)
		(fp_line
			(start 0.7874 0.4064)
			(end -0.7874 0.4064)
			(stroke
				(width 0.1524)
				(type default)
			)
			(layer "F.SilkS")
		)
		(fp_line
			(start 0.7874 -0.4064)
			(end 0.7874 0.4064)
			(stroke
				(width 0.1524)
				(type default)
			)
			(layer "F.SilkS")
		)
		(fp_line
			(start -0.7874 0.4064)
			(end -0.7874 -0.4064)
			(stroke
				(width 0.1524)
				(type default)
			)
			(layer "F.SilkS")
		)
		(fp_line
			(start -0.7874 -0.4064)
			(end 0.7874 -0.4064)
			(stroke
				(width 0.1524)
				(type default)
			)
			(layer "F.SilkS")
		)
		(fp_line
			(start 0.67945 0.3048)
			(end 0.120396 0.3048)
			(stroke
				(width 0.1)
				(type default)
			)
			(layer "F.Fab")
		)
		(fp_line
			(start 0.67945 -0.3048)
			(end 0.67945 0.3048)
			(stroke
				(width 0.1)
				(type default)
			)
			(layer "F.Fab")
		)
		(fp_line
			(start 0.12065 -0.2794)
			(end 0.12065 -0.3048)
			(stroke
				(width 0.1)
				(type default)
			)
			(layer "F.Fab")
		)
		(fp_line
			(start 0.12065 -0.3048)
			(end 0.67945 -0.3048)
			(stroke
				(width 0.1)
				(type default)
			)
			(layer "F.Fab")
		)
		(fp_line
			(start 0.120396 0.3048)
			(end 0.120396 0.2794)
			(stroke
				(width 0.1)
				(type default)
			)
			(layer "F.Fab")
		)
		(fp_line
			(start 0.120396 0.2794)
			(end -0.12065 0.2794)
			(stroke
				(width 0.1)
				(type default)
			)
			(layer "F.Fab")
		)
		(fp_line
			(start -0.12065 0.3048)
			(end -0.67945 0.3048)
			(stroke
				(width 0.1)
				(type default)
			)
			(layer "F.Fab")
		)
		(fp_line
			(start -0.12065 0.2794)
			(end -0.12065 0.3048)
			(stroke
				(width 0.1)
				(type default)
			)
			(layer "F.Fab")
		)
		(fp_line
			(start -0.12065 -0.2794)
			(end 0.12065 -0.2794)
			(stroke
				(width 0.1)
				(type default)
			)
			(layer "F.Fab")
		)
		(fp_line
			(start -0.12065 -0.305054)
			(end -0.12065 -0.2794)
			(stroke
				(width 0.1)
				(type default)
			)
			(layer "F.Fab")
		)
		(fp_line
			(start -0.67945 0.3048)
			(end -0.67945 -0.305054)
			(stroke
				(width 0.1)
				(type default)
			)
			(layer "F.Fab")
		)
		(fp_line
			(start -0.67945 -0.305054)
			(end -0.12065 -0.305054)
			(stroke
				(width 0.1)
				(type default)
			)
			(layer "F.Fab")
		)
		(pad "1" smd circle
			(at -0.40005 0 180)
			(size 0 0)
			(layers "F.Cu" "F.Mask" "F.Paste")
			(net "GND")
		)
		(pad "2" smd circle
			(at 0.40005 0 180)
			(size 0 0)
			(layers "F.Cu" "F.Mask" "F.Paste")
			(net "PWRGD_PSU_AC_PWROK")
		)
	)
	(footprint ""
		(layer "F.Cu")
		(at 82.01152 -70.08876 180)
		(property "Reference" "PC254"
			(at 0 0 180)
			(layer "F.SilkS")
			(hide yes)
			(effects
				(font
					(size 1.27 1.27)
				)
			)
		)
		(property "Value" ""
			(at 0 0 180)
			(layer "F.Fab")
			(effects
				(font
					(size 1.27 1.27)
				)
			)
		)
		(duplicate_pad_numbers_are_jumpers no)
		(fp_line
			(start 0.7874 0.4064)
			(end -0.7874 0.4064)
			(stroke
				(width 0.1524)
				(type default)
			)
			(layer "F.SilkS")
		)
		(fp_line
			(start 0.7874 -0.4064)
			(end 0.7874 0.4064)
			(stroke
				(width 0.1524)
				(type default)
			)
			(layer "F.SilkS")
		)
		(fp_line
			(start -0.7874 0.4064)
			(end -0.7874 -0.4064)
			(stroke
				(width 0.1524)
				(type default)
			)
			(layer "F.SilkS")
		)
		(fp_line
			(start -0.7874 -0.4064)
			(end 0.7874 -0.4064)
			(stroke
				(width 0.1524)
				(type default)
			)
			(layer "F.SilkS")
		)
		(fp_line
			(start 0.67945 0.3048)
			(end 0.120396 0.3048)
			(stroke
				(width 0.1)
				(type default)
			)
			(layer "F.Fab")
		)
		(fp_line
			(start 0.67945 -0.3048)
			(end 0.67945 0.3048)
			(stroke
				(width 0.1)
				(type default)
			)
			(layer "F.Fab")
		)
		(fp_line
			(start 0.12065 -0.2794)
			(end 0.12065 -0.3048)
			(stroke
				(width 0.1)
				(type default)
			)
			(layer "F.Fab")
		)
		(fp_line
			(start 0.12065 -0.3048)
			(end 0.67945 -0.3048)
			(stroke
				(width 0.1)
				(type default)
			)
			(layer "F.Fab")
		)
		(fp_line
			(start 0.120396 0.3048)
			(end 0.120396 0.2794)
			(stroke
				(width 0.1)
				(type default)
			)
			(layer "F.Fab")
		)
		(fp_line
			(start 0.120396 0.2794)
			(end -0.12065 0.2794)
			(stroke
				(width 0.1)
				(type default)
			)
			(layer "F.Fab")
		)
		(fp_line
			(start -0.12065 0.3048)
			(end -0.67945 0.3048)
			(stroke
				(width 0.1)
				(type default)
			)
			(layer "F.Fab")
		)
		(fp_line
			(start -0.12065 0.2794)
			(end -0.12065 0.3048)
			(stroke
				(width 0.1)
				(type default)
			)
			(layer "F.Fab")
		)
		(fp_line
			(start -0.12065 -0.2794)
			(end 0.12065 -0.2794)
			(stroke
				(width 0.1)
				(type default)
			)
			(layer "F.Fab")
		)
		(fp_line
			(start -0.12065 -0.305054)
			(end -0.12065 -0.2794)
			(stroke
				(width 0.1)
				(type default)
			)
			(layer "F.Fab")
		)
		(fp_line
			(start -0.67945 0.3048)
			(end -0.67945 -0.305054)
			(stroke
				(width 0.1)
				(type default)
			)
			(layer "F.Fab")
		)
		(fp_line
			(start -0.67945 -0.305054)
			(end -0.12065 -0.305054)
			(stroke
				(width 0.1)
				(type default)
			)
			(layer "F.Fab")
		)
		(pad "1" smd circle
			(at -0.40005 0 180)
			(size 0 0)
			(layers "F.Cu" "F.Mask" "F.Paste")
			(net "SW_P1V2_AUX_BST")
		)
		(pad "2" smd circle
			(at 0.40005 0 180)
			(size 0 0)
			(layers "F.Cu" "F.Mask" "F.Paste")
			(net "SW_P1V2_AUX_SW")
		)
	)
	(footprint ""
		(layer "F.Cu")
		(at 46.736 -34.6456 90)
		(property "Reference" "R763"
			(at 0 0 90)
			(layer "F.SilkS")
			(hide yes)
			(effects
				(font
					(size 1.27 1.27)
				)
			)
		)
		(property "Value" ""
			(at 0 0 90)
			(layer "F.Fab")
			(effects
				(font
					(size 1.27 1.27)
				)
			)
		)
		(duplicate_pad_numbers_are_jumpers no)
		(fp_line
			(start 0.7874 -0.4064)
			(end 0.7874 0.4064)
			(stroke
				(width 0.1524)
				(type default)
			)
			(layer "F.SilkS")
		)
		(fp_line
			(start -0.7874 -0.4064)
			(end 0.7874 -0.4064)
			(stroke
				(width 0.1524)
				(type default)
			)
			(layer "F.SilkS")
		)
		(fp_line
			(start 0.7874 0.4064)
			(end -0.7874 0.4064)
			(stroke
				(width 0.1524)
				(type default)
			)
			(layer "F.SilkS")
		)
		(fp_line
			(start -0.7874 0.4064)
			(end -0.7874 -0.4064)
			(stroke
				(width 0.1524)
				(type default)
			)
			(layer "F.SilkS")
		)
		(fp_line
			(start -0.12065 -0.305054)
			(end -0.12065 -0.2794)
			(stroke
				(width 0.1)
				(type default)
			)
			(layer "F.Fab")
		)
		(fp_line
			(start -0.67945 -0.305054)
			(end -0.12065 -0.305054)
			(stroke
				(width 0.1)
				(type default)
			)
			(layer "F.Fab")
		)
		(fp_line
			(start 0.67945 -0.3048)
			(end 0.67945 0.3048)
			(stroke
				(width 0.1)
				(type default)
			)
			(layer "F.Fab")
		)
		(fp_line
			(start 0.12065 -0.3048)
			(end 0.67945 -0.3048)
			(stroke
				(width 0.1)
				(type default)
			)
			(layer "F.Fab")
		)
		(fp_line
			(start 0.12065 -0.2794)
			(end 0.12065 -0.3048)
			(stroke
				(width 0.1)
				(type default)
			)
			(layer "F.Fab")
		)
		(fp_line
			(start -0.12065 -0.2794)
			(end 0.12065 -0.2794)
			(stroke
				(width 0.1)
				(type default)
			)
			(layer "F.Fab")
		)
		(fp_line
			(start 0.120396 0.2794)
			(end -0.12065 0.2794)
			(stroke
				(width 0.1)
				(type default)
			)
			(layer "F.Fab")
		)
		(fp_line
			(start -0.12065 0.2794)
			(end -0.12065 0.3048)
			(stroke
				(width 0.1)
				(type default)
			)
			(layer "F.Fab")
		)
		(fp_line
			(start 0.67945 0.3048)
			(end 0.120396 0.3048)
			(stroke
				(width 0.1)
				(type default)
			)
			(layer "F.Fab")
		)
		(fp_line
			(start 0.120396 0.3048)
			(end 0.120396 0.2794)
			(stroke
				(width 0.1)
				(type default)
			)
			(layer "F.Fab")
		)
		(fp_line
			(start -0.12065 0.3048)
			(end -0.67945 0.3048)
			(stroke
				(width 0.1)
				(type default)
			)
			(layer "F.Fab")
		)
		(fp_line
			(start -0.67945 0.3048)
			(end -0.67945 -0.305054)
			(stroke
				(width 0.1)
				(type default)
			)
			(layer "F.Fab")
		)
		(pad "1" smd circle
			(at -0.40005 0 90)
			(size 0 0)
			(layers "F.Cu" "F.Mask" "F.Paste")
			(net "FM_PCH_BMC_THERMTRIP_N")
		)
		(pad "2" smd circle
			(at 0.40005 0 90)
			(size 0 0)
			(layers "F.Cu" "F.Mask" "F.Paste")
			(net "FM_PLT_BMC_THERMTRIP_N_R")
		)
	)
	(footprint ""
		(layer "F.Cu")
		(at 26.750264 -54.189122)
		(property "Reference" "H1"
			(at -1.7272 -4.511548 0)
			(unlocked yes)
			(layer "B.SilkS")
			(effects
				(font
					(size 0.7874 0.5842)
					(thickness 0.1524)
				)
				(justify left mirror)
			)
		)
		(property "Value" ""
			(at 0 0 0)
			(layer "F.Fab")
			(effects
				(font
					(size 1.27 1.27)
				)
			)
		)
		(duplicate_pad_numbers_are_jumpers no)
		(pad "1" thru_hole circle
			(at 0 0)
			(size 4.5212 4.5212)
			(drill 3.81)
			(layers "*.Cu" "*.Mask")
			(remove_unused_layers no)
			(net "GND")
			(clearance -0.1016)
			(padstack
				(mode front_inner_back)
				(layer "Inner"
					(shape circle)
					(size 5.6134 5.6134)
					(clearance -0.6477)
				)
				(layer "B.Cu"
					(shape circle)
					(size 8.001 8.001)
					(clearance -1.8415)
				)
			)
		)
	)
	(footprint ""
		(layer "F.Cu")
		(at 6.858 -57.404)
		(property "Reference" "PL4"
			(at 0 0 0)
			(layer "F.SilkS")
			(hide yes)
			(effects
				(font
					(size 1.27 1.27)
				)
			)
		)
		(property "Value" ""
			(at 0 0 0)
			(layer "F.Fab")
			(effects
				(font
					(size 1.27 1.27)
				)
			)
		)
		(duplicate_pad_numbers_are_jumpers no)
		(fp_line
			(start -1.27 -0.5842)
			(end 1.27 -0.5842)
			(stroke
				(width 0.1524)
				(type default)
			)
			(layer "F.SilkS")
		)
		(fp_line
			(start -1.27 -0.5588)
			(end -1.27 -0.5842)
			(stroke
				(width 0.1524)
				(type default)
			)
			(layer "F.SilkS")
		)
		(fp_line
			(start -1.27 0.5842)
			(end -1.27 -0.5842)
			(stroke
				(width 0.1524)
				(type default)
			)
			(layer "F.SilkS")
		)
		(fp_line
			(start -0.127 0.5842)
			(end -0.127 -0.5842)
			(stroke
				(width 0.1524)
				(type default)
			)
			(layer "F.SilkS")
		)
		(fp_line
			(start 0.127 0.5842)
			(end 0.127 -0.5842)
			(stroke
				(width 0.1524)
				(type default)
			)
			(layer "F.SilkS")
		)
		(fp_line
			(start 1.27 0.5842)
			(end -1.27 0.5842)
			(stroke
				(width 0.1524)
				(type default)
			)
			(layer "F.SilkS")
		)
		(fp_line
			(start 1.27 0.5842)
			(end 1.27 -0.5842)
			(stroke
				(width 0.1524)
				(type default)
			)
			(layer "F.SilkS")
		)
		(fp_line
			(start -1.194308 -0.406654)
			(end -0.9144 -0.406654)
			(stroke
				(width 0.1)
				(type default)
			)
			(layer "F.Fab")
		)
		(fp_line
			(start -1.194308 0.406654)
			(end -1.194308 -0.406654)
			(stroke
				(width 0.1)
				(type default)
			)
			(layer "F.Fab")
		)
		(fp_line
			(start -0.9144 -0.508)
			(end 0.9144 -0.508)
			(stroke
				(width 0.1)
				(type default)
			)
			(layer "F.Fab")
		)
		(fp_line
			(start -0.9144 -0.406654)
			(end -0.9144 -0.508)
			(stroke
				(width 0.1)
				(type default)
			)
			(layer "F.Fab")
		)
		(fp_line
			(start -0.9144 0.406654)
			(end -1.194308 0.406654)
			(stroke
				(width 0.1)
				(type default)
			)
			(layer "F.Fab")
		)
		(fp_line
			(start -0.9144 0.508)
			(end -0.9144 0.406654)
			(stroke
				(width 0.1)
				(type default)
			)
			(layer "F.Fab")
		)
		(fp_line
			(start 0.9144 -0.508)
			(end 0.9144 -0.406654)
			(stroke
				(width 0.1)
				(type default)
			)
			(layer "F.Fab")
		)
		(fp_line
			(start 0.9144 -0.406654)
			(end 1.1938 -0.406654)
			(stroke
				(width 0.1)
				(type default)
			)
			(layer "F.Fab")
		)
		(fp_line
			(start 0.9144 0.4064)
			(end 0.9144 0.508)
			(stroke
				(width 0.1)
				(type default)
			)
			(layer "F.Fab")
		)
		(fp_line
			(start 0.9144 0.508)
			(end -0.9144 0.508)
			(stroke
				(width 0.1)
				(type default)
			)
			(layer "F.Fab")
		)
		(fp_line
			(start 1.1938 -0.406654)
			(end 1.1938 0.4064)
			(stroke
				(width 0.1)
				(type default)
			)
			(layer "F.Fab")
		)
		(fp_line
			(start 1.1938 0.4064)
			(end 0.9144 0.4064)
			(stroke
				(width 0.1)
				(type default)
			)
			(layer "F.Fab")
		)
		(pad "1" smd rect
			(at -0.7366 0 270)
			(size 0.7112 0.8128)
			(layers "F.Cu" "F.Mask" "F.Paste")
			(net "P12V_AUX")
		)
		(pad "2" smd rect
			(at 0.7366 0 270)
			(size 0.7112 0.8128)
			(layers "F.Cu" "F.Mask" "F.Paste")
			(net "SW_P5V_AUX_FLT")
		)
	)
	(footprint ""
		(layer "F.Cu")
		(at 7.112 -31.837122 -90)
		(property "Reference" "PC213"
			(at 0 0 270)
			(layer "F.SilkS")
			(hide yes)
			(effects
				(font
					(size 1.27 1.27)
				)
			)
		)
		(property "Value" ""
			(at 0 0 270)
			(layer "F.Fab")
			(effects
				(font
					(size 1.27 1.27)
				)
			)
		)
		(duplicate_pad_numbers_are_jumpers no)
		(fp_line
			(start -1.651 0.8382)
			(end -1.651 -0.8382)
			(stroke
				(width 0.1524)
				(type default)
			)
			(layer "F.SilkS")
		)
		(fp_line
			(start 0 0.8382)
			(end 0 -0.8382)
			(stroke
				(width 0.1524)
				(type default)
			)
			(layer "F.SilkS")
		)
		(fp_line
			(start 1.651 0.8382)
			(end -1.651 0.8382)
			(stroke
				(width 0.1524)
				(type default)
			)
			(layer "F.SilkS")
		)
		(fp_line
			(start -1.651 -0.8382)
			(end 1.651 -0.8382)
			(stroke
				(width 0.1524)
				(type default)
			)
			(layer "F.SilkS")
		)
		(fp_line
			(start 1.651 -0.8382)
			(end 1.651 0.8382)
			(stroke
				(width 0.1524)
				(type default)
			)
			(layer "F.SilkS")
		)
		(fp_line
			(start -1.55956 0.7366)
			(end -1.524 0.7366)
			(stroke
				(width 0.1)
				(type default)
			)
			(layer "F.Fab")
		)
		(fp_line
			(start -1.524 0.7366)
			(end 1.524 0.7366)
			(stroke
				(width 0.1)
				(type default)
			)
			(layer "F.Fab")
		)
		(fp_line
			(start 1.524 0.7366)
			(end 1.55956 0.7366)
			(stroke
				(width 0.1)
				(type default)
			)
			(layer "F.Fab")
		)
		(fp_line
			(start 1.55956 0.7366)
			(end 1.55956 -0.7366)
			(stroke
				(width 0.1)
				(type default)
			)
			(layer "F.Fab")
		)
		(fp_line
			(start -1.55956 -0.7366)
			(end -1.55956 0.7366)
			(stroke
				(width 0.1)
				(type default)
			)
			(layer "F.Fab")
		)
		(fp_line
			(start -1.524 -0.7366)
			(end -1.55956 -0.7366)
			(stroke
				(width 0.1)
				(type default)
			)
			(layer "F.Fab")
		)
		(fp_line
			(start 1.524 -0.7366)
			(end -1.524 -0.7366)
			(stroke
				(width 0.1)
				(type default)
			)
			(layer "F.Fab")
		)
		(fp_line
			(start 1.55956 -0.7366)
			(end 1.524 -0.7366)
			(stroke
				(width 0.1)
				(type default)
			)
			(layer "F.Fab")
		)
		(pad "1" smd rect
			(at -0.94996 0 90)
			(size 1.1176 1.3716)
			(layers "F.Cu" "F.Mask" "F.Paste")
			(net "P5V_AUX")
		)
		(pad "2" smd rect
			(at 0.94996 0 90)
			(size 1.1176 1.3716)
			(layers "F.Cu" "F.Mask" "F.Paste")
			(net "GND")
		)
	)
	(footprint ""
		(layer "F.Cu")
		(at 76.252324 -47.907448)
		(property "Reference" "U1"
			(at -4.664456 -10.397744 0)
			(unlocked yes)
			(layer "F.SilkS")
			(effects
				(font
					(size 0.7874 0.5842)
					(thickness 0.1524)
				)
				(justify left)
			)
		)
		(property "Value" ""
			(at 0 0 0)
			(layer "F.Fab")
			(effects
				(font
					(size 1.27 1.27)
				)
			)
		)
		(duplicate_pad_numbers_are_jumpers no)
		(fp_line
			(start -6.800088 -9.700006)
			(end 0.418846 -9.700006)
			(stroke
				(width 0.1524)
				(type default)
			)
			(layer "F.SilkS")
		)
		(fp_line
			(start -6.800088 -8.030972)
			(end -6.800088 -9.700006)
			(stroke
				(width 0.1524)
				(type default)
			)
			(layer "F.SilkS")
		)
		(fp_line
			(start -6.800088 -5.976112)
			(end -6.800088 -7.147052)
			(stroke
				(width 0.1524)
				(type default)
			)
			(layer "F.SilkS")
		)
		(fp_line
			(start -6.800088 -4.261612)
			(end -6.800088 -5.069332)
			(stroke
				(width 0.1524)
				(type default)
			)
			(layer "F.SilkS")
		)
		(fp_line
			(start -6.800088 -3.088132)
			(end -6.800088 -3.357372)
			(stroke
				(width 0.1524)
				(type default)
			)
			(layer "F.SilkS")
		)
		(fp_line
			(start -6.800088 -0.936752)
			(end -6.800088 -1.876552)
			(stroke
				(width 0.1524)
				(type default)
			)
			(layer "F.SilkS")
		)
		(fp_line
			(start -6.800088 5.718048)
			(end -6.800088 0.333248)
			(stroke
				(width 0.1524)
				(type default)
			)
			(layer "F.SilkS")
		)
		(fp_line
			(start -6.800088 9.700006)
			(end -6.800088 6.886448)
			(stroke
				(width 0.1524)
				(type default)
			)
			(layer "F.SilkS")
		)
		(fp_line
			(start -3.800094 -6.700012)
			(end 3.800094 -6.700012)
			(stroke
				(width 0.1524)
				(type default)
			)
			(layer "F.SilkS")
		)
		(fp_line
			(start -3.800094 6.700012)
			(end -3.800094 -6.700012)
			(stroke
				(width 0.1524)
				(type default)
			)
			(layer "F.SilkS")
		)
		(fp_line
			(start -0.103124 9.700006)
			(end -6.800088 9.700006)
			(stroke
				(width 0.1524)
				(type default)
			)
			(layer "F.SilkS")
		)
		(fp_line
			(start 2.214626 -9.700006)
			(end 2.566416 -9.700006)
			(stroke
				(width 0.1524)
				(type default)
			)
			(layer "F.SilkS")
		)
		(fp_line
			(start 3.800094 -6.700012)
			(end 3.800094 6.700012)
			(stroke
				(width 0.1524)
				(type default)
			)
			(layer "F.SilkS")
		)
		(fp_line
			(start 3.800094 6.700012)
			(end -3.800094 6.700012)
			(stroke
				(width 0.1524)
				(type default)
			)
			(layer "F.SilkS")
		)
		(fp_line
			(start 4.313682 -9.700006)
			(end 4.71424 -9.700006)
			(stroke
				(width 0.1524)
				(type default)
			)
			(layer "F.SilkS")
		)
		(fp_line
			(start 6.485636 -9.700006)
			(end 6.800088 -9.700006)
			(stroke
				(width 0.1524)
				(type default)
			)
			(layer "F.SilkS")
		)
		(fp_line
			(start 6.800088 -9.700006)
			(end 6.800088 -0.123952)
			(stroke
				(width 0.1524)
				(type default)
			)
			(layer "F.SilkS")
		)
		(fp_line
			(start 6.800088 1.120648)
			(end 6.800088 3.025648)
			(stroke
				(width 0.1524)
				(type default)
			)
			(layer "F.SilkS")
		)
		(fp_line
			(start 6.800088 4.194048)
			(end 6.800088 5.464048)
			(stroke
				(width 0.1524)
				(type default)
			)
			(layer "F.SilkS")
		)
		(fp_line
			(start 6.800088 7.038848)
			(end 6.800088 9.700006)
			(stroke
				(width 0.1524)
				(type default)
			)
			(layer "F.SilkS")
		)
		(fp_line
			(start 6.800088 9.700006)
			(end 5.256276 9.700006)
			(stroke
				(width 0.1524)
				(type default)
			)
			(layer "F.SilkS")
		)
		(fp_poly
			(pts
				(xy -6.7818 -9.6774) (xy -2.9972 -9.7028) (xy -2.993898 -9.70534) (xy -4.241038 -8.4582) (xy -2.563368 -6.78053)
				(xy -2.587498 -6.7564) (xy -3.809238 -6.7564) (xy -3.809238 -5.5626) (xy -3.847338 -5.5245) (xy -5.511038 -7.1882)
				(xy -6.755638 -5.9436) (xy -6.781038 -5.969)
			)
			(stroke
				(width 0)
				(type default)
			)
			(fill yes)
			(layer "F.SilkS")
		)
		(fp_line
			(start -3.800094 -6.700012)
			(end 3.800094 -6.700012)
			(stroke
				(width 0.1)
				(type default)
			)
			(layer "F.Fab")
		)
		(fp_line
			(start -3.800094 6.700012)
			(end -3.800094 -6.700012)
			(stroke
				(width 0.1)
				(type default)
			)
			(layer "F.Fab")
		)
		(fp_line
			(start 3.800094 -6.700012)
			(end 3.800094 6.700012)
			(stroke
				(width 0.1)
				(type default)
			)
			(layer "F.Fab")
		)
		(fp_line
			(start 3.800094 6.700012)
			(end -3.800094 6.700012)
			(stroke
				(width 0.1)
				(type default)
			)
			(layer "F.Fab")
		)
		(fp_text user "A"
			(at -5.496052 -5.769356 0)
			(unlocked yes)
			(layer "F.SilkS")
			(effects
				(font
					(size 0.635 0.4064)
					(thickness 0.1524)
				)
				(justify left)
			)
		)
		(fp_text user "C"
			(at -5.496052 -4.169156 0)
			(unlocked yes)
			(layer "F.SilkS")
			(effects
				(font
					(size 0.635 0.4064)
					(thickness 0.1524)
				)
				(justify left)
			)
		)
		(fp_text user "E"
			(at -5.496052 -2.56921 0)
			(unlocked yes)
			(layer "F.SilkS")
			(effects
				(font
					(size 0.635 0.4064)
					(thickness 0.1524)
				)
				(justify left)
			)
		)
		(fp_text user "G"
			(at -5.496052 -0.969264 0)
			(unlocked yes)
			(layer "F.SilkS")
			(effects
				(font
					(size 0.635 0.4064)
					(thickness 0.1524)
				)
				(justify left)
			)
		)
		(fp_text user "J"
			(at -5.496052 0.630682 0)
			(unlocked yes)
			(layer "F.SilkS")
			(effects
				(font
					(size 0.635 0.4064)
					(thickness 0.1524)
				)
				(justify left)
			)
		)
		(fp_text user "L"
			(at -5.496052 2.230882 0)
			(unlocked yes)
			(layer "F.SilkS")
			(effects
				(font
					(size 0.635 0.4064)
					(thickness 0.1524)
				)
				(justify left)
			)
		)
		(fp_text user "N"
			(at -5.496052 3.830828 0)
			(unlocked yes)
			(layer "F.SilkS")
			(effects
				(font
					(size 0.635 0.4064)
					(thickness 0.1524)
				)
				(justify left)
			)
		)
		(fp_text user "R"
			(at -5.496052 5.430774 0)
			(unlocked yes)
			(layer "F.SilkS")
			(effects
				(font
					(size 0.635 0.4064)
					(thickness 0.1524)
				)
				(justify left)
			)
		)
		(fp_text user "T"
			(at -4.68503 6.241288 0)
			(unlocked yes)
			(layer "F.SilkS")
			(effects
				(font
					(size 0.635 0.4064)
					(thickness 0.1524)
				)
				(justify left)
			)
		)
		(fp_text user "B"
			(at -4.677156 -5.096256 0)
			(unlocked yes)
			(layer "F.SilkS")
			(effects
				(font
					(size 0.635 0.4064)
					(thickness 0.1524)
				)
				(justify left)
			)
		)
		(fp_text user "D"
			(at -4.677156 -3.49631 0)
			(unlocked yes)
			(layer "F.SilkS")
			(effects
				(font
					(size 0.635 0.4064)
					(thickness 0.1524)
				)
				(justify left)
			)
		)
		(fp_text user "F"
			(at -4.677156 -1.896364 0)
			(unlocked yes)
			(layer "F.SilkS")
			(effects
				(font
					(size 0.635 0.4064)
					(thickness 0.1524)
				)
				(justify left)
			)
		)
		(fp_text user "H"
			(at -4.677156 -0.296164 0)
			(unlocked yes)
			(layer "F.SilkS")
			(effects
				(font
					(size 0.635 0.4064)
					(thickness 0.1524)
				)
				(justify left)
			)
		)
		(fp_text user "K"
			(at -4.677156 1.303782 0)
			(unlocked yes)
			(layer "F.SilkS")
			(effects
				(font
					(size 0.635 0.4064)
					(thickness 0.1524)
				)
				(justify left)
			)
		)
		(fp_text user "M"
			(at -4.677156 2.903728 0)
			(unlocked yes)
			(layer "F.SilkS")
			(effects
				(font
					(size 0.635 0.4064)
					(thickness 0.1524)
				)
				(justify left)
			)
		)
		(fp_text user "P"
			(at -4.677156 4.503674 0)
			(unlocked yes)
			(layer "F.SilkS")
			(effects
				(font
					(size 0.635 0.4064)
					(thickness 0.1524)
				)
				(justify left)
			)
		)
		(fp_text user "1"
			(at -3.292094 -7.897114 0)
			(unlocked yes)
			(layer "F.SilkS")
			(effects
				(font
					(size 0.635 0.4064)
					(thickness 0.1524)
				)
				(justify left)
			)
		)
		(fp_text user "2"
			(at -2.491994 -7.897114 0)
			(unlocked yes)
			(layer "F.SilkS")
			(effects
				(font
					(size 0.635 0.4064)
					(thickness 0.1524)
				)
				(justify left)
			)
		)
		(fp_text user "3"
			(at -1.692148 -7.897114 0)
			(unlocked yes)
			(layer "F.SilkS")
			(effects
				(font
					(size 0.635 0.4064)
					(thickness 0.1524)
				)
				(justify left)
			)
		)
		(fp_text user "7"
			(at 1.507998 -7.897114 0)
			(unlocked yes)
			(layer "F.SilkS")
			(effects
				(font
					(size 0.635 0.4064)
					(thickness 0.1524)
				)
				(justify left)
			)
		)
		(fp_text user "8"
			(at 2.307844 -7.897114 0)
			(unlocked yes)
			(layer "F.SilkS")
			(effects
				(font
					(size 0.635 0.4064)
					(thickness 0.1524)
				)
				(justify left)
			)
		)
		(fp_text user "9"
			(at 3.107944 -7.897114 0)
			(unlocked yes)
			(layer "F.SilkS")
			(effects
				(font
					(size 0.635 0.4064)
					(thickness 0.1524)
				)
				(justify left)
			)
		)
		(fp_text user "A"
			(at -5.496052 -5.769356 0)
			(unlocked yes)
			(layer "F.Fab")
			(effects
				(font
					(size 0.635 0.4064)
					(thickness 0.1524)
				)
				(justify left)
			)
		)
		(fp_text user "T"
			(at -4.68503 6.241288 0)
			(unlocked yes)
			(layer "F.Fab")
			(effects
				(font
					(size 0.635 0.4064)
					(thickness 0.1524)
				)
				(justify left)
			)
		)
		(fp_text user "1"
			(at -3.292094 -7.897114 0)
			(unlocked yes)
			(layer "F.Fab")
			(effects
				(font
					(size 0.635 0.4064)
					(thickness 0.1524)
				)
				(justify left)
			)
		)
		(fp_text user "9"
			(at 3.107944 -7.897114 0)
			(unlocked yes)
			(layer "F.Fab")
			(effects
				(font
					(size 0.635 0.4064)
					(thickness 0.1524)
				)
				(justify left)
			)
		)
		(pad "A1" smd circle
			(at -3.199892 -5.999988)
			(size 0.3683 0.3683)
			(layers "F.Cu" "F.Mask" "F.Paste")
			(net "P1V2_AUX")
		)
		(pad "A2" smd circle
			(at -2.400046 -5.999988)
			(size 0.3683 0.3683)
			(layers "F.Cu" "F.Mask" "F.Paste")
			(net "GND")
		)
		(pad "A3" smd circle
			(at -1.599946 -5.999988)
			(size 0.3683 0.3683)
			(layers "F.Cu" "F.Mask" "F.Paste")
			(net "M_BMC_DDR4_DQ<8>")
		)
		(pad "A7" smd circle
			(at 1.599946 -5.999988)
			(size 0.3683 0.3683)
			(layers "F.Cu" "F.Mask" "F.Paste")
			(net "M_BMC_DDR4_DQS1_N")
		)
		(pad "A8" smd circle
			(at 2.400046 -5.999988)
			(size 0.3683 0.3683)
			(layers "F.Cu" "F.Mask" "F.Paste")
			(net "GND")
		)
		(pad "A9" smd circle
			(at 3.199892 -5.999988)
			(size 0.3683 0.3683)
			(layers "F.Cu" "F.Mask" "F.Paste")
			(net "P1V2_AUX")
		)
		(pad "B1" smd circle
			(at -3.199892 -5.199888)
			(size 0.3683 0.3683)
			(layers "F.Cu" "F.Mask" "F.Paste")
			(net "P2V5_AUX")
		)
		(pad "B2" smd circle
			(at -2.400046 -5.199888)
			(size 0.3683 0.3683)
			(layers "F.Cu" "F.Mask" "F.Paste")
			(net "GND")
		)
		(pad "B3" smd circle
			(at -1.599946 -5.199888)
			(size 0.3683 0.3683)
			(layers "F.Cu" "F.Mask" "F.Paste")
			(net "P1V2_AUX")
		)
		(pad "B7" smd circle
			(at 1.599946 -5.199888)
			(size 0.3683 0.3683)
			(layers "F.Cu" "F.Mask" "F.Paste")
			(net "M_BMC_DDR4_DQS1_P")
		)
		(pad "B8" smd circle
			(at 2.400046 -5.199888)
			(size 0.3683 0.3683)
			(layers "F.Cu" "F.Mask" "F.Paste")
			(net "M_BMC_DDR4_DQ<9>")
		)
		(pad "B9" smd circle
			(at 3.199892 -5.199888)
			(size 0.3683 0.3683)
			(layers "F.Cu" "F.Mask" "F.Paste")
			(net "P1V2_AUX")
		)
		(pad "C1" smd circle
			(at -3.199892 -4.400042)
			(size 0.3683 0.3683)
			(layers "F.Cu" "F.Mask" "F.Paste")
			(net "P1V2_AUX")
		)
		(pad "C2" smd circle
			(at -2.400046 -4.400042)
			(size 0.3683 0.3683)
			(layers "F.Cu" "F.Mask" "F.Paste")
			(net "M_BMC_DDR4_DQ<12>")
		)
		(pad "C3" smd circle
			(at -1.599946 -4.400042)
			(size 0.3683 0.3683)
			(layers "F.Cu" "F.Mask" "F.Paste")
			(net "M_BMC_DDR4_DQ<10>")
		)
		(pad "C7" smd circle
			(at 1.599946 -4.400042)
			(size 0.3683 0.3683)
			(layers "F.Cu" "F.Mask" "F.Paste")
			(net "M_BMC_DDR4_DQ<11>")
		)
		(pad "C8" smd circle
			(at 2.400046 -4.400042)
			(size 0.3683 0.3683)
			(layers "F.Cu" "F.Mask" "F.Paste")
			(net "M_BMC_DDR4_DQ<13>")
		)
		(pad "C9" smd circle
			(at 3.199892 -4.400042)
			(size 0.3683 0.3683)
			(layers "F.Cu" "F.Mask" "F.Paste")
			(net "GND")
		)
		(pad "D1" smd circle
			(at -3.199892 -3.599942)
			(size 0.3683 0.3683)
			(layers "F.Cu" "F.Mask" "F.Paste")
			(net "P1V2_AUX")
		)
		(pad "D2" smd circle
			(at -2.400046 -3.599942)
			(size 0.3683 0.3683)
			(layers "F.Cu" "F.Mask" "F.Paste")
			(net "GND")
		)
		(pad "D3" smd circle
			(at -1.599946 -3.599942)
			(size 0.3683 0.3683)
			(layers "F.Cu" "F.Mask" "F.Paste")
			(net "M_BMC_DDR4_DQ<14>")
		)
		(pad "D7" smd circle
			(at 1.599946 -3.599942)
			(size 0.3683 0.3683)
			(layers "F.Cu" "F.Mask" "F.Paste")
			(net "M_BMC_DDR4_DQ<15>")
		)
		(pad "D8" smd circle
			(at 2.400046 -3.599942)
			(size 0.3683 0.3683)
			(layers "F.Cu" "F.Mask" "F.Paste")
			(net "GND")
		)
		(pad "D9" smd circle
			(at 3.199892 -3.599942)
			(size 0.3683 0.3683)
			(layers "F.Cu" "F.Mask" "F.Paste")
			(net "P1V2_AUX")
		)
		(pad "E1" smd circle
			(at -3.199892 -2.800096)
			(size 0.3683 0.3683)
			(layers "F.Cu" "F.Mask" "F.Paste")
			(net "GND")
		)
		(pad "E2" smd circle
			(at -2.400046 -2.800096)
			(size 0.3683 0.3683)
			(layers "F.Cu" "F.Mask" "F.Paste")
			(net "M_BMC_DDR4_MDM1")
		)
		(pad "E3" smd circle
			(at -1.599946 -2.800096)
			(size 0.3683 0.3683)
			(layers "F.Cu" "F.Mask" "F.Paste")
			(net "GND")
		)
		(pad "E7" smd circle
			(at 1.599946 -2.800096)
			(size 0.3683 0.3683)
			(layers "F.Cu" "F.Mask" "F.Paste")
			(net "M_BMC_DDR4_MDM0")
		)
		(pad "E8" smd circle
			(at 2.400046 -2.800096)
			(size 0.3683 0.3683)
			(layers "F.Cu" "F.Mask" "F.Paste")
			(net "GND")
		)
		(pad "E9" smd circle
			(at 3.199892 -2.800096)
			(size 0.3683 0.3683)
			(layers "F.Cu" "F.Mask" "F.Paste")
			(net "M_BMC_DDR4_ZQU")
		)
		(pad "F1" smd circle
			(at -3.199892 -1.999996)
			(size 0.3683 0.3683)
			(layers "F.Cu" "F.Mask" "F.Paste")
			(net "GND")
		)
		(pad "F2" smd circle
			(at -2.400046 -1.999996)
			(size 0.3683 0.3683)
			(layers "F.Cu" "F.Mask" "F.Paste")
			(net "P1V2_AUX")
		)
		(pad "F3" smd circle
			(at -1.599946 -1.999996)
			(size 0.3683 0.3683)
			(layers "F.Cu" "F.Mask" "F.Paste")
			(net "M_BMC_DDR4_DQS0_N")
		)
		(pad "F7" smd circle
			(at 1.599946 -1.999996)
			(size 0.3683 0.3683)
			(layers "F.Cu" "F.Mask" "F.Paste")
			(net "M_BMC_DDR4_DQ<1>")
		)
		(pad "F8" smd circle
			(at 2.400046 -1.999996)
			(size 0.3683 0.3683)
			(layers "F.Cu" "F.Mask" "F.Paste")
			(net "P1V2_AUX")
		)
		(pad "F9" smd circle
			(at 3.199892 -1.999996)
			(size 0.3683 0.3683)
			(layers "F.Cu" "F.Mask" "F.Paste")
			(net "PD_M_BMC_DDR4_ZQ")
		)
		(pad "G1" smd circle
			(at -3.199892 -1.199896)
			(size 0.3683 0.3683)
			(layers "F.Cu" "F.Mask" "F.Paste")
			(net "P1V2_AUX")
		)
		(pad "G2" smd circle
			(at -2.400046 -1.199896)
			(size 0.3683 0.3683)
			(layers "F.Cu" "F.Mask" "F.Paste")
			(net "M_BMC_DDR4_DQ<0>")
		)
		(pad "G3" smd circle
			(at -1.599946 -1.199896)
			(size 0.3683 0.3683)
			(layers "F.Cu" "F.Mask" "F.Paste")
			(net "M_BMC_DDR4_DQS0_P")
		)
		(pad "G7" smd circle
			(at 1.599946 -1.199896)
			(size 0.3683 0.3683)
			(layers "F.Cu" "F.Mask" "F.Paste")
			(net "P1V2_AUX")
		)
		(pad "G8" smd circle
			(at 2.400046 -1.199896)
			(size 0.3683 0.3683)
			(layers "F.Cu" "F.Mask" "F.Paste")
			(net "GND")
		)
		(pad "G9" smd circle
			(at 3.199892 -1.199896)
			(size 0.3683 0.3683)
			(layers "F.Cu" "F.Mask" "F.Paste")
			(net "P1V2_AUX")
		)
		(pad "H1" smd circle
			(at -3.199892 -0.40005)
			(size 0.3683 0.3683)
			(layers "F.Cu" "F.Mask" "F.Paste")
			(net "GND")
		)
		(pad "H2" smd circle
			(at -2.400046 -0.40005)
			(size 0.3683 0.3683)
			(layers "F.Cu" "F.Mask" "F.Paste")
			(net "M_BMC_DDR4_DQ<4>")
		)
		(pad "H3" smd circle
			(at -1.599946 -0.40005)
			(size 0.3683 0.3683)
			(layers "F.Cu" "F.Mask" "F.Paste")
			(net "M_BMC_DDR4_DQ<2>")
		)
		(pad "H7" smd circle
			(at 1.599946 -0.40005)
			(size 0.3683 0.3683)
			(layers "F.Cu" "F.Mask" "F.Paste")
			(net "M_BMC_DDR4_DQ<3>")
		)
		(pad "H8" smd circle
			(at 2.400046 -0.40005)
			(size 0.3683 0.3683)
			(layers "F.Cu" "F.Mask" "F.Paste")
			(net "M_BMC_DDR4_DQ<5>")
		)
		(pad "H9" smd circle
			(at 3.199892 -0.40005)
			(size 0.3683 0.3683)
			(layers "F.Cu" "F.Mask" "F.Paste")
			(net "GND")
		)
		(pad "J1" smd circle
			(at -3.199892 0.40005)
			(size 0.3683 0.3683)
			(layers "F.Cu" "F.Mask" "F.Paste")
			(net "P1V2_AUX")
		)
		(pad "J2" smd circle
			(at -2.400046 0.40005)
			(size 0.3683 0.3683)
			(layers "F.Cu" "F.Mask" "F.Paste")
			(net "P1V2_AUX")
		)
		(pad "J3" smd circle
			(at -1.599946 0.40005)
			(size 0.3683 0.3683)
			(layers "F.Cu" "F.Mask" "F.Paste")
			(net "M_BMC_DDR4_DQ<6>")
		)
		(pad "J7" smd circle
			(at 1.599946 0.40005)
			(size 0.3683 0.3683)
			(layers "F.Cu" "F.Mask" "F.Paste")
			(net "M_BMC_DDR4_DQ<7>")
		)
		(pad "J8" smd circle
			(at 2.400046 0.40005)
			(size 0.3683 0.3683)
			(layers "F.Cu" "F.Mask" "F.Paste")
			(net "P1V2_AUX")
		)
		(pad "J9" smd circle
			(at 3.199892 0.40005)
			(size 0.3683 0.3683)
			(layers "F.Cu" "F.Mask" "F.Paste")
			(net "P1V2_AUX")
		)
		(pad "K1" smd circle
			(at -3.199892 1.199896)
			(size 0.3683 0.3683)
			(layers "F.Cu" "F.Mask" "F.Paste")
			(net "GND")
		)
		(pad "K2" smd circle
			(at -2.400046 1.199896)
			(size 0.3683 0.3683)
			(layers "F.Cu" "F.Mask" "F.Paste")
			(net "M_BMC_DDR4_MCKE")
		)
		(pad "K3" smd circle
			(at -1.599946 1.199896)
			(size 0.3683 0.3683)
			(layers "F.Cu" "F.Mask" "F.Paste")
			(net "M_BMC_DDR4_MODT")
		)
		(pad "K7" smd circle
			(at 1.599946 1.199896)
			(size 0.3683 0.3683)
			(layers "F.Cu" "F.Mask" "F.Paste")
			(net "M_BMC_DDR4_MCLK_DP")
		)
		(pad "K8" smd circle
			(at 2.400046 1.199896)
			(size 0.3683 0.3683)
			(layers "F.Cu" "F.Mask" "F.Paste")
			(net "M_BMC_DDR4_MCLK_DN")
		)
		(pad "K9" smd circle
			(at 3.199892 1.199896)
			(size 0.3683 0.3683)
			(layers "F.Cu" "F.Mask" "F.Paste")
			(net "GND")
		)
		(pad "L1" smd circle
			(at -3.199892 1.999996)
			(size 0.3683 0.3683)
			(layers "F.Cu" "F.Mask" "F.Paste")
			(net "P1V2_AUX")
		)
		(pad "L2" smd circle
			(at -2.400046 1.999996)
			(size 0.3683 0.3683)
			(layers "F.Cu" "F.Mask" "F.Paste")
			(net "M_BMC_DDR4_MWE_N")
		)
		(pad "L3" smd circle
			(at -1.599946 1.999996)
			(size 0.3683 0.3683)
			(layers "F.Cu" "F.Mask" "F.Paste")
			(net "M_BMC_DDR4_MACT_N")
		)
		(pad "L7" smd circle
			(at 1.599946 1.999996)
			(size 0.3683 0.3683)
			(layers "F.Cu" "F.Mask" "F.Paste")
			(net "M_BMC_DDR4_MCS_N")
		)
		(pad "L8" smd circle
			(at 2.400046 1.999996)
			(size 0.3683 0.3683)
			(layers "F.Cu" "F.Mask" "F.Paste")
			(net "M_BMC_DDR4_MRAS_N")
		)
		(pad "L9" smd circle
			(at 3.199892 1.999996)
			(size 0.3683 0.3683)
			(layers "F.Cu" "F.Mask" "F.Paste")
			(net "P1V2_AUX")
		)
		(pad "M1" smd circle
			(at -3.199892 2.800096)
			(size 0.3683 0.3683)
			(layers "F.Cu" "F.Mask" "F.Paste")
			(net "P0V6_DDR_VREF_AUX")
		)
		(pad "M2" smd circle
			(at -2.400046 2.800096)
			(size 0.3683 0.3683)
			(layers "F.Cu" "F.Mask" "F.Paste")
			(net "M_BMC_DDR4_MBG0")
		)
		(pad "M3" smd circle
			(at -1.599946 2.800096)
			(size 0.3683 0.3683)
			(layers "F.Cu" "F.Mask" "F.Paste")
			(net "M_BMC_DDR4_MA<10>")
		)
		(pad "M7" smd circle
			(at 1.599946 2.800096)
			(size 0.3683 0.3683)
			(layers "F.Cu" "F.Mask" "F.Paste")
			(net "M_BMC_DDR4_MA<12>")
		)
		(pad "M8" smd circle
			(at 2.400046 2.800096)
			(size 0.3683 0.3683)
			(layers "F.Cu" "F.Mask" "F.Paste")
			(net "M_BMC_DDR4_MCAS_N")
		)
		(pad "M9" smd circle
			(at 3.199892 2.800096)
			(size 0.3683 0.3683)
			(layers "F.Cu" "F.Mask" "F.Paste")
			(net "M_BMC_DDR4_BG1")
		)
		(pad "N1" smd circle
			(at -3.199892 3.599942)
			(size 0.3683 0.3683)
			(layers "F.Cu" "F.Mask" "F.Paste")
			(net "GND")
		)
		(pad "N2" smd circle
			(at -2.400046 3.599942)
			(size 0.3683 0.3683)
			(layers "F.Cu" "F.Mask" "F.Paste")
			(net "M_BMC_DDR4_MBA0")
		)
		(pad "N3" smd circle
			(at -1.599946 3.599942)
			(size 0.3683 0.3683)
			(layers "F.Cu" "F.Mask" "F.Paste")
			(net "M_BMC_DDR4_MA<4>")
		)
		(pad "N7" smd circle
			(at 1.599946 3.599942)
			(size 0.3683 0.3683)
			(layers "F.Cu" "F.Mask" "F.Paste")
			(net "M_BMC_DDR4_MA<3>")
		)
		(pad "N8" smd circle
			(at 2.400046 3.599942)
			(size 0.3683 0.3683)
			(layers "F.Cu" "F.Mask" "F.Paste")
			(net "M_BMC_DDR4_MBA1")
		)
		(pad "N9" smd circle
			(at 3.199892 3.599942)
			(size 0.3683 0.3683)
			(layers "F.Cu" "F.Mask" "F.Paste")
			(net "PD_M_BMC_DDR4_TEN")
		)
		(pad "P1" smd circle
			(at -3.199892 4.400042)
			(size 0.3683 0.3683)
			(layers "F.Cu" "F.Mask" "F.Paste")
			(net "M_BMC_DDR4_RST_N")
		)
		(pad "P2" smd circle
			(at -2.400046 4.400042)
			(size 0.3683 0.3683)
			(layers "F.Cu" "F.Mask" "F.Paste")
			(net "M_BMC_DDR4_MA<6>")
		)
		(pad "P3" smd circle
			(at -1.599946 4.400042)
			(size 0.3683 0.3683)
			(layers "F.Cu" "F.Mask" "F.Paste")
			(net "M_BMC_DDR4_MA<0>")
		)
		(pad "P7" smd circle
			(at 1.599946 4.400042)
			(size 0.3683 0.3683)
			(layers "F.Cu" "F.Mask" "F.Paste")
			(net "M_BMC_DDR4_MA<1>")
		)
		(pad "P8" smd circle
			(at 2.400046 4.400042)
			(size 0.3683 0.3683)
			(layers "F.Cu" "F.Mask" "F.Paste")
			(net "M_BMC_DDR4_MA<5>")
		)
		(pad "P9" smd circle
			(at 3.199892 4.400042)
			(size 0.3683 0.3683)
			(layers "F.Cu" "F.Mask" "F.Paste")
			(net "M_BMC_DDR4_ALERT_N")
		)
		(pad "R1" smd circle
			(at -3.199892 5.199888)
			(size 0.3683 0.3683)
			(layers "F.Cu" "F.Mask" "F.Paste")
			(net "P1V2_AUX")
		)
		(pad "R2" smd circle
			(at -2.400046 5.199888)
			(size 0.3683 0.3683)
			(layers "F.Cu" "F.Mask" "F.Paste")
			(net "M_BMC_DDR4_MA<8>")
		)
		(pad "R3" smd circle
			(at -1.599946 5.199888)
			(size 0.3683 0.3683)
			(layers "F.Cu" "F.Mask" "F.Paste")
			(net "M_BMC_DDR4_MA<2>")
		)
		(pad "R7" smd circle
			(at 1.599946 5.199888)
			(size 0.3683 0.3683)
			(layers "F.Cu" "F.Mask" "F.Paste")
			(net "M_BMC_DDR4_MA<9>")
		)
		(pad "R8" smd circle
			(at 2.400046 5.199888)
			(size 0.3683 0.3683)
			(layers "F.Cu" "F.Mask" "F.Paste")
			(net "M_BMC_DDR4_MA<7>")
		)
		(pad "R9" smd circle
			(at 3.199892 5.199888)
			(size 0.3683 0.3683)
			(layers "F.Cu" "F.Mask" "F.Paste")
			(net "P2V5_AUX")
		)
		(pad "T1" smd circle
			(at -3.199892 5.999988)
			(size 0.3683 0.3683)
			(layers "F.Cu" "F.Mask" "F.Paste")
			(net "GND")
		)
		(pad "T2" smd circle
			(at -2.400046 5.999988)
			(size 0.3683 0.3683)
			(layers "F.Cu" "F.Mask" "F.Paste")
			(net "M_BMC_DDR4_MA<11>")
		)
		(pad "T3" smd circle
			(at -1.599946 5.999988)
			(size 0.3683 0.3683)
			(layers "F.Cu" "F.Mask" "F.Paste")
			(net "PD_M_BMC_DDR4_PAR")
		)
		(pad "T7" smd circle
			(at 1.599946 5.999988)
			(size 0.3683 0.3683)
			(layers "F.Cu" "F.Mask" "F.Paste")
			(net "GND")
		)
		(pad "T8" smd circle
			(at 2.400046 5.999988)
			(size 0.3683 0.3683)
			(layers "F.Cu" "F.Mask" "F.Paste")
			(net "M_BMC_DDR4_MA<13>")
		)
		(pad "T9" smd circle
			(at 3.199892 5.999988)
			(size 0.3683 0.3683)
			(layers "F.Cu" "F.Mask" "F.Paste")
			(net "P1V2_AUX")
		)
	)
	(footprint ""
		(layer "F.Cu")
		(at 78.723744 -35.527488 90)
		(property "Reference" "R336"
			(at 0 0 90)
			(layer "F.SilkS")
			(hide yes)
			(effects
				(font
					(size 1.27 1.27)
				)
			)
		)
		(property "Value" ""
			(at 0 0 90)
			(layer "F.Fab")
			(effects
				(font
					(size 1.27 1.27)
				)
			)
		)
		(duplicate_pad_numbers_are_jumpers no)
		(fp_line
			(start 0.7874 -0.4064)
			(end 0.7874 0.4064)
			(stroke
				(width 0.1524)
				(type default)
			)
			(layer "F.SilkS")
		)
		(fp_line
			(start -0.7874 -0.4064)
			(end 0.7874 -0.4064)
			(stroke
				(width 0.1524)
				(type default)
			)
			(layer "F.SilkS")
		)
		(fp_line
			(start 0.7874 0.4064)
			(end -0.7874 0.4064)
			(stroke
				(width 0.1524)
				(type default)
			)
			(layer "F.SilkS")
		)
		(fp_line
			(start -0.7874 0.4064)
			(end -0.7874 -0.4064)
			(stroke
				(width 0.1524)
				(type default)
			)
			(layer "F.SilkS")
		)
		(fp_line
			(start -0.12065 -0.305054)
			(end -0.12065 -0.2794)
			(stroke
				(width 0.1)
				(type default)
			)
			(layer "F.Fab")
		)
		(fp_line
			(start -0.67945 -0.305054)
			(end -0.12065 -0.305054)
			(stroke
				(width 0.1)
				(type default)
			)
			(layer "F.Fab")
		)
		(fp_line
			(start 0.67945 -0.3048)
			(end 0.67945 0.3048)
			(stroke
				(width 0.1)
				(type default)
			)
			(layer "F.Fab")
		)
		(fp_line
			(start 0.12065 -0.3048)
			(end 0.67945 -0.3048)
			(stroke
				(width 0.1)
				(type default)
			)
			(layer "F.Fab")
		)
		(fp_line
			(start 0.12065 -0.2794)
			(end 0.12065 -0.3048)
			(stroke
				(width 0.1)
				(type default)
			)
			(layer "F.Fab")
		)
		(fp_line
			(start -0.12065 -0.2794)
			(end 0.12065 -0.2794)
			(stroke
				(width 0.1)
				(type default)
			)
			(layer "F.Fab")
		)
		(fp_line
			(start 0.120396 0.2794)
			(end -0.12065 0.2794)
			(stroke
				(width 0.1)
				(type default)
			)
			(layer "F.Fab")
		)
		(fp_line
			(start -0.12065 0.2794)
			(end -0.12065 0.3048)
			(stroke
				(width 0.1)
				(type default)
			)
			(layer "F.Fab")
		)
		(fp_line
			(start 0.67945 0.3048)
			(end 0.120396 0.3048)
			(stroke
				(width 0.1)
				(type default)
			)
			(layer "F.Fab")
		)
		(fp_line
			(start 0.120396 0.3048)
			(end 0.120396 0.2794)
			(stroke
				(width 0.1)
				(type default)
			)
			(layer "F.Fab")
		)
		(fp_line
			(start -0.12065 0.3048)
			(end -0.67945 0.3048)
			(stroke
				(width 0.1)
				(type default)
			)
			(layer "F.Fab")
		)
		(fp_line
			(start -0.67945 0.3048)
			(end -0.67945 -0.305054)
			(stroke
				(width 0.1)
				(type default)
			)
			(layer "F.Fab")
		)
		(pad "1" smd circle
			(at -0.40005 0 90)
			(size 0 0)
			(layers "F.Cu" "F.Mask" "F.Paste")
			(net "GND")
		)
		(pad "2" smd circle
			(at 0.40005 0 90)
			(size 0 0)
			(layers "F.Cu" "F.Mask" "F.Paste")
			(net "M_BMC_DDR4_MA<10>")
		)
	)
	(footprint ""
		(layer "F.Cu")
		(at 55.626 -10.795 90)
		(property "Reference" "R389"
			(at 0 0 90)
			(layer "F.SilkS")
			(hide yes)
			(effects
				(font
					(size 1.27 1.27)
				)
			)
		)
		(property "Value" ""
			(at 0 0 90)
			(layer "F.Fab")
			(effects
				(font
					(size 1.27 1.27)
				)
			)
		)
		(duplicate_pad_numbers_are_jumpers no)
		(fp_line
			(start 0.7874 -0.4064)
			(end 0.7874 0.4064)
			(stroke
				(width 0.1524)
				(type default)
			)
			(layer "F.SilkS")
		)
		(fp_line
			(start -0.7874 -0.4064)
			(end 0.7874 -0.4064)
			(stroke
				(width 0.1524)
				(type default)
			)
			(layer "F.SilkS")
		)
		(fp_line
			(start 0.7874 0.4064)
			(end -0.7874 0.4064)
			(stroke
				(width 0.1524)
				(type default)
			)
			(layer "F.SilkS")
		)
		(fp_line
			(start -0.7874 0.4064)
			(end -0.7874 -0.4064)
			(stroke
				(width 0.1524)
				(type default)
			)
			(layer "F.SilkS")
		)
		(fp_line
			(start -0.12065 -0.305054)
			(end -0.12065 -0.2794)
			(stroke
				(width 0.1)
				(type default)
			)
			(layer "F.Fab")
		)
		(fp_line
			(start -0.67945 -0.305054)
			(end -0.12065 -0.305054)
			(stroke
				(width 0.1)
				(type default)
			)
			(layer "F.Fab")
		)
		(fp_line
			(start 0.67945 -0.3048)
			(end 0.67945 0.3048)
			(stroke
				(width 0.1)
				(type default)
			)
			(layer "F.Fab")
		)
		(fp_line
			(start 0.12065 -0.3048)
			(end 0.67945 -0.3048)
			(stroke
				(width 0.1)
				(type default)
			)
			(layer "F.Fab")
		)
		(fp_line
			(start 0.12065 -0.2794)
			(end 0.12065 -0.3048)
			(stroke
				(width 0.1)
				(type default)
			)
			(layer "F.Fab")
		)
		(fp_line
			(start -0.12065 -0.2794)
			(end 0.12065 -0.2794)
			(stroke
				(width 0.1)
				(type default)
			)
			(layer "F.Fab")
		)
		(fp_line
			(start 0.120396 0.2794)
			(end -0.12065 0.2794)
			(stroke
				(width 0.1)
				(type default)
			)
			(layer "F.Fab")
		)
		(fp_line
			(start -0.12065 0.2794)
			(end -0.12065 0.3048)
			(stroke
				(width 0.1)
				(type default)
			)
			(layer "F.Fab")
		)
		(fp_line
			(start 0.67945 0.3048)
			(end 0.120396 0.3048)
			(stroke
				(width 0.1)
				(type default)
			)
			(layer "F.Fab")
		)
		(fp_line
			(start 0.120396 0.3048)
			(end 0.120396 0.2794)
			(stroke
				(width 0.1)
				(type default)
			)
			(layer "F.Fab")
		)
		(fp_line
			(start -0.12065 0.3048)
			(end -0.67945 0.3048)
			(stroke
				(width 0.1)
				(type default)
			)
			(layer "F.Fab")
		)
		(fp_line
			(start -0.67945 0.3048)
			(end -0.67945 -0.305054)
			(stroke
				(width 0.1)
				(type default)
			)
			(layer "F.Fab")
		)
		(pad "1" smd circle
			(at -0.40005 0 90)
			(size 0 0)
			(layers "F.Cu" "F.Mask" "F.Paste")
			(net "LED_D21_R1")
		)
		(pad "2" smd circle
			(at 0.40005 0 90)
			(size 0 0)
			(layers "F.Cu" "F.Mask" "F.Paste")
			(net "P12V_AUX")
		)
	)
	(footprint ""
		(layer "F.Cu")
		(at 31.75 -26.67 180)
		(property "Reference" "U34"
			(at -1.432052 -0.5842 90)
			(unlocked yes)
			(layer "F.SilkS")
			(effects
				(font
					(size 0.7874 0.5842)
					(thickness 0.1524)
				)
				(justify left)
			)
		)
		(property "Value" ""
			(at 0 0 180)
			(layer "F.Fab")
			(effects
				(font
					(size 1.27 1.27)
				)
			)
		)
		(duplicate_pad_numbers_are_jumpers no)
		(fp_line
			(start 0.791464 1.287526)
			(end 0.791464 -1.287526)
			(stroke
				(width 0.1524)
				(type default)
			)
			(layer "F.SilkS")
		)
		(fp_line
			(start 0.791464 -1.287526)
			(end -0.791464 -1.287526)
			(stroke
				(width 0.1524)
				(type default)
			)
			(layer "F.SilkS")
		)
		(fp_line
			(start -0.791464 1.287526)
			(end 0.791464 1.287526)
			(stroke
				(width 0.1524)
				(type default)
			)
			(layer "F.SilkS")
		)
		(fp_line
			(start -0.791464 -1.287526)
			(end -0.791464 1.287526)
			(stroke
				(width 0.1524)
				(type default)
			)
			(layer "F.SilkS")
		)
		(fp_poly
			(pts
				(xy -1.651 -1.253998) (xy -1.651 -0.745998) (xy -1.143 -0.999998)
			)
			(stroke
				(width 0)
				(type default)
			)
			(fill yes)
			(layer "F.SilkS")
		)
		(fp_line
			(start 0.537464 1.287526)
			(end 0.537464 -1.287526)
			(stroke
				(width 0.1)
				(type default)
			)
			(layer "F.Fab")
		)
		(fp_line
			(start 0.537464 -1.287526)
			(end -0.537464 -1.287526)
			(stroke
				(width 0.1)
				(type default)
			)
			(layer "F.Fab")
		)
		(fp_line
			(start -0.537464 1.287526)
			(end 0.537464 1.287526)
			(stroke
				(width 0.1)
				(type default)
			)
			(layer "F.Fab")
		)
		(fp_line
			(start -0.537464 -1.287526)
			(end -0.537464 1.287526)
			(stroke
				(width 0.1)
				(type default)
			)
			(layer "F.Fab")
		)
		(fp_poly
			(pts
				(xy -1.651 -1.253998) (xy -1.651 -0.745998) (xy -1.143 -0.999998)
			)
			(stroke
				(width 0)
				(type default)
			)
			(fill yes)
			(layer "F.Fab")
		)
		(pad "1" smd rect
			(at -0.387604 -0.999998 270)
			(size 0.254 0.635)
			(layers "F.Cu" "F.Mask" "F.Paste")
			(net "V_BMC_LS_DDC_SCL_R")
		)
		(pad "2" smd rect
			(at -0.387604 -0.499872 270)
			(size 0.254 0.635)
			(layers "F.Cu" "F.Mask" "F.Paste")
			(net "V_BMC_LS_DDC_SDA_R")
		)
		(pad "3" smd rect
			(at -0.350012 0 270)
			(size 0.4572 0.6858)
			(layers "F.Cu" "F.Mask" "F.Paste")
			(net "GND")
		)
		(pad "4" smd rect
			(at -0.387604 0.499872 270)
			(size 0.254 0.635)
			(layers "F.Cu" "F.Mask" "F.Paste")
			(net "V_VGAHS_BUF")
		)
		(pad "5" smd rect
			(at -0.387604 0.999998 270)
			(size 0.254 0.635)
			(layers "F.Cu" "F.Mask" "F.Paste")
			(net "V_VGAVS_BUF")
		)
		(pad "6" smd rect
			(at 0.387604 0.999998 270)
			(size 0.254 0.635)
			(layers "F.Cu" "F.Mask" "F.Paste")
			(net "V_VGAVS_BUF")
		)
		(pad "7" smd rect
			(at 0.387604 0.499872 270)
			(size 0.254 0.635)
			(layers "F.Cu" "F.Mask" "F.Paste")
			(net "V_VGAHS_BUF")
		)
		(pad "8" smd rect
			(at 0.412496 0 270)
			(size 0.4572 0.5842)
			(layers "F.Cu" "F.Mask" "F.Paste")
			(net "GND")
		)
		(pad "9" smd rect
			(at 0.387604 -0.499872 270)
			(size 0.254 0.635)
			(layers "F.Cu" "F.Mask" "F.Paste")
			(net "V_BMC_LS_DDC_SDA_R")
		)
		(pad "10" smd rect
			(at 0.387604 -0.999998 270)
			(size 0.254 0.635)
			(layers "F.Cu" "F.Mask" "F.Paste")
			(net "V_BMC_LS_DDC_SCL_R")
		)
	)
	(footprint ""
		(layer "F.Cu")
		(at 11.070844 -14.812518)
		(property "Reference" "C200"
			(at 0 0 0)
			(layer "F.SilkS")
			(hide yes)
			(effects
				(font
					(size 1.27 1.27)
				)
			)
		)
		(property "Value" ""
			(at 0 0 0)
			(layer "F.Fab")
			(effects
				(font
					(size 1.27 1.27)
				)
			)
		)
		(duplicate_pad_numbers_are_jumpers no)
		(fp_line
			(start -0.7874 -0.4064)
			(end 0.7874 -0.4064)
			(stroke
				(width 0.1524)
				(type default)
			)
			(layer "F.SilkS")
		)
		(fp_line
			(start -0.7874 0.4064)
			(end -0.7874 -0.4064)
			(stroke
				(width 0.1524)
				(type default)
			)
			(layer "F.SilkS")
		)
		(fp_line
			(start 0.7874 -0.4064)
			(end 0.7874 0.4064)
			(stroke
				(width 0.1524)
				(type default)
			)
			(layer "F.SilkS")
		)
		(fp_line
			(start 0.7874 0.4064)
			(end -0.7874 0.4064)
			(stroke
				(width 0.1524)
				(type default)
			)
			(layer "F.SilkS")
		)
		(fp_line
			(start -0.67945 -0.305054)
			(end -0.12065 -0.305054)
			(stroke
				(width 0.1)
				(type default)
			)
			(layer "F.Fab")
		)
		(fp_line
			(start -0.67945 0.3048)
			(end -0.67945 -0.305054)
			(stroke
				(width 0.1)
				(type default)
			)
			(layer "F.Fab")
		)
		(fp_line
			(start -0.12065 -0.305054)
			(end -0.12065 -0.2794)
			(stroke
				(width 0.1)
				(type default)
			)
			(layer "F.Fab")
		)
		(fp_line
			(start -0.12065 -0.2794)
			(end 0.12065 -0.2794)
			(stroke
				(width 0.1)
				(type default)
			)
			(layer "F.Fab")
		)
		(fp_line
			(start -0.12065 0.2794)
			(end -0.12065 0.3048)
			(stroke
				(width 0.1)
				(type default)
			)
			(layer "F.Fab")
		)
		(fp_line
			(start -0.12065 0.3048)
			(end -0.67945 0.3048)
			(stroke
				(width 0.1)
				(type default)
			)
			(layer "F.Fab")
		)
		(fp_line
			(start 0.120396 0.2794)
			(end -0.12065 0.2794)
			(stroke
				(width 0.1)
				(type default)
			)
			(layer "F.Fab")
		)
		(fp_line
			(start 0.120396 0.3048)
			(end 0.120396 0.2794)
			(stroke
				(width 0.1)
				(type default)
			)
			(layer "F.Fab")
		)
		(fp_line
			(start 0.12065 -0.3048)
			(end 0.67945 -0.3048)
			(stroke
				(width 0.1)
				(type default)
			)
			(layer "F.Fab")
		)
		(fp_line
			(start 0.12065 -0.2794)
			(end 0.12065 -0.3048)
			(stroke
				(width 0.1)
				(type default)
			)
			(layer "F.Fab")
		)
		(fp_line
			(start 0.67945 -0.3048)
			(end 0.67945 0.3048)
			(stroke
				(width 0.1)
				(type default)
			)
			(layer "F.Fab")
		)
		(fp_line
			(start 0.67945 0.3048)
			(end 0.120396 0.3048)
			(stroke
				(width 0.1)
				(type default)
			)
			(layer "F.Fab")
		)
		(pad "1" smd circle
			(at -0.40005 0)
			(size 0 0)
			(layers "F.Cu" "F.Mask" "F.Paste")
			(net "P3V3_AUX")
		)
		(pad "2" smd circle
			(at 0.40005 0)
			(size 0 0)
			(layers "F.Cu" "F.Mask" "F.Paste")
			(net "GND")
		)
	)
	(footprint ""
		(layer "F.Cu")
		(at 60.549028 -30.867604 90)
		(property "Reference" "R252"
			(at 0 0 90)
			(layer "F.SilkS")
			(hide yes)
			(effects
				(font
					(size 1.27 1.27)
				)
			)
		)
		(property "Value" ""
			(at 0 0 90)
			(layer "F.Fab")
			(effects
				(font
					(size 1.27 1.27)
				)
			)
		)
		(duplicate_pad_numbers_are_jumpers no)
		(fp_line
			(start 0.7874 -0.4064)
			(end 0.7874 0.4064)
			(stroke
				(width 0.1524)
				(type default)
			)
			(layer "F.SilkS")
		)
		(fp_line
			(start -0.7874 -0.4064)
			(end 0.7874 -0.4064)
			(stroke
				(width 0.1524)
				(type default)
			)
			(layer "F.SilkS")
		)
		(fp_line
			(start 0.7874 0.4064)
			(end -0.7874 0.4064)
			(stroke
				(width 0.1524)
				(type default)
			)
			(layer "F.SilkS")
		)
		(fp_line
			(start -0.7874 0.4064)
			(end -0.7874 -0.4064)
			(stroke
				(width 0.1524)
				(type default)
			)
			(layer "F.SilkS")
		)
		(fp_line
			(start -0.12065 -0.305054)
			(end -0.12065 -0.2794)
			(stroke
				(width 0.1)
				(type default)
			)
			(layer "F.Fab")
		)
		(fp_line
			(start -0.67945 -0.305054)
			(end -0.12065 -0.305054)
			(stroke
				(width 0.1)
				(type default)
			)
			(layer "F.Fab")
		)
		(fp_line
			(start 0.67945 -0.3048)
			(end 0.67945 0.3048)
			(stroke
				(width 0.1)
				(type default)
			)
			(layer "F.Fab")
		)
		(fp_line
			(start 0.12065 -0.3048)
			(end 0.67945 -0.3048)
			(stroke
				(width 0.1)
				(type default)
			)
			(layer "F.Fab")
		)
		(fp_line
			(start 0.12065 -0.2794)
			(end 0.12065 -0.3048)
			(stroke
				(width 0.1)
				(type default)
			)
			(layer "F.Fab")
		)
		(fp_line
			(start -0.12065 -0.2794)
			(end 0.12065 -0.2794)
			(stroke
				(width 0.1)
				(type default)
			)
			(layer "F.Fab")
		)
		(fp_line
			(start 0.120396 0.2794)
			(end -0.12065 0.2794)
			(stroke
				(width 0.1)
				(type default)
			)
			(layer "F.Fab")
		)
		(fp_line
			(start -0.12065 0.2794)
			(end -0.12065 0.3048)
			(stroke
				(width 0.1)
				(type default)
			)
			(layer "F.Fab")
		)
		(fp_line
			(start 0.67945 0.3048)
			(end 0.120396 0.3048)
			(stroke
				(width 0.1)
				(type default)
			)
			(layer "F.Fab")
		)
		(fp_line
			(start 0.120396 0.3048)
			(end 0.120396 0.2794)
			(stroke
				(width 0.1)
				(type default)
			)
			(layer "F.Fab")
		)
		(fp_line
			(start -0.12065 0.3048)
			(end -0.67945 0.3048)
			(stroke
				(width 0.1)
				(type default)
			)
			(layer "F.Fab")
		)
		(fp_line
			(start -0.67945 0.3048)
			(end -0.67945 -0.305054)
			(stroke
				(width 0.1)
				(type default)
			)
			(layer "F.Fab")
		)
		(pad "1" smd circle
			(at -0.40005 0 90)
			(size 0 0)
			(layers "F.Cu" "F.Mask" "F.Paste")
			(net "P3V3_AUX")
		)
		(pad "2" smd circle
			(at 0.40005 0 90)
			(size 0 0)
			(layers "F.Cu" "F.Mask" "F.Paste")
			(net "SMB_BMC_MM5_R_SCL")
		)
	)
	(footprint ""
		(layer "F.Cu")
		(at 75.184 -20.193 180)
		(property "Reference" "R283"
			(at 0 0 180)
			(layer "F.SilkS")
			(hide yes)
			(effects
				(font
					(size 1.27 1.27)
				)
			)
		)
		(property "Value" ""
			(at 0 0 180)
			(layer "F.Fab")
			(effects
				(font
					(size 1.27 1.27)
				)
			)
		)
		(duplicate_pad_numbers_are_jumpers no)
		(fp_line
			(start 0.7874 0.4064)
			(end -0.7874 0.4064)
			(stroke
				(width 0.1524)
				(type default)
			)
			(layer "F.SilkS")
		)
		(fp_line
			(start 0.7874 -0.4064)
			(end 0.7874 0.4064)
			(stroke
				(width 0.1524)
				(type default)
			)
			(layer "F.SilkS")
		)
		(fp_line
			(start -0.7874 0.4064)
			(end -0.7874 -0.4064)
			(stroke
				(width 0.1524)
				(type default)
			)
			(layer "F.SilkS")
		)
		(fp_line
			(start -0.7874 -0.4064)
			(end 0.7874 -0.4064)
			(stroke
				(width 0.1524)
				(type default)
			)
			(layer "F.SilkS")
		)
		(fp_line
			(start 0.67945 0.3048)
			(end 0.120396 0.3048)
			(stroke
				(width 0.1)
				(type default)
			)
			(layer "F.Fab")
		)
		(fp_line
			(start 0.67945 -0.3048)
			(end 0.67945 0.3048)
			(stroke
				(width 0.1)
				(type default)
			)
			(layer "F.Fab")
		)
		(fp_line
			(start 0.12065 -0.2794)
			(end 0.12065 -0.3048)
			(stroke
				(width 0.1)
				(type default)
			)
			(layer "F.Fab")
		)
		(fp_line
			(start 0.12065 -0.3048)
			(end 0.67945 -0.3048)
			(stroke
				(width 0.1)
				(type default)
			)
			(layer "F.Fab")
		)
		(fp_line
			(start 0.120396 0.3048)
			(end 0.120396 0.2794)
			(stroke
				(width 0.1)
				(type default)
			)
			(layer "F.Fab")
		)
		(fp_line
			(start 0.120396 0.2794)
			(end -0.12065 0.2794)
			(stroke
				(width 0.1)
				(type default)
			)
			(layer "F.Fab")
		)
		(fp_line
			(start -0.12065 0.3048)
			(end -0.67945 0.3048)
			(stroke
				(width 0.1)
				(type default)
			)
			(layer "F.Fab")
		)
		(fp_line
			(start -0.12065 0.2794)
			(end -0.12065 0.3048)
			(stroke
				(width 0.1)
				(type default)
			)
			(layer "F.Fab")
		)
		(fp_line
			(start -0.12065 -0.2794)
			(end 0.12065 -0.2794)
			(stroke
				(width 0.1)
				(type default)
			)
			(layer "F.Fab")
		)
		(fp_line
			(start -0.12065 -0.305054)
			(end -0.12065 -0.2794)
			(stroke
				(width 0.1)
				(type default)
			)
			(layer "F.Fab")
		)
		(fp_line
			(start -0.67945 0.3048)
			(end -0.67945 -0.305054)
			(stroke
				(width 0.1)
				(type default)
			)
			(layer "F.Fab")
		)
		(fp_line
			(start -0.67945 -0.305054)
			(end -0.12065 -0.305054)
			(stroke
				(width 0.1)
				(type default)
			)
			(layer "F.Fab")
		)
		(pad "1" smd circle
			(at -0.40005 0 180)
			(size 0 0)
			(layers "F.Cu" "F.Mask" "F.Paste")
			(net "FM_UARTSW_LSB_N")
		)
		(pad "2" smd circle
			(at 0.40005 0 180)
			(size 0 0)
			(layers "F.Cu" "F.Mask" "F.Paste")
			(net "FM_UARTSW_LSB_R1_N")
		)
	)
	(footprint ""
		(layer "F.Cu")
		(at 85.29955 -44.427394 180)
		(property "Reference" "R333"
			(at 0 0 180)
			(layer "F.SilkS")
			(hide yes)
			(effects
				(font
					(size 1.27 1.27)
				)
			)
		)
		(property "Value" ""
			(at 0 0 180)
			(layer "F.Fab")
			(effects
				(font
					(size 1.27 1.27)
				)
			)
		)
		(duplicate_pad_numbers_are_jumpers no)
		(fp_line
			(start 0.7874 0.4064)
			(end -0.7874 0.4064)
			(stroke
				(width 0.1524)
				(type default)
			)
			(layer "F.SilkS")
		)
		(fp_line
			(start 0.7874 -0.4064)
			(end 0.7874 0.4064)
			(stroke
				(width 0.1524)
				(type default)
			)
			(layer "F.SilkS")
		)
		(fp_line
			(start -0.7874 0.4064)
			(end -0.7874 -0.4064)
			(stroke
				(width 0.1524)
				(type default)
			)
			(layer "F.SilkS")
		)
		(fp_line
			(start -0.7874 -0.4064)
			(end 0.7874 -0.4064)
			(stroke
				(width 0.1524)
				(type default)
			)
			(layer "F.SilkS")
		)
		(fp_line
			(start 0.67945 0.3048)
			(end 0.120396 0.3048)
			(stroke
				(width 0.1)
				(type default)
			)
			(layer "F.Fab")
		)
		(fp_line
			(start 0.67945 -0.3048)
			(end 0.67945 0.3048)
			(stroke
				(width 0.1)
				(type default)
			)
			(layer "F.Fab")
		)
		(fp_line
			(start 0.12065 -0.2794)
			(end 0.12065 -0.3048)
			(stroke
				(width 0.1)
				(type default)
			)
			(layer "F.Fab")
		)
		(fp_line
			(start 0.12065 -0.3048)
			(end 0.67945 -0.3048)
			(stroke
				(width 0.1)
				(type default)
			)
			(layer "F.Fab")
		)
		(fp_line
			(start 0.120396 0.3048)
			(end 0.120396 0.2794)
			(stroke
				(width 0.1)
				(type default)
			)
			(layer "F.Fab")
		)
		(fp_line
			(start 0.120396 0.2794)
			(end -0.12065 0.2794)
			(stroke
				(width 0.1)
				(type default)
			)
			(layer "F.Fab")
		)
		(fp_line
			(start -0.12065 0.3048)
			(end -0.67945 0.3048)
			(stroke
				(width 0.1)
				(type default)
			)
			(layer "F.Fab")
		)
		(fp_line
			(start -0.12065 0.2794)
			(end -0.12065 0.3048)
			(stroke
				(width 0.1)
				(type default)
			)
			(layer "F.Fab")
		)
		(fp_line
			(start -0.12065 -0.2794)
			(end 0.12065 -0.2794)
			(stroke
				(width 0.1)
				(type default)
			)
			(layer "F.Fab")
		)
		(fp_line
			(start -0.12065 -0.305054)
			(end -0.12065 -0.2794)
			(stroke
				(width 0.1)
				(type default)
			)
			(layer "F.Fab")
		)
		(fp_line
			(start -0.67945 0.3048)
			(end -0.67945 -0.305054)
			(stroke
				(width 0.1)
				(type default)
			)
			(layer "F.Fab")
		)
		(fp_line
			(start -0.67945 -0.305054)
			(end -0.12065 -0.305054)
			(stroke
				(width 0.1)
				(type default)
			)
			(layer "F.Fab")
		)
		(pad "1" smd circle
			(at -0.40005 0 180)
			(size 0 0)
			(layers "F.Cu" "F.Mask" "F.Paste")
			(net "GND")
		)
		(pad "2" smd circle
			(at 0.40005 0 180)
			(size 0 0)
			(layers "F.Cu" "F.Mask" "F.Paste")
			(net "M_BMC_DDR4_MA<7>")
		)
	)
	(footprint ""
		(layer "F.Cu")
		(at 57.18556 -94.5896)
		(property "Reference" "R464"
			(at 0 0 0)
			(layer "F.SilkS")
			(hide yes)
			(effects
				(font
					(size 1.27 1.27)
				)
			)
		)
		(property "Value" ""
			(at 0 0 0)
			(layer "F.Fab")
			(effects
				(font
					(size 1.27 1.27)
				)
			)
		)
		(duplicate_pad_numbers_are_jumpers no)
		(fp_line
			(start -0.7874 -0.4064)
			(end 0.7874 -0.4064)
			(stroke
				(width 0.1524)
				(type default)
			)
			(layer "F.SilkS")
		)
		(fp_line
			(start -0.7874 0.4064)
			(end -0.7874 -0.4064)
			(stroke
				(width 0.1524)
				(type default)
			)
			(layer "F.SilkS")
		)
		(fp_line
			(start 0.7874 -0.4064)
			(end 0.7874 0.4064)
			(stroke
				(width 0.1524)
				(type default)
			)
			(layer "F.SilkS")
		)
		(fp_line
			(start 0.7874 0.4064)
			(end -0.7874 0.4064)
			(stroke
				(width 0.1524)
				(type default)
			)
			(layer "F.SilkS")
		)
		(fp_line
			(start -0.67945 -0.305054)
			(end -0.12065 -0.305054)
			(stroke
				(width 0.1)
				(type default)
			)
			(layer "F.Fab")
		)
		(fp_line
			(start -0.67945 0.3048)
			(end -0.67945 -0.305054)
			(stroke
				(width 0.1)
				(type default)
			)
			(layer "F.Fab")
		)
		(fp_line
			(start -0.12065 -0.305054)
			(end -0.12065 -0.2794)
			(stroke
				(width 0.1)
				(type default)
			)
			(layer "F.Fab")
		)
		(fp_line
			(start -0.12065 -0.2794)
			(end 0.12065 -0.2794)
			(stroke
				(width 0.1)
				(type default)
			)
			(layer "F.Fab")
		)
		(fp_line
			(start -0.12065 0.2794)
			(end -0.12065 0.3048)
			(stroke
				(width 0.1)
				(type default)
			)
			(layer "F.Fab")
		)
		(fp_line
			(start -0.12065 0.3048)
			(end -0.67945 0.3048)
			(stroke
				(width 0.1)
				(type default)
			)
			(layer "F.Fab")
		)
		(fp_line
			(start 0.120396 0.2794)
			(end -0.12065 0.2794)
			(stroke
				(width 0.1)
				(type default)
			)
			(layer "F.Fab")
		)
		(fp_line
			(start 0.120396 0.3048)
			(end 0.120396 0.2794)
			(stroke
				(width 0.1)
				(type default)
			)
			(layer "F.Fab")
		)
		(fp_line
			(start 0.12065 -0.3048)
			(end 0.67945 -0.3048)
			(stroke
				(width 0.1)
				(type default)
			)
			(layer "F.Fab")
		)
		(fp_line
			(start 0.12065 -0.2794)
			(end 0.12065 -0.3048)
			(stroke
				(width 0.1)
				(type default)
			)
			(layer "F.Fab")
		)
		(fp_line
			(start 0.67945 -0.3048)
			(end 0.67945 0.3048)
			(stroke
				(width 0.1)
				(type default)
			)
			(layer "F.Fab")
		)
		(fp_line
			(start 0.67945 0.3048)
			(end 0.120396 0.3048)
			(stroke
				(width 0.1)
				(type default)
			)
			(layer "F.Fab")
		)
		(pad "1" smd circle
			(at -0.40005 0)
			(size 0 0)
			(layers "F.Cu" "F.Mask" "F.Paste")
			(net "P3V3_AUX")
		)
		(pad "2" smd circle
			(at 0.40005 0)
			(size 0 0)
			(layers "F.Cu" "F.Mask" "F.Paste")
			(net "FM_TPM_PRSNT_0_N")
		)
	)
	(footprint ""
		(layer "F.Cu")
		(at 16.690086 -10.729976 90)
		(property "Reference" "J14"
			(at 0.573024 -3.328416 90)
			(unlocked yes)
			(layer "F.SilkS")
			(effects
				(font
					(size 0.7874 0.5842)
					(thickness 0.1524)
				)
				(justify left)
			)
		)
		(property "Value" ""
			(at 0 0 90)
			(layer "F.Fab")
			(effects
				(font
					(size 1.27 1.27)
				)
			)
		)
		(duplicate_pad_numbers_are_jumpers no)
		(fp_line
			(start 3.81 -1.459992)
			(end 3.81 9.079992)
			(stroke
				(width 0.1524)
				(type default)
			)
			(layer "F.SilkS")
		)
		(fp_line
			(start -1.27 -1.459992)
			(end 3.81 -1.459992)
			(stroke
				(width 0.1524)
				(type default)
			)
			(layer "F.SilkS")
		)
		(fp_line
			(start 3.81 9.079992)
			(end -1.27 9.079992)
			(stroke
				(width 0.1524)
				(type default)
			)
			(layer "F.SilkS")
		)
		(fp_line
			(start -1.27 9.079992)
			(end -1.27 -1.459992)
			(stroke
				(width 0.1524)
				(type default)
			)
			(layer "F.SilkS")
		)
		(fp_poly
			(pts
				(xy -2.54 0.508) (xy -2.54 -0.508) (xy -1.524 0)
			)
			(stroke
				(width 0)
				(type default)
			)
			(fill yes)
			(layer "F.SilkS")
		)
		(fp_line
			(start 3.81 -1.459992)
			(end 3.81 9.079992)
			(stroke
				(width 0.1)
				(type default)
			)
			(layer "F.Fab")
		)
		(fp_line
			(start -1.27 -1.459992)
			(end 3.81 -1.459992)
			(stroke
				(width 0.1)
				(type default)
			)
			(layer "F.Fab")
		)
		(fp_line
			(start 3.81 9.079992)
			(end -1.27 9.079992)
			(stroke
				(width 0.1)
				(type default)
			)
			(layer "F.Fab")
		)
		(fp_line
			(start -1.27 9.079992)
			(end -1.27 -1.459992)
			(stroke
				(width 0.1)
				(type default)
			)
			(layer "F.Fab")
		)
		(fp_poly
			(pts
				(xy -2.54 0.508) (xy -2.54 -0.508) (xy -1.524 0)
			)
			(stroke
				(width 0)
				(type default)
			)
			(fill yes)
			(layer "F.Fab")
		)
		(fp_text user "2"
			(at 2.629154 -2.288286 0)
			(unlocked yes)
			(layer "F.SilkS")
			(effects
				(font
					(size 0.7874 0.5842)
					(thickness 0.1524)
				)
			)
		)
		(fp_text user "8"
			(at 4.48183 7.6073 0)
			(unlocked yes)
			(layer "F.SilkS")
			(effects
				(font
					(size 0.7874 0.5842)
					(thickness 0.1524)
				)
			)
		)
		(fp_text user "7"
			(at -1.908556 8.800592 0)
			(unlocked yes)
			(layer "F.SilkS")
			(effects
				(font
					(size 0.7874 0.5842)
					(thickness 0.1524)
				)
			)
		)
		(fp_text user "2"
			(at 2.56413 -1.1811 0)
			(unlocked yes)
			(layer "B.SilkS")
			(effects
				(font
					(size 0.7874 0.5842)
					(thickness 0.1524)
				)
				(justify mirror)
			)
		)
		(fp_text user "1"
			(at -0.05207 -1.1303 0)
			(unlocked yes)
			(layer "B.SilkS")
			(effects
				(font
					(size 0.7874 0.5842)
					(thickness 0.1524)
				)
				(justify mirror)
			)
		)
		(fp_text user "7"
			(at -0.01397 8.7249 0)
			(unlocked yes)
			(layer "B.SilkS")
			(effects
				(font
					(size 0.7874 0.5842)
					(thickness 0.1524)
				)
				(justify mirror)
			)
		)
		(fp_text user "8"
			(at 2.56413 8.7757 0)
			(unlocked yes)
			(layer "B.SilkS")
			(effects
				(font
					(size 0.7874 0.5842)
					(thickness 0.1524)
				)
				(justify mirror)
			)
		)
		(fp_text user "2"
			(at 2.56413 -1.1811 0)
			(unlocked yes)
			(layer "B.Fab")
			(effects
				(font
					(size 0.7874 0.5842)
					(thickness 0.1524)
				)
				(justify mirror)
			)
		)
		(fp_text user "1"
			(at -0.05207 -1.1303 0)
			(unlocked yes)
			(layer "B.Fab")
			(effects
				(font
					(size 0.7874 0.5842)
					(thickness 0.1524)
				)
				(justify mirror)
			)
		)
		(fp_text user "7"
			(at -0.01397 8.7249 0)
			(unlocked yes)
			(layer "B.Fab")
			(effects
				(font
					(size 0.7874 0.5842)
					(thickness 0.1524)
				)
				(justify mirror)
			)
		)
		(fp_text user "8"
			(at 2.56413 8.7757 0)
			(unlocked yes)
			(layer "B.Fab")
			(effects
				(font
					(size 0.7874 0.5842)
					(thickness 0.1524)
				)
				(justify mirror)
			)
		)
		(fp_text user "2"
			(at 4.48183 0 0)
			(unlocked yes)
			(layer "F.Fab")
			(effects
				(font
					(size 0.7874 0.5842)
					(thickness 0.1524)
				)
			)
		)
		(fp_text user "7"
			(at -2.07137 7.5565 0)
			(unlocked yes)
			(layer "F.Fab")
			(effects
				(font
					(size 0.7874 0.5842)
					(thickness 0.1524)
				)
			)
		)
		(fp_text user "8"
			(at 4.48183 7.6073 0)
			(unlocked yes)
			(layer "F.Fab")
			(effects
				(font
					(size 0.7874 0.5842)
					(thickness 0.1524)
				)
			)
		)
		(pad "1" thru_hole rect
			(at 0 0)
			(size 1.5494 1.5494)
			(drill 1.0414)
			(layers "*.Cu" "*.Mask")
			(remove_unused_layers no)
			(net "P3V3_AUX")
			(clearance 0)
			(padstack
				(mode front_inner_back)
				(layer "Inner"
					(shape circle)
					(size 1.5494 1.5494)
					(clearance 0)
				)
				(layer "B.Cu"
					(shape rect)
					(size 1.5494 1.5494)
					(clearance 0)
				)
			)
		)
		(pad "2" thru_hole circle
			(at 2.54 0)
			(size 1.5494 1.5494)
			(drill 1.0414)
			(layers "*.Cu" "*.Mask")
			(remove_unused_layers no)
			(net "SMB_TMP421_BMC_MM2_SDA")
			(clearance 0)
		)
		(pad "3" thru_hole circle
			(at 0 2.54)
			(size 1.5494 1.5494)
			(drill 1.0414)
			(layers "*.Cu" "*.Mask")
			(remove_unused_layers no)
			(net "TMC75_A0")
			(clearance 0)
		)
		(pad "4" thru_hole circle
			(at 2.54 2.54)
			(size 1.5494 1.5494)
			(drill 1.0414)
			(layers "*.Cu" "*.Mask")
			(remove_unused_layers no)
			(net "SMB_TMP421_BMC_MM2_SCL")
			(clearance 0)
		)
		(pad "5" thru_hole circle
			(at 0 5.08)
			(size 1.5494 1.5494)
			(drill 1.0414)
			(layers "*.Cu" "*.Mask")
			(remove_unused_layers no)
			(net "TMC75_A1")
			(clearance 0)
		)
		(pad "6" thru_hole circle
			(at 2.54 5.08)
			(size 1.5494 1.5494)
			(drill 1.0414)
			(layers "*.Cu" "*.Mask")
			(remove_unused_layers no)
			(net "SMB_BMC_ALERT16_R_N")
			(clearance 0)
		)
		(pad "7" thru_hole circle
			(at 0 7.62)
			(size 1.5494 1.5494)
			(drill 1.0414)
			(layers "*.Cu" "*.Mask")
			(remove_unused_layers no)
			(net "TMC75_A2")
			(clearance 0)
		)
		(pad "8" thru_hole circle
			(at 2.54 7.62)
			(size 1.5494 1.5494)
			(drill 1.0414)
			(layers "*.Cu" "*.Mask")
			(remove_unused_layers no)
			(net "GND")
			(clearance 0)
		)
	)
	(footprint ""
		(layer "F.Cu")
		(at 78.994 -82.55 -90)
		(property "Reference" "C226"
			(at 0 0 270)
			(layer "F.SilkS")
			(hide yes)
			(effects
				(font
					(size 1.27 1.27)
				)
			)
		)
		(property "Value" ""
			(at 0 0 270)
			(layer "F.Fab")
			(effects
				(font
					(size 1.27 1.27)
				)
			)
		)
		(duplicate_pad_numbers_are_jumpers no)
		(fp_line
			(start -0.7874 0.4064)
			(end -0.7874 -0.4064)
			(stroke
				(width 0.1524)
				(type default)
			)
			(layer "F.SilkS")
		)
		(fp_line
			(start 0.7874 0.4064)
			(end -0.7874 0.4064)
			(stroke
				(width 0.1524)
				(type default)
			)
			(layer "F.SilkS")
		)
		(fp_line
			(start -0.7874 -0.4064)
			(end 0.7874 -0.4064)
			(stroke
				(width 0.1524)
				(type default)
			)
			(layer "F.SilkS")
		)
		(fp_line
			(start 0.7874 -0.4064)
			(end 0.7874 0.4064)
			(stroke
				(width 0.1524)
				(type default)
			)
			(layer "F.SilkS")
		)
		(fp_line
			(start -0.67945 0.3048)
			(end -0.67945 -0.305054)
			(stroke
				(width 0.1)
				(type default)
			)
			(layer "F.Fab")
		)
		(fp_line
			(start -0.12065 0.3048)
			(end -0.67945 0.3048)
			(stroke
				(width 0.1)
				(type default)
			)
			(layer "F.Fab")
		)
		(fp_line
			(start 0.120396 0.3048)
			(end 0.120396 0.2794)
			(stroke
				(width 0.1)
				(type default)
			)
			(layer "F.Fab")
		)
		(fp_line
			(start 0.67945 0.3048)
			(end 0.120396 0.3048)
			(stroke
				(width 0.1)
				(type default)
			)
			(layer "F.Fab")
		)
		(fp_line
			(start -0.12065 0.2794)
			(end -0.12065 0.3048)
			(stroke
				(width 0.1)
				(type default)
			)
			(layer "F.Fab")
		)
		(fp_line
			(start 0.120396 0.2794)
			(end -0.12065 0.2794)
			(stroke
				(width 0.1)
				(type default)
			)
			(layer "F.Fab")
		)
		(fp_line
			(start -0.12065 -0.2794)
			(end 0.12065 -0.2794)
			(stroke
				(width 0.1)
				(type default)
			)
			(layer "F.Fab")
		)
		(fp_line
			(start 0.12065 -0.2794)
			(end 0.12065 -0.3048)
			(stroke
				(width 0.1)
				(type default)
			)
			(layer "F.Fab")
		)
		(fp_line
			(start 0.12065 -0.3048)
			(end 0.67945 -0.3048)
			(stroke
				(width 0.1)
				(type default)
			)
			(layer "F.Fab")
		)
		(fp_line
			(start 0.67945 -0.3048)
			(end 0.67945 0.3048)
			(stroke
				(width 0.1)
				(type default)
			)
			(layer "F.Fab")
		)
		(fp_line
			(start -0.67945 -0.305054)
			(end -0.12065 -0.305054)
			(stroke
				(width 0.1)
				(type default)
			)
			(layer "F.Fab")
		)
		(fp_line
			(start -0.12065 -0.305054)
			(end -0.12065 -0.2794)
			(stroke
				(width 0.1)
				(type default)
			)
			(layer "F.Fab")
		)
		(pad "1" smd circle
			(at -0.40005 0 270)
			(size 0 0)
			(layers "F.Cu" "F.Mask" "F.Paste")
			(net "P12V_AUX")
		)
		(pad "2" smd circle
			(at 0.40005 0 270)
			(size 0 0)
			(layers "F.Cu" "F.Mask" "F.Paste")
			(net "GND")
		)
	)
	(footprint ""
		(layer "F.Cu")
		(at 56.79948 -65.76822 180)
		(property "Reference" "R465"
			(at 0 0 180)
			(layer "F.SilkS")
			(hide yes)
			(effects
				(font
					(size 1.27 1.27)
				)
			)
		)
		(property "Value" ""
			(at 0 0 180)
			(layer "F.Fab")
			(effects
				(font
					(size 1.27 1.27)
				)
			)
		)
		(duplicate_pad_numbers_are_jumpers no)
		(fp_line
			(start 0.7874 0.4064)
			(end -0.7874 0.4064)
			(stroke
				(width 0.1524)
				(type default)
			)
			(layer "F.SilkS")
		)
		(fp_line
			(start 0.7874 -0.4064)
			(end 0.7874 0.4064)
			(stroke
				(width 0.1524)
				(type default)
			)
			(layer "F.SilkS")
		)
		(fp_line
			(start -0.7874 0.4064)
			(end -0.7874 -0.4064)
			(stroke
				(width 0.1524)
				(type default)
			)
			(layer "F.SilkS")
		)
		(fp_line
			(start -0.7874 -0.4064)
			(end 0.7874 -0.4064)
			(stroke
				(width 0.1524)
				(type default)
			)
			(layer "F.SilkS")
		)
		(fp_line
			(start 0.67945 0.3048)
			(end 0.120396 0.3048)
			(stroke
				(width 0.1)
				(type default)
			)
			(layer "F.Fab")
		)
		(fp_line
			(start 0.67945 -0.3048)
			(end 0.67945 0.3048)
			(stroke
				(width 0.1)
				(type default)
			)
			(layer "F.Fab")
		)
		(fp_line
			(start 0.12065 -0.2794)
			(end 0.12065 -0.3048)
			(stroke
				(width 0.1)
				(type default)
			)
			(layer "F.Fab")
		)
		(fp_line
			(start 0.12065 -0.3048)
			(end 0.67945 -0.3048)
			(stroke
				(width 0.1)
				(type default)
			)
			(layer "F.Fab")
		)
		(fp_line
			(start 0.120396 0.3048)
			(end 0.120396 0.2794)
			(stroke
				(width 0.1)
				(type default)
			)
			(layer "F.Fab")
		)
		(fp_line
			(start 0.120396 0.2794)
			(end -0.12065 0.2794)
			(stroke
				(width 0.1)
				(type default)
			)
			(layer "F.Fab")
		)
		(fp_line
			(start -0.12065 0.3048)
			(end -0.67945 0.3048)
			(stroke
				(width 0.1)
				(type default)
			)
			(layer "F.Fab")
		)
		(fp_line
			(start -0.12065 0.2794)
			(end -0.12065 0.3048)
			(stroke
				(width 0.1)
				(type default)
			)
			(layer "F.Fab")
		)
		(fp_line
			(start -0.12065 -0.2794)
			(end 0.12065 -0.2794)
			(stroke
				(width 0.1)
				(type default)
			)
			(layer "F.Fab")
		)
		(fp_line
			(start -0.12065 -0.305054)
			(end -0.12065 -0.2794)
			(stroke
				(width 0.1)
				(type default)
			)
			(layer "F.Fab")
		)
		(fp_line
			(start -0.67945 0.3048)
			(end -0.67945 -0.305054)
			(stroke
				(width 0.1)
				(type default)
			)
			(layer "F.Fab")
		)
		(fp_line
			(start -0.67945 -0.305054)
			(end -0.12065 -0.305054)
			(stroke
				(width 0.1)
				(type default)
			)
			(layer "F.Fab")
		)
		(pad "1" smd circle
			(at -0.40005 0 180)
			(size 0 0)
			(layers "F.Cu" "F.Mask" "F.Paste")
			(net "FM_FLASH_LATCH_N_R1")
		)
		(pad "2" smd circle
			(at 0.40005 0 180)
			(size 0 0)
			(layers "F.Cu" "F.Mask" "F.Paste")
			(net "FM_FLASH_LATCH_N")
		)
	)
	(footprint ""
		(layer "F.Cu")
		(at 46.863 -23.368 180)
		(property "Reference" "R384"
			(at 0 0 180)
			(layer "F.SilkS")
			(hide yes)
			(effects
				(font
					(size 1.27 1.27)
				)
			)
		)
		(property "Value" ""
			(at 0 0 180)
			(layer "F.Fab")
			(effects
				(font
					(size 1.27 1.27)
				)
			)
		)
		(duplicate_pad_numbers_are_jumpers no)
		(fp_line
			(start 0.7874 0.4064)
			(end -0.7874 0.4064)
			(stroke
				(width 0.1524)
				(type default)
			)
			(layer "F.SilkS")
		)
		(fp_line
			(start 0.7874 -0.4064)
			(end 0.7874 0.4064)
			(stroke
				(width 0.1524)
				(type default)
			)
			(layer "F.SilkS")
		)
		(fp_line
			(start -0.7874 0.4064)
			(end -0.7874 -0.4064)
			(stroke
				(width 0.1524)
				(type default)
			)
			(layer "F.SilkS")
		)
		(fp_line
			(start -0.7874 -0.4064)
			(end 0.7874 -0.4064)
			(stroke
				(width 0.1524)
				(type default)
			)
			(layer "F.SilkS")
		)
		(fp_line
			(start 0.67945 0.3048)
			(end 0.120396 0.3048)
			(stroke
				(width 0.1)
				(type default)
			)
			(layer "F.Fab")
		)
		(fp_line
			(start 0.67945 -0.3048)
			(end 0.67945 0.3048)
			(stroke
				(width 0.1)
				(type default)
			)
			(layer "F.Fab")
		)
		(fp_line
			(start 0.12065 -0.2794)
			(end 0.12065 -0.3048)
			(stroke
				(width 0.1)
				(type default)
			)
			(layer "F.Fab")
		)
		(fp_line
			(start 0.12065 -0.3048)
			(end 0.67945 -0.3048)
			(stroke
				(width 0.1)
				(type default)
			)
			(layer "F.Fab")
		)
		(fp_line
			(start 0.120396 0.3048)
			(end 0.120396 0.2794)
			(stroke
				(width 0.1)
				(type default)
			)
			(layer "F.Fab")
		)
		(fp_line
			(start 0.120396 0.2794)
			(end -0.12065 0.2794)
			(stroke
				(width 0.1)
				(type default)
			)
			(layer "F.Fab")
		)
		(fp_line
			(start -0.12065 0.3048)
			(end -0.67945 0.3048)
			(stroke
				(width 0.1)
				(type default)
			)
			(layer "F.Fab")
		)
		(fp_line
			(start -0.12065 0.2794)
			(end -0.12065 0.3048)
			(stroke
				(width 0.1)
				(type default)
			)
			(layer "F.Fab")
		)
		(fp_line
			(start -0.12065 -0.2794)
			(end 0.12065 -0.2794)
			(stroke
				(width 0.1)
				(type default)
			)
			(layer "F.Fab")
		)
		(fp_line
			(start -0.12065 -0.305054)
			(end -0.12065 -0.2794)
			(stroke
				(width 0.1)
				(type default)
			)
			(layer "F.Fab")
		)
		(fp_line
			(start -0.67945 0.3048)
			(end -0.67945 -0.305054)
			(stroke
				(width 0.1)
				(type default)
			)
			(layer "F.Fab")
		)
		(fp_line
			(start -0.67945 -0.305054)
			(end -0.12065 -0.305054)
			(stroke
				(width 0.1)
				(type default)
			)
			(layer "F.Fab")
		)
		(pad "1" smd circle
			(at -0.40005 0 180)
			(size 0 0)
			(layers "F.Cu" "F.Mask" "F.Paste")
			(net "USB_OC0_REAR_N")
		)
		(pad "2" smd circle
			(at 0.40005 0 180)
			(size 0 0)
			(layers "F.Cu" "F.Mask" "F.Paste")
			(net "USB_OC0_REAR_R_N")
		)
	)
	(footprint ""
		(layer "F.Cu")
		(at 24.3332 -30.6324 90)
		(property "Reference" "PR193"
			(at 0 0 90)
			(layer "F.SilkS")
			(hide yes)
			(effects
				(font
					(size 1.27 1.27)
				)
			)
		)
		(property "Value" ""
			(at 0 0 90)
			(layer "F.Fab")
			(effects
				(font
					(size 1.27 1.27)
				)
			)
		)
		(duplicate_pad_numbers_are_jumpers no)
		(fp_line
			(start 0.7874 -0.4064)
			(end 0.7874 0.4064)
			(stroke
				(width 0.1524)
				(type default)
			)
			(layer "F.SilkS")
		)
		(fp_line
			(start -0.7874 -0.4064)
			(end 0.7874 -0.4064)
			(stroke
				(width 0.1524)
				(type default)
			)
			(layer "F.SilkS")
		)
		(fp_line
			(start 0.7874 0.4064)
			(end -0.7874 0.4064)
			(stroke
				(width 0.1524)
				(type default)
			)
			(layer "F.SilkS")
		)
		(fp_line
			(start -0.7874 0.4064)
			(end -0.7874 -0.4064)
			(stroke
				(width 0.1524)
				(type default)
			)
			(layer "F.SilkS")
		)
		(fp_line
			(start -0.12065 -0.305054)
			(end -0.12065 -0.2794)
			(stroke
				(width 0.1)
				(type default)
			)
			(layer "F.Fab")
		)
		(fp_line
			(start -0.67945 -0.305054)
			(end -0.12065 -0.305054)
			(stroke
				(width 0.1)
				(type default)
			)
			(layer "F.Fab")
		)
		(fp_line
			(start 0.67945 -0.3048)
			(end 0.67945 0.3048)
			(stroke
				(width 0.1)
				(type default)
			)
			(layer "F.Fab")
		)
		(fp_line
			(start 0.12065 -0.3048)
			(end 0.67945 -0.3048)
			(stroke
				(width 0.1)
				(type default)
			)
			(layer "F.Fab")
		)
		(fp_line
			(start 0.12065 -0.2794)
			(end 0.12065 -0.3048)
			(stroke
				(width 0.1)
				(type default)
			)
			(layer "F.Fab")
		)
		(fp_line
			(start -0.12065 -0.2794)
			(end 0.12065 -0.2794)
			(stroke
				(width 0.1)
				(type default)
			)
			(layer "F.Fab")
		)
		(fp_line
			(start 0.120396 0.2794)
			(end -0.12065 0.2794)
			(stroke
				(width 0.1)
				(type default)
			)
			(layer "F.Fab")
		)
		(fp_line
			(start -0.12065 0.2794)
			(end -0.12065 0.3048)
			(stroke
				(width 0.1)
				(type default)
			)
			(layer "F.Fab")
		)
		(fp_line
			(start 0.67945 0.3048)
			(end 0.120396 0.3048)
			(stroke
				(width 0.1)
				(type default)
			)
			(layer "F.Fab")
		)
		(fp_line
			(start 0.120396 0.3048)
			(end 0.120396 0.2794)
			(stroke
				(width 0.1)
				(type default)
			)
			(layer "F.Fab")
		)
		(fp_line
			(start -0.12065 0.3048)
			(end -0.67945 0.3048)
			(stroke
				(width 0.1)
				(type default)
			)
			(layer "F.Fab")
		)
		(fp_line
			(start -0.67945 0.3048)
			(end -0.67945 -0.305054)
			(stroke
				(width 0.1)
				(type default)
			)
			(layer "F.Fab")
		)
		(pad "1" smd circle
			(at -0.40005 0 90)
			(size 0 0)
			(layers "F.Cu" "F.Mask" "F.Paste")
			(net "P3V3_AUX")
		)
		(pad "2" smd circle
			(at 0.40005 0 90)
			(size 0 0)
			(layers "F.Cu" "F.Mask" "F.Paste")
			(net "PVCC2_AUX")
		)
	)
	(footprint ""
		(layer "F.Cu")
		(at 74.74712 -35.127438)
		(property "Reference" "C124"
			(at 0 0 0)
			(layer "F.SilkS")
			(hide yes)
			(effects
				(font
					(size 1.27 1.27)
				)
			)
		)
		(property "Value" ""
			(at 0 0 0)
			(layer "F.Fab")
			(effects
				(font
					(size 1.27 1.27)
				)
			)
		)
		(duplicate_pad_numbers_are_jumpers no)
		(fp_line
			(start -1.2954 -0.5842)
			(end 1.2954 -0.5842)
			(stroke
				(width 0.1524)
				(type default)
			)
			(layer "F.SilkS")
		)
		(fp_line
			(start -1.2954 0.5842)
			(end -1.2954 -0.5842)
			(stroke
				(width 0.1524)
				(type default)
			)
			(layer "F.SilkS")
		)
		(fp_line
			(start 0 -0.5842)
			(end 0 0.5842)
			(stroke
				(width 0.1524)
				(type default)
			)
			(layer "F.SilkS")
		)
		(fp_line
			(start 1.2954 -0.5842)
			(end 1.2954 0.5842)
			(stroke
				(width 0.1524)
				(type default)
			)
			(layer "F.SilkS")
		)
		(fp_line
			(start 1.2954 0.5842)
			(end -1.2954 0.5842)
			(stroke
				(width 0.1524)
				(type default)
			)
			(layer "F.SilkS")
		)
		(fp_line
			(start -1.1938 -0.4064)
			(end -0.8636 -0.4064)
			(stroke
				(width 0.1)
				(type default)
			)
			(layer "F.Fab")
		)
		(fp_line
			(start -1.1938 0.4064)
			(end -1.1938 -0.4064)
			(stroke
				(width 0.1)
				(type default)
			)
			(layer "F.Fab")
		)
		(fp_line
			(start -0.8636 -0.4572)
			(end 0.8636 -0.4572)
			(stroke
				(width 0.1)
				(type default)
			)
			(layer "F.Fab")
		)
		(fp_line
			(start -0.8636 -0.4064)
			(end -0.8636 -0.4572)
			(stroke
				(width 0.1)
				(type default)
			)
			(layer "F.Fab")
		)
		(fp_line
			(start -0.8636 0.4064)
			(end -1.1938 0.4064)
			(stroke
				(width 0.1)
				(type default)
			)
			(layer "F.Fab")
		)
		(fp_line
			(start -0.8636 0.4572)
			(end -0.8636 0.4064)
			(stroke
				(width 0.1)
				(type default)
			)
			(layer "F.Fab")
		)
		(fp_line
			(start 0.8636 -0.4572)
			(end 0.8636 -0.4064)
			(stroke
				(width 0.1)
				(type default)
			)
			(layer "F.Fab")
		)
		(fp_line
			(start 0.8636 -0.4064)
			(end 1.1938 -0.4064)
			(stroke
				(width 0.1)
				(type default)
			)
			(layer "F.Fab")
		)
		(fp_line
			(start 0.8636 0.4064)
			(end 0.8636 0.4572)
			(stroke
				(width 0.1)
				(type default)
			)
			(layer "F.Fab")
		)
		(fp_line
			(start 0.8636 0.4572)
			(end -0.8636 0.4572)
			(stroke
				(width 0.1)
				(type default)
			)
			(layer "F.Fab")
		)
		(fp_line
			(start 1.1938 -0.4064)
			(end 1.1938 0.4064)
			(stroke
				(width 0.1)
				(type default)
			)
			(layer "F.Fab")
		)
		(fp_line
			(start 1.1938 0.4064)
			(end 0.8636 0.4064)
			(stroke
				(width 0.1)
				(type default)
			)
			(layer "F.Fab")
		)
		(pad "1" smd rect
			(at -0.7366 0 270)
			(size 0.7112 0.8128)
			(layers "F.Cu" "F.Mask" "F.Paste")
			(net "P1V8_AUX")
		)
		(pad "2" smd rect
			(at 0.7366 0 270)
			(size 0.7112 0.8128)
			(layers "F.Cu" "F.Mask" "F.Paste")
			(net "GND")
		)
	)
	(footprint ""
		(layer "F.Cu")
		(at 81.701386 -74.883264 180)
		(property "Reference" "PC253"
			(at 0 0 180)
			(layer "F.SilkS")
			(hide yes)
			(effects
				(font
					(size 1.27 1.27)
				)
			)
		)
		(property "Value" ""
			(at 0 0 180)
			(layer "F.Fab")
			(effects
				(font
					(size 1.27 1.27)
				)
			)
		)
		(duplicate_pad_numbers_are_jumpers no)
		(fp_line
			(start 0.7874 0.4064)
			(end -0.7874 0.4064)
			(stroke
				(width 0.1524)
				(type default)
			)
			(layer "F.SilkS")
		)
		(fp_line
			(start 0.7874 -0.4064)
			(end 0.7874 0.4064)
			(stroke
				(width 0.1524)
				(type default)
			)
			(layer "F.SilkS")
		)
		(fp_line
			(start -0.7874 0.4064)
			(end -0.7874 -0.4064)
			(stroke
				(width 0.1524)
				(type default)
			)
			(layer "F.SilkS")
		)
		(fp_line
			(start -0.7874 -0.4064)
			(end 0.7874 -0.4064)
			(stroke
				(width 0.1524)
				(type default)
			)
			(layer "F.SilkS")
		)
		(fp_line
			(start 0.67945 0.3048)
			(end 0.120396 0.3048)
			(stroke
				(width 0.1)
				(type default)
			)
			(layer "F.Fab")
		)
		(fp_line
			(start 0.67945 -0.3048)
			(end 0.67945 0.3048)
			(stroke
				(width 0.1)
				(type default)
			)
			(layer "F.Fab")
		)
		(fp_line
			(start 0.12065 -0.2794)
			(end 0.12065 -0.3048)
			(stroke
				(width 0.1)
				(type default)
			)
			(layer "F.Fab")
		)
		(fp_line
			(start 0.12065 -0.3048)
			(end 0.67945 -0.3048)
			(stroke
				(width 0.1)
				(type default)
			)
			(layer "F.Fab")
		)
		(fp_line
			(start 0.120396 0.3048)
			(end 0.120396 0.2794)
			(stroke
				(width 0.1)
				(type default)
			)
			(layer "F.Fab")
		)
		(fp_line
			(start 0.120396 0.2794)
			(end -0.12065 0.2794)
			(stroke
				(width 0.1)
				(type default)
			)
			(layer "F.Fab")
		)
		(fp_line
			(start -0.12065 0.3048)
			(end -0.67945 0.3048)
			(stroke
				(width 0.1)
				(type default)
			)
			(layer "F.Fab")
		)
		(fp_line
			(start -0.12065 0.2794)
			(end -0.12065 0.3048)
			(stroke
				(width 0.1)
				(type default)
			)
			(layer "F.Fab")
		)
		(fp_line
			(start -0.12065 -0.2794)
			(end 0.12065 -0.2794)
			(stroke
				(width 0.1)
				(type default)
			)
			(layer "F.Fab")
		)
		(fp_line
			(start -0.12065 -0.305054)
			(end -0.12065 -0.2794)
			(stroke
				(width 0.1)
				(type default)
			)
			(layer "F.Fab")
		)
		(fp_line
			(start -0.67945 0.3048)
			(end -0.67945 -0.305054)
			(stroke
				(width 0.1)
				(type default)
			)
			(layer "F.Fab")
		)
		(fp_line
			(start -0.67945 -0.305054)
			(end -0.12065 -0.305054)
			(stroke
				(width 0.1)
				(type default)
			)
			(layer "F.Fab")
		)
		(pad "1" smd circle
			(at -0.40005 0 180)
			(size 0 0)
			(layers "F.Cu" "F.Mask" "F.Paste")
			(net "SW_P1V2_AUX_FLT")
		)
		(pad "2" smd circle
			(at 0.40005 0 180)
			(size 0 0)
			(layers "F.Cu" "F.Mask" "F.Paste")
			(net "GND")
		)
	)
	(footprint ""
		(layer "F.Cu")
		(at 39.9542 -48.6918 180)
		(property "Reference" "R177"
			(at 0 0 180)
			(layer "F.SilkS")
			(hide yes)
			(effects
				(font
					(size 1.27 1.27)
				)
			)
		)
		(property "Value" ""
			(at 0 0 180)
			(layer "F.Fab")
			(effects
				(font
					(size 1.27 1.27)
				)
			)
		)
		(duplicate_pad_numbers_are_jumpers no)
		(fp_line
			(start 0.7874 0.4064)
			(end -0.7874 0.4064)
			(stroke
				(width 0.1524)
				(type default)
			)
			(layer "F.SilkS")
		)
		(fp_line
			(start 0.7874 -0.4064)
			(end 0.7874 0.4064)
			(stroke
				(width 0.1524)
				(type default)
			)
			(layer "F.SilkS")
		)
		(fp_line
			(start -0.7874 0.4064)
			(end -0.7874 -0.4064)
			(stroke
				(width 0.1524)
				(type default)
			)
			(layer "F.SilkS")
		)
		(fp_line
			(start -0.7874 -0.4064)
			(end 0.7874 -0.4064)
			(stroke
				(width 0.1524)
				(type default)
			)
			(layer "F.SilkS")
		)
		(fp_line
			(start 0.67945 0.3048)
			(end 0.120396 0.3048)
			(stroke
				(width 0.1)
				(type default)
			)
			(layer "F.Fab")
		)
		(fp_line
			(start 0.67945 -0.3048)
			(end 0.67945 0.3048)
			(stroke
				(width 0.1)
				(type default)
			)
			(layer "F.Fab")
		)
		(fp_line
			(start 0.12065 -0.2794)
			(end 0.12065 -0.3048)
			(stroke
				(width 0.1)
				(type default)
			)
			(layer "F.Fab")
		)
		(fp_line
			(start 0.12065 -0.3048)
			(end 0.67945 -0.3048)
			(stroke
				(width 0.1)
				(type default)
			)
			(layer "F.Fab")
		)
		(fp_line
			(start 0.120396 0.3048)
			(end 0.120396 0.2794)
			(stroke
				(width 0.1)
				(type default)
			)
			(layer "F.Fab")
		)
		(fp_line
			(start 0.120396 0.2794)
			(end -0.12065 0.2794)
			(stroke
				(width 0.1)
				(type default)
			)
			(layer "F.Fab")
		)
		(fp_line
			(start -0.12065 0.3048)
			(end -0.67945 0.3048)
			(stroke
				(width 0.1)
				(type default)
			)
			(layer "F.Fab")
		)
		(fp_line
			(start -0.12065 0.2794)
			(end -0.12065 0.3048)
			(stroke
				(width 0.1)
				(type default)
			)
			(layer "F.Fab")
		)
		(fp_line
			(start -0.12065 -0.2794)
			(end 0.12065 -0.2794)
			(stroke
				(width 0.1)
				(type default)
			)
			(layer "F.Fab")
		)
		(fp_line
			(start -0.12065 -0.305054)
			(end -0.12065 -0.2794)
			(stroke
				(width 0.1)
				(type default)
			)
			(layer "F.Fab")
		)
		(fp_line
			(start -0.67945 0.3048)
			(end -0.67945 -0.305054)
			(stroke
				(width 0.1)
				(type default)
			)
			(layer "F.Fab")
		)
		(fp_line
			(start -0.67945 -0.305054)
			(end -0.12065 -0.305054)
			(stroke
				(width 0.1)
				(type default)
			)
			(layer "F.Fab")
		)
		(pad "1" smd circle
			(at -0.40005 0 180)
			(size 0 0)
			(layers "F.Cu" "F.Mask" "F.Paste")
			(net "H_CPU1_PROCHOT_LVC1_N")
		)
		(pad "2" smd circle
			(at 0.40005 0 180)
			(size 0 0)
			(layers "F.Cu" "F.Mask" "F.Paste")
			(net "H_CPU1_PROCHOT_LVC1_R_N")
		)
	)
	(footprint ""
		(layer "F.Cu")
		(at 9.65581 -57.393332 180)
		(property "Reference" "PL19"
			(at 0 0 180)
			(layer "F.SilkS")
			(hide yes)
			(effects
				(font
					(size 1.27 1.27)
				)
			)
		)
		(property "Value" ""
			(at 0 0 180)
			(layer "F.Fab")
			(effects
				(font
					(size 1.27 1.27)
				)
			)
		)
		(duplicate_pad_numbers_are_jumpers no)
		(fp_line
			(start 1.27 0.5842)
			(end 1.27 -0.5842)
			(stroke
				(width 0.1524)
				(type default)
			)
			(layer "F.SilkS")
		)
		(fp_line
			(start 1.27 0.5842)
			(end -1.27 0.5842)
			(stroke
				(width 0.1524)
				(type default)
			)
			(layer "F.SilkS")
		)
		(fp_line
			(start 0.127 0.5842)
			(end 0.127 -0.5842)
			(stroke
				(width 0.1524)
				(type default)
			)
			(layer "F.SilkS")
		)
		(fp_line
			(start -0.127 0.5842)
			(end -0.127 -0.5842)
			(stroke
				(width 0.1524)
				(type default)
			)
			(layer "F.SilkS")
		)
		(fp_line
			(start -1.27 0.5842)
			(end -1.27 -0.5842)
			(stroke
				(width 0.1524)
				(type default)
			)
			(layer "F.SilkS")
		)
		(fp_line
			(start -1.27 -0.5588)
			(end -1.27 -0.5842)
			(stroke
				(width 0.1524)
				(type default)
			)
			(layer "F.SilkS")
		)
		(fp_line
			(start -1.27 -0.5842)
			(end 1.27 -0.5842)
			(stroke
				(width 0.1524)
				(type default)
			)
			(layer "F.SilkS")
		)
		(fp_line
			(start 1.1938 0.4064)
			(end 0.9144 0.4064)
			(stroke
				(width 0.1)
				(type default)
			)
			(layer "F.Fab")
		)
		(fp_line
			(start 1.1938 -0.406654)
			(end 1.1938 0.4064)
			(stroke
				(width 0.1)
				(type default)
			)
			(layer "F.Fab")
		)
		(fp_line
			(start 0.9144 0.508)
			(end -0.9144 0.508)
			(stroke
				(width 0.1)
				(type default)
			)
			(layer "F.Fab")
		)
		(fp_line
			(start 0.9144 0.4064)
			(end 0.9144 0.508)
			(stroke
				(width 0.1)
				(type default)
			)
			(layer "F.Fab")
		)
		(fp_line
			(start 0.9144 -0.406654)
			(end 1.1938 -0.406654)
			(stroke
				(width 0.1)
				(type default)
			)
			(layer "F.Fab")
		)
		(fp_line
			(start 0.9144 -0.508)
			(end 0.9144 -0.406654)
			(stroke
				(width 0.1)
				(type default)
			)
			(layer "F.Fab")
		)
		(fp_line
			(start -0.9144 0.508)
			(end -0.9144 0.406654)
			(stroke
				(width 0.1)
				(type default)
			)
			(layer "F.Fab")
		)
		(fp_line
			(start -0.9144 0.406654)
			(end -1.194308 0.406654)
			(stroke
				(width 0.1)
				(type default)
			)
			(layer "F.Fab")
		)
		(fp_line
			(start -0.9144 -0.406654)
			(end -0.9144 -0.508)
			(stroke
				(width 0.1)
				(type default)
			)
			(layer "F.Fab")
		)
		(fp_line
			(start -0.9144 -0.508)
			(end 0.9144 -0.508)
			(stroke
				(width 0.1)
				(type default)
			)
			(layer "F.Fab")
		)
		(fp_line
			(start -1.194308 0.406654)
			(end -1.194308 -0.406654)
			(stroke
				(width 0.1)
				(type default)
			)
			(layer "F.Fab")
		)
		(fp_line
			(start -1.194308 -0.406654)
			(end -0.9144 -0.406654)
			(stroke
				(width 0.1)
				(type default)
			)
			(layer "F.Fab")
		)
		(pad "1" smd rect
			(at -0.7366 0 90)
			(size 0.7112 0.8128)
			(layers "F.Cu" "F.Mask" "F.Paste")
			(net "P12V_AUX")
		)
		(pad "2" smd rect
			(at 0.7366 0 90)
			(size 0.7112 0.8128)
			(layers "F.Cu" "F.Mask" "F.Paste")
			(net "SW_P3V3_AUX_FLT")
		)
	)
	(footprint ""
		(layer "F.Cu")
		(at 81.6102 -17.907 180)
		(property "Reference" "U32"
			(at 2.101088 1.814322 0)
			(unlocked yes)
			(layer "F.SilkS")
			(effects
				(font
					(size 0.7874 0.5842)
					(thickness 0.1524)
				)
				(justify left)
			)
		)
		(property "Value" ""
			(at 0 0 180)
			(layer "F.Fab")
			(effects
				(font
					(size 1.27 1.27)
				)
			)
		)
		(duplicate_pad_numbers_are_jumpers no)
		(fp_line
			(start 1.695958 1.124966)
			(end -1.695958 1.124966)
			(stroke
				(width 0.1524)
				(type default)
			)
			(layer "F.SilkS")
		)
		(fp_line
			(start 1.695958 -1.124966)
			(end 1.695958 1.124966)
			(stroke
				(width 0.1524)
				(type default)
			)
			(layer "F.SilkS")
		)
		(fp_line
			(start -1.695958 1.124966)
			(end -1.695958 -1.124966)
			(stroke
				(width 0.1524)
				(type default)
			)
			(layer "F.SilkS")
		)
		(fp_line
			(start -1.695958 -1.124966)
			(end 1.695958 -1.124966)
			(stroke
				(width 0.1524)
				(type default)
			)
			(layer "F.SilkS")
		)
		(fp_poly
			(pts
				(xy -0.359918 -2.054352) (xy -0.712216 -1.457452) (xy -0.978154 -2.097278)
			)
			(stroke
				(width 0)
				(type default)
			)
			(fill yes)
			(layer "F.SilkS")
		)
		(fp_line
			(start 0.674878 1.124966)
			(end -0.674878 1.124966)
			(stroke
				(width 0.1)
				(type default)
			)
			(layer "F.Fab")
		)
		(fp_line
			(start 0.674878 -1.124966)
			(end 0.674878 1.124966)
			(stroke
				(width 0.1)
				(type default)
			)
			(layer "F.Fab")
		)
		(fp_line
			(start -0.674878 1.124966)
			(end -0.674878 -1.124966)
			(stroke
				(width 0.1)
				(type default)
			)
			(layer "F.Fab")
		)
		(fp_line
			(start -0.674878 -1.124966)
			(end 0.674878 -1.124966)
			(stroke
				(width 0.1)
				(type default)
			)
			(layer "F.Fab")
		)
		(fp_poly
			(pts
				(xy -2.4892 -0.959866) (xy -1.86944 -0.649986) (xy -2.4892 -0.340106)
			)
			(stroke
				(width 0)
				(type default)
			)
			(fill yes)
			(layer "F.Fab")
		)
		(pad "1" smd rect
			(at -0.94488 -0.649986 270)
			(size 0.3556 1.2446)
			(layers "F.Cu" "F.Mask" "F.Paste")
			(net "TP_ID_BUF")
		)
		(pad "2" smd rect
			(at -0.94488 0 270)
			(size 0.3556 1.2446)
			(layers "F.Cu" "F.Mask" "F.Paste")
			(net "REAR_ID_RST_BTN_N")
		)
		(pad "3" smd rect
			(at -0.94488 0.649986 270)
			(size 0.3556 1.2446)
			(layers "F.Cu" "F.Mask" "F.Paste")
			(net "GND")
		)
		(pad "4" smd rect
			(at 0.94488 0.649986 270)
			(size 0.3556 1.2446)
			(layers "F.Cu" "F.Mask" "F.Paste")
			(net "ID_RST_BTN_BMC_N")
		)
		(pad "5" smd rect
			(at 0.94488 -0.649986 270)
			(size 0.3556 1.2446)
			(layers "F.Cu" "F.Mask" "F.Paste")
			(net "P3V3_AUX")
		)
	)
	(footprint ""
		(layer "F.Cu")
		(at 22.373082 -31.361888 90)
		(property "Reference" "PC260"
			(at 0 0 90)
			(layer "F.SilkS")
			(hide yes)
			(effects
				(font
					(size 1.27 1.27)
				)
			)
		)
		(property "Value" ""
			(at 0 0 90)
			(layer "F.Fab")
			(effects
				(font
					(size 1.27 1.27)
				)
			)
		)
		(duplicate_pad_numbers_are_jumpers no)
		(fp_line
			(start 0.7874 -0.4064)
			(end 0.7874 0.4064)
			(stroke
				(width 0.1524)
				(type default)
			)
			(layer "F.SilkS")
		)
		(fp_line
			(start -0.7874 -0.4064)
			(end 0.7874 -0.4064)
			(stroke
				(width 0.1524)
				(type default)
			)
			(layer "F.SilkS")
		)
		(fp_line
			(start 0.7874 0.4064)
			(end -0.7874 0.4064)
			(stroke
				(width 0.1524)
				(type default)
			)
			(layer "F.SilkS")
		)
		(fp_line
			(start -0.7874 0.4064)
			(end -0.7874 -0.4064)
			(stroke
				(width 0.1524)
				(type default)
			)
			(layer "F.SilkS")
		)
		(fp_line
			(start -0.12065 -0.305054)
			(end -0.12065 -0.2794)
			(stroke
				(width 0.1)
				(type default)
			)
			(layer "F.Fab")
		)
		(fp_line
			(start -0.67945 -0.305054)
			(end -0.12065 -0.305054)
			(stroke
				(width 0.1)
				(type default)
			)
			(layer "F.Fab")
		)
		(fp_line
			(start 0.67945 -0.3048)
			(end 0.67945 0.3048)
			(stroke
				(width 0.1)
				(type default)
			)
			(layer "F.Fab")
		)
		(fp_line
			(start 0.12065 -0.3048)
			(end 0.67945 -0.3048)
			(stroke
				(width 0.1)
				(type default)
			)
			(layer "F.Fab")
		)
		(fp_line
			(start 0.12065 -0.2794)
			(end 0.12065 -0.3048)
			(stroke
				(width 0.1)
				(type default)
			)
			(layer "F.Fab")
		)
		(fp_line
			(start -0.12065 -0.2794)
			(end 0.12065 -0.2794)
			(stroke
				(width 0.1)
				(type default)
			)
			(layer "F.Fab")
		)
		(fp_line
			(start 0.120396 0.2794)
			(end -0.12065 0.2794)
			(stroke
				(width 0.1)
				(type default)
			)
			(layer "F.Fab")
		)
		(fp_line
			(start -0.12065 0.2794)
			(end -0.12065 0.3048)
			(stroke
				(width 0.1)
				(type default)
			)
			(layer "F.Fab")
		)
		(fp_line
			(start 0.67945 0.3048)
			(end 0.120396 0.3048)
			(stroke
				(width 0.1)
				(type default)
			)
			(layer "F.Fab")
		)
		(fp_line
			(start 0.120396 0.3048)
			(end 0.120396 0.2794)
			(stroke
				(width 0.1)
				(type default)
			)
			(layer "F.Fab")
		)
		(fp_line
			(start -0.12065 0.3048)
			(end -0.67945 0.3048)
			(stroke
				(width 0.1)
				(type default)
			)
			(layer "F.Fab")
		)
		(fp_line
			(start -0.67945 0.3048)
			(end -0.67945 -0.305054)
			(stroke
				(width 0.1)
				(type default)
			)
			(layer "F.Fab")
		)
		(pad "1" smd circle
			(at -0.40005 0 90)
			(size 0 0)
			(layers "F.Cu" "F.Mask" "F.Paste")
			(net "P1V0_AUX_VCC")
		)
		(pad "2" smd circle
			(at 0.40005 0 90)
			(size 0 0)
			(layers "F.Cu" "F.Mask" "F.Paste")
			(net "GND")
		)
	)
	(footprint ""
		(layer "F.Cu")
		(at 7.239 -59.309 180)
		(property "Reference" "PC219"
			(at 0 0 180)
			(layer "F.SilkS")
			(hide yes)
			(effects
				(font
					(size 1.27 1.27)
				)
			)
		)
		(property "Value" ""
			(at 0 0 180)
			(layer "F.Fab")
			(effects
				(font
					(size 1.27 1.27)
				)
			)
		)
		(duplicate_pad_numbers_are_jumpers no)
		(fp_line
			(start 1.524 0.762)
			(end -1.524 0.762)
			(stroke
				(width 0.1524)
				(type default)
			)
			(layer "F.SilkS")
		)
		(fp_line
			(start 1.524 -0.762)
			(end 1.524 0.762)
			(stroke
				(width 0.1524)
				(type default)
			)
			(layer "F.SilkS")
		)
		(fp_line
			(start -1.524 0.762)
			(end -1.524 -0.762)
			(stroke
				(width 0.1524)
				(type default)
			)
			(layer "F.SilkS")
		)
		(fp_line
			(start -1.524 -0.762)
			(end 1.524 -0.762)
			(stroke
				(width 0.1524)
				(type default)
			)
			(layer "F.SilkS")
		)
		(fp_line
			(start 1.1049 0.724916)
			(end 1.1049 -0.724916)
			(stroke
				(width 0.1)
				(type default)
			)
			(layer "F.Fab")
		)
		(fp_line
			(start 1.1049 -0.724916)
			(end -1.1049 -0.724916)
			(stroke
				(width 0.1)
				(type default)
			)
			(layer "F.Fab")
		)
		(fp_line
			(start -1.1049 0.724916)
			(end 1.1049 0.724916)
			(stroke
				(width 0.1)
				(type default)
			)
			(layer "F.Fab")
		)
		(fp_line
			(start -1.1049 -0.724916)
			(end -1.1049 0.724916)
			(stroke
				(width 0.1)
				(type default)
			)
			(layer "F.Fab")
		)
		(pad "1" smd rect
			(at -0.889 0)
			(size 1.016 1.27)
			(layers "F.Cu" "F.Mask" "F.Paste")
			(net "SW_P3V3_AUX_FLT")
		)
		(pad "2" smd rect
			(at 0.889 0)
			(size 1.016 1.27)
			(layers "F.Cu" "F.Mask" "F.Paste")
			(net "GND")
		)
	)
	(footprint ""
		(layer "F.Cu")
		(at 78.907894 -28.196032 -90)
		(property "Reference" "D0"
			(at 2.237232 -7.427976 90)
			(unlocked yes)
			(layer "F.SilkS")
			(effects
				(font
					(size 0.7874 0.5842)
					(thickness 0.1524)
				)
				(justify left)
			)
		)
		(property "Value" ""
			(at 0 0 270)
			(layer "F.Fab")
			(effects
				(font
					(size 1.27 1.27)
				)
			)
		)
		(duplicate_pad_numbers_are_jumpers no)
		(fp_line
			(start -1.3208 0.5588)
			(end -1.3208 -0.5588)
			(stroke
				(width 0.1524)
				(type default)
			)
			(layer "F.SilkS")
		)
		(fp_line
			(start 1.3208 0.5588)
			(end -1.3208 0.5588)
			(stroke
				(width 0.1524)
				(type default)
			)
			(layer "F.SilkS")
		)
		(fp_line
			(start 1.6256 0.5588)
			(end 1.6256 -0.5588)
			(stroke
				(width 0.1524)
				(type default)
			)
			(layer "F.SilkS")
		)
		(fp_line
			(start 1.778 0.5588)
			(end 1.3208 0.5588)
			(stroke
				(width 0.1524)
				(type default)
			)
			(layer "F.SilkS")
		)
		(fp_line
			(start -1.3208 -0.5588)
			(end 1.3208 -0.5588)
			(stroke
				(width 0.1524)
				(type default)
			)
			(layer "F.SilkS")
		)
		(fp_line
			(start 1.3208 -0.5588)
			(end 1.3208 0.5588)
			(stroke
				(width 0.1524)
				(type default)
			)
			(layer "F.SilkS")
		)
		(fp_line
			(start 1.4732 -0.5588)
			(end 1.4732 0.5588)
			(stroke
				(width 0.1524)
				(type default)
			)
			(layer "F.SilkS")
		)
		(fp_line
			(start 1.778 -0.5588)
			(end 1.778 0.5588)
			(stroke
				(width 0.1524)
				(type default)
			)
			(layer "F.SilkS")
		)
		(fp_line
			(start 1.778 -0.5588)
			(end 1.3208 -0.5588)
			(stroke
				(width 0.1524)
				(type default)
			)
			(layer "F.SilkS")
		)
		(fp_line
			(start -1.235964 0.508)
			(end -1.1684 0.508)
			(stroke
				(width 0.1)
				(type default)
			)
			(layer "F.Fab")
		)
		(fp_line
			(start -1.1684 0.508)
			(end 1.1684 0.508)
			(stroke
				(width 0.1)
				(type default)
			)
			(layer "F.Fab")
		)
		(fp_line
			(start 1.1684 0.508)
			(end 1.236726 0.508)
			(stroke
				(width 0.1)
				(type default)
			)
			(layer "F.Fab")
		)
		(fp_line
			(start 1.236726 0.508)
			(end 1.236726 -0.508)
			(stroke
				(width 0.1)
				(type default)
			)
			(layer "F.Fab")
		)
		(fp_line
			(start -1.235964 -0.508)
			(end -1.235964 0.508)
			(stroke
				(width 0.1)
				(type default)
			)
			(layer "F.Fab")
		)
		(fp_line
			(start -1.1684 -0.508)
			(end -1.235964 -0.508)
			(stroke
				(width 0.1)
				(type default)
			)
			(layer "F.Fab")
		)
		(fp_line
			(start 1.1684 -0.508)
			(end -1.1684 -0.508)
			(stroke
				(width 0.1)
				(type default)
			)
			(layer "F.Fab")
		)
		(fp_line
			(start 1.236726 -0.508)
			(end 1.1684 -0.508)
			(stroke
				(width 0.1)
				(type default)
			)
			(layer "F.Fab")
		)
		(fp_text user "-"
			(at 1.654302 -0.867156 270)
			(unlocked yes)
			(layer "F.SilkS")
			(effects
				(font
					(size 1.905 1.4224)
					(thickness 0.1524)
				)
				(justify left)
			)
		)
		(fp_text user "+"
			(at -0.711454 -0.930402 90)
			(unlocked yes)
			(layer "F.SilkS")
			(effects
				(font
					(size 1.905 1.4224)
					(thickness 0.1524)
				)
				(justify left)
			)
		)
		(fp_text user "+"
			(at -2.5654 -0.24765 270)
			(unlocked yes)
			(layer "F.Fab")
			(effects
				(font
					(size 1.905 1.4224)
					(thickness 0.1524)
				)
				(justify left)
			)
		)
		(fp_text user "-"
			(at 1.524 -0.24765 270)
			(unlocked yes)
			(layer "F.Fab")
			(effects
				(font
					(size 1.905 1.4224)
					(thickness 0.1524)
				)
				(justify left)
			)
		)
		(pad "A" smd rect
			(at -0.750062 0 270)
			(size 0.8128 0.8128)
			(layers "F.Cu" "F.Mask" "F.Paste")
			(net "LED_POSTCODE_0_R")
		)
		(pad "C" smd rect
			(at 0.750062 0 270)
			(size 0.8128 0.8128)
			(layers "F.Cu" "F.Mask" "F.Paste")
			(net "GND")
		)
	)
	(footprint ""
		(layer "F.Cu")
		(at 24.9682 -62.3062 90)
		(property "Reference" "U2"
			(at -3.81 0.89027 90)
			(unlocked yes)
			(layer "F.SilkS")
			(effects
				(font
					(size 0.7874 0.5842)
					(thickness 0.1524)
				)
				(justify left)
			)
		)
		(property "Value" ""
			(at 0 0 90)
			(layer "F.Fab")
			(effects
				(font
					(size 1.27 1.27)
				)
			)
		)
		(duplicate_pad_numbers_are_jumpers no)
		(fp_line
			(start 0.8636 -1.050036)
			(end 0.542036 -1.050036)
			(stroke
				(width 0.1524)
				(type default)
			)
			(layer "F.SilkS")
		)
		(fp_line
			(start 0.542036 -1.050036)
			(end 0 -0.508)
			(stroke
				(width 0.1524)
				(type default)
			)
			(layer "F.SilkS")
		)
		(fp_line
			(start -0.542036 -1.050036)
			(end -0.8636 -1.050036)
			(stroke
				(width 0.1524)
				(type default)
			)
			(layer "F.SilkS")
		)
		(fp_line
			(start -0.8636 -1.050036)
			(end -0.8636 1.050036)
			(stroke
				(width 0.1524)
				(type default)
			)
			(layer "F.SilkS")
		)
		(fp_line
			(start 0 -0.508)
			(end -0.542036 -1.050036)
			(stroke
				(width 0.1524)
				(type default)
			)
			(layer "F.SilkS")
		)
		(fp_line
			(start 0.8636 1.050036)
			(end 0.8636 -1.050036)
			(stroke
				(width 0.1524)
				(type default)
			)
			(layer "F.SilkS")
		)
		(fp_line
			(start -0.8636 1.050036)
			(end 0.8636 1.050036)
			(stroke
				(width 0.1524)
				(type default)
			)
			(layer "F.SilkS")
		)
		(fp_poly
			(pts
				(xy -2.794 -1.258062) (xy -2.794 -0.242062) (xy -1.778 -0.750062)
			)
			(stroke
				(width 0)
				(type default)
			)
			(fill yes)
			(layer "F.SilkS")
		)
		(fp_line
			(start 1.199896 -1.050036)
			(end -1.199896 -1.050036)
			(stroke
				(width 0.1)
				(type default)
			)
			(layer "F.Fab")
		)
		(fp_line
			(start -1.199896 -1.050036)
			(end -1.199896 1.050036)
			(stroke
				(width 0.1)
				(type default)
			)
			(layer "F.Fab")
		)
		(fp_line
			(start 1.199896 1.050036)
			(end 1.199896 -1.050036)
			(stroke
				(width 0.1)
				(type default)
			)
			(layer "F.Fab")
		)
		(fp_line
			(start -1.199896 1.050036)
			(end 1.199896 1.050036)
			(stroke
				(width 0.1)
				(type default)
			)
			(layer "F.Fab")
		)
		(fp_poly
			(pts
				(xy -2.794 -1.258062) (xy -2.794 -0.242062) (xy -1.778 -0.750062)
			)
			(stroke
				(width 0)
				(type default)
			)
			(fill yes)
			(layer "F.Fab")
		)
		(pad "1" smd rect
			(at -1.35001 -0.750062)
			(size 0.2794 0.7112)
			(layers "F.Cu" "F.Mask" "F.Paste")
			(net "UART_BIC_DBG_TX")
		)
		(pad "2" smd rect
			(at -1.35001 -0.249936)
			(size 0.2794 0.7112)
			(layers "F.Cu" "F.Mask" "F.Paste")
			(net "UART_BMC_5_TXD_BUF1_R")
		)
		(pad "3" smd rect
			(at -1.35001 0.249936)
			(size 0.2794 0.7112)
			(layers "F.Cu" "F.Mask" "F.Paste")
			(net "UART_BMC_1_TXD_R")
		)
		(pad "4" smd rect
			(at -1.35001 0.750062)
			(size 0.2794 0.7112)
			(layers "F.Cu" "F.Mask" "F.Paste")
			(net "GND")
		)
		(pad "5" smd rect
			(at 1.35001 0.750062)
			(size 0.2794 0.7112)
			(layers "F.Cu" "F.Mask" "F.Paste")
			(net "FM_UARTSW_LSB_N")
		)
		(pad "6" smd rect
			(at 1.35001 0.249936)
			(size 0.2794 0.7112)
			(layers "F.Cu" "F.Mask" "F.Paste")
			(net "FM_UARTSW_MSB_N")
		)
		(pad "7" smd rect
			(at 1.35001 -0.249936)
			(size 0.2794 0.7112)
			(layers "F.Cu" "F.Mask" "F.Paste")
			(net "SPA_SOUT_SW_BUF")
		)
		(pad "8" smd rect
			(at 1.35001 -0.750062)
			(size 0.2794 0.7112)
			(layers "F.Cu" "F.Mask" "F.Paste")
			(net "P3V3_AUX")
		)
	)
	(footprint ""
		(layer "F.Cu")
		(at 8.849106 -78.183994 90)
		(property "Reference" "PC228"
			(at 0 0 90)
			(layer "F.SilkS")
			(hide yes)
			(effects
				(font
					(size 1.27 1.27)
				)
			)
		)
		(property "Value" ""
			(at 0 0 90)
			(layer "F.Fab")
			(effects
				(font
					(size 1.27 1.27)
				)
			)
		)
		(duplicate_pad_numbers_are_jumpers no)
		(fp_line
			(start 1.651 -0.8382)
			(end 1.651 0.8382)
			(stroke
				(width 0.1524)
				(type default)
			)
			(layer "F.SilkS")
		)
		(fp_line
			(start -1.651 -0.8382)
			(end 1.651 -0.8382)
			(stroke
				(width 0.1524)
				(type default)
			)
			(layer "F.SilkS")
		)
		(fp_line
			(start 1.651 0.8382)
			(end -1.651 0.8382)
			(stroke
				(width 0.1524)
				(type default)
			)
			(layer "F.SilkS")
		)
		(fp_line
			(start 0 0.8382)
			(end 0 -0.8382)
			(stroke
				(width 0.1524)
				(type default)
			)
			(layer "F.SilkS")
		)
		(fp_line
			(start -1.651 0.8382)
			(end -1.651 -0.8382)
			(stroke
				(width 0.1524)
				(type default)
			)
			(layer "F.SilkS")
		)
		(fp_line
			(start 1.55956 -0.7366)
			(end 1.524 -0.7366)
			(stroke
				(width 0.1)
				(type default)
			)
			(layer "F.Fab")
		)
		(fp_line
			(start 1.524 -0.7366)
			(end -1.524 -0.7366)
			(stroke
				(width 0.1)
				(type default)
			)
			(layer "F.Fab")
		)
		(fp_line
			(start -1.524 -0.7366)
			(end -1.55956 -0.7366)
			(stroke
				(width 0.1)
				(type default)
			)
			(layer "F.Fab")
		)
		(fp_line
			(start -1.55956 -0.7366)
			(end -1.55956 0.7366)
			(stroke
				(width 0.1)
				(type default)
			)
			(layer "F.Fab")
		)
		(fp_line
			(start 1.55956 0.7366)
			(end 1.55956 -0.7366)
			(stroke
				(width 0.1)
				(type default)
			)
			(layer "F.Fab")
		)
		(fp_line
			(start 1.524 0.7366)
			(end 1.55956 0.7366)
			(stroke
				(width 0.1)
				(type default)
			)
			(layer "F.Fab")
		)
		(fp_line
			(start -1.524 0.7366)
			(end 1.524 0.7366)
			(stroke
				(width 0.1)
				(type default)
			)
			(layer "F.Fab")
		)
		(fp_line
			(start -1.55956 0.7366)
			(end -1.524 0.7366)
			(stroke
				(width 0.1)
				(type default)
			)
			(layer "F.Fab")
		)
		(pad "1" smd rect
			(at -0.94996 0 270)
			(size 1.1176 1.3716)
			(layers "F.Cu" "F.Mask" "F.Paste")
			(net "P3V3_AUX")
		)
		(pad "2" smd rect
			(at 0.94996 0 270)
			(size 1.1176 1.3716)
			(layers "F.Cu" "F.Mask" "F.Paste")
			(net "GND")
		)
	)
	(footprint ""
		(layer "F.Cu")
		(at 38.608 -108.966 180)
		(property "Reference" "R63"
			(at 0 0 180)
			(layer "F.SilkS")
			(hide yes)
			(effects
				(font
					(size 1.27 1.27)
				)
			)
		)
		(property "Value" ""
			(at 0 0 180)
			(layer "F.Fab")
			(effects
				(font
					(size 1.27 1.27)
				)
			)
		)
		(duplicate_pad_numbers_are_jumpers no)
		(fp_line
			(start 0.7874 0.4064)
			(end -0.7874 0.4064)
			(stroke
				(width 0.1524)
				(type default)
			)
			(layer "F.SilkS")
		)
		(fp_line
			(start 0.7874 -0.4064)
			(end 0.7874 0.4064)
			(stroke
				(width 0.1524)
				(type default)
			)
			(layer "F.SilkS")
		)
		(fp_line
			(start -0.7874 0.4064)
			(end -0.7874 -0.4064)
			(stroke
				(width 0.1524)
				(type default)
			)
			(layer "F.SilkS")
		)
		(fp_line
			(start -0.7874 -0.4064)
			(end 0.7874 -0.4064)
			(stroke
				(width 0.1524)
				(type default)
			)
			(layer "F.SilkS")
		)
		(fp_line
			(start 0.67945 0.3048)
			(end 0.120396 0.3048)
			(stroke
				(width 0.1)
				(type default)
			)
			(layer "F.Fab")
		)
		(fp_line
			(start 0.67945 -0.3048)
			(end 0.67945 0.3048)
			(stroke
				(width 0.1)
				(type default)
			)
			(layer "F.Fab")
		)
		(fp_line
			(start 0.12065 -0.2794)
			(end 0.12065 -0.3048)
			(stroke
				(width 0.1)
				(type default)
			)
			(layer "F.Fab")
		)
		(fp_line
			(start 0.12065 -0.3048)
			(end 0.67945 -0.3048)
			(stroke
				(width 0.1)
				(type default)
			)
			(layer "F.Fab")
		)
		(fp_line
			(start 0.120396 0.3048)
			(end 0.120396 0.2794)
			(stroke
				(width 0.1)
				(type default)
			)
			(layer "F.Fab")
		)
		(fp_line
			(start 0.120396 0.2794)
			(end -0.12065 0.2794)
			(stroke
				(width 0.1)
				(type default)
			)
			(layer "F.Fab")
		)
		(fp_line
			(start -0.12065 0.3048)
			(end -0.67945 0.3048)
			(stroke
				(width 0.1)
				(type default)
			)
			(layer "F.Fab")
		)
		(fp_line
			(start -0.12065 0.2794)
			(end -0.12065 0.3048)
			(stroke
				(width 0.1)
				(type default)
			)
			(layer "F.Fab")
		)
		(fp_line
			(start -0.12065 -0.2794)
			(end 0.12065 -0.2794)
			(stroke
				(width 0.1)
				(type default)
			)
			(layer "F.Fab")
		)
		(fp_line
			(start -0.12065 -0.305054)
			(end -0.12065 -0.2794)
			(stroke
				(width 0.1)
				(type default)
			)
			(layer "F.Fab")
		)
		(fp_line
			(start -0.67945 0.3048)
			(end -0.67945 -0.305054)
			(stroke
				(width 0.1)
				(type default)
			)
			(layer "F.Fab")
		)
		(fp_line
			(start -0.67945 -0.305054)
			(end -0.12065 -0.305054)
			(stroke
				(width 0.1)
				(type default)
			)
			(layer "F.Fab")
		)
		(pad "1" smd circle
			(at -0.40005 0 180)
			(size 0 0)
			(layers "F.Cu" "F.Mask" "F.Paste")
			(net "SGPIO_CLK_1")
		)
		(pad "2" smd circle
			(at 0.40005 0 180)
			(size 0 0)
			(layers "F.Cu" "F.Mask" "F.Paste")
			(net "GND")
		)
	)
	(footprint ""
		(layer "F.Cu")
		(at 85.29955 -39.347394 180)
		(property "Reference" "R343"
			(at 0 0 180)
			(layer "F.SilkS")
			(hide yes)
			(effects
				(font
					(size 1.27 1.27)
				)
			)
		)
		(property "Value" ""
			(at 0 0 180)
			(layer "F.Fab")
			(effects
				(font
					(size 1.27 1.27)
				)
			)
		)
		(duplicate_pad_numbers_are_jumpers no)
		(fp_line
			(start 0.7874 0.4064)
			(end -0.7874 0.4064)
			(stroke
				(width 0.1524)
				(type default)
			)
			(layer "F.SilkS")
		)
		(fp_line
			(start 0.7874 -0.4064)
			(end 0.7874 0.4064)
			(stroke
				(width 0.1524)
				(type default)
			)
			(layer "F.SilkS")
		)
		(fp_line
			(start -0.7874 0.4064)
			(end -0.7874 -0.4064)
			(stroke
				(width 0.1524)
				(type default)
			)
			(layer "F.SilkS")
		)
		(fp_line
			(start -0.7874 -0.4064)
			(end 0.7874 -0.4064)
			(stroke
				(width 0.1524)
				(type default)
			)
			(layer "F.SilkS")
		)
		(fp_line
			(start 0.67945 0.3048)
			(end 0.120396 0.3048)
			(stroke
				(width 0.1)
				(type default)
			)
			(layer "F.Fab")
		)
		(fp_line
			(start 0.67945 -0.3048)
			(end 0.67945 0.3048)
			(stroke
				(width 0.1)
				(type default)
			)
			(layer "F.Fab")
		)
		(fp_line
			(start 0.12065 -0.2794)
			(end 0.12065 -0.3048)
			(stroke
				(width 0.1)
				(type default)
			)
			(layer "F.Fab")
		)
		(fp_line
			(start 0.12065 -0.3048)
			(end 0.67945 -0.3048)
			(stroke
				(width 0.1)
				(type default)
			)
			(layer "F.Fab")
		)
		(fp_line
			(start 0.120396 0.3048)
			(end 0.120396 0.2794)
			(stroke
				(width 0.1)
				(type default)
			)
			(layer "F.Fab")
		)
		(fp_line
			(start 0.120396 0.2794)
			(end -0.12065 0.2794)
			(stroke
				(width 0.1)
				(type default)
			)
			(layer "F.Fab")
		)
		(fp_line
			(start -0.12065 0.3048)
			(end -0.67945 0.3048)
			(stroke
				(width 0.1)
				(type default)
			)
			(layer "F.Fab")
		)
		(fp_line
			(start -0.12065 0.2794)
			(end -0.12065 0.3048)
			(stroke
				(width 0.1)
				(type default)
			)
			(layer "F.Fab")
		)
		(fp_line
			(start -0.12065 -0.2794)
			(end 0.12065 -0.2794)
			(stroke
				(width 0.1)
				(type default)
			)
			(layer "F.Fab")
		)
		(fp_line
			(start -0.12065 -0.305054)
			(end -0.12065 -0.2794)
			(stroke
				(width 0.1)
				(type default)
			)
			(layer "F.Fab")
		)
		(fp_line
			(start -0.67945 0.3048)
			(end -0.67945 -0.305054)
			(stroke
				(width 0.1)
				(type default)
			)
			(layer "F.Fab")
		)
		(fp_line
			(start -0.67945 -0.305054)
			(end -0.12065 -0.305054)
			(stroke
				(width 0.1)
				(type default)
			)
			(layer "F.Fab")
		)
		(pad "1" smd circle
			(at -0.40005 0 180)
			(size 0 0)
			(layers "F.Cu" "F.Mask" "F.Paste")
			(net "GND")
		)
		(pad "2" smd circle
			(at 0.40005 0 180)
			(size 0 0)
			(layers "F.Cu" "F.Mask" "F.Paste")
			(net "M_BMC_DDR4_MCS_N")
		)
	)
	(footprint ""
		(layer "F.Cu")
		(at 69.097398 -62.725808 -90)
		(property "Reference" "C80"
			(at 0 0 270)
			(layer "F.SilkS")
			(hide yes)
			(effects
				(font
					(size 1.27 1.27)
				)
			)
		)
		(property "Value" ""
			(at 0 0 270)
			(layer "F.Fab")
			(effects
				(font
					(size 1.27 1.27)
				)
			)
		)
		(duplicate_pad_numbers_are_jumpers no)
		(fp_line
			(start -0.7874 0.4064)
			(end -0.7874 -0.4064)
			(stroke
				(width 0.1524)
				(type default)
			)
			(layer "F.SilkS")
		)
		(fp_line
			(start 0.7874 0.4064)
			(end -0.7874 0.4064)
			(stroke
				(width 0.1524)
				(type default)
			)
			(layer "F.SilkS")
		)
		(fp_line
			(start -0.7874 -0.4064)
			(end 0.7874 -0.4064)
			(stroke
				(width 0.1524)
				(type default)
			)
			(layer "F.SilkS")
		)
		(fp_line
			(start 0.7874 -0.4064)
			(end 0.7874 0.4064)
			(stroke
				(width 0.1524)
				(type default)
			)
			(layer "F.SilkS")
		)
		(fp_line
			(start -0.67945 0.3048)
			(end -0.67945 -0.305054)
			(stroke
				(width 0.1)
				(type default)
			)
			(layer "F.Fab")
		)
		(fp_line
			(start -0.12065 0.3048)
			(end -0.67945 0.3048)
			(stroke
				(width 0.1)
				(type default)
			)
			(layer "F.Fab")
		)
		(fp_line
			(start 0.120396 0.3048)
			(end 0.120396 0.2794)
			(stroke
				(width 0.1)
				(type default)
			)
			(layer "F.Fab")
		)
		(fp_line
			(start 0.67945 0.3048)
			(end 0.120396 0.3048)
			(stroke
				(width 0.1)
				(type default)
			)
			(layer "F.Fab")
		)
		(fp_line
			(start -0.12065 0.2794)
			(end -0.12065 0.3048)
			(stroke
				(width 0.1)
				(type default)
			)
			(layer "F.Fab")
		)
		(fp_line
			(start 0.120396 0.2794)
			(end -0.12065 0.2794)
			(stroke
				(width 0.1)
				(type default)
			)
			(layer "F.Fab")
		)
		(fp_line
			(start -0.12065 -0.2794)
			(end 0.12065 -0.2794)
			(stroke
				(width 0.1)
				(type default)
			)
			(layer "F.Fab")
		)
		(fp_line
			(start 0.12065 -0.2794)
			(end 0.12065 -0.3048)
			(stroke
				(width 0.1)
				(type default)
			)
			(layer "F.Fab")
		)
		(fp_line
			(start 0.12065 -0.3048)
			(end 0.67945 -0.3048)
			(stroke
				(width 0.1)
				(type default)
			)
			(layer "F.Fab")
		)
		(fp_line
			(start 0.67945 -0.3048)
			(end 0.67945 0.3048)
			(stroke
				(width 0.1)
				(type default)
			)
			(layer "F.Fab")
		)
		(fp_line
			(start -0.67945 -0.305054)
			(end -0.12065 -0.305054)
			(stroke
				(width 0.1)
				(type default)
			)
			(layer "F.Fab")
		)
		(fp_line
			(start -0.12065 -0.305054)
			(end -0.12065 -0.2794)
			(stroke
				(width 0.1)
				(type default)
			)
			(layer "F.Fab")
		)
		(pad "1" smd circle
			(at -0.40005 0 270)
			(size 0 0)
			(layers "F.Cu" "F.Mask" "F.Paste")
			(net "P1V8_STBY_RC_VCC18A")
		)
		(pad "2" smd circle
			(at 0.40005 0 270)
			(size 0 0)
			(layers "F.Cu" "F.Mask" "F.Paste")
			(net "GND")
		)
	)
	(footprint ""
		(layer "F.Cu")
		(at 45.085 -83.6168)
		(property "Reference" "R559"
			(at 0 0 0)
			(layer "F.SilkS")
			(hide yes)
			(effects
				(font
					(size 1.27 1.27)
				)
			)
		)
		(property "Value" ""
			(at 0 0 0)
			(layer "F.Fab")
			(effects
				(font
					(size 1.27 1.27)
				)
			)
		)
		(duplicate_pad_numbers_are_jumpers no)
		(fp_line
			(start -0.7874 -0.4064)
			(end 0.7874 -0.4064)
			(stroke
				(width 0.1524)
				(type default)
			)
			(layer "F.SilkS")
		)
		(fp_line
			(start -0.7874 0.4064)
			(end -0.7874 -0.4064)
			(stroke
				(width 0.1524)
				(type default)
			)
			(layer "F.SilkS")
		)
		(fp_line
			(start 0.7874 -0.4064)
			(end 0.7874 0.4064)
			(stroke
				(width 0.1524)
				(type default)
			)
			(layer "F.SilkS")
		)
		(fp_line
			(start 0.7874 0.4064)
			(end -0.7874 0.4064)
			(stroke
				(width 0.1524)
				(type default)
			)
			(layer "F.SilkS")
		)
		(fp_line
			(start -0.67945 -0.305054)
			(end -0.12065 -0.305054)
			(stroke
				(width 0.1)
				(type default)
			)
			(layer "F.Fab")
		)
		(fp_line
			(start -0.67945 0.3048)
			(end -0.67945 -0.305054)
			(stroke
				(width 0.1)
				(type default)
			)
			(layer "F.Fab")
		)
		(fp_line
			(start -0.12065 -0.305054)
			(end -0.12065 -0.2794)
			(stroke
				(width 0.1)
				(type default)
			)
			(layer "F.Fab")
		)
		(fp_line
			(start -0.12065 -0.2794)
			(end 0.12065 -0.2794)
			(stroke
				(width 0.1)
				(type default)
			)
			(layer "F.Fab")
		)
		(fp_line
			(start -0.12065 0.2794)
			(end -0.12065 0.3048)
			(stroke
				(width 0.1)
				(type default)
			)
			(layer "F.Fab")
		)
		(fp_line
			(start -0.12065 0.3048)
			(end -0.67945 0.3048)
			(stroke
				(width 0.1)
				(type default)
			)
			(layer "F.Fab")
		)
		(fp_line
			(start 0.120396 0.2794)
			(end -0.12065 0.2794)
			(stroke
				(width 0.1)
				(type default)
			)
			(layer "F.Fab")
		)
		(fp_line
			(start 0.120396 0.3048)
			(end 0.120396 0.2794)
			(stroke
				(width 0.1)
				(type default)
			)
			(layer "F.Fab")
		)
		(fp_line
			(start 0.12065 -0.3048)
			(end 0.67945 -0.3048)
			(stroke
				(width 0.1)
				(type default)
			)
			(layer "F.Fab")
		)
		(fp_line
			(start 0.12065 -0.2794)
			(end 0.12065 -0.3048)
			(stroke
				(width 0.1)
				(type default)
			)
			(layer "F.Fab")
		)
		(fp_line
			(start 0.67945 -0.3048)
			(end 0.67945 0.3048)
			(stroke
				(width 0.1)
				(type default)
			)
			(layer "F.Fab")
		)
		(fp_line
			(start 0.67945 0.3048)
			(end 0.120396 0.3048)
			(stroke
				(width 0.1)
				(type default)
			)
			(layer "F.Fab")
		)
		(pad "1" smd circle
			(at -0.40005 0)
			(size 0 0)
			(layers "F.Cu" "F.Mask" "F.Paste")
			(net "SPI_BMC_BT_WP0_N_R")
		)
		(pad "2" smd circle
			(at 0.40005 0)
			(size 0 0)
			(layers "F.Cu" "F.Mask" "F.Paste")
			(net "FLASH_LATCH_Q_N_R2")
		)
	)
	(footprint ""
		(layer "F.Cu")
		(at 60.380118 -6.290056)
		(property "Reference" "D22"
			(at -1.143 -2.708148 0)
			(unlocked yes)
			(layer "F.SilkS")
			(effects
				(font
					(size 0.7874 0.5842)
					(thickness 0.1524)
				)
				(justify left)
			)
		)
		(property "Value" ""
			(at 0 0 0)
			(layer "F.Fab")
			(effects
				(font
					(size 1.27 1.27)
				)
			)
		)
		(duplicate_pad_numbers_are_jumpers no)
		(fp_line
			(start -1.080008 -1.999996)
			(end 3.620008 -1.999996)
			(stroke
				(width 0.1524)
				(type default)
			)
			(layer "F.SilkS")
		)
		(fp_line
			(start -1.080008 3.999992)
			(end -1.080008 -1.999996)
			(stroke
				(width 0.1524)
				(type default)
			)
			(layer "F.SilkS")
		)
		(fp_line
			(start -0.230124 3.999992)
			(end -1.080008 3.999992)
			(stroke
				(width 0.1524)
				(type default)
			)
			(layer "F.SilkS")
		)
		(fp_line
			(start -0.230124 5.199888)
			(end -0.230124 3.999992)
			(stroke
				(width 0.1524)
				(type default)
			)
			(layer "F.SilkS")
		)
		(fp_line
			(start 2.770124 3.999992)
			(end 2.770124 5.199888)
			(stroke
				(width 0.1524)
				(type default)
			)
			(layer "F.SilkS")
		)
		(fp_line
			(start 3.620008 -1.999996)
			(end 3.620008 3.999992)
			(stroke
				(width 0.1524)
				(type default)
			)
			(layer "F.SilkS")
		)
		(fp_line
			(start 3.620008 3.999992)
			(end 2.770124 3.999992)
			(stroke
				(width 0.1524)
				(type default)
			)
			(layer "F.SilkS")
		)
		(fp_arc
			(start 1.27 6.700012)
			(mid 0.209252 6.260636)
			(end -0.230124 5.199888)
			(stroke
				(width 0.1524)
				(type default)
			)
			(layer "F.SilkS")
		)
		(fp_arc
			(start 2.770124 5.199888)
			(mid 2.330748 6.260636)
			(end 1.27 6.700012)
			(stroke
				(width 0.1524)
				(type default)
			)
			(layer "F.SilkS")
		)
		(fp_line
			(start -1.080008 -1.999996)
			(end 3.620008 -1.999996)
			(stroke
				(width 0.1)
				(type default)
			)
			(layer "F.Fab")
		)
		(fp_line
			(start -1.080008 3.999992)
			(end -1.080008 -1.999996)
			(stroke
				(width 0.1)
				(type default)
			)
			(layer "F.Fab")
		)
		(fp_line
			(start -0.230124 3.999992)
			(end -1.080008 3.999992)
			(stroke
				(width 0.1)
				(type default)
			)
			(layer "F.Fab")
		)
		(fp_line
			(start -0.230124 5.199888)
			(end -0.230124 3.999992)
			(stroke
				(width 0.1)
				(type default)
			)
			(layer "F.Fab")
		)
		(fp_line
			(start 2.770124 3.999992)
			(end 2.770124 5.199888)
			(stroke
				(width 0.1)
				(type default)
			)
			(layer "F.Fab")
		)
		(fp_line
			(start 3.620008 -1.999996)
			(end 3.620008 3.999992)
			(stroke
				(width 0.1)
				(type default)
			)
			(layer "F.Fab")
		)
		(fp_line
			(start 3.620008 3.999992)
			(end 2.770124 3.999992)
			(stroke
				(width 0.1)
				(type default)
			)
			(layer "F.Fab")
		)
		(fp_arc
			(start 1.27 6.700012)
			(mid 0.209252 6.260636)
			(end -0.230124 5.199888)
			(stroke
				(width 0.1)
				(type default)
			)
			(layer "F.Fab")
		)
		(fp_arc
			(start 2.770124 5.199888)
			(mid 2.330748 6.260636)
			(end 1.27 6.700012)
			(stroke
				(width 0.1)
				(type default)
			)
			(layer "F.Fab")
		)
		(pad "A" thru_hole rect
			(at 0 0)
			(size 1.2192 1.2192)
			(drill 0.8128)
			(layers "*.Cu" "*.Mask")
			(remove_unused_layers no)
			(net "LED_D22_R")
			(clearance 0.0508)
			(thermal_gap 0.0508)
			(padstack
				(mode front_inner_back)
				(layer "Inner"
					(shape circle)
					(size 1.2192 1.2192)
					(clearance 0.0508)
				)
				(layer "B.Cu"
					(shape rect)
					(size 1.2192 1.2192)
					(clearance 0.0508)
				)
			)
		)
		(pad "C" thru_hole circle
			(at 2.54 0)
			(size 1.2192 1.2192)
			(drill 0.8128)
			(layers "*.Cu" "*.Mask")
			(remove_unused_layers no)
			(net "LED_D22_R1")
			(clearance 0.0508)
			(thermal_gap 0.0508)
		)
	)
	(footprint ""
		(layer "F.Cu")
		(at 47.752 -34.6456 -90)
		(property "Reference" "R132"
			(at 0 0 270)
			(layer "F.SilkS")
			(hide yes)
			(effects
				(font
					(size 1.27 1.27)
				)
			)
		)
		(property "Value" ""
			(at 0 0 270)
			(layer "F.Fab")
			(effects
				(font
					(size 1.27 1.27)
				)
			)
		)
		(duplicate_pad_numbers_are_jumpers no)
		(fp_line
			(start -0.7874 0.4064)
			(end -0.7874 -0.4064)
			(stroke
				(width 0.1524)
				(type default)
			)
			(layer "F.SilkS")
		)
		(fp_line
			(start 0.7874 0.4064)
			(end -0.7874 0.4064)
			(stroke
				(width 0.1524)
				(type default)
			)
			(layer "F.SilkS")
		)
		(fp_line
			(start -0.7874 -0.4064)
			(end 0.7874 -0.4064)
			(stroke
				(width 0.1524)
				(type default)
			)
			(layer "F.SilkS")
		)
		(fp_line
			(start 0.7874 -0.4064)
			(end 0.7874 0.4064)
			(stroke
				(width 0.1524)
				(type default)
			)
			(layer "F.SilkS")
		)
		(fp_line
			(start -0.67945 0.3048)
			(end -0.67945 -0.305054)
			(stroke
				(width 0.1)
				(type default)
			)
			(layer "F.Fab")
		)
		(fp_line
			(start -0.12065 0.3048)
			(end -0.67945 0.3048)
			(stroke
				(width 0.1)
				(type default)
			)
			(layer "F.Fab")
		)
		(fp_line
			(start 0.120396 0.3048)
			(end 0.120396 0.2794)
			(stroke
				(width 0.1)
				(type default)
			)
			(layer "F.Fab")
		)
		(fp_line
			(start 0.67945 0.3048)
			(end 0.120396 0.3048)
			(stroke
				(width 0.1)
				(type default)
			)
			(layer "F.Fab")
		)
		(fp_line
			(start -0.12065 0.2794)
			(end -0.12065 0.3048)
			(stroke
				(width 0.1)
				(type default)
			)
			(layer "F.Fab")
		)
		(fp_line
			(start 0.120396 0.2794)
			(end -0.12065 0.2794)
			(stroke
				(width 0.1)
				(type default)
			)
			(layer "F.Fab")
		)
		(fp_line
			(start -0.12065 -0.2794)
			(end 0.12065 -0.2794)
			(stroke
				(width 0.1)
				(type default)
			)
			(layer "F.Fab")
		)
		(fp_line
			(start 0.12065 -0.2794)
			(end 0.12065 -0.3048)
			(stroke
				(width 0.1)
				(type default)
			)
			(layer "F.Fab")
		)
		(fp_line
			(start 0.12065 -0.3048)
			(end 0.67945 -0.3048)
			(stroke
				(width 0.1)
				(type default)
			)
			(layer "F.Fab")
		)
		(fp_line
			(start 0.67945 -0.3048)
			(end 0.67945 0.3048)
			(stroke
				(width 0.1)
				(type default)
			)
			(layer "F.Fab")
		)
		(fp_line
			(start -0.67945 -0.305054)
			(end -0.12065 -0.305054)
			(stroke
				(width 0.1)
				(type default)
			)
			(layer "F.Fab")
		)
		(fp_line
			(start -0.12065 -0.305054)
			(end -0.12065 -0.2794)
			(stroke
				(width 0.1)
				(type default)
			)
			(layer "F.Fab")
		)
		(pad "1" smd circle
			(at -0.40005 0 270)
			(size 0 0)
			(layers "F.Cu" "F.Mask" "F.Paste")
			(net "SMB_BMC_MM1_R_SCL")
		)
		(pad "2" smd circle
			(at 0.40005 0 270)
			(size 0 0)
			(layers "F.Cu" "F.Mask" "F.Paste")
			(net "SMB_BMC_MM1_SCL")
		)
	)
	(footprint ""
		(layer "F.Cu")
		(at 16.50365 -29.5783 180)
		(property "Reference" "PR543"
			(at 0 0 180)
			(layer "F.SilkS")
			(hide yes)
			(effects
				(font
					(size 1.27 1.27)
				)
			)
		)
		(property "Value" ""
			(at 0 0 180)
			(layer "F.Fab")
			(effects
				(font
					(size 1.27 1.27)
				)
			)
		)
		(duplicate_pad_numbers_are_jumpers no)
		(fp_line
			(start 0.7874 0.4064)
			(end -0.7874 0.4064)
			(stroke
				(width 0.1524)
				(type default)
			)
			(layer "F.SilkS")
		)
		(fp_line
			(start 0.7874 -0.4064)
			(end 0.7874 0.4064)
			(stroke
				(width 0.1524)
				(type default)
			)
			(layer "F.SilkS")
		)
		(fp_line
			(start -0.7874 0.4064)
			(end -0.7874 -0.4064)
			(stroke
				(width 0.1524)
				(type default)
			)
			(layer "F.SilkS")
		)
		(fp_line
			(start -0.7874 -0.4064)
			(end 0.7874 -0.4064)
			(stroke
				(width 0.1524)
				(type default)
			)
			(layer "F.SilkS")
		)
		(fp_line
			(start 0.67945 0.3048)
			(end 0.120396 0.3048)
			(stroke
				(width 0.1)
				(type default)
			)
			(layer "F.Fab")
		)
		(fp_line
			(start 0.67945 -0.3048)
			(end 0.67945 0.3048)
			(stroke
				(width 0.1)
				(type default)
			)
			(layer "F.Fab")
		)
		(fp_line
			(start 0.12065 -0.2794)
			(end 0.12065 -0.3048)
			(stroke
				(width 0.1)
				(type default)
			)
			(layer "F.Fab")
		)
		(fp_line
			(start 0.12065 -0.3048)
			(end 0.67945 -0.3048)
			(stroke
				(width 0.1)
				(type default)
			)
			(layer "F.Fab")
		)
		(fp_line
			(start 0.120396 0.3048)
			(end 0.120396 0.2794)
			(stroke
				(width 0.1)
				(type default)
			)
			(layer "F.Fab")
		)
		(fp_line
			(start 0.120396 0.2794)
			(end -0.12065 0.2794)
			(stroke
				(width 0.1)
				(type default)
			)
			(layer "F.Fab")
		)
		(fp_line
			(start -0.12065 0.3048)
			(end -0.67945 0.3048)
			(stroke
				(width 0.1)
				(type default)
			)
			(layer "F.Fab")
		)
		(fp_line
			(start -0.12065 0.2794)
			(end -0.12065 0.3048)
			(stroke
				(width 0.1)
				(type default)
			)
			(layer "F.Fab")
		)
		(fp_line
			(start -0.12065 -0.2794)
			(end 0.12065 -0.2794)
			(stroke
				(width 0.1)
				(type default)
			)
			(layer "F.Fab")
		)
		(fp_line
			(start -0.12065 -0.305054)
			(end -0.12065 -0.2794)
			(stroke
				(width 0.1)
				(type default)
			)
			(layer "F.Fab")
		)
		(fp_line
			(start -0.67945 0.3048)
			(end -0.67945 -0.305054)
			(stroke
				(width 0.1)
				(type default)
			)
			(layer "F.Fab")
		)
		(fp_line
			(start -0.67945 -0.305054)
			(end -0.12065 -0.305054)
			(stroke
				(width 0.1)
				(type default)
			)
			(layer "F.Fab")
		)
		(pad "1" smd circle
			(at -0.40005 0 180)
			(size 0 0)
			(layers "F.Cu" "F.Mask" "F.Paste")
			(net "P1V0_AUX_MODE")
		)
		(pad "2" smd circle
			(at 0.40005 0 180)
			(size 0 0)
			(layers "F.Cu" "F.Mask" "F.Paste")
			(net "GND")
		)
	)
	(footprint ""
		(layer "F.Cu")
		(at 56.0324 -82.8802 -90)
		(property "Reference" "R554"
			(at 0 0 270)
			(layer "F.SilkS")
			(hide yes)
			(effects
				(font
					(size 1.27 1.27)
				)
			)
		)
		(property "Value" ""
			(at 0 0 270)
			(layer "F.Fab")
			(effects
				(font
					(size 1.27 1.27)
				)
			)
		)
		(duplicate_pad_numbers_are_jumpers no)
		(fp_line
			(start -0.7874 0.4064)
			(end -0.7874 -0.4064)
			(stroke
				(width 0.1524)
				(type default)
			)
			(layer "F.SilkS")
		)
		(fp_line
			(start 0.7874 0.4064)
			(end -0.7874 0.4064)
			(stroke
				(width 0.1524)
				(type default)
			)
			(layer "F.SilkS")
		)
		(fp_line
			(start -0.7874 -0.4064)
			(end 0.7874 -0.4064)
			(stroke
				(width 0.1524)
				(type default)
			)
			(layer "F.SilkS")
		)
		(fp_line
			(start 0.7874 -0.4064)
			(end 0.7874 0.4064)
			(stroke
				(width 0.1524)
				(type default)
			)
			(layer "F.SilkS")
		)
		(fp_line
			(start -0.67945 0.3048)
			(end -0.67945 -0.305054)
			(stroke
				(width 0.1)
				(type default)
			)
			(layer "F.Fab")
		)
		(fp_line
			(start -0.12065 0.3048)
			(end -0.67945 0.3048)
			(stroke
				(width 0.1)
				(type default)
			)
			(layer "F.Fab")
		)
		(fp_line
			(start 0.120396 0.3048)
			(end 0.120396 0.2794)
			(stroke
				(width 0.1)
				(type default)
			)
			(layer "F.Fab")
		)
		(fp_line
			(start 0.67945 0.3048)
			(end 0.120396 0.3048)
			(stroke
				(width 0.1)
				(type default)
			)
			(layer "F.Fab")
		)
		(fp_line
			(start -0.12065 0.2794)
			(end -0.12065 0.3048)
			(stroke
				(width 0.1)
				(type default)
			)
			(layer "F.Fab")
		)
		(fp_line
			(start 0.120396 0.2794)
			(end -0.12065 0.2794)
			(stroke
				(width 0.1)
				(type default)
			)
			(layer "F.Fab")
		)
		(fp_line
			(start -0.12065 -0.2794)
			(end 0.12065 -0.2794)
			(stroke
				(width 0.1)
				(type default)
			)
			(layer "F.Fab")
		)
		(fp_line
			(start 0.12065 -0.2794)
			(end 0.12065 -0.3048)
			(stroke
				(width 0.1)
				(type default)
			)
			(layer "F.Fab")
		)
		(fp_line
			(start 0.12065 -0.3048)
			(end 0.67945 -0.3048)
			(stroke
				(width 0.1)
				(type default)
			)
			(layer "F.Fab")
		)
		(fp_line
			(start 0.67945 -0.3048)
			(end 0.67945 0.3048)
			(stroke
				(width 0.1)
				(type default)
			)
			(layer "F.Fab")
		)
		(fp_line
			(start -0.67945 -0.305054)
			(end -0.12065 -0.305054)
			(stroke
				(width 0.1)
				(type default)
			)
			(layer "F.Fab")
		)
		(fp_line
			(start -0.12065 -0.305054)
			(end -0.12065 -0.2794)
			(stroke
				(width 0.1)
				(type default)
			)
			(layer "F.Fab")
		)
		(pad "1" smd circle
			(at -0.40005 0 270)
			(size 0 0)
			(layers "F.Cu" "F.Mask" "F.Paste")
			(net "P3V3_AUX")
		)
		(pad "2" smd circle
			(at 0.40005 0 270)
			(size 0 0)
			(layers "F.Cu" "F.Mask" "F.Paste")
			(net "FLASH_R_WP_STATUS")
		)
	)
	(footprint ""
		(layer "F.Cu")
		(at 54.61 -10.795 -90)
		(property "Reference" "R286"
			(at 0 0 270)
			(layer "F.SilkS")
			(hide yes)
			(effects
				(font
					(size 1.27 1.27)
				)
			)
		)
		(property "Value" ""
			(at 0 0 270)
			(layer "F.Fab")
			(effects
				(font
					(size 1.27 1.27)
				)
			)
		)
		(duplicate_pad_numbers_are_jumpers no)
		(fp_line
			(start -0.7874 0.4064)
			(end -0.7874 -0.4064)
			(stroke
				(width 0.1524)
				(type default)
			)
			(layer "F.SilkS")
		)
		(fp_line
			(start 0.7874 0.4064)
			(end -0.7874 0.4064)
			(stroke
				(width 0.1524)
				(type default)
			)
			(layer "F.SilkS")
		)
		(fp_line
			(start -0.7874 -0.4064)
			(end 0.7874 -0.4064)
			(stroke
				(width 0.1524)
				(type default)
			)
			(layer "F.SilkS")
		)
		(fp_line
			(start 0.7874 -0.4064)
			(end 0.7874 0.4064)
			(stroke
				(width 0.1524)
				(type default)
			)
			(layer "F.SilkS")
		)
		(fp_line
			(start -0.67945 0.3048)
			(end -0.67945 -0.305054)
			(stroke
				(width 0.1)
				(type default)
			)
			(layer "F.Fab")
		)
		(fp_line
			(start -0.12065 0.3048)
			(end -0.67945 0.3048)
			(stroke
				(width 0.1)
				(type default)
			)
			(layer "F.Fab")
		)
		(fp_line
			(start 0.120396 0.3048)
			(end 0.120396 0.2794)
			(stroke
				(width 0.1)
				(type default)
			)
			(layer "F.Fab")
		)
		(fp_line
			(start 0.67945 0.3048)
			(end 0.120396 0.3048)
			(stroke
				(width 0.1)
				(type default)
			)
			(layer "F.Fab")
		)
		(fp_line
			(start -0.12065 0.2794)
			(end -0.12065 0.3048)
			(stroke
				(width 0.1)
				(type default)
			)
			(layer "F.Fab")
		)
		(fp_line
			(start 0.120396 0.2794)
			(end -0.12065 0.2794)
			(stroke
				(width 0.1)
				(type default)
			)
			(layer "F.Fab")
		)
		(fp_line
			(start -0.12065 -0.2794)
			(end 0.12065 -0.2794)
			(stroke
				(width 0.1)
				(type default)
			)
			(layer "F.Fab")
		)
		(fp_line
			(start 0.12065 -0.2794)
			(end 0.12065 -0.3048)
			(stroke
				(width 0.1)
				(type default)
			)
			(layer "F.Fab")
		)
		(fp_line
			(start 0.12065 -0.3048)
			(end 0.67945 -0.3048)
			(stroke
				(width 0.1)
				(type default)
			)
			(layer "F.Fab")
		)
		(fp_line
			(start 0.67945 -0.3048)
			(end 0.67945 0.3048)
			(stroke
				(width 0.1)
				(type default)
			)
			(layer "F.Fab")
		)
		(fp_line
			(start -0.67945 -0.305054)
			(end -0.12065 -0.305054)
			(stroke
				(width 0.1)
				(type default)
			)
			(layer "F.Fab")
		)
		(fp_line
			(start -0.12065 -0.305054)
			(end -0.12065 -0.2794)
			(stroke
				(width 0.1)
				(type default)
			)
			(layer "F.Fab")
		)
		(pad "1" smd circle
			(at -0.40005 0 270)
			(size 0 0)
			(layers "F.Cu" "F.Mask" "F.Paste")
			(net "LED_D21_R2")
		)
		(pad "2" smd circle
			(at 0.40005 0 270)
			(size 0 0)
			(layers "F.Cu" "F.Mask" "F.Paste")
			(net "LED_D21_R1")
		)
	)
	(footprint ""
		(layer "F.Cu")
		(at 66.0146 -66.0146)
		(property "Reference" "R468"
			(at 0 0 0)
			(layer "F.SilkS")
			(hide yes)
			(effects
				(font
					(size 1.27 1.27)
				)
			)
		)
		(property "Value" ""
			(at 0 0 0)
			(layer "F.Fab")
			(effects
				(font
					(size 1.27 1.27)
				)
			)
		)
		(duplicate_pad_numbers_are_jumpers no)
		(fp_line
			(start -0.7874 -0.4064)
			(end 0.7874 -0.4064)
			(stroke
				(width 0.1524)
				(type default)
			)
			(layer "F.SilkS")
		)
		(fp_line
			(start -0.7874 0.4064)
			(end -0.7874 -0.4064)
			(stroke
				(width 0.1524)
				(type default)
			)
			(layer "F.SilkS")
		)
		(fp_line
			(start 0.7874 -0.4064)
			(end 0.7874 0.4064)
			(stroke
				(width 0.1524)
				(type default)
			)
			(layer "F.SilkS")
		)
		(fp_line
			(start 0.7874 0.4064)
			(end -0.7874 0.4064)
			(stroke
				(width 0.1524)
				(type default)
			)
			(layer "F.SilkS")
		)
		(fp_line
			(start -0.67945 -0.305054)
			(end -0.12065 -0.305054)
			(stroke
				(width 0.1)
				(type default)
			)
			(layer "F.Fab")
		)
		(fp_line
			(start -0.67945 0.3048)
			(end -0.67945 -0.305054)
			(stroke
				(width 0.1)
				(type default)
			)
			(layer "F.Fab")
		)
		(fp_line
			(start -0.12065 -0.305054)
			(end -0.12065 -0.2794)
			(stroke
				(width 0.1)
				(type default)
			)
			(layer "F.Fab")
		)
		(fp_line
			(start -0.12065 -0.2794)
			(end 0.12065 -0.2794)
			(stroke
				(width 0.1)
				(type default)
			)
			(layer "F.Fab")
		)
		(fp_line
			(start -0.12065 0.2794)
			(end -0.12065 0.3048)
			(stroke
				(width 0.1)
				(type default)
			)
			(layer "F.Fab")
		)
		(fp_line
			(start -0.12065 0.3048)
			(end -0.67945 0.3048)
			(stroke
				(width 0.1)
				(type default)
			)
			(layer "F.Fab")
		)
		(fp_line
			(start 0.120396 0.2794)
			(end -0.12065 0.2794)
			(stroke
				(width 0.1)
				(type default)
			)
			(layer "F.Fab")
		)
		(fp_line
			(start 0.120396 0.3048)
			(end 0.120396 0.2794)
			(stroke
				(width 0.1)
				(type default)
			)
			(layer "F.Fab")
		)
		(fp_line
			(start 0.12065 -0.3048)
			(end 0.67945 -0.3048)
			(stroke
				(width 0.1)
				(type default)
			)
			(layer "F.Fab")
		)
		(fp_line
			(start 0.12065 -0.2794)
			(end 0.12065 -0.3048)
			(stroke
				(width 0.1)
				(type default)
			)
			(layer "F.Fab")
		)
		(fp_line
			(start 0.67945 -0.3048)
			(end 0.67945 0.3048)
			(stroke
				(width 0.1)
				(type default)
			)
			(layer "F.Fab")
		)
		(fp_line
			(start 0.67945 0.3048)
			(end 0.120396 0.3048)
			(stroke
				(width 0.1)
				(type default)
			)
			(layer "F.Fab")
		)
		(pad "1" smd circle
			(at -0.40005 0)
			(size 0 0)
			(layers "F.Cu" "F.Mask" "F.Paste")
			(net "SPI_BMC_TPM_CLK_R1")
		)
		(pad "2" smd circle
			(at 0.40005 0)
			(size 0 0)
			(layers "F.Cu" "F.Mask" "F.Paste")
			(net "SPI_BMC_TPM_CLK")
		)
	)
	(footprint ""
		(layer "F.Cu")
		(at 72.644 -16.256 90)
		(property "Reference" "C28"
			(at 0 0 90)
			(layer "F.SilkS")
			(hide yes)
			(effects
				(font
					(size 1.27 1.27)
				)
			)
		)
		(property "Value" ""
			(at 0 0 90)
			(layer "F.Fab")
			(effects
				(font
					(size 1.27 1.27)
				)
			)
		)
		(duplicate_pad_numbers_are_jumpers no)
		(fp_line
			(start 0.7874 -0.4064)
			(end 0.7874 0.4064)
			(stroke
				(width 0.1524)
				(type default)
			)
			(layer "F.SilkS")
		)
		(fp_line
			(start -0.7874 -0.4064)
			(end 0.7874 -0.4064)
			(stroke
				(width 0.1524)
				(type default)
			)
			(layer "F.SilkS")
		)
		(fp_line
			(start 0.7874 0.4064)
			(end -0.7874 0.4064)
			(stroke
				(width 0.1524)
				(type default)
			)
			(layer "F.SilkS")
		)
		(fp_line
			(start -0.7874 0.4064)
			(end -0.7874 -0.4064)
			(stroke
				(width 0.1524)
				(type default)
			)
			(layer "F.SilkS")
		)
		(fp_line
			(start -0.12065 -0.305054)
			(end -0.12065 -0.2794)
			(stroke
				(width 0.1)
				(type default)
			)
			(layer "F.Fab")
		)
		(fp_line
			(start -0.67945 -0.305054)
			(end -0.12065 -0.305054)
			(stroke
				(width 0.1)
				(type default)
			)
			(layer "F.Fab")
		)
		(fp_line
			(start 0.67945 -0.3048)
			(end 0.67945 0.3048)
			(stroke
				(width 0.1)
				(type default)
			)
			(layer "F.Fab")
		)
		(fp_line
			(start 0.12065 -0.3048)
			(end 0.67945 -0.3048)
			(stroke
				(width 0.1)
				(type default)
			)
			(layer "F.Fab")
		)
		(fp_line
			(start 0.12065 -0.2794)
			(end 0.12065 -0.3048)
			(stroke
				(width 0.1)
				(type default)
			)
			(layer "F.Fab")
		)
		(fp_line
			(start -0.12065 -0.2794)
			(end 0.12065 -0.2794)
			(stroke
				(width 0.1)
				(type default)
			)
			(layer "F.Fab")
		)
		(fp_line
			(start 0.120396 0.2794)
			(end -0.12065 0.2794)
			(stroke
				(width 0.1)
				(type default)
			)
			(layer "F.Fab")
		)
		(fp_line
			(start -0.12065 0.2794)
			(end -0.12065 0.3048)
			(stroke
				(width 0.1)
				(type default)
			)
			(layer "F.Fab")
		)
		(fp_line
			(start 0.67945 0.3048)
			(end 0.120396 0.3048)
			(stroke
				(width 0.1)
				(type default)
			)
			(layer "F.Fab")
		)
		(fp_line
			(start 0.120396 0.3048)
			(end 0.120396 0.2794)
			(stroke
				(width 0.1)
				(type default)
			)
			(layer "F.Fab")
		)
		(fp_line
			(start -0.12065 0.3048)
			(end -0.67945 0.3048)
			(stroke
				(width 0.1)
				(type default)
			)
			(layer "F.Fab")
		)
		(fp_line
			(start -0.67945 0.3048)
			(end -0.67945 -0.305054)
			(stroke
				(width 0.1)
				(type default)
			)
			(layer "F.Fab")
		)
		(pad "1" smd circle
			(at -0.40005 0 90)
			(size 0 0)
			(layers "F.Cu" "F.Mask" "F.Paste")
			(net "REAR_AC_PWR_BTN_N")
		)
		(pad "2" smd circle
			(at 0.40005 0 90)
			(size 0 0)
			(layers "F.Cu" "F.Mask" "F.Paste")
			(net "GND")
		)
	)
	(footprint ""
		(layer "F.Cu")
		(at 29.591 -22.9108 -90)
		(property "Reference" "D12"
			(at 1.27 -2.524252 90)
			(unlocked yes)
			(layer "F.SilkS")
			(effects
				(font
					(size 0.7874 0.5842)
					(thickness 0.1524)
				)
				(justify left)
			)
		)
		(property "Value" ""
			(at 0 0 270)
			(layer "F.Fab")
			(effects
				(font
					(size 1.27 1.27)
				)
			)
		)
		(duplicate_pad_numbers_are_jumpers no)
		(fp_line
			(start -1.7272 1.634744)
			(end -1.7272 -1.665224)
			(stroke
				(width 0.1524)
				(type default)
			)
			(layer "F.SilkS")
		)
		(fp_line
			(start 1.739646 1.634744)
			(end -1.7272 1.634744)
			(stroke
				(width 0.1524)
				(type default)
			)
			(layer "F.SilkS")
		)
		(fp_line
			(start 0 -0.930148)
			(end 0.571246 -1.665224)
			(stroke
				(width 0.1524)
				(type default)
			)
			(layer "F.SilkS")
		)
		(fp_line
			(start -1.7272 -1.665224)
			(end -0.5588 -1.665224)
			(stroke
				(width 0.1524)
				(type default)
			)
			(layer "F.SilkS")
		)
		(fp_line
			(start -0.5588 -1.665224)
			(end 0 -0.930148)
			(stroke
				(width 0.1524)
				(type default)
			)
			(layer "F.SilkS")
		)
		(fp_line
			(start 0.571246 -1.665224)
			(end 1.739646 -1.665224)
			(stroke
				(width 0.1524)
				(type default)
			)
			(layer "F.SilkS")
		)
		(fp_line
			(start 1.739646 -1.665224)
			(end 1.739646 1.634744)
			(stroke
				(width 0.1524)
				(type default)
			)
			(layer "F.SilkS")
		)
		(fp_poly
			(pts
				(xy -1.5748 -2.772664) (xy -0.8128 -2.772664) (xy -1.1938 -2.010664)
			)
			(stroke
				(width 0)
				(type default)
			)
			(fill yes)
			(layer "F.SilkS")
		)
		(fp_line
			(start -0.843788 1.534922)
			(end -0.843788 -1.565148)
			(stroke
				(width 0.1)
				(type default)
			)
			(layer "F.Fab")
		)
		(fp_line
			(start 0.856234 1.534922)
			(end -0.843788 1.534922)
			(stroke
				(width 0.1)
				(type default)
			)
			(layer "F.Fab")
		)
		(fp_line
			(start -0.843788 -1.565148)
			(end 0.856234 -1.565148)
			(stroke
				(width 0.1)
				(type default)
			)
			(layer "F.Fab")
		)
		(fp_line
			(start 0.856234 -1.565148)
			(end 0.856234 1.534922)
			(stroke
				(width 0.1)
				(type default)
			)
			(layer "F.Fab")
		)
		(fp_poly
			(pts
				(xy -2.747264 -0.5842) (xy -2.747264 -1.3462) (xy -1.985264 -0.9652)
			)
			(stroke
				(width 0)
				(type default)
			)
			(fill yes)
			(layer "F.Fab")
		)
		(pad "1" smd rect
			(at -1.1938 -0.9652 180)
			(size 0.5588 0.8128)
			(layers "F.Cu" "F.Mask" "F.Paste")
			(net "CRT_VCC5")
		)
		(pad "2" smd rect
			(at -1.1938 -0.01524 180)
			(size 0.5588 0.8128)
			(layers "F.Cu" "F.Mask" "F.Paste")
			(net "GND")
		)
		(pad "3" smd rect
			(at -1.1938 0.93472 180)
			(size 0.5588 0.8128)
			(layers "F.Cu" "F.Mask" "F.Paste")
			(net "CRT_VCC5")
		)
		(pad "4" smd rect
			(at 1.206246 0.93472 180)
			(size 0.5588 0.8128)
			(layers "F.Cu" "F.Mask" "F.Paste")
			(net "CRT_VCC5")
		)
		(pad "5" smd rect
			(at 1.206246 -0.01524 180)
			(size 0.5588 0.8128)
			(layers "F.Cu" "F.Mask" "F.Paste")
			(net "GND")
		)
		(pad "6" smd rect
			(at 1.206246 -0.9652 180)
			(size 0.5588 0.8128)
			(layers "F.Cu" "F.Mask" "F.Paste")
			(net "CRT_VCC5")
		)
	)
	(footprint ""
		(layer "F.Cu")
		(at 33.3248 -66.5226 180)
		(property "Reference" "R758"
			(at 0 0 180)
			(layer "F.SilkS")
			(hide yes)
			(effects
				(font
					(size 1.27 1.27)
				)
			)
		)
		(property "Value" ""
			(at 0 0 180)
			(layer "F.Fab")
			(effects
				(font
					(size 1.27 1.27)
				)
			)
		)
		(duplicate_pad_numbers_are_jumpers no)
		(fp_line
			(start 0.7874 0.4064)
			(end -0.7874 0.4064)
			(stroke
				(width 0.1524)
				(type default)
			)
			(layer "F.SilkS")
		)
		(fp_line
			(start 0.7874 -0.4064)
			(end 0.7874 0.4064)
			(stroke
				(width 0.1524)
				(type default)
			)
			(layer "F.SilkS")
		)
		(fp_line
			(start -0.7874 0.4064)
			(end -0.7874 -0.4064)
			(stroke
				(width 0.1524)
				(type default)
			)
			(layer "F.SilkS")
		)
		(fp_line
			(start -0.7874 -0.4064)
			(end 0.7874 -0.4064)
			(stroke
				(width 0.1524)
				(type default)
			)
			(layer "F.SilkS")
		)
		(fp_line
			(start 0.67945 0.3048)
			(end 0.120396 0.3048)
			(stroke
				(width 0.1)
				(type default)
			)
			(layer "F.Fab")
		)
		(fp_line
			(start 0.67945 -0.3048)
			(end 0.67945 0.3048)
			(stroke
				(width 0.1)
				(type default)
			)
			(layer "F.Fab")
		)
		(fp_line
			(start 0.12065 -0.2794)
			(end 0.12065 -0.3048)
			(stroke
				(width 0.1)
				(type default)
			)
			(layer "F.Fab")
		)
		(fp_line
			(start 0.12065 -0.3048)
			(end 0.67945 -0.3048)
			(stroke
				(width 0.1)
				(type default)
			)
			(layer "F.Fab")
		)
		(fp_line
			(start 0.120396 0.3048)
			(end 0.120396 0.2794)
			(stroke
				(width 0.1)
				(type default)
			)
			(layer "F.Fab")
		)
		(fp_line
			(start 0.120396 0.2794)
			(end -0.12065 0.2794)
			(stroke
				(width 0.1)
				(type default)
			)
			(layer "F.Fab")
		)
		(fp_line
			(start -0.12065 0.3048)
			(end -0.67945 0.3048)
			(stroke
				(width 0.1)
				(type default)
			)
			(layer "F.Fab")
		)
		(fp_line
			(start -0.12065 0.2794)
			(end -0.12065 0.3048)
			(stroke
				(width 0.1)
				(type default)
			)
			(layer "F.Fab")
		)
		(fp_line
			(start -0.12065 -0.2794)
			(end 0.12065 -0.2794)
			(stroke
				(width 0.1)
				(type default)
			)
			(layer "F.Fab")
		)
		(fp_line
			(start -0.12065 -0.305054)
			(end -0.12065 -0.2794)
			(stroke
				(width 0.1)
				(type default)
			)
			(layer "F.Fab")
		)
		(fp_line
			(start -0.67945 0.3048)
			(end -0.67945 -0.305054)
			(stroke
				(width 0.1)
				(type default)
			)
			(layer "F.Fab")
		)
		(fp_line
			(start -0.67945 -0.305054)
			(end -0.12065 -0.305054)
			(stroke
				(width 0.1)
				(type default)
			)
			(layer "F.Fab")
		)
		(pad "1" smd circle
			(at -0.40005 0 180)
			(size 0 0)
			(layers "F.Cu" "F.Mask" "F.Paste")
			(net "P3V3_RGM")
		)
		(pad "2" smd circle
			(at 0.40005 0 180)
			(size 0 0)
			(layers "F.Cu" "F.Mask" "F.Paste")
			(net "UART_BMC_5_RXD_R")
		)
	)
	(footprint ""
		(layer "F.Cu")
		(at 12.319 -98.4758)
		(property "Reference" "R886"
			(at 0 0 0)
			(layer "F.SilkS")
			(hide yes)
			(effects
				(font
					(size 1.27 1.27)
				)
			)
		)
		(property "Value" ""
			(at 0 0 0)
			(layer "F.Fab")
			(effects
				(font
					(size 1.27 1.27)
				)
			)
		)
		(duplicate_pad_numbers_are_jumpers no)
		(fp_line
			(start -0.7874 -0.4064)
			(end 0.7874 -0.4064)
			(stroke
				(width 0.1524)
				(type default)
			)
			(layer "F.SilkS")
		)
		(fp_line
			(start -0.7874 0.4064)
			(end -0.7874 -0.4064)
			(stroke
				(width 0.1524)
				(type default)
			)
			(layer "F.SilkS")
		)
		(fp_line
			(start 0.7874 -0.4064)
			(end 0.7874 0.4064)
			(stroke
				(width 0.1524)
				(type default)
			)
			(layer "F.SilkS")
		)
		(fp_line
			(start 0.7874 0.4064)
			(end -0.7874 0.4064)
			(stroke
				(width 0.1524)
				(type default)
			)
			(layer "F.SilkS")
		)
		(fp_line
			(start -0.67945 -0.305054)
			(end -0.12065 -0.305054)
			(stroke
				(width 0.1)
				(type default)
			)
			(layer "F.Fab")
		)
		(fp_line
			(start -0.67945 0.3048)
			(end -0.67945 -0.305054)
			(stroke
				(width 0.1)
				(type default)
			)
			(layer "F.Fab")
		)
		(fp_line
			(start -0.12065 -0.305054)
			(end -0.12065 -0.2794)
			(stroke
				(width 0.1)
				(type default)
			)
			(layer "F.Fab")
		)
		(fp_line
			(start -0.12065 -0.2794)
			(end 0.12065 -0.2794)
			(stroke
				(width 0.1)
				(type default)
			)
			(layer "F.Fab")
		)
		(fp_line
			(start -0.12065 0.2794)
			(end -0.12065 0.3048)
			(stroke
				(width 0.1)
				(type default)
			)
			(layer "F.Fab")
		)
		(fp_line
			(start -0.12065 0.3048)
			(end -0.67945 0.3048)
			(stroke
				(width 0.1)
				(type default)
			)
			(layer "F.Fab")
		)
		(fp_line
			(start 0.120396 0.2794)
			(end -0.12065 0.2794)
			(stroke
				(width 0.1)
				(type default)
			)
			(layer "F.Fab")
		)
		(fp_line
			(start 0.120396 0.3048)
			(end 0.120396 0.2794)
			(stroke
				(width 0.1)
				(type default)
			)
			(layer "F.Fab")
		)
		(fp_line
			(start 0.12065 -0.3048)
			(end 0.67945 -0.3048)
			(stroke
				(width 0.1)
				(type default)
			)
			(layer "F.Fab")
		)
		(fp_line
			(start 0.12065 -0.2794)
			(end 0.12065 -0.3048)
			(stroke
				(width 0.1)
				(type default)
			)
			(layer "F.Fab")
		)
		(fp_line
			(start 0.67945 -0.3048)
			(end 0.67945 0.3048)
			(stroke
				(width 0.1)
				(type default)
			)
			(layer "F.Fab")
		)
		(fp_line
			(start 0.67945 0.3048)
			(end 0.120396 0.3048)
			(stroke
				(width 0.1)
				(type default)
			)
			(layer "F.Fab")
		)
		(pad "1" smd circle
			(at -0.40005 0)
			(size 0 0)
			(layers "F.Cu" "F.Mask" "F.Paste")
			(net "P3V3_AUX")
		)
		(pad "2" smd circle
			(at 0.40005 0)
			(size 0 0)
			(layers "F.Cu" "F.Mask" "F.Paste")
			(net "PWRGD_P5V_AUX_R1")
		)
	)
	(footprint ""
		(layer "F.Cu")
		(at 41.061894 -22.159976)
		(property "Reference" "L21"
			(at 0 0 0)
			(layer "F.SilkS")
			(hide yes)
			(effects
				(font
					(size 1.27 1.27)
				)
			)
		)
		(property "Value" ""
			(at 0 0 0)
			(layer "F.Fab")
			(effects
				(font
					(size 1.27 1.27)
				)
			)
		)
		(duplicate_pad_numbers_are_jumpers no)
		(fp_line
			(start -0.8636 -1.524)
			(end -0.381508 -1.524)
			(stroke
				(width 0.1524)
				(type default)
			)
			(layer "F.SilkS")
		)
		(fp_line
			(start -0.8636 1.524)
			(end -0.8636 -1.524)
			(stroke
				(width 0.1524)
				(type default)
			)
			(layer "F.SilkS")
		)
		(fp_line
			(start -0.465328 1.524)
			(end -0.8636 1.524)
			(stroke
				(width 0.1524)
				(type default)
			)
			(layer "F.SilkS")
		)
		(fp_line
			(start 0.441452 -1.524)
			(end 0.8636 -1.524)
			(stroke
				(width 0.1524)
				(type default)
			)
			(layer "F.SilkS")
		)
		(fp_line
			(start 0.8636 -1.524)
			(end 0.8636 1.524)
			(stroke
				(width 0.1524)
				(type default)
			)
			(layer "F.SilkS")
		)
		(fp_line
			(start 0.8636 1.524)
			(end 0.492252 1.524)
			(stroke
				(width 0.1524)
				(type default)
			)
			(layer "F.SilkS")
		)
		(fp_poly
			(pts
				(xy -0.875538 -1.918208) (xy -1.414272 -2.09804) (xy -1.055116 -2.457196)
			)
			(stroke
				(width 0)
				(type default)
			)
			(fill yes)
			(layer "F.SilkS")
		)
		(fp_line
			(start -0.700024 -1.100074)
			(end 0.700024 -1.100074)
			(stroke
				(width 0.1)
				(type default)
			)
			(layer "F.Fab")
		)
		(fp_line
			(start -0.700024 1.100074)
			(end -0.700024 -1.100074)
			(stroke
				(width 0.1)
				(type default)
			)
			(layer "F.Fab")
		)
		(fp_line
			(start 0.700024 -1.100074)
			(end 0.700024 1.100074)
			(stroke
				(width 0.1)
				(type default)
			)
			(layer "F.Fab")
		)
		(fp_line
			(start 0.700024 1.100074)
			(end -0.700024 1.100074)
			(stroke
				(width 0.1)
				(type default)
			)
			(layer "F.Fab")
		)
		(fp_poly
			(pts
				(xy -0.4572 -1.6256) (xy -0.7112 -2.1336) (xy -0.2032 -2.1336)
			)
			(stroke
				(width 0)
				(type default)
			)
			(fill yes)
			(layer "F.Fab")
		)
		(pad "1" smd rect
			(at -0.424942 -0.849884)
			(size 0.3556 0.9144)
			(layers "F.Cu" "F.Mask" "F.Paste")
			(net "USB3_01_MUX_FB_TXP")
		)
		(pad "2" smd rect
			(at -0.424942 0.849884)
			(size 0.3556 0.9144)
			(layers "F.Cu" "F.Mask" "F.Paste")
			(net "USB3_01_FB_TXP")
		)
		(pad "3" smd rect
			(at 0.424942 0.849884)
			(size 0.3556 0.9144)
			(layers "F.Cu" "F.Mask" "F.Paste")
			(net "USB3_01_FB_TXN")
		)
		(pad "4" smd rect
			(at 0.424942 -0.849884)
			(size 0.3556 0.9144)
			(layers "F.Cu" "F.Mask" "F.Paste")
			(net "USB3_01_MUX_FB_TXN")
		)
	)
	(footprint ""
		(layer "F.Cu")
		(at 84.201 -94.488)
		(property "Reference" "R97"
			(at 0 0 0)
			(layer "F.SilkS")
			(hide yes)
			(effects
				(font
					(size 1.27 1.27)
				)
			)
		)
		(property "Value" ""
			(at 0 0 0)
			(layer "F.Fab")
			(effects
				(font
					(size 1.27 1.27)
				)
			)
		)
		(duplicate_pad_numbers_are_jumpers no)
		(fp_line
			(start -0.7874 -0.4064)
			(end 0.7874 -0.4064)
			(stroke
				(width 0.1524)
				(type default)
			)
			(layer "F.SilkS")
		)
		(fp_line
			(start -0.7874 0.4064)
			(end -0.7874 -0.4064)
			(stroke
				(width 0.1524)
				(type default)
			)
			(layer "F.SilkS")
		)
		(fp_line
			(start 0.7874 -0.4064)
			(end 0.7874 0.4064)
			(stroke
				(width 0.1524)
				(type default)
			)
			(layer "F.SilkS")
		)
		(fp_line
			(start 0.7874 0.4064)
			(end -0.7874 0.4064)
			(stroke
				(width 0.1524)
				(type default)
			)
			(layer "F.SilkS")
		)
		(fp_line
			(start -0.67945 -0.305054)
			(end -0.12065 -0.305054)
			(stroke
				(width 0.1)
				(type default)
			)
			(layer "F.Fab")
		)
		(fp_line
			(start -0.67945 0.3048)
			(end -0.67945 -0.305054)
			(stroke
				(width 0.1)
				(type default)
			)
			(layer "F.Fab")
		)
		(fp_line
			(start -0.12065 -0.305054)
			(end -0.12065 -0.2794)
			(stroke
				(width 0.1)
				(type default)
			)
			(layer "F.Fab")
		)
		(fp_line
			(start -0.12065 -0.2794)
			(end 0.12065 -0.2794)
			(stroke
				(width 0.1)
				(type default)
			)
			(layer "F.Fab")
		)
		(fp_line
			(start -0.12065 0.2794)
			(end -0.12065 0.3048)
			(stroke
				(width 0.1)
				(type default)
			)
			(layer "F.Fab")
		)
		(fp_line
			(start -0.12065 0.3048)
			(end -0.67945 0.3048)
			(stroke
				(width 0.1)
				(type default)
			)
			(layer "F.Fab")
		)
		(fp_line
			(start 0.120396 0.2794)
			(end -0.12065 0.2794)
			(stroke
				(width 0.1)
				(type default)
			)
			(layer "F.Fab")
		)
		(fp_line
			(start 0.120396 0.3048)
			(end 0.120396 0.2794)
			(stroke
				(width 0.1)
				(type default)
			)
			(layer "F.Fab")
		)
		(fp_line
			(start 0.12065 -0.3048)
			(end 0.67945 -0.3048)
			(stroke
				(width 0.1)
				(type default)
			)
			(layer "F.Fab")
		)
		(fp_line
			(start 0.12065 -0.2794)
			(end 0.12065 -0.3048)
			(stroke
				(width 0.1)
				(type default)
			)
			(layer "F.Fab")
		)
		(fp_line
			(start 0.67945 -0.3048)
			(end 0.67945 0.3048)
			(stroke
				(width 0.1)
				(type default)
			)
			(layer "F.Fab")
		)
		(fp_line
			(start 0.67945 0.3048)
			(end 0.120396 0.3048)
			(stroke
				(width 0.1)
				(type default)
			)
			(layer "F.Fab")
		)
		(pad "1" smd circle
			(at -0.40005 0)
			(size 0 0)
			(layers "F.Cu" "F.Mask" "F.Paste")
			(net "SPI_BMC_TPM_MOSI_R")
		)
		(pad "2" smd circle
			(at 0.40005 0)
			(size 0 0)
			(layers "F.Cu" "F.Mask" "F.Paste")
			(net "SPI_BMC_TPM_MOSI")
		)
	)
	(footprint ""
		(layer "F.Cu")
		(at 10.98296 -78.236318 90)
		(property "Reference" "PC229"
			(at 0 0 90)
			(layer "F.SilkS")
			(hide yes)
			(effects
				(font
					(size 1.27 1.27)
				)
			)
		)
		(property "Value" ""
			(at 0 0 90)
			(layer "F.Fab")
			(effects
				(font
					(size 1.27 1.27)
				)
			)
		)
		(duplicate_pad_numbers_are_jumpers no)
		(fp_line
			(start 1.651 -0.8382)
			(end 1.651 0.8382)
			(stroke
				(width 0.1524)
				(type default)
			)
			(layer "F.SilkS")
		)
		(fp_line
			(start -1.651 -0.8382)
			(end 1.651 -0.8382)
			(stroke
				(width 0.1524)
				(type default)
			)
			(layer "F.SilkS")
		)
		(fp_line
			(start 1.651 0.8382)
			(end -1.651 0.8382)
			(stroke
				(width 0.1524)
				(type default)
			)
			(layer "F.SilkS")
		)
		(fp_line
			(start 0 0.8382)
			(end 0 -0.8382)
			(stroke
				(width 0.1524)
				(type default)
			)
			(layer "F.SilkS")
		)
		(fp_line
			(start -1.651 0.8382)
			(end -1.651 -0.8382)
			(stroke
				(width 0.1524)
				(type default)
			)
			(layer "F.SilkS")
		)
		(fp_line
			(start 1.55956 -0.7366)
			(end 1.524 -0.7366)
			(stroke
				(width 0.1)
				(type default)
			)
			(layer "F.Fab")
		)
		(fp_line
			(start 1.524 -0.7366)
			(end -1.524 -0.7366)
			(stroke
				(width 0.1)
				(type default)
			)
			(layer "F.Fab")
		)
		(fp_line
			(start -1.524 -0.7366)
			(end -1.55956 -0.7366)
			(stroke
				(width 0.1)
				(type default)
			)
			(layer "F.Fab")
		)
		(fp_line
			(start -1.55956 -0.7366)
			(end -1.55956 0.7366)
			(stroke
				(width 0.1)
				(type default)
			)
			(layer "F.Fab")
		)
		(fp_line
			(start 1.55956 0.7366)
			(end 1.55956 -0.7366)
			(stroke
				(width 0.1)
				(type default)
			)
			(layer "F.Fab")
		)
		(fp_line
			(start 1.524 0.7366)
			(end 1.55956 0.7366)
			(stroke
				(width 0.1)
				(type default)
			)
			(layer "F.Fab")
		)
		(fp_line
			(start -1.524 0.7366)
			(end 1.524 0.7366)
			(stroke
				(width 0.1)
				(type default)
			)
			(layer "F.Fab")
		)
		(fp_line
			(start -1.55956 0.7366)
			(end -1.524 0.7366)
			(stroke
				(width 0.1)
				(type default)
			)
			(layer "F.Fab")
		)
		(pad "1" smd rect
			(at -0.94996 0 270)
			(size 1.1176 1.3716)
			(layers "F.Cu" "F.Mask" "F.Paste")
			(net "P3V3_AUX")
		)
		(pad "2" smd rect
			(at 0.94996 0 270)
			(size 1.1176 1.3716)
			(layers "F.Cu" "F.Mask" "F.Paste")
			(net "GND")
		)
	)
	(footprint ""
		(layer "F.Cu")
		(at 13.081 -58.6232 90)
		(property "Reference" "U42"
			(at -2.49047 2.6416 0)
			(unlocked yes)
			(layer "F.SilkS")
			(effects
				(font
					(size 0.7874 0.5842)
					(thickness 0.1524)
				)
			)
		)
		(property "Value" ""
			(at 0 0 90)
			(layer "F.Fab")
			(effects
				(font
					(size 1.27 1.27)
				)
			)
		)
		(duplicate_pad_numbers_are_jumpers no)
		(fp_line
			(start 1.834896 -1.575054)
			(end 1.834896 1.575054)
			(stroke
				(width 0.1524)
				(type default)
			)
			(layer "F.SilkS")
		)
		(fp_line
			(start 0.508 -1.575054)
			(end 1.834896 -1.575054)
			(stroke
				(width 0.1524)
				(type default)
			)
			(layer "F.SilkS")
		)
		(fp_line
			(start -0.508 -1.575054)
			(end 0 -1.016)
			(stroke
				(width 0.1524)
				(type default)
			)
			(layer "F.SilkS")
		)
		(fp_line
			(start -1.834896 -1.575054)
			(end -0.508 -1.575054)
			(stroke
				(width 0.1524)
				(type default)
			)
			(layer "F.SilkS")
		)
		(fp_line
			(start 0 -1.016)
			(end 0.508 -1.575054)
			(stroke
				(width 0.1524)
				(type default)
			)
			(layer "F.SilkS")
		)
		(fp_line
			(start 1.834896 1.575054)
			(end -1.834896 1.575054)
			(stroke
				(width 0.1524)
				(type default)
			)
			(layer "F.SilkS")
		)
		(fp_line
			(start -1.834896 1.575054)
			(end -1.834896 -1.575054)
			(stroke
				(width 0.1524)
				(type default)
			)
			(layer "F.SilkS")
		)
		(fp_poly
			(pts
				(xy -3.003296 -1.45796) (xy -3.003296 -0.44196) (xy -1.987296 -0.94996)
			)
			(stroke
				(width 0)
				(type default)
			)
			(fill yes)
			(layer "F.SilkS")
		)
		(fp_line
			(start 0.824992 -1.575054)
			(end 0.824992 1.575054)
			(stroke
				(width 0.1)
				(type default)
			)
			(layer "F.Fab")
		)
		(fp_line
			(start -0.824992 -1.575054)
			(end 0.824992 -1.575054)
			(stroke
				(width 0.1)
				(type default)
			)
			(layer "F.Fab")
		)
		(fp_line
			(start 0.824992 1.575054)
			(end -0.824992 1.575054)
			(stroke
				(width 0.1)
				(type default)
			)
			(layer "F.Fab")
		)
		(fp_line
			(start -0.824992 1.575054)
			(end -0.824992 -1.575054)
			(stroke
				(width 0.1)
				(type default)
			)
			(layer "F.Fab")
		)
		(fp_poly
			(pts
				(xy -3.003296 -1.45796) (xy -3.003296 -0.44196) (xy -1.987296 -0.94996)
			)
			(stroke
				(width 0)
				(type default)
			)
			(fill yes)
			(layer "F.Fab")
		)
		(pad "1" smd rect
			(at -1.199896 -0.94996)
			(size 0.7112 1.016)
			(layers "F.Cu" "F.Mask" "F.Paste")
			(net "PWRGD_P5V_AUX")
		)
		(pad "2" smd rect
			(at -1.199896 0)
			(size 0.7112 1.016)
			(layers "F.Cu" "F.Mask" "F.Paste")
			(net "PWRGD_P1V8_AUX")
		)
		(pad "3" smd rect
			(at -1.199896 0.94996)
			(size 0.7112 1.016)
			(layers "F.Cu" "F.Mask" "F.Paste")
			(net "GND")
		)
		(pad "4" smd rect
			(at 1.199896 0.94996)
			(size 0.7112 1.016)
			(layers "F.Cu" "F.Mask" "F.Paste")
			(net "EN_P3V3")
		)
		(pad "5" smd rect
			(at 1.199896 -0.94996)
			(size 0.7112 1.016)
			(layers "F.Cu" "F.Mask" "F.Paste")
			(net "P3V3_LDO")
		)
	)
	(footprint ""
		(layer "F.Cu")
		(at 45.256196 -65.918334 90)
		(property "Reference" "R21"
			(at 0 0 90)
			(layer "F.SilkS")
			(hide yes)
			(effects
				(font
					(size 1.27 1.27)
				)
			)
		)
		(property "Value" ""
			(at 0 0 90)
			(layer "F.Fab")
			(effects
				(font
					(size 1.27 1.27)
				)
			)
		)
		(duplicate_pad_numbers_are_jumpers no)
		(fp_line
			(start 0.7874 -0.4064)
			(end 0.7874 0.4064)
			(stroke
				(width 0.1524)
				(type default)
			)
			(layer "F.SilkS")
		)
		(fp_line
			(start -0.7874 -0.4064)
			(end 0.7874 -0.4064)
			(stroke
				(width 0.1524)
				(type default)
			)
			(layer "F.SilkS")
		)
		(fp_line
			(start 0.7874 0.4064)
			(end -0.7874 0.4064)
			(stroke
				(width 0.1524)
				(type default)
			)
			(layer "F.SilkS")
		)
		(fp_line
			(start -0.7874 0.4064)
			(end -0.7874 -0.4064)
			(stroke
				(width 0.1524)
				(type default)
			)
			(layer "F.SilkS")
		)
		(fp_line
			(start -0.12065 -0.305054)
			(end -0.12065 -0.2794)
			(stroke
				(width 0.1)
				(type default)
			)
			(layer "F.Fab")
		)
		(fp_line
			(start -0.67945 -0.305054)
			(end -0.12065 -0.305054)
			(stroke
				(width 0.1)
				(type default)
			)
			(layer "F.Fab")
		)
		(fp_line
			(start 0.67945 -0.3048)
			(end 0.67945 0.3048)
			(stroke
				(width 0.1)
				(type default)
			)
			(layer "F.Fab")
		)
		(fp_line
			(start 0.12065 -0.3048)
			(end 0.67945 -0.3048)
			(stroke
				(width 0.1)
				(type default)
			)
			(layer "F.Fab")
		)
		(fp_line
			(start 0.12065 -0.2794)
			(end 0.12065 -0.3048)
			(stroke
				(width 0.1)
				(type default)
			)
			(layer "F.Fab")
		)
		(fp_line
			(start -0.12065 -0.2794)
			(end 0.12065 -0.2794)
			(stroke
				(width 0.1)
				(type default)
			)
			(layer "F.Fab")
		)
		(fp_line
			(start 0.120396 0.2794)
			(end -0.12065 0.2794)
			(stroke
				(width 0.1)
				(type default)
			)
			(layer "F.Fab")
		)
		(fp_line
			(start -0.12065 0.2794)
			(end -0.12065 0.3048)
			(stroke
				(width 0.1)
				(type default)
			)
			(layer "F.Fab")
		)
		(fp_line
			(start 0.67945 0.3048)
			(end 0.120396 0.3048)
			(stroke
				(width 0.1)
				(type default)
			)
			(layer "F.Fab")
		)
		(fp_line
			(start 0.120396 0.3048)
			(end 0.120396 0.2794)
			(stroke
				(width 0.1)
				(type default)
			)
			(layer "F.Fab")
		)
		(fp_line
			(start -0.12065 0.3048)
			(end -0.67945 0.3048)
			(stroke
				(width 0.1)
				(type default)
			)
			(layer "F.Fab")
		)
		(fp_line
			(start -0.67945 0.3048)
			(end -0.67945 -0.305054)
			(stroke
				(width 0.1)
				(type default)
			)
			(layer "F.Fab")
		)
		(pad "1" smd circle
			(at -0.40005 0 90)
			(size 0 0)
			(layers "F.Cu" "F.Mask" "F.Paste")
			(net "V_DACG_R")
		)
		(pad "2" smd circle
			(at 0.40005 0 90)
			(size 0 0)
			(layers "F.Cu" "F.Mask" "F.Paste")
			(net "V_DACG")
		)
	)
	(footprint ""
		(layer "F.Cu")
		(at 11.29538 -67.4116 -90)
		(property "Reference" "C151"
			(at 0 0 270)
			(layer "F.SilkS")
			(hide yes)
			(effects
				(font
					(size 1.27 1.27)
				)
			)
		)
		(property "Value" ""
			(at 0 0 270)
			(layer "F.Fab")
			(effects
				(font
					(size 1.27 1.27)
				)
			)
		)
		(duplicate_pad_numbers_are_jumpers no)
		(fp_line
			(start -0.7874 0.4064)
			(end -0.7874 -0.4064)
			(stroke
				(width 0.1524)
				(type default)
			)
			(layer "F.SilkS")
		)
		(fp_line
			(start 0.7874 0.4064)
			(end -0.7874 0.4064)
			(stroke
				(width 0.1524)
				(type default)
			)
			(layer "F.SilkS")
		)
		(fp_line
			(start -0.7874 -0.4064)
			(end 0.7874 -0.4064)
			(stroke
				(width 0.1524)
				(type default)
			)
			(layer "F.SilkS")
		)
		(fp_line
			(start 0.7874 -0.4064)
			(end 0.7874 0.4064)
			(stroke
				(width 0.1524)
				(type default)
			)
			(layer "F.SilkS")
		)
		(fp_line
			(start -0.67945 0.3048)
			(end -0.67945 -0.305054)
			(stroke
				(width 0.1)
				(type default)
			)
			(layer "F.Fab")
		)
		(fp_line
			(start -0.12065 0.3048)
			(end -0.67945 0.3048)
			(stroke
				(width 0.1)
				(type default)
			)
			(layer "F.Fab")
		)
		(fp_line
			(start 0.120396 0.3048)
			(end 0.120396 0.2794)
			(stroke
				(width 0.1)
				(type default)
			)
			(layer "F.Fab")
		)
		(fp_line
			(start 0.67945 0.3048)
			(end 0.120396 0.3048)
			(stroke
				(width 0.1)
				(type default)
			)
			(layer "F.Fab")
		)
		(fp_line
			(start -0.12065 0.2794)
			(end -0.12065 0.3048)
			(stroke
				(width 0.1)
				(type default)
			)
			(layer "F.Fab")
		)
		(fp_line
			(start 0.120396 0.2794)
			(end -0.12065 0.2794)
			(stroke
				(width 0.1)
				(type default)
			)
			(layer "F.Fab")
		)
		(fp_line
			(start -0.12065 -0.2794)
			(end 0.12065 -0.2794)
			(stroke
				(width 0.1)
				(type default)
			)
			(layer "F.Fab")
		)
		(fp_line
			(start 0.12065 -0.2794)
			(end 0.12065 -0.3048)
			(stroke
				(width 0.1)
				(type default)
			)
			(layer "F.Fab")
		)
		(fp_line
			(start 0.12065 -0.3048)
			(end 0.67945 -0.3048)
			(stroke
				(width 0.1)
				(type default)
			)
			(layer "F.Fab")
		)
		(fp_line
			(start 0.67945 -0.3048)
			(end 0.67945 0.3048)
			(stroke
				(width 0.1)
				(type default)
			)
			(layer "F.Fab")
		)
		(fp_line
			(start -0.67945 -0.305054)
			(end -0.12065 -0.305054)
			(stroke
				(width 0.1)
				(type default)
			)
			(layer "F.Fab")
		)
		(fp_line
			(start -0.12065 -0.305054)
			(end -0.12065 -0.2794)
			(stroke
				(width 0.1)
				(type default)
			)
			(layer "F.Fab")
		)
		(pad "1" smd circle
			(at -0.40005 0 270)
			(size 0 0)
			(layers "F.Cu" "F.Mask" "F.Paste")
			(net "PWRGD_P3V3_AUX_R")
		)
		(pad "2" smd circle
			(at 0.40005 0 270)
			(size 0 0)
			(layers "F.Cu" "F.Mask" "F.Paste")
			(net "GND")
		)
	)
	(footprint ""
		(layer "F.Cu")
		(at 12.7762 -67.2084)
		(property "Reference" "R293"
			(at 0 0 0)
			(layer "F.SilkS")
			(hide yes)
			(effects
				(font
					(size 1.27 1.27)
				)
			)
		)
		(property "Value" ""
			(at 0 0 0)
			(layer "F.Fab")
			(effects
				(font
					(size 1.27 1.27)
				)
			)
		)
		(duplicate_pad_numbers_are_jumpers no)
		(fp_line
			(start -0.7874 -0.4064)
			(end 0.7874 -0.4064)
			(stroke
				(width 0.1524)
				(type default)
			)
			(layer "F.SilkS")
		)
		(fp_line
			(start -0.7874 0.4064)
			(end -0.7874 -0.4064)
			(stroke
				(width 0.1524)
				(type default)
			)
			(layer "F.SilkS")
		)
		(fp_line
			(start 0.7874 -0.4064)
			(end 0.7874 0.4064)
			(stroke
				(width 0.1524)
				(type default)
			)
			(layer "F.SilkS")
		)
		(fp_line
			(start 0.7874 0.4064)
			(end -0.7874 0.4064)
			(stroke
				(width 0.1524)
				(type default)
			)
			(layer "F.SilkS")
		)
		(fp_line
			(start -0.67945 -0.305054)
			(end -0.12065 -0.305054)
			(stroke
				(width 0.1)
				(type default)
			)
			(layer "F.Fab")
		)
		(fp_line
			(start -0.67945 0.3048)
			(end -0.67945 -0.305054)
			(stroke
				(width 0.1)
				(type default)
			)
			(layer "F.Fab")
		)
		(fp_line
			(start -0.12065 -0.305054)
			(end -0.12065 -0.2794)
			(stroke
				(width 0.1)
				(type default)
			)
			(layer "F.Fab")
		)
		(fp_line
			(start -0.12065 -0.2794)
			(end 0.12065 -0.2794)
			(stroke
				(width 0.1)
				(type default)
			)
			(layer "F.Fab")
		)
		(fp_line
			(start -0.12065 0.2794)
			(end -0.12065 0.3048)
			(stroke
				(width 0.1)
				(type default)
			)
			(layer "F.Fab")
		)
		(fp_line
			(start -0.12065 0.3048)
			(end -0.67945 0.3048)
			(stroke
				(width 0.1)
				(type default)
			)
			(layer "F.Fab")
		)
		(fp_line
			(start 0.120396 0.2794)
			(end -0.12065 0.2794)
			(stroke
				(width 0.1)
				(type default)
			)
			(layer "F.Fab")
		)
		(fp_line
			(start 0.120396 0.3048)
			(end 0.120396 0.2794)
			(stroke
				(width 0.1)
				(type default)
			)
			(layer "F.Fab")
		)
		(fp_line
			(start 0.12065 -0.3048)
			(end 0.67945 -0.3048)
			(stroke
				(width 0.1)
				(type default)
			)
			(layer "F.Fab")
		)
		(fp_line
			(start 0.12065 -0.2794)
			(end 0.12065 -0.3048)
			(stroke
				(width 0.1)
				(type default)
			)
			(layer "F.Fab")
		)
		(fp_line
			(start 0.67945 -0.3048)
			(end 0.67945 0.3048)
			(stroke
				(width 0.1)
				(type default)
			)
			(layer "F.Fab")
		)
		(fp_line
			(start 0.67945 0.3048)
			(end 0.120396 0.3048)
			(stroke
				(width 0.1)
				(type default)
			)
			(layer "F.Fab")
		)
		(pad "1" smd circle
			(at -0.40005 0)
			(size 0 0)
			(layers "F.Cu" "F.Mask" "F.Paste")
			(net "PWRGD_P3V3_AUX_R")
		)
		(pad "2" smd circle
			(at 0.40005 0)
			(size 0 0)
			(layers "F.Cu" "F.Mask" "F.Paste")
			(net "PWRGD_P3V3_AUX")
		)
	)
	(footprint ""
		(layer "F.Cu")
		(at 26.1112 -21.971 90)
		(property "Reference" "R29"
			(at 0 0 90)
			(layer "F.SilkS")
			(hide yes)
			(effects
				(font
					(size 1.27 1.27)
				)
			)
		)
		(property "Value" ""
			(at 0 0 90)
			(layer "F.Fab")
			(effects
				(font
					(size 1.27 1.27)
				)
			)
		)
		(duplicate_pad_numbers_are_jumpers no)
		(fp_line
			(start 0.7874 -0.4064)
			(end 0.7874 0.4064)
			(stroke
				(width 0.1524)
				(type default)
			)
			(layer "F.SilkS")
		)
		(fp_line
			(start -0.7874 -0.4064)
			(end 0.7874 -0.4064)
			(stroke
				(width 0.1524)
				(type default)
			)
			(layer "F.SilkS")
		)
		(fp_line
			(start 0.7874 0.4064)
			(end -0.7874 0.4064)
			(stroke
				(width 0.1524)
				(type default)
			)
			(layer "F.SilkS")
		)
		(fp_line
			(start -0.7874 0.4064)
			(end -0.7874 -0.4064)
			(stroke
				(width 0.1524)
				(type default)
			)
			(layer "F.SilkS")
		)
		(fp_line
			(start -0.12065 -0.305054)
			(end -0.12065 -0.2794)
			(stroke
				(width 0.1)
				(type default)
			)
			(layer "F.Fab")
		)
		(fp_line
			(start -0.67945 -0.305054)
			(end -0.12065 -0.305054)
			(stroke
				(width 0.1)
				(type default)
			)
			(layer "F.Fab")
		)
		(fp_line
			(start 0.67945 -0.3048)
			(end 0.67945 0.3048)
			(stroke
				(width 0.1)
				(type default)
			)
			(layer "F.Fab")
		)
		(fp_line
			(start 0.12065 -0.3048)
			(end 0.67945 -0.3048)
			(stroke
				(width 0.1)
				(type default)
			)
			(layer "F.Fab")
		)
		(fp_line
			(start 0.12065 -0.2794)
			(end 0.12065 -0.3048)
			(stroke
				(width 0.1)
				(type default)
			)
			(layer "F.Fab")
		)
		(fp_line
			(start -0.12065 -0.2794)
			(end 0.12065 -0.2794)
			(stroke
				(width 0.1)
				(type default)
			)
			(layer "F.Fab")
		)
		(fp_line
			(start 0.120396 0.2794)
			(end -0.12065 0.2794)
			(stroke
				(width 0.1)
				(type default)
			)
			(layer "F.Fab")
		)
		(fp_line
			(start -0.12065 0.2794)
			(end -0.12065 0.3048)
			(stroke
				(width 0.1)
				(type default)
			)
			(layer "F.Fab")
		)
		(fp_line
			(start 0.67945 0.3048)
			(end 0.120396 0.3048)
			(stroke
				(width 0.1)
				(type default)
			)
			(layer "F.Fab")
		)
		(fp_line
			(start 0.120396 0.3048)
			(end 0.120396 0.2794)
			(stroke
				(width 0.1)
				(type default)
			)
			(layer "F.Fab")
		)
		(fp_line
			(start -0.12065 0.3048)
			(end -0.67945 0.3048)
			(stroke
				(width 0.1)
				(type default)
			)
			(layer "F.Fab")
		)
		(fp_line
			(start -0.67945 0.3048)
			(end -0.67945 -0.305054)
			(stroke
				(width 0.1)
				(type default)
			)
			(layer "F.Fab")
		)
		(pad "1" smd circle
			(at -0.40005 0 90)
			(size 0 0)
			(layers "F.Cu" "F.Mask" "F.Paste")
			(net "V_BMC_LS_DDC_SDA")
		)
		(pad "2" smd circle
			(at 0.40005 0 90)
			(size 0 0)
			(layers "F.Cu" "F.Mask" "F.Paste")
			(net "V_BMC_LS_DDC_SDA_R")
		)
	)
	(footprint ""
		(layer "F.Cu")
		(at 59.99988 -107.700064)
		(property "Reference" "H4"
			(at -2.8702 -3.241548 0)
			(unlocked yes)
			(layer "F.SilkS")
			(effects
				(font
					(size 0.7874 0.5842)
					(thickness 0.1524)
				)
				(justify left)
			)
		)
		(property "Value" ""
			(at 0 0 0)
			(layer "F.Fab")
			(effects
				(font
					(size 1.27 1.27)
				)
			)
		)
		(duplicate_pad_numbers_are_jumpers no)
		(pad "1" thru_hole circle
			(at 0 0)
			(size 6.0198 6.0198)
			(drill 3.4036)
			(layers "*.Cu" "*.Mask")
			(remove_unused_layers no)
			(net "GND")
			(clearance -1.0541)
		)
	)
	(footprint ""
		(layer "F.Cu")
		(at 29.951172 -83.816952 90)
		(property "Reference" "R48"
			(at 0 0 90)
			(layer "F.SilkS")
			(hide yes)
			(effects
				(font
					(size 1.27 1.27)
				)
			)
		)
		(property "Value" ""
			(at 0 0 90)
			(layer "F.Fab")
			(effects
				(font
					(size 1.27 1.27)
				)
			)
		)
		(duplicate_pad_numbers_are_jumpers no)
		(fp_line
			(start 0.7874 -0.4064)
			(end 0.7874 0.4064)
			(stroke
				(width 0.1524)
				(type default)
			)
			(layer "F.SilkS")
		)
		(fp_line
			(start -0.7874 -0.4064)
			(end 0.7874 -0.4064)
			(stroke
				(width 0.1524)
				(type default)
			)
			(layer "F.SilkS")
		)
		(fp_line
			(start 0.7874 0.4064)
			(end -0.7874 0.4064)
			(stroke
				(width 0.1524)
				(type default)
			)
			(layer "F.SilkS")
		)
		(fp_line
			(start -0.7874 0.4064)
			(end -0.7874 -0.4064)
			(stroke
				(width 0.1524)
				(type default)
			)
			(layer "F.SilkS")
		)
		(fp_line
			(start -0.12065 -0.305054)
			(end -0.12065 -0.2794)
			(stroke
				(width 0.1)
				(type default)
			)
			(layer "F.Fab")
		)
		(fp_line
			(start -0.67945 -0.305054)
			(end -0.12065 -0.305054)
			(stroke
				(width 0.1)
				(type default)
			)
			(layer "F.Fab")
		)
		(fp_line
			(start 0.67945 -0.3048)
			(end 0.67945 0.3048)
			(stroke
				(width 0.1)
				(type default)
			)
			(layer "F.Fab")
		)
		(fp_line
			(start 0.12065 -0.3048)
			(end 0.67945 -0.3048)
			(stroke
				(width 0.1)
				(type default)
			)
			(layer "F.Fab")
		)
		(fp_line
			(start 0.12065 -0.2794)
			(end 0.12065 -0.3048)
			(stroke
				(width 0.1)
				(type default)
			)
			(layer "F.Fab")
		)
		(fp_line
			(start -0.12065 -0.2794)
			(end 0.12065 -0.2794)
			(stroke
				(width 0.1)
				(type default)
			)
			(layer "F.Fab")
		)
		(fp_line
			(start 0.120396 0.2794)
			(end -0.12065 0.2794)
			(stroke
				(width 0.1)
				(type default)
			)
			(layer "F.Fab")
		)
		(fp_line
			(start -0.12065 0.2794)
			(end -0.12065 0.3048)
			(stroke
				(width 0.1)
				(type default)
			)
			(layer "F.Fab")
		)
		(fp_line
			(start 0.67945 0.3048)
			(end 0.120396 0.3048)
			(stroke
				(width 0.1)
				(type default)
			)
			(layer "F.Fab")
		)
		(fp_line
			(start 0.120396 0.3048)
			(end 0.120396 0.2794)
			(stroke
				(width 0.1)
				(type default)
			)
			(layer "F.Fab")
		)
		(fp_line
			(start -0.12065 0.3048)
			(end -0.67945 0.3048)
			(stroke
				(width 0.1)
				(type default)
			)
			(layer "F.Fab")
		)
		(fp_line
			(start -0.67945 0.3048)
			(end -0.67945 -0.305054)
			(stroke
				(width 0.1)
				(type default)
			)
			(layer "F.Fab")
		)
		(pad "1" smd circle
			(at -0.40005 0 90)
			(size 0 0)
			(layers "F.Cu" "F.Mask" "F.Paste")
			(net "EMMC_CMD_R")
		)
		(pad "2" smd circle
			(at 0.40005 0 90)
			(size 0 0)
			(layers "F.Cu" "F.Mask" "F.Paste")
			(net "BMC_EMMC_CMD")
		)
	)
	(footprint ""
		(layer "F.Cu")
		(at 12.684252 -78.053184 90)
		(property "Reference" "PC225"
			(at 0 0 90)
			(layer "F.SilkS")
			(hide yes)
			(effects
				(font
					(size 1.27 1.27)
				)
			)
		)
		(property "Value" ""
			(at 0 0 90)
			(layer "F.Fab")
			(effects
				(font
					(size 1.27 1.27)
				)
			)
		)
		(duplicate_pad_numbers_are_jumpers no)
		(fp_line
			(start 0.7874 -0.4064)
			(end 0.7874 0.4064)
			(stroke
				(width 0.1524)
				(type default)
			)
			(layer "F.SilkS")
		)
		(fp_line
			(start -0.7874 -0.4064)
			(end 0.7874 -0.4064)
			(stroke
				(width 0.1524)
				(type default)
			)
			(layer "F.SilkS")
		)
		(fp_line
			(start 0.7874 0.4064)
			(end -0.7874 0.4064)
			(stroke
				(width 0.1524)
				(type default)
			)
			(layer "F.SilkS")
		)
		(fp_line
			(start -0.7874 0.4064)
			(end -0.7874 -0.4064)
			(stroke
				(width 0.1524)
				(type default)
			)
			(layer "F.SilkS")
		)
		(fp_line
			(start -0.12065 -0.305054)
			(end -0.12065 -0.2794)
			(stroke
				(width 0.1)
				(type default)
			)
			(layer "F.Fab")
		)
		(fp_line
			(start -0.67945 -0.305054)
			(end -0.12065 -0.305054)
			(stroke
				(width 0.1)
				(type default)
			)
			(layer "F.Fab")
		)
		(fp_line
			(start 0.67945 -0.3048)
			(end 0.67945 0.3048)
			(stroke
				(width 0.1)
				(type default)
			)
			(layer "F.Fab")
		)
		(fp_line
			(start 0.12065 -0.3048)
			(end 0.67945 -0.3048)
			(stroke
				(width 0.1)
				(type default)
			)
			(layer "F.Fab")
		)
		(fp_line
			(start 0.12065 -0.2794)
			(end 0.12065 -0.3048)
			(stroke
				(width 0.1)
				(type default)
			)
			(layer "F.Fab")
		)
		(fp_line
			(start -0.12065 -0.2794)
			(end 0.12065 -0.2794)
			(stroke
				(width 0.1)
				(type default)
			)
			(layer "F.Fab")
		)
		(fp_line
			(start 0.120396 0.2794)
			(end -0.12065 0.2794)
			(stroke
				(width 0.1)
				(type default)
			)
			(layer "F.Fab")
		)
		(fp_line
			(start -0.12065 0.2794)
			(end -0.12065 0.3048)
			(stroke
				(width 0.1)
				(type default)
			)
			(layer "F.Fab")
		)
		(fp_line
			(start 0.67945 0.3048)
			(end 0.120396 0.3048)
			(stroke
				(width 0.1)
				(type default)
			)
			(layer "F.Fab")
		)
		(fp_line
			(start 0.120396 0.3048)
			(end 0.120396 0.2794)
			(stroke
				(width 0.1)
				(type default)
			)
			(layer "F.Fab")
		)
		(fp_line
			(start -0.12065 0.3048)
			(end -0.67945 0.3048)
			(stroke
				(width 0.1)
				(type default)
			)
			(layer "F.Fab")
		)
		(fp_line
			(start -0.67945 0.3048)
			(end -0.67945 -0.305054)
			(stroke
				(width 0.1)
				(type default)
			)
			(layer "F.Fab")
		)
		(pad "1" smd circle
			(at -0.40005 0 90)
			(size 0 0)
			(layers "F.Cu" "F.Mask" "F.Paste")
			(net "P3V3_AUX")
		)
		(pad "2" smd circle
			(at 0.40005 0 90)
			(size 0 0)
			(layers "F.Cu" "F.Mask" "F.Paste")
			(net "GND")
		)
	)
	(footprint ""
		(layer "F.Cu")
		(at 29.464 -31.369 180)
		(property "Reference" "R88"
			(at 0 0 180)
			(layer "F.SilkS")
			(hide yes)
			(effects
				(font
					(size 1.27 1.27)
				)
			)
		)
		(property "Value" ""
			(at 0 0 180)
			(layer "F.Fab")
			(effects
				(font
					(size 1.27 1.27)
				)
			)
		)
		(duplicate_pad_numbers_are_jumpers no)
		(fp_line
			(start 0.7874 0.4064)
			(end -0.7874 0.4064)
			(stroke
				(width 0.1524)
				(type default)
			)
			(layer "F.SilkS")
		)
		(fp_line
			(start 0.7874 -0.4064)
			(end 0.7874 0.4064)
			(stroke
				(width 0.1524)
				(type default)
			)
			(layer "F.SilkS")
		)
		(fp_line
			(start -0.7874 0.4064)
			(end -0.7874 -0.4064)
			(stroke
				(width 0.1524)
				(type default)
			)
			(layer "F.SilkS")
		)
		(fp_line
			(start -0.7874 -0.4064)
			(end 0.7874 -0.4064)
			(stroke
				(width 0.1524)
				(type default)
			)
			(layer "F.SilkS")
		)
		(fp_line
			(start 0.67945 0.3048)
			(end 0.120396 0.3048)
			(stroke
				(width 0.1)
				(type default)
			)
			(layer "F.Fab")
		)
		(fp_line
			(start 0.67945 -0.3048)
			(end 0.67945 0.3048)
			(stroke
				(width 0.1)
				(type default)
			)
			(layer "F.Fab")
		)
		(fp_line
			(start 0.12065 -0.2794)
			(end 0.12065 -0.3048)
			(stroke
				(width 0.1)
				(type default)
			)
			(layer "F.Fab")
		)
		(fp_line
			(start 0.12065 -0.3048)
			(end 0.67945 -0.3048)
			(stroke
				(width 0.1)
				(type default)
			)
			(layer "F.Fab")
		)
		(fp_line
			(start 0.120396 0.3048)
			(end 0.120396 0.2794)
			(stroke
				(width 0.1)
				(type default)
			)
			(layer "F.Fab")
		)
		(fp_line
			(start 0.120396 0.2794)
			(end -0.12065 0.2794)
			(stroke
				(width 0.1)
				(type default)
			)
			(layer "F.Fab")
		)
		(fp_line
			(start -0.12065 0.3048)
			(end -0.67945 0.3048)
			(stroke
				(width 0.1)
				(type default)
			)
			(layer "F.Fab")
		)
		(fp_line
			(start -0.12065 0.2794)
			(end -0.12065 0.3048)
			(stroke
				(width 0.1)
				(type default)
			)
			(layer "F.Fab")
		)
		(fp_line
			(start -0.12065 -0.2794)
			(end 0.12065 -0.2794)
			(stroke
				(width 0.1)
				(type default)
			)
			(layer "F.Fab")
		)
		(fp_line
			(start -0.12065 -0.305054)
			(end -0.12065 -0.2794)
			(stroke
				(width 0.1)
				(type default)
			)
			(layer "F.Fab")
		)
		(fp_line
			(start -0.67945 0.3048)
			(end -0.67945 -0.305054)
			(stroke
				(width 0.1)
				(type default)
			)
			(layer "F.Fab")
		)
		(fp_line
			(start -0.67945 -0.305054)
			(end -0.12065 -0.305054)
			(stroke
				(width 0.1)
				(type default)
			)
			(layer "F.Fab")
		)
		(pad "1" smd circle
			(at -0.40005 0 180)
			(size 0 0)
			(layers "F.Cu" "F.Mask" "F.Paste")
			(net "V_DACG_IO")
		)
		(pad "2" smd circle
			(at 0.40005 0 180)
			(size 0 0)
			(layers "F.Cu" "F.Mask" "F.Paste")
			(net "GND")
		)
	)
	(footprint ""
		(layer "F.Cu")
		(at 28.321 -68.453 90)
		(property "Reference" "R850"
			(at 0 0 90)
			(layer "F.SilkS")
			(hide yes)
			(effects
				(font
					(size 1.27 1.27)
				)
			)
		)
		(property "Value" ""
			(at 0 0 90)
			(layer "F.Fab")
			(effects
				(font
					(size 1.27 1.27)
				)
			)
		)
		(duplicate_pad_numbers_are_jumpers no)
		(fp_line
			(start 0.7874 -0.4064)
			(end 0.7874 0.4064)
			(stroke
				(width 0.1524)
				(type default)
			)
			(layer "F.SilkS")
		)
		(fp_line
			(start -0.7874 -0.4064)
			(end 0.7874 -0.4064)
			(stroke
				(width 0.1524)
				(type default)
			)
			(layer "F.SilkS")
		)
		(fp_line
			(start 0.7874 0.4064)
			(end -0.7874 0.4064)
			(stroke
				(width 0.1524)
				(type default)
			)
			(layer "F.SilkS")
		)
		(fp_line
			(start -0.7874 0.4064)
			(end -0.7874 -0.4064)
			(stroke
				(width 0.1524)
				(type default)
			)
			(layer "F.SilkS")
		)
		(fp_line
			(start -0.12065 -0.305054)
			(end -0.12065 -0.2794)
			(stroke
				(width 0.1)
				(type default)
			)
			(layer "F.Fab")
		)
		(fp_line
			(start -0.67945 -0.305054)
			(end -0.12065 -0.305054)
			(stroke
				(width 0.1)
				(type default)
			)
			(layer "F.Fab")
		)
		(fp_line
			(start 0.67945 -0.3048)
			(end 0.67945 0.3048)
			(stroke
				(width 0.1)
				(type default)
			)
			(layer "F.Fab")
		)
		(fp_line
			(start 0.12065 -0.3048)
			(end 0.67945 -0.3048)
			(stroke
				(width 0.1)
				(type default)
			)
			(layer "F.Fab")
		)
		(fp_line
			(start 0.12065 -0.2794)
			(end 0.12065 -0.3048)
			(stroke
				(width 0.1)
				(type default)
			)
			(layer "F.Fab")
		)
		(fp_line
			(start -0.12065 -0.2794)
			(end 0.12065 -0.2794)
			(stroke
				(width 0.1)
				(type default)
			)
			(layer "F.Fab")
		)
		(fp_line
			(start 0.120396 0.2794)
			(end -0.12065 0.2794)
			(stroke
				(width 0.1)
				(type default)
			)
			(layer "F.Fab")
		)
		(fp_line
			(start -0.12065 0.2794)
			(end -0.12065 0.3048)
			(stroke
				(width 0.1)
				(type default)
			)
			(layer "F.Fab")
		)
		(fp_line
			(start 0.67945 0.3048)
			(end 0.120396 0.3048)
			(stroke
				(width 0.1)
				(type default)
			)
			(layer "F.Fab")
		)
		(fp_line
			(start 0.120396 0.3048)
			(end 0.120396 0.2794)
			(stroke
				(width 0.1)
				(type default)
			)
			(layer "F.Fab")
		)
		(fp_line
			(start -0.12065 0.3048)
			(end -0.67945 0.3048)
			(stroke
				(width 0.1)
				(type default)
			)
			(layer "F.Fab")
		)
		(fp_line
			(start -0.67945 0.3048)
			(end -0.67945 -0.305054)
			(stroke
				(width 0.1)
				(type default)
			)
			(layer "F.Fab")
		)
		(pad "1" smd circle
			(at -0.40005 0 90)
			(size 0 0)
			(layers "F.Cu" "F.Mask" "F.Paste")
			(net "SMB_BMC_MM16_R5_SDA")
		)
		(pad "2" smd circle
			(at 0.40005 0 90)
			(size 0 0)
			(layers "F.Cu" "F.Mask" "F.Paste")
			(net "SMB_BMC_MM16_R1_SDA")
		)
	)
	(footprint ""
		(layer "F.Cu")
		(at 32.70504 -68.504054 90)
		(property "Reference" "R659"
			(at 0 0 90)
			(layer "F.SilkS")
			(hide yes)
			(effects
				(font
					(size 1.27 1.27)
				)
			)
		)
		(property "Value" ""
			(at 0 0 90)
			(layer "F.Fab")
			(effects
				(font
					(size 1.27 1.27)
				)
			)
		)
		(duplicate_pad_numbers_are_jumpers no)
		(fp_line
			(start 0.7874 -0.4064)
			(end 0.7874 0.4064)
			(stroke
				(width 0.1524)
				(type default)
			)
			(layer "F.SilkS")
		)
		(fp_line
			(start -0.7874 -0.4064)
			(end 0.7874 -0.4064)
			(stroke
				(width 0.1524)
				(type default)
			)
			(layer "F.SilkS")
		)
		(fp_line
			(start 0.7874 0.4064)
			(end -0.7874 0.4064)
			(stroke
				(width 0.1524)
				(type default)
			)
			(layer "F.SilkS")
		)
		(fp_line
			(start -0.7874 0.4064)
			(end -0.7874 -0.4064)
			(stroke
				(width 0.1524)
				(type default)
			)
			(layer "F.SilkS")
		)
		(fp_line
			(start -0.12065 -0.305054)
			(end -0.12065 -0.2794)
			(stroke
				(width 0.1)
				(type default)
			)
			(layer "F.Fab")
		)
		(fp_line
			(start -0.67945 -0.305054)
			(end -0.12065 -0.305054)
			(stroke
				(width 0.1)
				(type default)
			)
			(layer "F.Fab")
		)
		(fp_line
			(start 0.67945 -0.3048)
			(end 0.67945 0.3048)
			(stroke
				(width 0.1)
				(type default)
			)
			(layer "F.Fab")
		)
		(fp_line
			(start 0.12065 -0.3048)
			(end 0.67945 -0.3048)
			(stroke
				(width 0.1)
				(type default)
			)
			(layer "F.Fab")
		)
		(fp_line
			(start 0.12065 -0.2794)
			(end 0.12065 -0.3048)
			(stroke
				(width 0.1)
				(type default)
			)
			(layer "F.Fab")
		)
		(fp_line
			(start -0.12065 -0.2794)
			(end 0.12065 -0.2794)
			(stroke
				(width 0.1)
				(type default)
			)
			(layer "F.Fab")
		)
		(fp_line
			(start 0.120396 0.2794)
			(end -0.12065 0.2794)
			(stroke
				(width 0.1)
				(type default)
			)
			(layer "F.Fab")
		)
		(fp_line
			(start -0.12065 0.2794)
			(end -0.12065 0.3048)
			(stroke
				(width 0.1)
				(type default)
			)
			(layer "F.Fab")
		)
		(fp_line
			(start 0.67945 0.3048)
			(end 0.120396 0.3048)
			(stroke
				(width 0.1)
				(type default)
			)
			(layer "F.Fab")
		)
		(fp_line
			(start 0.120396 0.3048)
			(end 0.120396 0.2794)
			(stroke
				(width 0.1)
				(type default)
			)
			(layer "F.Fab")
		)
		(fp_line
			(start -0.12065 0.3048)
			(end -0.67945 0.3048)
			(stroke
				(width 0.1)
				(type default)
			)
			(layer "F.Fab")
		)
		(fp_line
			(start -0.67945 0.3048)
			(end -0.67945 -0.305054)
			(stroke
				(width 0.1)
				(type default)
			)
			(layer "F.Fab")
		)
		(pad "1" smd circle
			(at -0.40005 0 90)
			(size 0 0)
			(layers "F.Cu" "F.Mask" "F.Paste")
			(net "P3V3_AUX")
		)
		(pad "2" smd circle
			(at 0.40005 0 90)
			(size 0 0)
			(layers "F.Cu" "F.Mask" "F.Paste")
			(net "EMMC_DT4_R")
		)
	)
	(footprint ""
		(layer "F.Cu")
		(at 23.495 -102.743 -90)
		(property "Reference" "R579"
			(at 0 0 270)
			(layer "F.SilkS")
			(hide yes)
			(effects
				(font
					(size 1.27 1.27)
				)
			)
		)
		(property "Value" ""
			(at 0 0 270)
			(layer "F.Fab")
			(effects
				(font
					(size 1.27 1.27)
				)
			)
		)
		(duplicate_pad_numbers_are_jumpers no)
		(fp_line
			(start -0.7874 0.4064)
			(end -0.7874 -0.4064)
			(stroke
				(width 0.1524)
				(type default)
			)
			(layer "F.SilkS")
		)
		(fp_line
			(start 0.7874 0.4064)
			(end -0.7874 0.4064)
			(stroke
				(width 0.1524)
				(type default)
			)
			(layer "F.SilkS")
		)
		(fp_line
			(start -0.7874 -0.4064)
			(end 0.7874 -0.4064)
			(stroke
				(width 0.1524)
				(type default)
			)
			(layer "F.SilkS")
		)
		(fp_line
			(start 0.7874 -0.4064)
			(end 0.7874 0.4064)
			(stroke
				(width 0.1524)
				(type default)
			)
			(layer "F.SilkS")
		)
		(fp_line
			(start -0.67945 0.3048)
			(end -0.67945 -0.305054)
			(stroke
				(width 0.1)
				(type default)
			)
			(layer "F.Fab")
		)
		(fp_line
			(start -0.12065 0.3048)
			(end -0.67945 0.3048)
			(stroke
				(width 0.1)
				(type default)
			)
			(layer "F.Fab")
		)
		(fp_line
			(start 0.120396 0.3048)
			(end 0.120396 0.2794)
			(stroke
				(width 0.1)
				(type default)
			)
			(layer "F.Fab")
		)
		(fp_line
			(start 0.67945 0.3048)
			(end 0.120396 0.3048)
			(stroke
				(width 0.1)
				(type default)
			)
			(layer "F.Fab")
		)
		(fp_line
			(start -0.12065 0.2794)
			(end -0.12065 0.3048)
			(stroke
				(width 0.1)
				(type default)
			)
			(layer "F.Fab")
		)
		(fp_line
			(start 0.120396 0.2794)
			(end -0.12065 0.2794)
			(stroke
				(width 0.1)
				(type default)
			)
			(layer "F.Fab")
		)
		(fp_line
			(start -0.12065 -0.2794)
			(end 0.12065 -0.2794)
			(stroke
				(width 0.1)
				(type default)
			)
			(layer "F.Fab")
		)
		(fp_line
			(start 0.12065 -0.2794)
			(end 0.12065 -0.3048)
			(stroke
				(width 0.1)
				(type default)
			)
			(layer "F.Fab")
		)
		(fp_line
			(start 0.12065 -0.3048)
			(end 0.67945 -0.3048)
			(stroke
				(width 0.1)
				(type default)
			)
			(layer "F.Fab")
		)
		(fp_line
			(start 0.67945 -0.3048)
			(end 0.67945 0.3048)
			(stroke
				(width 0.1)
				(type default)
			)
			(layer "F.Fab")
		)
		(fp_line
			(start -0.67945 -0.305054)
			(end -0.12065 -0.305054)
			(stroke
				(width 0.1)
				(type default)
			)
			(layer "F.Fab")
		)
		(fp_line
			(start -0.12065 -0.305054)
			(end -0.12065 -0.2794)
			(stroke
				(width 0.1)
				(type default)
			)
			(layer "F.Fab")
		)
		(pad "1" smd circle
			(at -0.40005 0 270)
			(size 0 0)
			(layers "F.Cu" "F.Mask" "F.Paste")
			(net "FM_DEBUG_PORT_PRSNT_N")
		)
		(pad "2" smd circle
			(at 0.40005 0 270)
			(size 0 0)
			(layers "F.Cu" "F.Mask" "F.Paste")
			(net "FM_DEBUG_PORT_R2_PRSNT_N")
		)
	)
	(footprint ""
		(layer "F.Cu")
		(at 80.4418 -30.8356 -90)
		(property "Reference" "R599"
			(at 0 0 270)
			(layer "F.SilkS")
			(hide yes)
			(effects
				(font
					(size 1.27 1.27)
				)
			)
		)
		(property "Value" ""
			(at 0 0 270)
			(layer "F.Fab")
			(effects
				(font
					(size 1.27 1.27)
				)
			)
		)
		(duplicate_pad_numbers_are_jumpers no)
		(fp_line
			(start -0.7874 0.4064)
			(end -0.7874 -0.4064)
			(stroke
				(width 0.1524)
				(type default)
			)
			(layer "F.SilkS")
		)
		(fp_line
			(start 0.7874 0.4064)
			(end -0.7874 0.4064)
			(stroke
				(width 0.1524)
				(type default)
			)
			(layer "F.SilkS")
		)
		(fp_line
			(start -0.7874 -0.4064)
			(end 0.7874 -0.4064)
			(stroke
				(width 0.1524)
				(type default)
			)
			(layer "F.SilkS")
		)
		(fp_line
			(start 0.7874 -0.4064)
			(end 0.7874 0.4064)
			(stroke
				(width 0.1524)
				(type default)
			)
			(layer "F.SilkS")
		)
		(fp_line
			(start -0.67945 0.3048)
			(end -0.67945 -0.305054)
			(stroke
				(width 0.1)
				(type default)
			)
			(layer "F.Fab")
		)
		(fp_line
			(start -0.12065 0.3048)
			(end -0.67945 0.3048)
			(stroke
				(width 0.1)
				(type default)
			)
			(layer "F.Fab")
		)
		(fp_line
			(start 0.120396 0.3048)
			(end 0.120396 0.2794)
			(stroke
				(width 0.1)
				(type default)
			)
			(layer "F.Fab")
		)
		(fp_line
			(start 0.67945 0.3048)
			(end 0.120396 0.3048)
			(stroke
				(width 0.1)
				(type default)
			)
			(layer "F.Fab")
		)
		(fp_line
			(start -0.12065 0.2794)
			(end -0.12065 0.3048)
			(stroke
				(width 0.1)
				(type default)
			)
			(layer "F.Fab")
		)
		(fp_line
			(start 0.120396 0.2794)
			(end -0.12065 0.2794)
			(stroke
				(width 0.1)
				(type default)
			)
			(layer "F.Fab")
		)
		(fp_line
			(start -0.12065 -0.2794)
			(end 0.12065 -0.2794)
			(stroke
				(width 0.1)
				(type default)
			)
			(layer "F.Fab")
		)
		(fp_line
			(start 0.12065 -0.2794)
			(end 0.12065 -0.3048)
			(stroke
				(width 0.1)
				(type default)
			)
			(layer "F.Fab")
		)
		(fp_line
			(start 0.12065 -0.3048)
			(end 0.67945 -0.3048)
			(stroke
				(width 0.1)
				(type default)
			)
			(layer "F.Fab")
		)
		(fp_line
			(start 0.67945 -0.3048)
			(end 0.67945 0.3048)
			(stroke
				(width 0.1)
				(type default)
			)
			(layer "F.Fab")
		)
		(fp_line
			(start -0.67945 -0.305054)
			(end -0.12065 -0.305054)
			(stroke
				(width 0.1)
				(type default)
			)
			(layer "F.Fab")
		)
		(fp_line
			(start -0.12065 -0.305054)
			(end -0.12065 -0.2794)
			(stroke
				(width 0.1)
				(type default)
			)
			(layer "F.Fab")
		)
		(pad "1" smd circle
			(at -0.40005 0 270)
			(size 0 0)
			(layers "F.Cu" "F.Mask" "F.Paste")
			(net "LED_POSTCODE_5")
		)
		(pad "2" smd circle
			(at 0.40005 0 270)
			(size 0 0)
			(layers "F.Cu" "F.Mask" "F.Paste")
			(net "LED_POSTCODE_5_R")
		)
	)
	(footprint ""
		(layer "F.Cu")
		(at 25.3238 -30.6324 90)
		(property "Reference" "PR205"
			(at 0 0 90)
			(layer "F.SilkS")
			(hide yes)
			(effects
				(font
					(size 1.27 1.27)
				)
			)
		)
		(property "Value" ""
			(at 0 0 90)
			(layer "F.Fab")
			(effects
				(font
					(size 1.27 1.27)
				)
			)
		)
		(duplicate_pad_numbers_are_jumpers no)
		(fp_line
			(start 0.7874 -0.4064)
			(end 0.7874 0.4064)
			(stroke
				(width 0.1524)
				(type default)
			)
			(layer "F.SilkS")
		)
		(fp_line
			(start -0.7874 -0.4064)
			(end 0.7874 -0.4064)
			(stroke
				(width 0.1524)
				(type default)
			)
			(layer "F.SilkS")
		)
		(fp_line
			(start 0.7874 0.4064)
			(end -0.7874 0.4064)
			(stroke
				(width 0.1524)
				(type default)
			)
			(layer "F.SilkS")
		)
		(fp_line
			(start -0.7874 0.4064)
			(end -0.7874 -0.4064)
			(stroke
				(width 0.1524)
				(type default)
			)
			(layer "F.SilkS")
		)
		(fp_line
			(start -0.12065 -0.305054)
			(end -0.12065 -0.2794)
			(stroke
				(width 0.1)
				(type default)
			)
			(layer "F.Fab")
		)
		(fp_line
			(start -0.67945 -0.305054)
			(end -0.12065 -0.305054)
			(stroke
				(width 0.1)
				(type default)
			)
			(layer "F.Fab")
		)
		(fp_line
			(start 0.67945 -0.3048)
			(end 0.67945 0.3048)
			(stroke
				(width 0.1)
				(type default)
			)
			(layer "F.Fab")
		)
		(fp_line
			(start 0.12065 -0.3048)
			(end 0.67945 -0.3048)
			(stroke
				(width 0.1)
				(type default)
			)
			(layer "F.Fab")
		)
		(fp_line
			(start 0.12065 -0.2794)
			(end 0.12065 -0.3048)
			(stroke
				(width 0.1)
				(type default)
			)
			(layer "F.Fab")
		)
		(fp_line
			(start -0.12065 -0.2794)
			(end 0.12065 -0.2794)
			(stroke
				(width 0.1)
				(type default)
			)
			(layer "F.Fab")
		)
		(fp_line
			(start 0.120396 0.2794)
			(end -0.12065 0.2794)
			(stroke
				(width 0.1)
				(type default)
			)
			(layer "F.Fab")
		)
		(fp_line
			(start -0.12065 0.2794)
			(end -0.12065 0.3048)
			(stroke
				(width 0.1)
				(type default)
			)
			(layer "F.Fab")
		)
		(fp_line
			(start 0.67945 0.3048)
			(end 0.120396 0.3048)
			(stroke
				(width 0.1)
				(type default)
			)
			(layer "F.Fab")
		)
		(fp_line
			(start 0.120396 0.3048)
			(end 0.120396 0.2794)
			(stroke
				(width 0.1)
				(type default)
			)
			(layer "F.Fab")
		)
		(fp_line
			(start -0.12065 0.3048)
			(end -0.67945 0.3048)
			(stroke
				(width 0.1)
				(type default)
			)
			(layer "F.Fab")
		)
		(fp_line
			(start -0.67945 0.3048)
			(end -0.67945 -0.305054)
			(stroke
				(width 0.1)
				(type default)
			)
			(layer "F.Fab")
		)
		(pad "1" smd circle
			(at -0.40005 0 90)
			(size 0 0)
			(layers "F.Cu" "F.Mask" "F.Paste")
			(net "P5V_AUX")
		)
		(pad "2" smd circle
			(at 0.40005 0 90)
			(size 0 0)
			(layers "F.Cu" "F.Mask" "F.Paste")
			(net "PVCC2_AUX")
		)
	)
	(footprint ""
		(layer "F.Cu")
		(at 6.100064 -22.690074)
		(property "Reference" "H5"
			(at -5.007864 -0.130556 0)
			(unlocked yes)
			(layer "F.SilkS")
			(effects
				(font
					(size 0.7874 0.5842)
					(thickness 0.1524)
				)
				(justify left)
			)
		)
		(property "Value" ""
			(at 0 0 0)
			(layer "F.Fab")
			(effects
				(font
					(size 1.27 1.27)
				)
			)
		)
		(duplicate_pad_numbers_are_jumpers no)
		(pad "1" thru_hole circle
			(at 0 0)
			(size 6.0452 6.0452)
			(drill 3.1496)
			(layers "*.Cu" "*.Mask")
			(remove_unused_layers no)
			(net "GND")
			(clearance -1.1938)
		)
	)
	(footprint ""
		(layer "F.Cu")
		(at 39.8272 -76.454)
		(property "Reference" "R550"
			(at 0 0 0)
			(layer "F.SilkS")
			(hide yes)
			(effects
				(font
					(size 1.27 1.27)
				)
			)
		)
		(property "Value" ""
			(at 0 0 0)
			(layer "F.Fab")
			(effects
				(font
					(size 1.27 1.27)
				)
			)
		)
		(duplicate_pad_numbers_are_jumpers no)
		(fp_line
			(start -0.7874 -0.4064)
			(end 0.7874 -0.4064)
			(stroke
				(width 0.1524)
				(type default)
			)
			(layer "F.SilkS")
		)
		(fp_line
			(start -0.7874 0.4064)
			(end -0.7874 -0.4064)
			(stroke
				(width 0.1524)
				(type default)
			)
			(layer "F.SilkS")
		)
		(fp_line
			(start 0.7874 -0.4064)
			(end 0.7874 0.4064)
			(stroke
				(width 0.1524)
				(type default)
			)
			(layer "F.SilkS")
		)
		(fp_line
			(start 0.7874 0.4064)
			(end -0.7874 0.4064)
			(stroke
				(width 0.1524)
				(type default)
			)
			(layer "F.SilkS")
		)
		(fp_line
			(start -0.67945 -0.305054)
			(end -0.12065 -0.305054)
			(stroke
				(width 0.1)
				(type default)
			)
			(layer "F.Fab")
		)
		(fp_line
			(start -0.67945 0.3048)
			(end -0.67945 -0.305054)
			(stroke
				(width 0.1)
				(type default)
			)
			(layer "F.Fab")
		)
		(fp_line
			(start -0.12065 -0.305054)
			(end -0.12065 -0.2794)
			(stroke
				(width 0.1)
				(type default)
			)
			(layer "F.Fab")
		)
		(fp_line
			(start -0.12065 -0.2794)
			(end 0.12065 -0.2794)
			(stroke
				(width 0.1)
				(type default)
			)
			(layer "F.Fab")
		)
		(fp_line
			(start -0.12065 0.2794)
			(end -0.12065 0.3048)
			(stroke
				(width 0.1)
				(type default)
			)
			(layer "F.Fab")
		)
		(fp_line
			(start -0.12065 0.3048)
			(end -0.67945 0.3048)
			(stroke
				(width 0.1)
				(type default)
			)
			(layer "F.Fab")
		)
		(fp_line
			(start 0.120396 0.2794)
			(end -0.12065 0.2794)
			(stroke
				(width 0.1)
				(type default)
			)
			(layer "F.Fab")
		)
		(fp_line
			(start 0.120396 0.3048)
			(end 0.120396 0.2794)
			(stroke
				(width 0.1)
				(type default)
			)
			(layer "F.Fab")
		)
		(fp_line
			(start 0.12065 -0.3048)
			(end 0.67945 -0.3048)
			(stroke
				(width 0.1)
				(type default)
			)
			(layer "F.Fab")
		)
		(fp_line
			(start 0.12065 -0.2794)
			(end 0.12065 -0.3048)
			(stroke
				(width 0.1)
				(type default)
			)
			(layer "F.Fab")
		)
		(fp_line
			(start 0.67945 -0.3048)
			(end 0.67945 0.3048)
			(stroke
				(width 0.1)
				(type default)
			)
			(layer "F.Fab")
		)
		(fp_line
			(start 0.67945 0.3048)
			(end 0.120396 0.3048)
			(stroke
				(width 0.1)
				(type default)
			)
			(layer "F.Fab")
		)
		(pad "1" smd circle
			(at -0.40005 0)
			(size 0 0)
			(layers "F.Cu" "F.Mask" "F.Paste")
			(net "SPI_BMC_IO0_FLASH_R")
		)
		(pad "2" smd circle
			(at 0.40005 0)
			(size 0 0)
			(layers "F.Cu" "F.Mask" "F.Paste")
			(net "SPI_BMC_BOOT_MOSI")
		)
	)
	(footprint ""
		(layer "F.Cu")
		(at 35.1536 -88.4682 180)
		(property "Reference" "R492"
			(at 0 0 180)
			(layer "F.SilkS")
			(hide yes)
			(effects
				(font
					(size 1.27 1.27)
				)
			)
		)
		(property "Value" ""
			(at 0 0 180)
			(layer "F.Fab")
			(effects
				(font
					(size 1.27 1.27)
				)
			)
		)
		(duplicate_pad_numbers_are_jumpers no)
		(fp_line
			(start 0.7874 0.4064)
			(end -0.7874 0.4064)
			(stroke
				(width 0.1524)
				(type default)
			)
			(layer "F.SilkS")
		)
		(fp_line
			(start 0.7874 -0.4064)
			(end 0.7874 0.4064)
			(stroke
				(width 0.1524)
				(type default)
			)
			(layer "F.SilkS")
		)
		(fp_line
			(start -0.7874 0.4064)
			(end -0.7874 -0.4064)
			(stroke
				(width 0.1524)
				(type default)
			)
			(layer "F.SilkS")
		)
		(fp_line
			(start -0.7874 -0.4064)
			(end 0.7874 -0.4064)
			(stroke
				(width 0.1524)
				(type default)
			)
			(layer "F.SilkS")
		)
		(fp_line
			(start 0.67945 0.3048)
			(end 0.120396 0.3048)
			(stroke
				(width 0.1)
				(type default)
			)
			(layer "F.Fab")
		)
		(fp_line
			(start 0.67945 -0.3048)
			(end 0.67945 0.3048)
			(stroke
				(width 0.1)
				(type default)
			)
			(layer "F.Fab")
		)
		(fp_line
			(start 0.12065 -0.2794)
			(end 0.12065 -0.3048)
			(stroke
				(width 0.1)
				(type default)
			)
			(layer "F.Fab")
		)
		(fp_line
			(start 0.12065 -0.3048)
			(end 0.67945 -0.3048)
			(stroke
				(width 0.1)
				(type default)
			)
			(layer "F.Fab")
		)
		(fp_line
			(start 0.120396 0.3048)
			(end 0.120396 0.2794)
			(stroke
				(width 0.1)
				(type default)
			)
			(layer "F.Fab")
		)
		(fp_line
			(start 0.120396 0.2794)
			(end -0.12065 0.2794)
			(stroke
				(width 0.1)
				(type default)
			)
			(layer "F.Fab")
		)
		(fp_line
			(start -0.12065 0.3048)
			(end -0.67945 0.3048)
			(stroke
				(width 0.1)
				(type default)
			)
			(layer "F.Fab")
		)
		(fp_line
			(start -0.12065 0.2794)
			(end -0.12065 0.3048)
			(stroke
				(width 0.1)
				(type default)
			)
			(layer "F.Fab")
		)
		(fp_line
			(start -0.12065 -0.2794)
			(end 0.12065 -0.2794)
			(stroke
				(width 0.1)
				(type default)
			)
			(layer "F.Fab")
		)
		(fp_line
			(start -0.12065 -0.305054)
			(end -0.12065 -0.2794)
			(stroke
				(width 0.1)
				(type default)
			)
			(layer "F.Fab")
		)
		(fp_line
			(start -0.67945 0.3048)
			(end -0.67945 -0.305054)
			(stroke
				(width 0.1)
				(type default)
			)
			(layer "F.Fab")
		)
		(fp_line
			(start -0.67945 -0.305054)
			(end -0.12065 -0.305054)
			(stroke
				(width 0.1)
				(type default)
			)
			(layer "F.Fab")
		)
		(pad "1" smd circle
			(at -0.40005 0 180)
			(size 0 0)
			(layers "F.Cu" "F.Mask" "F.Paste")
			(net "P3V3_AUX")
		)
		(pad "2" smd circle
			(at 0.40005 0 180)
			(size 0 0)
			(layers "F.Cu" "F.Mask" "F.Paste")
			(net "SPI_PCH_IO3_FLASH_R1")
		)
	)
	(footprint ""
		(layer "F.Cu")
		(at 26.543 -102.743 -90)
		(property "Reference" "R635"
			(at 0 0 270)
			(layer "F.SilkS")
			(hide yes)
			(effects
				(font
					(size 1.27 1.27)
				)
			)
		)
		(property "Value" ""
			(at 0 0 270)
			(layer "F.Fab")
			(effects
				(font
					(size 1.27 1.27)
				)
			)
		)
		(duplicate_pad_numbers_are_jumpers no)
		(fp_line
			(start -0.7874 0.4064)
			(end -0.7874 -0.4064)
			(stroke
				(width 0.1524)
				(type default)
			)
			(layer "F.SilkS")
		)
		(fp_line
			(start 0.7874 0.4064)
			(end -0.7874 0.4064)
			(stroke
				(width 0.1524)
				(type default)
			)
			(layer "F.SilkS")
		)
		(fp_line
			(start -0.7874 -0.4064)
			(end 0.7874 -0.4064)
			(stroke
				(width 0.1524)
				(type default)
			)
			(layer "F.SilkS")
		)
		(fp_line
			(start 0.7874 -0.4064)
			(end 0.7874 0.4064)
			(stroke
				(width 0.1524)
				(type default)
			)
			(layer "F.SilkS")
		)
		(fp_line
			(start -0.67945 0.3048)
			(end -0.67945 -0.305054)
			(stroke
				(width 0.1)
				(type default)
			)
			(layer "F.Fab")
		)
		(fp_line
			(start -0.12065 0.3048)
			(end -0.67945 0.3048)
			(stroke
				(width 0.1)
				(type default)
			)
			(layer "F.Fab")
		)
		(fp_line
			(start 0.120396 0.3048)
			(end 0.120396 0.2794)
			(stroke
				(width 0.1)
				(type default)
			)
			(layer "F.Fab")
		)
		(fp_line
			(start 0.67945 0.3048)
			(end 0.120396 0.3048)
			(stroke
				(width 0.1)
				(type default)
			)
			(layer "F.Fab")
		)
		(fp_line
			(start -0.12065 0.2794)
			(end -0.12065 0.3048)
			(stroke
				(width 0.1)
				(type default)
			)
			(layer "F.Fab")
		)
		(fp_line
			(start 0.120396 0.2794)
			(end -0.12065 0.2794)
			(stroke
				(width 0.1)
				(type default)
			)
			(layer "F.Fab")
		)
		(fp_line
			(start -0.12065 -0.2794)
			(end 0.12065 -0.2794)
			(stroke
				(width 0.1)
				(type default)
			)
			(layer "F.Fab")
		)
		(fp_line
			(start 0.12065 -0.2794)
			(end 0.12065 -0.3048)
			(stroke
				(width 0.1)
				(type default)
			)
			(layer "F.Fab")
		)
		(fp_line
			(start 0.12065 -0.3048)
			(end 0.67945 -0.3048)
			(stroke
				(width 0.1)
				(type default)
			)
			(layer "F.Fab")
		)
		(fp_line
			(start 0.67945 -0.3048)
			(end 0.67945 0.3048)
			(stroke
				(width 0.1)
				(type default)
			)
			(layer "F.Fab")
		)
		(fp_line
			(start -0.67945 -0.305054)
			(end -0.12065 -0.305054)
			(stroke
				(width 0.1)
				(type default)
			)
			(layer "F.Fab")
		)
		(fp_line
			(start -0.12065 -0.305054)
			(end -0.12065 -0.2794)
			(stroke
				(width 0.1)
				(type default)
			)
			(layer "F.Fab")
		)
		(pad "1" smd circle
			(at -0.40005 0 270)
			(size 0 0)
			(layers "F.Cu" "F.Mask" "F.Paste")
			(net "RST_WDTRST_PLD_N")
		)
		(pad "2" smd circle
			(at 0.40005 0 270)
			(size 0 0)
			(layers "F.Cu" "F.Mask" "F.Paste")
			(net "RST_WDTRST_PLD_R2_N")
		)
	)
	(footprint ""
		(layer "F.Cu")
		(at 48.768 -34.6456 -90)
		(property "Reference" "R133"
			(at 0 0 270)
			(layer "F.SilkS")
			(hide yes)
			(effects
				(font
					(size 1.27 1.27)
				)
			)
		)
		(property "Value" ""
			(at 0 0 270)
			(layer "F.Fab")
			(effects
				(font
					(size 1.27 1.27)
				)
			)
		)
		(duplicate_pad_numbers_are_jumpers no)
		(fp_line
			(start -0.7874 0.4064)
			(end -0.7874 -0.4064)
			(stroke
				(width 0.1524)
				(type default)
			)
			(layer "F.SilkS")
		)
		(fp_line
			(start 0.7874 0.4064)
			(end -0.7874 0.4064)
			(stroke
				(width 0.1524)
				(type default)
			)
			(layer "F.SilkS")
		)
		(fp_line
			(start -0.7874 -0.4064)
			(end 0.7874 -0.4064)
			(stroke
				(width 0.1524)
				(type default)
			)
			(layer "F.SilkS")
		)
		(fp_line
			(start 0.7874 -0.4064)
			(end 0.7874 0.4064)
			(stroke
				(width 0.1524)
				(type default)
			)
			(layer "F.SilkS")
		)
		(fp_line
			(start -0.67945 0.3048)
			(end -0.67945 -0.305054)
			(stroke
				(width 0.1)
				(type default)
			)
			(layer "F.Fab")
		)
		(fp_line
			(start -0.12065 0.3048)
			(end -0.67945 0.3048)
			(stroke
				(width 0.1)
				(type default)
			)
			(layer "F.Fab")
		)
		(fp_line
			(start 0.120396 0.3048)
			(end 0.120396 0.2794)
			(stroke
				(width 0.1)
				(type default)
			)
			(layer "F.Fab")
		)
		(fp_line
			(start 0.67945 0.3048)
			(end 0.120396 0.3048)
			(stroke
				(width 0.1)
				(type default)
			)
			(layer "F.Fab")
		)
		(fp_line
			(start -0.12065 0.2794)
			(end -0.12065 0.3048)
			(stroke
				(width 0.1)
				(type default)
			)
			(layer "F.Fab")
		)
		(fp_line
			(start 0.120396 0.2794)
			(end -0.12065 0.2794)
			(stroke
				(width 0.1)
				(type default)
			)
			(layer "F.Fab")
		)
		(fp_line
			(start -0.12065 -0.2794)
			(end 0.12065 -0.2794)
			(stroke
				(width 0.1)
				(type default)
			)
			(layer "F.Fab")
		)
		(fp_line
			(start 0.12065 -0.2794)
			(end 0.12065 -0.3048)
			(stroke
				(width 0.1)
				(type default)
			)
			(layer "F.Fab")
		)
		(fp_line
			(start 0.12065 -0.3048)
			(end 0.67945 -0.3048)
			(stroke
				(width 0.1)
				(type default)
			)
			(layer "F.Fab")
		)
		(fp_line
			(start 0.67945 -0.3048)
			(end 0.67945 0.3048)
			(stroke
				(width 0.1)
				(type default)
			)
			(layer "F.Fab")
		)
		(fp_line
			(start -0.67945 -0.305054)
			(end -0.12065 -0.305054)
			(stroke
				(width 0.1)
				(type default)
			)
			(layer "F.Fab")
		)
		(fp_line
			(start -0.12065 -0.305054)
			(end -0.12065 -0.2794)
			(stroke
				(width 0.1)
				(type default)
			)
			(layer "F.Fab")
		)
		(pad "1" smd circle
			(at -0.40005 0 270)
			(size 0 0)
			(layers "F.Cu" "F.Mask" "F.Paste")
			(net "SMB_BMC_MM1_R_SDA")
		)
		(pad "2" smd circle
			(at 0.40005 0 270)
			(size 0 0)
			(layers "F.Cu" "F.Mask" "F.Paste")
			(net "SMB_BMC_MM1_SDA")
		)
	)
	(footprint ""
		(layer "F.Cu")
		(at 35.941 -36.068 90)
		(property "Reference" "C53"
			(at 0 0 90)
			(layer "F.SilkS")
			(hide yes)
			(effects
				(font
					(size 1.27 1.27)
				)
			)
		)
		(property "Value" ""
			(at 0 0 90)
			(layer "F.Fab")
			(effects
				(font
					(size 1.27 1.27)
				)
			)
		)
		(duplicate_pad_numbers_are_jumpers no)
		(fp_line
			(start 0.7874 -0.4064)
			(end 0.7874 0.4064)
			(stroke
				(width 0.1524)
				(type default)
			)
			(layer "F.SilkS")
		)
		(fp_line
			(start -0.7874 -0.4064)
			(end 0.7874 -0.4064)
			(stroke
				(width 0.1524)
				(type default)
			)
			(layer "F.SilkS")
		)
		(fp_line
			(start 0.7874 0.4064)
			(end -0.7874 0.4064)
			(stroke
				(width 0.1524)
				(type default)
			)
			(layer "F.SilkS")
		)
		(fp_line
			(start -0.7874 0.4064)
			(end -0.7874 -0.4064)
			(stroke
				(width 0.1524)
				(type default)
			)
			(layer "F.SilkS")
		)
		(fp_line
			(start -0.12065 -0.305054)
			(end -0.12065 -0.2794)
			(stroke
				(width 0.1)
				(type default)
			)
			(layer "F.Fab")
		)
		(fp_line
			(start -0.67945 -0.305054)
			(end -0.12065 -0.305054)
			(stroke
				(width 0.1)
				(type default)
			)
			(layer "F.Fab")
		)
		(fp_line
			(start 0.67945 -0.3048)
			(end 0.67945 0.3048)
			(stroke
				(width 0.1)
				(type default)
			)
			(layer "F.Fab")
		)
		(fp_line
			(start 0.12065 -0.3048)
			(end 0.67945 -0.3048)
			(stroke
				(width 0.1)
				(type default)
			)
			(layer "F.Fab")
		)
		(fp_line
			(start 0.12065 -0.2794)
			(end 0.12065 -0.3048)
			(stroke
				(width 0.1)
				(type default)
			)
			(layer "F.Fab")
		)
		(fp_line
			(start -0.12065 -0.2794)
			(end 0.12065 -0.2794)
			(stroke
				(width 0.1)
				(type default)
			)
			(layer "F.Fab")
		)
		(fp_line
			(start 0.120396 0.2794)
			(end -0.12065 0.2794)
			(stroke
				(width 0.1)
				(type default)
			)
			(layer "F.Fab")
		)
		(fp_line
			(start -0.12065 0.2794)
			(end -0.12065 0.3048)
			(stroke
				(width 0.1)
				(type default)
			)
			(layer "F.Fab")
		)
		(fp_line
			(start 0.67945 0.3048)
			(end 0.120396 0.3048)
			(stroke
				(width 0.1)
				(type default)
			)
			(layer "F.Fab")
		)
		(fp_line
			(start 0.120396 0.3048)
			(end 0.120396 0.2794)
			(stroke
				(width 0.1)
				(type default)
			)
			(layer "F.Fab")
		)
		(fp_line
			(start -0.12065 0.3048)
			(end -0.67945 0.3048)
			(stroke
				(width 0.1)
				(type default)
			)
			(layer "F.Fab")
		)
		(fp_line
			(start -0.67945 0.3048)
			(end -0.67945 -0.305054)
			(stroke
				(width 0.1)
				(type default)
			)
			(layer "F.Fab")
		)
		(pad "1" smd circle
			(at -0.40005 0 90)
			(size 0 0)
			(layers "F.Cu" "F.Mask" "F.Paste")
			(net "P3V3_P1V8_I2C_I3C")
		)
		(pad "2" smd circle
			(at 0.40005 0 90)
			(size 0 0)
			(layers "F.Cu" "F.Mask" "F.Paste")
			(net "GND")
		)
	)
	(footprint ""
		(layer "F.Cu")
		(at 46.9646 -77.2668)
		(property "Reference" "R548"
			(at 0 0 0)
			(layer "F.SilkS")
			(hide yes)
			(effects
				(font
					(size 1.27 1.27)
				)
			)
		)
		(property "Value" ""
			(at 0 0 0)
			(layer "F.Fab")
			(effects
				(font
					(size 1.27 1.27)
				)
			)
		)
		(duplicate_pad_numbers_are_jumpers no)
		(fp_line
			(start -0.7874 -0.4064)
			(end 0.7874 -0.4064)
			(stroke
				(width 0.1524)
				(type default)
			)
			(layer "F.SilkS")
		)
		(fp_line
			(start -0.7874 0.4064)
			(end -0.7874 -0.4064)
			(stroke
				(width 0.1524)
				(type default)
			)
			(layer "F.SilkS")
		)
		(fp_line
			(start 0.7874 -0.4064)
			(end 0.7874 0.4064)
			(stroke
				(width 0.1524)
				(type default)
			)
			(layer "F.SilkS")
		)
		(fp_line
			(start 0.7874 0.4064)
			(end -0.7874 0.4064)
			(stroke
				(width 0.1524)
				(type default)
			)
			(layer "F.SilkS")
		)
		(fp_line
			(start -0.67945 -0.305054)
			(end -0.12065 -0.305054)
			(stroke
				(width 0.1)
				(type default)
			)
			(layer "F.Fab")
		)
		(fp_line
			(start -0.67945 0.3048)
			(end -0.67945 -0.305054)
			(stroke
				(width 0.1)
				(type default)
			)
			(layer "F.Fab")
		)
		(fp_line
			(start -0.12065 -0.305054)
			(end -0.12065 -0.2794)
			(stroke
				(width 0.1)
				(type default)
			)
			(layer "F.Fab")
		)
		(fp_line
			(start -0.12065 -0.2794)
			(end 0.12065 -0.2794)
			(stroke
				(width 0.1)
				(type default)
			)
			(layer "F.Fab")
		)
		(fp_line
			(start -0.12065 0.2794)
			(end -0.12065 0.3048)
			(stroke
				(width 0.1)
				(type default)
			)
			(layer "F.Fab")
		)
		(fp_line
			(start -0.12065 0.3048)
			(end -0.67945 0.3048)
			(stroke
				(width 0.1)
				(type default)
			)
			(layer "F.Fab")
		)
		(fp_line
			(start 0.120396 0.2794)
			(end -0.12065 0.2794)
			(stroke
				(width 0.1)
				(type default)
			)
			(layer "F.Fab")
		)
		(fp_line
			(start 0.120396 0.3048)
			(end 0.120396 0.2794)
			(stroke
				(width 0.1)
				(type default)
			)
			(layer "F.Fab")
		)
		(fp_line
			(start 0.12065 -0.3048)
			(end 0.67945 -0.3048)
			(stroke
				(width 0.1)
				(type default)
			)
			(layer "F.Fab")
		)
		(fp_line
			(start 0.12065 -0.2794)
			(end 0.12065 -0.3048)
			(stroke
				(width 0.1)
				(type default)
			)
			(layer "F.Fab")
		)
		(fp_line
			(start 0.67945 -0.3048)
			(end 0.67945 0.3048)
			(stroke
				(width 0.1)
				(type default)
			)
			(layer "F.Fab")
		)
		(fp_line
			(start 0.67945 0.3048)
			(end 0.120396 0.3048)
			(stroke
				(width 0.1)
				(type default)
			)
			(layer "F.Fab")
		)
		(pad "1" smd circle
			(at -0.40005 0)
			(size 0 0)
			(layers "F.Cu" "F.Mask" "F.Paste")
			(net "BMC_RSTIND_N")
		)
		(pad "2" smd circle
			(at 0.40005 0)
			(size 0 0)
			(layers "F.Cu" "F.Mask" "F.Paste")
			(net "RD_N")
		)
	)
	(footprint ""
		(layer "F.Cu")
		(at 40.0558 -42.4434)
		(property "Reference" "R443"
			(at 0 0 0)
			(layer "F.SilkS")
			(hide yes)
			(effects
				(font
					(size 1.27 1.27)
				)
			)
		)
		(property "Value" ""
			(at 0 0 0)
			(layer "F.Fab")
			(effects
				(font
					(size 1.27 1.27)
				)
			)
		)
		(duplicate_pad_numbers_are_jumpers no)
		(fp_line
			(start -0.7874 -0.4064)
			(end 0.7874 -0.4064)
			(stroke
				(width 0.1524)
				(type default)
			)
			(layer "F.SilkS")
		)
		(fp_line
			(start -0.7874 0.4064)
			(end -0.7874 -0.4064)
			(stroke
				(width 0.1524)
				(type default)
			)
			(layer "F.SilkS")
		)
		(fp_line
			(start 0.7874 -0.4064)
			(end 0.7874 0.4064)
			(stroke
				(width 0.1524)
				(type default)
			)
			(layer "F.SilkS")
		)
		(fp_line
			(start 0.7874 0.4064)
			(end -0.7874 0.4064)
			(stroke
				(width 0.1524)
				(type default)
			)
			(layer "F.SilkS")
		)
		(fp_line
			(start -0.67945 -0.305054)
			(end -0.12065 -0.305054)
			(stroke
				(width 0.1)
				(type default)
			)
			(layer "F.Fab")
		)
		(fp_line
			(start -0.67945 0.3048)
			(end -0.67945 -0.305054)
			(stroke
				(width 0.1)
				(type default)
			)
			(layer "F.Fab")
		)
		(fp_line
			(start -0.12065 -0.305054)
			(end -0.12065 -0.2794)
			(stroke
				(width 0.1)
				(type default)
			)
			(layer "F.Fab")
		)
		(fp_line
			(start -0.12065 -0.2794)
			(end 0.12065 -0.2794)
			(stroke
				(width 0.1)
				(type default)
			)
			(layer "F.Fab")
		)
		(fp_line
			(start -0.12065 0.2794)
			(end -0.12065 0.3048)
			(stroke
				(width 0.1)
				(type default)
			)
			(layer "F.Fab")
		)
		(fp_line
			(start -0.12065 0.3048)
			(end -0.67945 0.3048)
			(stroke
				(width 0.1)
				(type default)
			)
			(layer "F.Fab")
		)
		(fp_line
			(start 0.120396 0.2794)
			(end -0.12065 0.2794)
			(stroke
				(width 0.1)
				(type default)
			)
			(layer "F.Fab")
		)
		(fp_line
			(start 0.120396 0.3048)
			(end 0.120396 0.2794)
			(stroke
				(width 0.1)
				(type default)
			)
			(layer "F.Fab")
		)
		(fp_line
			(start 0.12065 -0.3048)
			(end 0.67945 -0.3048)
			(stroke
				(width 0.1)
				(type default)
			)
			(layer "F.Fab")
		)
		(fp_line
			(start 0.12065 -0.2794)
			(end 0.12065 -0.3048)
			(stroke
				(width 0.1)
				(type default)
			)
			(layer "F.Fab")
		)
		(fp_line
			(start 0.67945 -0.3048)
			(end 0.67945 0.3048)
			(stroke
				(width 0.1)
				(type default)
			)
			(layer "F.Fab")
		)
		(fp_line
			(start 0.67945 0.3048)
			(end 0.120396 0.3048)
			(stroke
				(width 0.1)
				(type default)
			)
			(layer "F.Fab")
		)
		(pad "1" smd circle
			(at -0.40005 0)
			(size 0 0)
			(layers "F.Cu" "F.Mask" "F.Paste")
			(net "SMB_BMC_ALERT4_N")
		)
		(pad "2" smd circle
			(at 0.40005 0)
			(size 0 0)
			(layers "F.Cu" "F.Mask" "F.Paste")
			(net "SMB_BMC_ALERT4_R_N")
		)
	)
	(footprint ""
		(layer "F.Cu")
		(at 37.865304 -47.587916)
		(property "Reference" "R145"
			(at 0 0 0)
			(layer "F.SilkS")
			(hide yes)
			(effects
				(font
					(size 1.27 1.27)
				)
			)
		)
		(property "Value" ""
			(at 0 0 0)
			(layer "F.Fab")
			(effects
				(font
					(size 1.27 1.27)
				)
			)
		)
		(duplicate_pad_numbers_are_jumpers no)
		(fp_line
			(start -0.7874 -0.4064)
			(end 0.7874 -0.4064)
			(stroke
				(width 0.1524)
				(type default)
			)
			(layer "F.SilkS")
		)
		(fp_line
			(start -0.7874 0.4064)
			(end -0.7874 -0.4064)
			(stroke
				(width 0.1524)
				(type default)
			)
			(layer "F.SilkS")
		)
		(fp_line
			(start 0.7874 -0.4064)
			(end 0.7874 0.4064)
			(stroke
				(width 0.1524)
				(type default)
			)
			(layer "F.SilkS")
		)
		(fp_line
			(start 0.7874 0.4064)
			(end -0.7874 0.4064)
			(stroke
				(width 0.1524)
				(type default)
			)
			(layer "F.SilkS")
		)
		(fp_line
			(start -0.67945 -0.305054)
			(end -0.12065 -0.305054)
			(stroke
				(width 0.1)
				(type default)
			)
			(layer "F.Fab")
		)
		(fp_line
			(start -0.67945 0.3048)
			(end -0.67945 -0.305054)
			(stroke
				(width 0.1)
				(type default)
			)
			(layer "F.Fab")
		)
		(fp_line
			(start -0.12065 -0.305054)
			(end -0.12065 -0.2794)
			(stroke
				(width 0.1)
				(type default)
			)
			(layer "F.Fab")
		)
		(fp_line
			(start -0.12065 -0.2794)
			(end 0.12065 -0.2794)
			(stroke
				(width 0.1)
				(type default)
			)
			(layer "F.Fab")
		)
		(fp_line
			(start -0.12065 0.2794)
			(end -0.12065 0.3048)
			(stroke
				(width 0.1)
				(type default)
			)
			(layer "F.Fab")
		)
		(fp_line
			(start -0.12065 0.3048)
			(end -0.67945 0.3048)
			(stroke
				(width 0.1)
				(type default)
			)
			(layer "F.Fab")
		)
		(fp_line
			(start 0.120396 0.2794)
			(end -0.12065 0.2794)
			(stroke
				(width 0.1)
				(type default)
			)
			(layer "F.Fab")
		)
		(fp_line
			(start 0.120396 0.3048)
			(end 0.120396 0.2794)
			(stroke
				(width 0.1)
				(type default)
			)
			(layer "F.Fab")
		)
		(fp_line
			(start 0.12065 -0.3048)
			(end 0.67945 -0.3048)
			(stroke
				(width 0.1)
				(type default)
			)
			(layer "F.Fab")
		)
		(fp_line
			(start 0.12065 -0.2794)
			(end 0.12065 -0.3048)
			(stroke
				(width 0.1)
				(type default)
			)
			(layer "F.Fab")
		)
		(fp_line
			(start 0.67945 -0.3048)
			(end 0.67945 0.3048)
			(stroke
				(width 0.1)
				(type default)
			)
			(layer "F.Fab")
		)
		(fp_line
			(start 0.67945 0.3048)
			(end 0.120396 0.3048)
			(stroke
				(width 0.1)
				(type default)
			)
			(layer "F.Fab")
		)
		(pad "1" smd circle
			(at -0.40005 0)
			(size 0 0)
			(layers "F.Cu" "F.Mask" "F.Paste")
			(net "P3V3_AUX")
		)
		(pad "2" smd circle
			(at 0.40005 0)
			(size 0 0)
			(layers "F.Cu" "F.Mask" "F.Paste")
			(net "SMB_BMC_MM12_SCL")
		)
	)
	(footprint ""
		(layer "F.Cu")
		(at 95.904304 42.085514 90)
		(property "Reference" "J16"
			(at -1.094486 2.801366 90)
			(unlocked yes)
			(layer "F.SilkS")
			(effects
				(font
					(size 0.7874 0.5842)
					(thickness 0.1524)
				)
				(justify left)
			)
		)
		(property "Value" ""
			(at 0 0 90)
			(layer "F.Fab")
			(effects
				(font
					(size 1.27 1.27)
				)
			)
		)
		(duplicate_pad_numbers_are_jumpers no)
		(fp_line
			(start 1.2192 -2.1082)
			(end 1.2192 -0.801878)
			(stroke
				(width 0.1524)
				(type default)
			)
			(layer "F.SilkS")
		)
		(fp_line
			(start -1.2192 -2.1082)
			(end 1.2192 -2.1082)
			(stroke
				(width 0.1524)
				(type default)
			)
			(layer "F.SilkS")
		)
		(fp_line
			(start 1.2192 0.810768)
			(end 1.2192 2.1082)
			(stroke
				(width 0.1524)
				(type default)
			)
			(layer "F.SilkS")
		)
		(fp_line
			(start 1.2192 2.1082)
			(end -1.2192 2.1082)
			(stroke
				(width 0.1524)
				(type default)
			)
			(layer "F.SilkS")
		)
		(fp_line
			(start -1.2192 2.1082)
			(end -1.2192 -2.1082)
			(stroke
				(width 0.1524)
				(type default)
			)
			(layer "F.SilkS")
		)
		(pad "" np_thru_hole circle
			(at -2.8829 -1.27)
			(size 1.0414 1.0414)
			(drill 1.0414)
			(layers "*.Cu" "*.Mask")
			(clearance 0.381)
			(thermal_gap 0.381)
		)
		(pad "" np_thru_hole circle
			(at -2.8829 1.27)
			(size 1.0414 1.0414)
			(drill 1.0414)
			(layers "*.Cu" "*.Mask")
			(clearance 0.381)
			(thermal_gap 0.381)
		)
		(pad "" np_thru_hole circle
			(at 3.4671 -1.27)
			(size 1.0414 1.0414)
			(drill 1.0414)
			(layers "*.Cu" "*.Mask")
			(clearance 0.381)
			(thermal_gap 0.381)
		)
		(pad "" np_thru_hole circle
			(at 3.4671 1.27)
			(size 1.0414 1.0414)
			(drill 1.0414)
			(layers "*.Cu" "*.Mask")
			(clearance 0.381)
			(thermal_gap 0.381)
		)
		(pad "1" smd rect
			(at 0.8255 -0.249936)
			(size 0.3048 0.508)
			(layers "F.Cu" "F.Mask" "F.Paste")
			(net "85_5INCH_IN4_DN")
		)
		(pad "2" smd rect
			(at 0.8255 0.249936)
			(size 0.3048 0.508)
			(layers "F.Cu" "F.Mask" "F.Paste")
			(net "85_5INCH_IN4_DP")
		)
		(pad "3" smd circle
			(at 0 0 90)
			(size 0 0)
			(layers "F.Cu" "F.Mask" "F.Paste")
			(net "GND_P1")
		)
		(zone
			(layer "F.Cu")
			(hatch none 0.5)
			(connect_pads
				(clearance 0)
			)
			(min_thickness 0.25)
			(keepout
				(tracks not_allowed)
				(vias allowed)
				(pads allowed)
				(copperpour not_allowed)
				(footprints allowed)
			)
			(placement
				(enabled no)
				(sheetname "")
			)
			(fill
				(thermal_gap 0.5)
				(thermal_bridge_width 0.5)
				(island_removal_mode 0)
			)
			(polygon
				(pts
					(xy 95.355664 40.967914) (xy 95.451168 40.967914) (xy 95.451168 41.564814) (xy 95.857568 41.564814)
					(xy 95.857568 40.967914) (xy 95.95104 40.967914) (xy 95.95104 41.564814) (xy 96.35744 41.564814)
					(xy 96.35744 40.967914) (xy 96.452944 40.967914) (xy 96.452944 41.666414) (xy 95.355664 41.666414)
				)
			)
		)
		(zone
			(layers "F.Cu" "B.Cu" "In1.Cu" "In2.Cu" "In3.Cu" "In4.Cu" "In5.Cu" "In6.Cu"
				"In7.Cu" "In8.Cu" "In9.Cu" "In10.Cu"
			)
			(hatch none 0.5)
			(connect_pads
				(clearance 0)
			)
			(min_thickness 0.25)
			(keepout
				(tracks not_allowed)
				(vias allowed)
				(pads allowed)
				(copperpour not_allowed)
				(footprints allowed)
			)
			(placement
				(enabled no)
				(sheetname "")
			)
			(fill
				(thermal_gap 0.5)
				(thermal_bridge_width 0.5)
				(island_removal_mode 0)
			)
			(polygon
				(pts
					(arc
						(start 95.561404 38.618414)
						(mid 93.707204 38.618414)
						(end 95.561404 38.618414)
					)
				)
			)
		)
		(zone
			(layers "F.Cu" "B.Cu" "In1.Cu" "In2.Cu" "In3.Cu" "In4.Cu" "In5.Cu" "In6.Cu"
				"In7.Cu" "In8.Cu" "In9.Cu" "In10.Cu"
			)
			(hatch none 0.5)
			(connect_pads
				(clearance 0)
			)
			(min_thickness 0.25)
			(keepout
				(tracks not_allowed)
				(vias allowed)
				(pads allowed)
				(copperpour not_allowed)
				(footprints allowed)
			)
			(placement
				(enabled no)
				(sheetname "")
			)
			(fill
				(thermal_gap 0.5)
				(thermal_bridge_width 0.5)
				(island_removal_mode 0)
			)
			(polygon
				(pts
					(arc
						(start 95.561404 44.968414)
						(mid 93.707204 44.968414)
						(end 95.561404 44.968414)
					)
				)
			)
		)
		(zone
			(layers "F.Cu" "B.Cu" "In1.Cu" "In2.Cu" "In3.Cu" "In4.Cu" "In5.Cu" "In6.Cu"
				"In7.Cu" "In8.Cu" "In9.Cu" "In10.Cu"
			)
			(hatch none 0.5)
			(connect_pads
				(clearance 0)
			)
			(min_thickness 0.25)
			(keepout
				(tracks not_allowed)
				(vias allowed)
				(pads allowed)
				(copperpour not_allowed)
				(footprints allowed)
			)
			(placement
				(enabled no)
				(sheetname "")
			)
			(fill
				(thermal_gap 0.5)
				(thermal_bridge_width 0.5)
				(island_removal_mode 0)
			)
			(polygon
				(pts
					(arc
						(start 98.101404 38.618414)
						(mid 96.247204 38.618414)
						(end 98.101404 38.618414)
					)
				)
			)
		)
		(zone
			(layers "F.Cu" "B.Cu" "In1.Cu" "In2.Cu" "In3.Cu" "In4.Cu" "In5.Cu" "In6.Cu"
				"In7.Cu" "In8.Cu" "In9.Cu" "In10.Cu"
			)
			(hatch none 0.5)
			(connect_pads
				(clearance 0)
			)
			(min_thickness 0.25)
			(keepout
				(tracks not_allowed)
				(vias allowed)
				(pads allowed)
				(copperpour not_allowed)
				(footprints allowed)
			)
			(placement
				(enabled no)
				(sheetname "")
			)
			(fill
				(thermal_gap 0.5)
				(thermal_bridge_width 0.5)
				(island_removal_mode 0)
			)
			(polygon
				(pts
					(arc
						(start 98.101404 44.968414)
						(mid 96.247204 44.968414)
						(end 98.101404 44.968414)
					)
				)
			)
		)
	)
	(footprint ""
		(layer "F.Cu")
		(at 13.335 -109.347 90)
		(property "Reference" "C271"
			(at 0 0 90)
			(layer "F.SilkS")
			(hide yes)
			(effects
				(font
					(size 1.27 1.27)
				)
			)
		)
		(property "Value" ""
			(at 0 0 90)
			(layer "F.Fab")
			(effects
				(font
					(size 1.27 1.27)
				)
			)
		)
		(duplicate_pad_numbers_are_jumpers no)
		(fp_line
			(start 0.7874 -0.4064)
			(end 0.7874 -0.1016)
			(stroke
				(width 0.1524)
				(type default)
			)
			(layer "F.SilkS")
		)
		(fp_line
			(start -0.7874 -0.4064)
			(end 0.7874 -0.4064)
			(stroke
				(width 0.1524)
				(type default)
			)
			(layer "F.SilkS")
		)
		(fp_line
			(start -0.7874 -0.0254)
			(end -0.7874 -0.4064)
			(stroke
				(width 0.1524)
				(type default)
			)
			(layer "F.SilkS")
		)
		(fp_line
			(start 0.4064 0.4064)
			(end -0.4318 0.4064)
			(stroke
				(width 0.1524)
				(type default)
			)
			(layer "F.SilkS")
		)
		(fp_line
			(start -0.12065 -0.305054)
			(end -0.12065 -0.2794)
			(stroke
				(width 0.1)
				(type default)
			)
			(layer "F.Fab")
		)
		(fp_line
			(start -0.67945 -0.305054)
			(end -0.12065 -0.305054)
			(stroke
				(width 0.1)
				(type default)
			)
			(layer "F.Fab")
		)
		(fp_line
			(start 0.67945 -0.3048)
			(end 0.67945 0.3048)
			(stroke
				(width 0.1)
				(type default)
			)
			(layer "F.Fab")
		)
		(fp_line
			(start 0.12065 -0.3048)
			(end 0.67945 -0.3048)
			(stroke
				(width 0.1)
				(type default)
			)
			(layer "F.Fab")
		)
		(fp_line
			(start 0.12065 -0.2794)
			(end 0.12065 -0.3048)
			(stroke
				(width 0.1)
				(type default)
			)
			(layer "F.Fab")
		)
		(fp_line
			(start -0.12065 -0.2794)
			(end 0.12065 -0.2794)
			(stroke
				(width 0.1)
				(type default)
			)
			(layer "F.Fab")
		)
		(fp_line
			(start 0.120396 0.2794)
			(end -0.12065 0.2794)
			(stroke
				(width 0.1)
				(type default)
			)
			(layer "F.Fab")
		)
		(fp_line
			(start -0.12065 0.2794)
			(end -0.12065 0.3048)
			(stroke
				(width 0.1)
				(type default)
			)
			(layer "F.Fab")
		)
		(fp_line
			(start 0.67945 0.3048)
			(end 0.120396 0.3048)
			(stroke
				(width 0.1)
				(type default)
			)
			(layer "F.Fab")
		)
		(fp_line
			(start 0.120396 0.3048)
			(end 0.120396 0.2794)
			(stroke
				(width 0.1)
				(type default)
			)
			(layer "F.Fab")
		)
		(fp_line
			(start -0.12065 0.3048)
			(end -0.67945 0.3048)
			(stroke
				(width 0.1)
				(type default)
			)
			(layer "F.Fab")
		)
		(fp_line
			(start -0.67945 0.3048)
			(end -0.67945 -0.305054)
			(stroke
				(width 0.1)
				(type default)
			)
			(layer "F.Fab")
		)
		(pad "1" smd circle
			(at -0.40005 0 90)
			(size 0 0)
			(layers "F.Cu" "F.Mask" "F.Paste")
			(net "P2E_GPU_TX_DN")
		)
		(pad "2" smd circle
			(at 0.40005 0 90)
			(size 0 0)
			(layers "F.Cu" "F.Mask" "F.Paste")
			(net "P2E_GPU_TX_C_DN")
		)
	)
	(footprint ""
		(layer "F.Cu")
		(at 16.0782 -65.8622 90)
		(property "Reference" "C501"
			(at 0 0 90)
			(layer "F.SilkS")
			(hide yes)
			(effects
				(font
					(size 1.27 1.27)
				)
			)
		)
		(property "Value" ""
			(at 0 0 90)
			(layer "F.Fab")
			(effects
				(font
					(size 1.27 1.27)
				)
			)
		)
		(duplicate_pad_numbers_are_jumpers no)
		(fp_line
			(start 0.7874 -0.4064)
			(end 0.7874 0.4064)
			(stroke
				(width 0.1524)
				(type default)
			)
			(layer "F.SilkS")
		)
		(fp_line
			(start -0.7874 -0.4064)
			(end 0.7874 -0.4064)
			(stroke
				(width 0.1524)
				(type default)
			)
			(layer "F.SilkS")
		)
		(fp_line
			(start 0.7874 0.4064)
			(end -0.7874 0.4064)
			(stroke
				(width 0.1524)
				(type default)
			)
			(layer "F.SilkS")
		)
		(fp_line
			(start -0.7874 0.4064)
			(end -0.7874 -0.4064)
			(stroke
				(width 0.1524)
				(type default)
			)
			(layer "F.SilkS")
		)
		(fp_line
			(start -0.12065 -0.305054)
			(end -0.12065 -0.2794)
			(stroke
				(width 0.1)
				(type default)
			)
			(layer "F.Fab")
		)
		(fp_line
			(start -0.67945 -0.305054)
			(end -0.12065 -0.305054)
			(stroke
				(width 0.1)
				(type default)
			)
			(layer "F.Fab")
		)
		(fp_line
			(start 0.67945 -0.3048)
			(end 0.67945 0.3048)
			(stroke
				(width 0.1)
				(type default)
			)
			(layer "F.Fab")
		)
		(fp_line
			(start 0.12065 -0.3048)
			(end 0.67945 -0.3048)
			(stroke
				(width 0.1)
				(type default)
			)
			(layer "F.Fab")
		)
		(fp_line
			(start 0.12065 -0.2794)
			(end 0.12065 -0.3048)
			(stroke
				(width 0.1)
				(type default)
			)
			(layer "F.Fab")
		)
		(fp_line
			(start -0.12065 -0.2794)
			(end 0.12065 -0.2794)
			(stroke
				(width 0.1)
				(type default)
			)
			(layer "F.Fab")
		)
		(fp_line
			(start 0.120396 0.2794)
			(end -0.12065 0.2794)
			(stroke
				(width 0.1)
				(type default)
			)
			(layer "F.Fab")
		)
		(fp_line
			(start -0.12065 0.2794)
			(end -0.12065 0.3048)
			(stroke
				(width 0.1)
				(type default)
			)
			(layer "F.Fab")
		)
		(fp_line
			(start 0.67945 0.3048)
			(end 0.120396 0.3048)
			(stroke
				(width 0.1)
				(type default)
			)
			(layer "F.Fab")
		)
		(fp_line
			(start 0.120396 0.3048)
			(end 0.120396 0.2794)
			(stroke
				(width 0.1)
				(type default)
			)
			(layer "F.Fab")
		)
		(fp_line
			(start -0.12065 0.3048)
			(end -0.67945 0.3048)
			(stroke
				(width 0.1)
				(type default)
			)
			(layer "F.Fab")
		)
		(fp_line
			(start -0.67945 0.3048)
			(end -0.67945 -0.305054)
			(stroke
				(width 0.1)
				(type default)
			)
			(layer "F.Fab")
		)
		(pad "1" smd circle
			(at -0.40005 0 90)
			(size 0 0)
			(layers "F.Cu" "F.Mask" "F.Paste")
			(net "P3V3_AUX")
		)
		(pad "2" smd circle
			(at 0.40005 0 90)
			(size 0 0)
			(layers "F.Cu" "F.Mask" "F.Paste")
			(net "GND")
		)
	)
	(footprint ""
		(layer "F.Cu")
		(at 68.189094 -92.61094)
		(property "Reference" "R503"
			(at 0 0 0)
			(layer "F.SilkS")
			(hide yes)
			(effects
				(font
					(size 1.27 1.27)
				)
			)
		)
		(property "Value" ""
			(at 0 0 0)
			(layer "F.Fab")
			(effects
				(font
					(size 1.27 1.27)
				)
			)
		)
		(duplicate_pad_numbers_are_jumpers no)
		(fp_line
			(start -0.7874 -0.4064)
			(end 0.7874 -0.4064)
			(stroke
				(width 0.1524)
				(type default)
			)
			(layer "F.SilkS")
		)
		(fp_line
			(start -0.7874 0.4064)
			(end -0.7874 -0.4064)
			(stroke
				(width 0.1524)
				(type default)
			)
			(layer "F.SilkS")
		)
		(fp_line
			(start 0.7874 -0.4064)
			(end 0.7874 0.4064)
			(stroke
				(width 0.1524)
				(type default)
			)
			(layer "F.SilkS")
		)
		(fp_line
			(start 0.7874 0.4064)
			(end -0.7874 0.4064)
			(stroke
				(width 0.1524)
				(type default)
			)
			(layer "F.SilkS")
		)
		(fp_line
			(start -0.67945 -0.305054)
			(end -0.12065 -0.305054)
			(stroke
				(width 0.1)
				(type default)
			)
			(layer "F.Fab")
		)
		(fp_line
			(start -0.67945 0.3048)
			(end -0.67945 -0.305054)
			(stroke
				(width 0.1)
				(type default)
			)
			(layer "F.Fab")
		)
		(fp_line
			(start -0.12065 -0.305054)
			(end -0.12065 -0.2794)
			(stroke
				(width 0.1)
				(type default)
			)
			(layer "F.Fab")
		)
		(fp_line
			(start -0.12065 -0.2794)
			(end 0.12065 -0.2794)
			(stroke
				(width 0.1)
				(type default)
			)
			(layer "F.Fab")
		)
		(fp_line
			(start -0.12065 0.2794)
			(end -0.12065 0.3048)
			(stroke
				(width 0.1)
				(type default)
			)
			(layer "F.Fab")
		)
		(fp_line
			(start -0.12065 0.3048)
			(end -0.67945 0.3048)
			(stroke
				(width 0.1)
				(type default)
			)
			(layer "F.Fab")
		)
		(fp_line
			(start 0.120396 0.2794)
			(end -0.12065 0.2794)
			(stroke
				(width 0.1)
				(type default)
			)
			(layer "F.Fab")
		)
		(fp_line
			(start 0.120396 0.3048)
			(end 0.120396 0.2794)
			(stroke
				(width 0.1)
				(type default)
			)
			(layer "F.Fab")
		)
		(fp_line
			(start 0.12065 -0.3048)
			(end 0.67945 -0.3048)
			(stroke
				(width 0.1)
				(type default)
			)
			(layer "F.Fab")
		)
		(fp_line
			(start 0.12065 -0.2794)
			(end 0.12065 -0.3048)
			(stroke
				(width 0.1)
				(type default)
			)
			(layer "F.Fab")
		)
		(fp_line
			(start 0.67945 -0.3048)
			(end 0.67945 0.3048)
			(stroke
				(width 0.1)
				(type default)
			)
			(layer "F.Fab")
		)
		(fp_line
			(start 0.67945 0.3048)
			(end 0.120396 0.3048)
			(stroke
				(width 0.1)
				(type default)
			)
			(layer "F.Fab")
		)
		(pad "1" smd circle
			(at -0.40005 0)
			(size 0 0)
			(layers "F.Cu" "F.Mask" "F.Paste")
			(net "RST_PLTRST_TPM_N")
		)
		(pad "2" smd circle
			(at 0.40005 0)
			(size 0 0)
			(layers "F.Cu" "F.Mask" "F.Paste")
			(net "RST_PLTRST_N")
		)
	)
	(footprint ""
		(layer "F.Cu")
		(at 36.1442 -70.4088 -90)
		(property "Reference" "C228"
			(at 0 0 270)
			(layer "F.SilkS")
			(hide yes)
			(effects
				(font
					(size 1.27 1.27)
				)
			)
		)
		(property "Value" ""
			(at 0 0 270)
			(layer "F.Fab")
			(effects
				(font
					(size 1.27 1.27)
				)
			)
		)
		(duplicate_pad_numbers_are_jumpers no)
		(fp_line
			(start -0.7874 0.4064)
			(end -0.7874 -0.4064)
			(stroke
				(width 0.1524)
				(type default)
			)
			(layer "F.SilkS")
		)
		(fp_line
			(start 0.7874 0.4064)
			(end -0.7874 0.4064)
			(stroke
				(width 0.1524)
				(type default)
			)
			(layer "F.SilkS")
		)
		(fp_line
			(start -0.7874 -0.4064)
			(end 0.7874 -0.4064)
			(stroke
				(width 0.1524)
				(type default)
			)
			(layer "F.SilkS")
		)
		(fp_line
			(start 0.7874 -0.4064)
			(end 0.7874 0.4064)
			(stroke
				(width 0.1524)
				(type default)
			)
			(layer "F.SilkS")
		)
		(fp_line
			(start -0.67945 0.3048)
			(end -0.67945 -0.305054)
			(stroke
				(width 0.1)
				(type default)
			)
			(layer "F.Fab")
		)
		(fp_line
			(start -0.12065 0.3048)
			(end -0.67945 0.3048)
			(stroke
				(width 0.1)
				(type default)
			)
			(layer "F.Fab")
		)
		(fp_line
			(start 0.120396 0.3048)
			(end 0.120396 0.2794)
			(stroke
				(width 0.1)
				(type default)
			)
			(layer "F.Fab")
		)
		(fp_line
			(start 0.67945 0.3048)
			(end 0.120396 0.3048)
			(stroke
				(width 0.1)
				(type default)
			)
			(layer "F.Fab")
		)
		(fp_line
			(start -0.12065 0.2794)
			(end -0.12065 0.3048)
			(stroke
				(width 0.1)
				(type default)
			)
			(layer "F.Fab")
		)
		(fp_line
			(start 0.120396 0.2794)
			(end -0.12065 0.2794)
			(stroke
				(width 0.1)
				(type default)
			)
			(layer "F.Fab")
		)
		(fp_line
			(start -0.12065 -0.2794)
			(end 0.12065 -0.2794)
			(stroke
				(width 0.1)
				(type default)
			)
			(layer "F.Fab")
		)
		(fp_line
			(start 0.12065 -0.2794)
			(end 0.12065 -0.3048)
			(stroke
				(width 0.1)
				(type default)
			)
			(layer "F.Fab")
		)
		(fp_line
			(start 0.12065 -0.3048)
			(end 0.67945 -0.3048)
			(stroke
				(width 0.1)
				(type default)
			)
			(layer "F.Fab")
		)
		(fp_line
			(start 0.67945 -0.3048)
			(end 0.67945 0.3048)
			(stroke
				(width 0.1)
				(type default)
			)
			(layer "F.Fab")
		)
		(fp_line
			(start -0.67945 -0.305054)
			(end -0.12065 -0.305054)
			(stroke
				(width 0.1)
				(type default)
			)
			(layer "F.Fab")
		)
		(fp_line
			(start -0.12065 -0.305054)
			(end -0.12065 -0.2794)
			(stroke
				(width 0.1)
				(type default)
			)
			(layer "F.Fab")
		)
		(pad "1" smd circle
			(at -0.40005 0 270)
			(size 0 0)
			(layers "F.Cu" "F.Mask" "F.Paste")
			(net "P3V3_AUX")
		)
		(pad "2" smd circle
			(at 0.40005 0 270)
			(size 0 0)
			(layers "F.Cu" "F.Mask" "F.Paste")
			(net "GND")
		)
	)
	(footprint ""
		(layer "F.Cu")
		(at 47.879 -67.818 180)
		(property "Reference" "R319"
			(at 0 0 180)
			(layer "F.SilkS")
			(hide yes)
			(effects
				(font
					(size 1.27 1.27)
				)
			)
		)
		(property "Value" ""
			(at 0 0 180)
			(layer "F.Fab")
			(effects
				(font
					(size 1.27 1.27)
				)
			)
		)
		(duplicate_pad_numbers_are_jumpers no)
		(fp_line
			(start 0.7874 0.4064)
			(end -0.7874 0.4064)
			(stroke
				(width 0.1524)
				(type default)
			)
			(layer "F.SilkS")
		)
		(fp_line
			(start 0.7874 -0.4064)
			(end 0.7874 0.4064)
			(stroke
				(width 0.1524)
				(type default)
			)
			(layer "F.SilkS")
		)
		(fp_line
			(start -0.7874 0.4064)
			(end -0.7874 -0.4064)
			(stroke
				(width 0.1524)
				(type default)
			)
			(layer "F.SilkS")
		)
		(fp_line
			(start -0.7874 -0.4064)
			(end 0.7874 -0.4064)
			(stroke
				(width 0.1524)
				(type default)
			)
			(layer "F.SilkS")
		)
		(fp_line
			(start 0.67945 0.3048)
			(end 0.120396 0.3048)
			(stroke
				(width 0.1)
				(type default)
			)
			(layer "F.Fab")
		)
		(fp_line
			(start 0.67945 -0.3048)
			(end 0.67945 0.3048)
			(stroke
				(width 0.1)
				(type default)
			)
			(layer "F.Fab")
		)
		(fp_line
			(start 0.12065 -0.2794)
			(end 0.12065 -0.3048)
			(stroke
				(width 0.1)
				(type default)
			)
			(layer "F.Fab")
		)
		(fp_line
			(start 0.12065 -0.3048)
			(end 0.67945 -0.3048)
			(stroke
				(width 0.1)
				(type default)
			)
			(layer "F.Fab")
		)
		(fp_line
			(start 0.120396 0.3048)
			(end 0.120396 0.2794)
			(stroke
				(width 0.1)
				(type default)
			)
			(layer "F.Fab")
		)
		(fp_line
			(start 0.120396 0.2794)
			(end -0.12065 0.2794)
			(stroke
				(width 0.1)
				(type default)
			)
			(layer "F.Fab")
		)
		(fp_line
			(start -0.12065 0.3048)
			(end -0.67945 0.3048)
			(stroke
				(width 0.1)
				(type default)
			)
			(layer "F.Fab")
		)
		(fp_line
			(start -0.12065 0.2794)
			(end -0.12065 0.3048)
			(stroke
				(width 0.1)
				(type default)
			)
			(layer "F.Fab")
		)
		(fp_line
			(start -0.12065 -0.2794)
			(end 0.12065 -0.2794)
			(stroke
				(width 0.1)
				(type default)
			)
			(layer "F.Fab")
		)
		(fp_line
			(start -0.12065 -0.305054)
			(end -0.12065 -0.2794)
			(stroke
				(width 0.1)
				(type default)
			)
			(layer "F.Fab")
		)
		(fp_line
			(start -0.67945 0.3048)
			(end -0.67945 -0.305054)
			(stroke
				(width 0.1)
				(type default)
			)
			(layer "F.Fab")
		)
		(fp_line
			(start -0.67945 -0.305054)
			(end -0.12065 -0.305054)
			(stroke
				(width 0.1)
				(type default)
			)
			(layer "F.Fab")
		)
		(pad "1" smd circle
			(at -0.40005 0 180)
			(size 0 0)
			(layers "F.Cu" "F.Mask" "F.Paste")
			(net "P3V3_AUX")
		)
		(pad "2" smd circle
			(at 0.40005 0 180)
			(size 0 0)
			(layers "F.Cu" "F.Mask" "F.Paste")
			(net "BMC_ID_BEEP_SEL")
		)
	)
	(footprint ""
		(layer "F.Cu")
		(at 26.416 -40.0304)
		(property "Reference" ""
			(at 0 0 0)
			(layer "F.SilkS")
			(hide yes)
			(effects
				(font
					(size 1.27 1.27)
				)
			)
		)
		(property "Value" ""
			(at 0 0 0)
			(layer "F.Fab")
			(effects
				(font
					(size 1.27 1.27)
				)
			)
		)
		(duplicate_pad_numbers_are_jumpers no)
		(pad "1" smd circle
			(at 0 0)
			(size 0.9906 0.9906)
			(layers "F.Cu" "F.Mask" "F.Paste")
			(net "Net_326")
		)
		(zone
			(layer "F.Cu")
			(hatch none 0.5)
			(connect_pads
				(clearance 0)
			)
			(min_thickness 0.25)
			(keepout
				(tracks not_allowed)
				(vias allowed)
				(pads allowed)
				(copperpour not_allowed)
				(footprints allowed)
			)
			(placement
				(enabled no)
				(sheetname "")
			)
			(fill
				(thermal_gap 0.5)
				(thermal_bridge_width 0.5)
				(island_removal_mode 0)
			)
			(polygon
				(pts
					(arc
						(start 28.0416 -40.0304)
						(mid 24.7904 -40.0304)
						(end 28.0416 -40.0304)
					)
				)
			)
		)
	)
	(footprint ""
		(layer "F.Cu")
		(at 76.691744 -37.559488 -90)
		(property "Reference" "R353"
			(at 0 0 270)
			(layer "F.SilkS")
			(hide yes)
			(effects
				(font
					(size 1.27 1.27)
				)
			)
		)
		(property "Value" ""
			(at 0 0 270)
			(layer "F.Fab")
			(effects
				(font
					(size 1.27 1.27)
				)
			)
		)
		(duplicate_pad_numbers_are_jumpers no)
		(fp_line
			(start -0.7874 0.4064)
			(end -0.7874 -0.4064)
			(stroke
				(width 0.1524)
				(type default)
			)
			(layer "F.SilkS")
		)
		(fp_line
			(start 0.7874 0.4064)
			(end -0.7874 0.4064)
			(stroke
				(width 0.1524)
				(type default)
			)
			(layer "F.SilkS")
		)
		(fp_line
			(start -0.7874 -0.4064)
			(end 0.7874 -0.4064)
			(stroke
				(width 0.1524)
				(type default)
			)
			(layer "F.SilkS")
		)
		(fp_line
			(start 0.7874 -0.4064)
			(end 0.7874 0.4064)
			(stroke
				(width 0.1524)
				(type default)
			)
			(layer "F.SilkS")
		)
		(fp_line
			(start -0.67945 0.3048)
			(end -0.67945 -0.305054)
			(stroke
				(width 0.1)
				(type default)
			)
			(layer "F.Fab")
		)
		(fp_line
			(start -0.12065 0.3048)
			(end -0.67945 0.3048)
			(stroke
				(width 0.1)
				(type default)
			)
			(layer "F.Fab")
		)
		(fp_line
			(start 0.120396 0.3048)
			(end 0.120396 0.2794)
			(stroke
				(width 0.1)
				(type default)
			)
			(layer "F.Fab")
		)
		(fp_line
			(start 0.67945 0.3048)
			(end 0.120396 0.3048)
			(stroke
				(width 0.1)
				(type default)
			)
			(layer "F.Fab")
		)
		(fp_line
			(start -0.12065 0.2794)
			(end -0.12065 0.3048)
			(stroke
				(width 0.1)
				(type default)
			)
			(layer "F.Fab")
		)
		(fp_line
			(start 0.120396 0.2794)
			(end -0.12065 0.2794)
			(stroke
				(width 0.1)
				(type default)
			)
			(layer "F.Fab")
		)
		(fp_line
			(start -0.12065 -0.2794)
			(end 0.12065 -0.2794)
			(stroke
				(width 0.1)
				(type default)
			)
			(layer "F.Fab")
		)
		(fp_line
			(start 0.12065 -0.2794)
			(end 0.12065 -0.3048)
			(stroke
				(width 0.1)
				(type default)
			)
			(layer "F.Fab")
		)
		(fp_line
			(start 0.12065 -0.3048)
			(end 0.67945 -0.3048)
			(stroke
				(width 0.1)
				(type default)
			)
			(layer "F.Fab")
		)
		(fp_line
			(start 0.67945 -0.3048)
			(end 0.67945 0.3048)
			(stroke
				(width 0.1)
				(type default)
			)
			(layer "F.Fab")
		)
		(fp_line
			(start -0.67945 -0.305054)
			(end -0.12065 -0.305054)
			(stroke
				(width 0.1)
				(type default)
			)
			(layer "F.Fab")
		)
		(fp_line
			(start -0.12065 -0.305054)
			(end -0.12065 -0.2794)
			(stroke
				(width 0.1)
				(type default)
			)
			(layer "F.Fab")
		)
		(pad "1" smd circle
			(at -0.40005 0 270)
			(size 0 0)
			(layers "F.Cu" "F.Mask" "F.Paste")
			(net "M_BMC_DDR4_MA<2>")
		)
		(pad "2" smd circle
			(at 0.40005 0 270)
			(size 0 0)
			(layers "F.Cu" "F.Mask" "F.Paste")
			(net "P1V2_AUX")
		)
	)
	(footprint ""
		(layer "F.Cu")
		(at 7.98322 -46.798738)
		(property "Reference" "PC210"
			(at 0 0 0)
			(layer "F.SilkS")
			(hide yes)
			(effects
				(font
					(size 1.27 1.27)
				)
			)
		)
		(property "Value" ""
			(at 0 0 0)
			(layer "F.Fab")
			(effects
				(font
					(size 1.27 1.27)
				)
			)
		)
		(duplicate_pad_numbers_are_jumpers no)
		(fp_line
			(start -0.7874 -0.4064)
			(end 0.7874 -0.4064)
			(stroke
				(width 0.1524)
				(type default)
			)
			(layer "F.SilkS")
		)
		(fp_line
			(start -0.7874 0.4064)
			(end -0.7874 -0.4064)
			(stroke
				(width 0.1524)
				(type default)
			)
			(layer "F.SilkS")
		)
		(fp_line
			(start 0.7874 -0.4064)
			(end 0.7874 0.4064)
			(stroke
				(width 0.1524)
				(type default)
			)
			(layer "F.SilkS")
		)
		(fp_line
			(start 0.7874 0.4064)
			(end -0.7874 0.4064)
			(stroke
				(width 0.1524)
				(type default)
			)
			(layer "F.SilkS")
		)
		(fp_line
			(start -0.67945 -0.305054)
			(end -0.12065 -0.305054)
			(stroke
				(width 0.1)
				(type default)
			)
			(layer "F.Fab")
		)
		(fp_line
			(start -0.67945 0.3048)
			(end -0.67945 -0.305054)
			(stroke
				(width 0.1)
				(type default)
			)
			(layer "F.Fab")
		)
		(fp_line
			(start -0.12065 -0.305054)
			(end -0.12065 -0.2794)
			(stroke
				(width 0.1)
				(type default)
			)
			(layer "F.Fab")
		)
		(fp_line
			(start -0.12065 -0.2794)
			(end 0.12065 -0.2794)
			(stroke
				(width 0.1)
				(type default)
			)
			(layer "F.Fab")
		)
		(fp_line
			(start -0.12065 0.2794)
			(end -0.12065 0.3048)
			(stroke
				(width 0.1)
				(type default)
			)
			(layer "F.Fab")
		)
		(fp_line
			(start -0.12065 0.3048)
			(end -0.67945 0.3048)
			(stroke
				(width 0.1)
				(type default)
			)
			(layer "F.Fab")
		)
		(fp_line
			(start 0.120396 0.2794)
			(end -0.12065 0.2794)
			(stroke
				(width 0.1)
				(type default)
			)
			(layer "F.Fab")
		)
		(fp_line
			(start 0.120396 0.3048)
			(end 0.120396 0.2794)
			(stroke
				(width 0.1)
				(type default)
			)
			(layer "F.Fab")
		)
		(fp_line
			(start 0.12065 -0.3048)
			(end 0.67945 -0.3048)
			(stroke
				(width 0.1)
				(type default)
			)
			(layer "F.Fab")
		)
		(fp_line
			(start 0.12065 -0.2794)
			(end 0.12065 -0.3048)
			(stroke
				(width 0.1)
				(type default)
			)
			(layer "F.Fab")
		)
		(fp_line
			(start 0.67945 -0.3048)
			(end 0.67945 0.3048)
			(stroke
				(width 0.1)
				(type default)
			)
			(layer "F.Fab")
		)
		(fp_line
			(start 0.67945 0.3048)
			(end 0.120396 0.3048)
			(stroke
				(width 0.1)
				(type default)
			)
			(layer "F.Fab")
		)
		(pad "1" smd circle
			(at -0.40005 0)
			(size 0 0)
			(layers "F.Cu" "F.Mask" "F.Paste")
			(net "SW_P5V_AUX_FLT")
		)
		(pad "2" smd circle
			(at 0.40005 0)
			(size 0 0)
			(layers "F.Cu" "F.Mask" "F.Paste")
			(net "GND")
		)
	)
	(footprint ""
		(layer "F.Cu")
		(at 4.581398 -78.196186 90)
		(property "Reference" "PC226"
			(at 0 0 90)
			(layer "F.SilkS")
			(hide yes)
			(effects
				(font
					(size 1.27 1.27)
				)
			)
		)
		(property "Value" ""
			(at 0 0 90)
			(layer "F.Fab")
			(effects
				(font
					(size 1.27 1.27)
				)
			)
		)
		(duplicate_pad_numbers_are_jumpers no)
		(fp_line
			(start 1.651 -0.8382)
			(end 1.651 0.8382)
			(stroke
				(width 0.1524)
				(type default)
			)
			(layer "F.SilkS")
		)
		(fp_line
			(start -1.651 -0.8382)
			(end 1.651 -0.8382)
			(stroke
				(width 0.1524)
				(type default)
			)
			(layer "F.SilkS")
		)
		(fp_line
			(start 1.651 0.8382)
			(end -1.651 0.8382)
			(stroke
				(width 0.1524)
				(type default)
			)
			(layer "F.SilkS")
		)
		(fp_line
			(start 0 0.8382)
			(end 0 -0.8382)
			(stroke
				(width 0.1524)
				(type default)
			)
			(layer "F.SilkS")
		)
		(fp_line
			(start -1.651 0.8382)
			(end -1.651 -0.8382)
			(stroke
				(width 0.1524)
				(type default)
			)
			(layer "F.SilkS")
		)
		(fp_line
			(start 1.55956 -0.7366)
			(end 1.524 -0.7366)
			(stroke
				(width 0.1)
				(type default)
			)
			(layer "F.Fab")
		)
		(fp_line
			(start 1.524 -0.7366)
			(end -1.524 -0.7366)
			(stroke
				(width 0.1)
				(type default)
			)
			(layer "F.Fab")
		)
		(fp_line
			(start -1.524 -0.7366)
			(end -1.55956 -0.7366)
			(stroke
				(width 0.1)
				(type default)
			)
			(layer "F.Fab")
		)
		(fp_line
			(start -1.55956 -0.7366)
			(end -1.55956 0.7366)
			(stroke
				(width 0.1)
				(type default)
			)
			(layer "F.Fab")
		)
		(fp_line
			(start 1.55956 0.7366)
			(end 1.55956 -0.7366)
			(stroke
				(width 0.1)
				(type default)
			)
			(layer "F.Fab")
		)
		(fp_line
			(start 1.524 0.7366)
			(end 1.55956 0.7366)
			(stroke
				(width 0.1)
				(type default)
			)
			(layer "F.Fab")
		)
		(fp_line
			(start -1.524 0.7366)
			(end 1.524 0.7366)
			(stroke
				(width 0.1)
				(type default)
			)
			(layer "F.Fab")
		)
		(fp_line
			(start -1.55956 0.7366)
			(end -1.524 0.7366)
			(stroke
				(width 0.1)
				(type default)
			)
			(layer "F.Fab")
		)
		(pad "1" smd rect
			(at -0.94996 0 270)
			(size 1.1176 1.3716)
			(layers "F.Cu" "F.Mask" "F.Paste")
			(net "P3V3_AUX")
		)
		(pad "2" smd rect
			(at 0.94996 0 270)
			(size 1.1176 1.3716)
			(layers "F.Cu" "F.Mask" "F.Paste")
			(net "GND")
		)
	)
	(footprint ""
		(layer "F.Cu")
		(at 10.033 -89.408)
		(property "Reference" "C223"
			(at 0 0 0)
			(layer "F.SilkS")
			(hide yes)
			(effects
				(font
					(size 1.27 1.27)
				)
			)
		)
		(property "Value" ""
			(at 0 0 0)
			(layer "F.Fab")
			(effects
				(font
					(size 1.27 1.27)
				)
			)
		)
		(duplicate_pad_numbers_are_jumpers no)
		(fp_line
			(start -0.7874 -0.4064)
			(end 0.7874 -0.4064)
			(stroke
				(width 0.1524)
				(type default)
			)
			(layer "F.SilkS")
		)
		(fp_line
			(start -0.7874 0.4064)
			(end -0.7874 -0.4064)
			(stroke
				(width 0.1524)
				(type default)
			)
			(layer "F.SilkS")
		)
		(fp_line
			(start 0.7874 -0.4064)
			(end 0.7874 0.4064)
			(stroke
				(width 0.1524)
				(type default)
			)
			(layer "F.SilkS")
		)
		(fp_line
			(start 0.7874 0.4064)
			(end -0.7874 0.4064)
			(stroke
				(width 0.1524)
				(type default)
			)
			(layer "F.SilkS")
		)
		(fp_line
			(start -0.67945 -0.305054)
			(end -0.12065 -0.305054)
			(stroke
				(width 0.1)
				(type default)
			)
			(layer "F.Fab")
		)
		(fp_line
			(start -0.67945 0.3048)
			(end -0.67945 -0.305054)
			(stroke
				(width 0.1)
				(type default)
			)
			(layer "F.Fab")
		)
		(fp_line
			(start -0.12065 -0.305054)
			(end -0.12065 -0.2794)
			(stroke
				(width 0.1)
				(type default)
			)
			(layer "F.Fab")
		)
		(fp_line
			(start -0.12065 -0.2794)
			(end 0.12065 -0.2794)
			(stroke
				(width 0.1)
				(type default)
			)
			(layer "F.Fab")
		)
		(fp_line
			(start -0.12065 0.2794)
			(end -0.12065 0.3048)
			(stroke
				(width 0.1)
				(type default)
			)
			(layer "F.Fab")
		)
		(fp_line
			(start -0.12065 0.3048)
			(end -0.67945 0.3048)
			(stroke
				(width 0.1)
				(type default)
			)
			(layer "F.Fab")
		)
		(fp_line
			(start 0.120396 0.2794)
			(end -0.12065 0.2794)
			(stroke
				(width 0.1)
				(type default)
			)
			(layer "F.Fab")
		)
		(fp_line
			(start 0.120396 0.3048)
			(end 0.120396 0.2794)
			(stroke
				(width 0.1)
				(type default)
			)
			(layer "F.Fab")
		)
		(fp_line
			(start 0.12065 -0.3048)
			(end 0.67945 -0.3048)
			(stroke
				(width 0.1)
				(type default)
			)
			(layer "F.Fab")
		)
		(fp_line
			(start 0.12065 -0.2794)
			(end 0.12065 -0.3048)
			(stroke
				(width 0.1)
				(type default)
			)
			(layer "F.Fab")
		)
		(fp_line
			(start 0.67945 -0.3048)
			(end 0.67945 0.3048)
			(stroke
				(width 0.1)
				(type default)
			)
			(layer "F.Fab")
		)
		(fp_line
			(start 0.67945 0.3048)
			(end 0.120396 0.3048)
			(stroke
				(width 0.1)
				(type default)
			)
			(layer "F.Fab")
		)
		(pad "1" smd circle
			(at -0.40005 0)
			(size 0 0)
			(layers "F.Cu" "F.Mask" "F.Paste")
			(net "RST_BMC_SRST_BUF_R_N")
		)
		(pad "2" smd circle
			(at 0.40005 0)
			(size 0 0)
			(layers "F.Cu" "F.Mask" "F.Paste")
			(net "GND")
		)
	)
	(footprint ""
		(layer "F.Cu")
		(at 29.1592 -65.8622 90)
		(property "Reference" "C268"
			(at 0 0 90)
			(layer "F.SilkS")
			(hide yes)
			(effects
				(font
					(size 1.27 1.27)
				)
			)
		)
		(property "Value" ""
			(at 0 0 90)
			(layer "F.Fab")
			(effects
				(font
					(size 1.27 1.27)
				)
			)
		)
		(duplicate_pad_numbers_are_jumpers no)
		(fp_line
			(start 0.7874 -0.4064)
			(end 0.7874 0.4064)
			(stroke
				(width 0.1524)
				(type default)
			)
			(layer "F.SilkS")
		)
		(fp_line
			(start -0.7874 -0.4064)
			(end 0.7874 -0.4064)
			(stroke
				(width 0.1524)
				(type default)
			)
			(layer "F.SilkS")
		)
		(fp_line
			(start 0.7874 0.4064)
			(end -0.7874 0.4064)
			(stroke
				(width 0.1524)
				(type default)
			)
			(layer "F.SilkS")
		)
		(fp_line
			(start -0.7874 0.4064)
			(end -0.7874 -0.4064)
			(stroke
				(width 0.1524)
				(type default)
			)
			(layer "F.SilkS")
		)
		(fp_line
			(start -0.12065 -0.305054)
			(end -0.12065 -0.2794)
			(stroke
				(width 0.1)
				(type default)
			)
			(layer "F.Fab")
		)
		(fp_line
			(start -0.67945 -0.305054)
			(end -0.12065 -0.305054)
			(stroke
				(width 0.1)
				(type default)
			)
			(layer "F.Fab")
		)
		(fp_line
			(start 0.67945 -0.3048)
			(end 0.67945 0.3048)
			(stroke
				(width 0.1)
				(type default)
			)
			(layer "F.Fab")
		)
		(fp_line
			(start 0.12065 -0.3048)
			(end 0.67945 -0.3048)
			(stroke
				(width 0.1)
				(type default)
			)
			(layer "F.Fab")
		)
		(fp_line
			(start 0.12065 -0.2794)
			(end 0.12065 -0.3048)
			(stroke
				(width 0.1)
				(type default)
			)
			(layer "F.Fab")
		)
		(fp_line
			(start -0.12065 -0.2794)
			(end 0.12065 -0.2794)
			(stroke
				(width 0.1)
				(type default)
			)
			(layer "F.Fab")
		)
		(fp_line
			(start 0.120396 0.2794)
			(end -0.12065 0.2794)
			(stroke
				(width 0.1)
				(type default)
			)
			(layer "F.Fab")
		)
		(fp_line
			(start -0.12065 0.2794)
			(end -0.12065 0.3048)
			(stroke
				(width 0.1)
				(type default)
			)
			(layer "F.Fab")
		)
		(fp_line
			(start 0.67945 0.3048)
			(end 0.120396 0.3048)
			(stroke
				(width 0.1)
				(type default)
			)
			(layer "F.Fab")
		)
		(fp_line
			(start 0.120396 0.3048)
			(end 0.120396 0.2794)
			(stroke
				(width 0.1)
				(type default)
			)
			(layer "F.Fab")
		)
		(fp_line
			(start -0.12065 0.3048)
			(end -0.67945 0.3048)
			(stroke
				(width 0.1)
				(type default)
			)
			(layer "F.Fab")
		)
		(fp_line
			(start -0.67945 0.3048)
			(end -0.67945 -0.305054)
			(stroke
				(width 0.1)
				(type default)
			)
			(layer "F.Fab")
		)
		(pad "1" smd circle
			(at -0.40005 0 90)
			(size 0 0)
			(layers "F.Cu" "F.Mask" "F.Paste")
			(net "P3V3_AUX")
		)
		(pad "2" smd circle
			(at 0.40005 0 90)
			(size 0 0)
			(layers "F.Cu" "F.Mask" "F.Paste")
			(net "GND")
		)
	)
	(footprint ""
		(layer "F.Cu")
		(at 51.816 -30.861 90)
		(property "Reference" "R692"
			(at 0 0 90)
			(layer "F.SilkS")
			(hide yes)
			(effects
				(font
					(size 1.27 1.27)
				)
			)
		)
		(property "Value" ""
			(at 0 0 90)
			(layer "F.Fab")
			(effects
				(font
					(size 1.27 1.27)
				)
			)
		)
		(duplicate_pad_numbers_are_jumpers no)
		(fp_line
			(start 0.7874 -0.4064)
			(end 0.7874 0.4064)
			(stroke
				(width 0.1524)
				(type default)
			)
			(layer "F.SilkS")
		)
		(fp_line
			(start -0.7874 -0.4064)
			(end 0.7874 -0.4064)
			(stroke
				(width 0.1524)
				(type default)
			)
			(layer "F.SilkS")
		)
		(fp_line
			(start 0.7874 0.4064)
			(end -0.7874 0.4064)
			(stroke
				(width 0.1524)
				(type default)
			)
			(layer "F.SilkS")
		)
		(fp_line
			(start -0.7874 0.4064)
			(end -0.7874 -0.4064)
			(stroke
				(width 0.1524)
				(type default)
			)
			(layer "F.SilkS")
		)
		(fp_line
			(start -0.12065 -0.305054)
			(end -0.12065 -0.2794)
			(stroke
				(width 0.1)
				(type default)
			)
			(layer "F.Fab")
		)
		(fp_line
			(start -0.67945 -0.305054)
			(end -0.12065 -0.305054)
			(stroke
				(width 0.1)
				(type default)
			)
			(layer "F.Fab")
		)
		(fp_line
			(start 0.67945 -0.3048)
			(end 0.67945 0.3048)
			(stroke
				(width 0.1)
				(type default)
			)
			(layer "F.Fab")
		)
		(fp_line
			(start 0.12065 -0.3048)
			(end 0.67945 -0.3048)
			(stroke
				(width 0.1)
				(type default)
			)
			(layer "F.Fab")
		)
		(fp_line
			(start 0.12065 -0.2794)
			(end 0.12065 -0.3048)
			(stroke
				(width 0.1)
				(type default)
			)
			(layer "F.Fab")
		)
		(fp_line
			(start -0.12065 -0.2794)
			(end 0.12065 -0.2794)
			(stroke
				(width 0.1)
				(type default)
			)
			(layer "F.Fab")
		)
		(fp_line
			(start 0.120396 0.2794)
			(end -0.12065 0.2794)
			(stroke
				(width 0.1)
				(type default)
			)
			(layer "F.Fab")
		)
		(fp_line
			(start -0.12065 0.2794)
			(end -0.12065 0.3048)
			(stroke
				(width 0.1)
				(type default)
			)
			(layer "F.Fab")
		)
		(fp_line
			(start 0.67945 0.3048)
			(end 0.120396 0.3048)
			(stroke
				(width 0.1)
				(type default)
			)
			(layer "F.Fab")
		)
		(fp_line
			(start 0.120396 0.3048)
			(end 0.120396 0.2794)
			(stroke
				(width 0.1)
				(type default)
			)
			(layer "F.Fab")
		)
		(fp_line
			(start -0.12065 0.3048)
			(end -0.67945 0.3048)
			(stroke
				(width 0.1)
				(type default)
			)
			(layer "F.Fab")
		)
		(fp_line
			(start -0.67945 0.3048)
			(end -0.67945 -0.305054)
			(stroke
				(width 0.1)
				(type default)
			)
			(layer "F.Fab")
		)
		(pad "1" smd circle
			(at -0.40005 0 90)
			(size 0 0)
			(layers "F.Cu" "F.Mask" "F.Paste")
			(net "P3V3_AUX")
		)
		(pad "2" smd circle
			(at 0.40005 0 90)
			(size 0 0)
			(layers "F.Cu" "F.Mask" "F.Paste")
			(net "SMB_BMC_MM15_SDA")
		)
	)
	(footprint ""
		(layer "F.Cu")
		(at 45.259244 -30.791404 90)
		(property "Reference" "R244"
			(at 0 0 90)
			(layer "F.SilkS")
			(hide yes)
			(effects
				(font
					(size 1.27 1.27)
				)
			)
		)
		(property "Value" ""
			(at 0 0 90)
			(layer "F.Fab")
			(effects
				(font
					(size 1.27 1.27)
				)
			)
		)
		(duplicate_pad_numbers_are_jumpers no)
		(fp_line
			(start 0.7874 -0.4064)
			(end 0.7874 0.4064)
			(stroke
				(width 0.1524)
				(type default)
			)
			(layer "F.SilkS")
		)
		(fp_line
			(start -0.7874 -0.4064)
			(end 0.7874 -0.4064)
			(stroke
				(width 0.1524)
				(type default)
			)
			(layer "F.SilkS")
		)
		(fp_line
			(start 0.7874 0.4064)
			(end -0.7874 0.4064)
			(stroke
				(width 0.1524)
				(type default)
			)
			(layer "F.SilkS")
		)
		(fp_line
			(start -0.7874 0.4064)
			(end -0.7874 -0.4064)
			(stroke
				(width 0.1524)
				(type default)
			)
			(layer "F.SilkS")
		)
		(fp_line
			(start -0.12065 -0.305054)
			(end -0.12065 -0.2794)
			(stroke
				(width 0.1)
				(type default)
			)
			(layer "F.Fab")
		)
		(fp_line
			(start -0.67945 -0.305054)
			(end -0.12065 -0.305054)
			(stroke
				(width 0.1)
				(type default)
			)
			(layer "F.Fab")
		)
		(fp_line
			(start 0.67945 -0.3048)
			(end 0.67945 0.3048)
			(stroke
				(width 0.1)
				(type default)
			)
			(layer "F.Fab")
		)
		(fp_line
			(start 0.12065 -0.3048)
			(end 0.67945 -0.3048)
			(stroke
				(width 0.1)
				(type default)
			)
			(layer "F.Fab")
		)
		(fp_line
			(start 0.12065 -0.2794)
			(end 0.12065 -0.3048)
			(stroke
				(width 0.1)
				(type default)
			)
			(layer "F.Fab")
		)
		(fp_line
			(start -0.12065 -0.2794)
			(end 0.12065 -0.2794)
			(stroke
				(width 0.1)
				(type default)
			)
			(layer "F.Fab")
		)
		(fp_line
			(start 0.120396 0.2794)
			(end -0.12065 0.2794)
			(stroke
				(width 0.1)
				(type default)
			)
			(layer "F.Fab")
		)
		(fp_line
			(start -0.12065 0.2794)
			(end -0.12065 0.3048)
			(stroke
				(width 0.1)
				(type default)
			)
			(layer "F.Fab")
		)
		(fp_line
			(start 0.67945 0.3048)
			(end 0.120396 0.3048)
			(stroke
				(width 0.1)
				(type default)
			)
			(layer "F.Fab")
		)
		(fp_line
			(start 0.120396 0.3048)
			(end 0.120396 0.2794)
			(stroke
				(width 0.1)
				(type default)
			)
			(layer "F.Fab")
		)
		(fp_line
			(start -0.12065 0.3048)
			(end -0.67945 0.3048)
			(stroke
				(width 0.1)
				(type default)
			)
			(layer "F.Fab")
		)
		(fp_line
			(start -0.67945 0.3048)
			(end -0.67945 -0.305054)
			(stroke
				(width 0.1)
				(type default)
			)
			(layer "F.Fab")
		)
		(pad "1" smd circle
			(at -0.40005 0 90)
			(size 0 0)
			(layers "F.Cu" "F.Mask" "F.Paste")
			(net "P3V3_AUX")
		)
		(pad "2" smd circle
			(at 0.40005 0 90)
			(size 0 0)
			(layers "F.Cu" "F.Mask" "F.Paste")
			(net "SMB_BMC_MM1_SCL")
		)
	)
	(footprint ""
		(layer "F.Cu")
		(at 23.47087 -33.904174 -90)
		(property "Reference" "PR500"
			(at 0 0 270)
			(layer "F.SilkS")
			(hide yes)
			(effects
				(font
					(size 1.27 1.27)
				)
			)
		)
		(property "Value" ""
			(at 0 0 270)
			(layer "F.Fab")
			(effects
				(font
					(size 1.27 1.27)
				)
			)
		)
		(duplicate_pad_numbers_are_jumpers no)
		(fp_line
			(start -0.7874 0.4064)
			(end -0.7874 -0.4064)
			(stroke
				(width 0.1524)
				(type default)
			)
			(layer "F.SilkS")
		)
		(fp_line
			(start 0.7874 0.4064)
			(end -0.7874 0.4064)
			(stroke
				(width 0.1524)
				(type default)
			)
			(layer "F.SilkS")
		)
		(fp_line
			(start -0.7874 -0.4064)
			(end 0.7874 -0.4064)
			(stroke
				(width 0.1524)
				(type default)
			)
			(layer "F.SilkS")
		)
		(fp_line
			(start 0.7874 -0.4064)
			(end 0.7874 0.4064)
			(stroke
				(width 0.1524)
				(type default)
			)
			(layer "F.SilkS")
		)
		(fp_line
			(start -0.67945 0.3048)
			(end -0.67945 -0.305054)
			(stroke
				(width 0.1)
				(type default)
			)
			(layer "F.Fab")
		)
		(fp_line
			(start -0.12065 0.3048)
			(end -0.67945 0.3048)
			(stroke
				(width 0.1)
				(type default)
			)
			(layer "F.Fab")
		)
		(fp_line
			(start 0.120396 0.3048)
			(end 0.120396 0.2794)
			(stroke
				(width 0.1)
				(type default)
			)
			(layer "F.Fab")
		)
		(fp_line
			(start 0.67945 0.3048)
			(end 0.120396 0.3048)
			(stroke
				(width 0.1)
				(type default)
			)
			(layer "F.Fab")
		)
		(fp_line
			(start -0.12065 0.2794)
			(end -0.12065 0.3048)
			(stroke
				(width 0.1)
				(type default)
			)
			(layer "F.Fab")
		)
		(fp_line
			(start 0.120396 0.2794)
			(end -0.12065 0.2794)
			(stroke
				(width 0.1)
				(type default)
			)
			(layer "F.Fab")
		)
		(fp_line
			(start -0.12065 -0.2794)
			(end 0.12065 -0.2794)
			(stroke
				(width 0.1)
				(type default)
			)
			(layer "F.Fab")
		)
		(fp_line
			(start 0.12065 -0.2794)
			(end 0.12065 -0.3048)
			(stroke
				(width 0.1)
				(type default)
			)
			(layer "F.Fab")
		)
		(fp_line
			(start 0.12065 -0.3048)
			(end 0.67945 -0.3048)
			(stroke
				(width 0.1)
				(type default)
			)
			(layer "F.Fab")
		)
		(fp_line
			(start 0.67945 -0.3048)
			(end 0.67945 0.3048)
			(stroke
				(width 0.1)
				(type default)
			)
			(layer "F.Fab")
		)
		(fp_line
			(start -0.67945 -0.305054)
			(end -0.12065 -0.305054)
			(stroke
				(width 0.1)
				(type default)
			)
			(layer "F.Fab")
		)
		(fp_line
			(start -0.12065 -0.305054)
			(end -0.12065 -0.2794)
			(stroke
				(width 0.1)
				(type default)
			)
			(layer "F.Fab")
		)
		(pad "1" smd circle
			(at -0.40005 0 270)
			(size 0 0)
			(layers "F.Cu" "F.Mask" "F.Paste")
			(net "P3V3_AUX")
		)
		(pad "2" smd circle
			(at 0.40005 0 270)
			(size 0 0)
			(layers "F.Cu" "F.Mask" "F.Paste")
			(net "PWRGD_P1V0_AUX_R")
		)
	)
	(footprint ""
		(layer "F.Cu")
		(at 4.218432 -47.989744 90)
		(property "Reference" "PC208"
			(at 0 0 90)
			(layer "F.SilkS")
			(hide yes)
			(effects
				(font
					(size 1.27 1.27)
				)
			)
		)
		(property "Value" ""
			(at 0 0 90)
			(layer "F.Fab")
			(effects
				(font
					(size 1.27 1.27)
				)
			)
		)
		(duplicate_pad_numbers_are_jumpers no)
		(fp_line
			(start 0.7874 -0.4064)
			(end 0.7874 0.4064)
			(stroke
				(width 0.1524)
				(type default)
			)
			(layer "F.SilkS")
		)
		(fp_line
			(start -0.7874 -0.4064)
			(end 0.7874 -0.4064)
			(stroke
				(width 0.1524)
				(type default)
			)
			(layer "F.SilkS")
		)
		(fp_line
			(start 0.7874 0.4064)
			(end -0.7874 0.4064)
			(stroke
				(width 0.1524)
				(type default)
			)
			(layer "F.SilkS")
		)
		(fp_line
			(start -0.7874 0.4064)
			(end -0.7874 -0.4064)
			(stroke
				(width 0.1524)
				(type default)
			)
			(layer "F.SilkS")
		)
		(fp_line
			(start -0.12065 -0.305054)
			(end -0.12065 -0.2794)
			(stroke
				(width 0.1)
				(type default)
			)
			(layer "F.Fab")
		)
		(fp_line
			(start -0.67945 -0.305054)
			(end -0.12065 -0.305054)
			(stroke
				(width 0.1)
				(type default)
			)
			(layer "F.Fab")
		)
		(fp_line
			(start 0.67945 -0.3048)
			(end 0.67945 0.3048)
			(stroke
				(width 0.1)
				(type default)
			)
			(layer "F.Fab")
		)
		(fp_line
			(start 0.12065 -0.3048)
			(end 0.67945 -0.3048)
			(stroke
				(width 0.1)
				(type default)
			)
			(layer "F.Fab")
		)
		(fp_line
			(start 0.12065 -0.2794)
			(end 0.12065 -0.3048)
			(stroke
				(width 0.1)
				(type default)
			)
			(layer "F.Fab")
		)
		(fp_line
			(start -0.12065 -0.2794)
			(end 0.12065 -0.2794)
			(stroke
				(width 0.1)
				(type default)
			)
			(layer "F.Fab")
		)
		(fp_line
			(start 0.120396 0.2794)
			(end -0.12065 0.2794)
			(stroke
				(width 0.1)
				(type default)
			)
			(layer "F.Fab")
		)
		(fp_line
			(start -0.12065 0.2794)
			(end -0.12065 0.3048)
			(stroke
				(width 0.1)
				(type default)
			)
			(layer "F.Fab")
		)
		(fp_line
			(start 0.67945 0.3048)
			(end 0.120396 0.3048)
			(stroke
				(width 0.1)
				(type default)
			)
			(layer "F.Fab")
		)
		(fp_line
			(start 0.120396 0.3048)
			(end 0.120396 0.2794)
			(stroke
				(width 0.1)
				(type default)
			)
			(layer "F.Fab")
		)
		(fp_line
			(start -0.12065 0.3048)
			(end -0.67945 0.3048)
			(stroke
				(width 0.1)
				(type default)
			)
			(layer "F.Fab")
		)
		(fp_line
			(start -0.67945 0.3048)
			(end -0.67945 -0.305054)
			(stroke
				(width 0.1)
				(type default)
			)
			(layer "F.Fab")
		)
		(pad "1" smd circle
			(at -0.40005 0 90)
			(size 0 0)
			(layers "F.Cu" "F.Mask" "F.Paste")
			(net "P5V_AUX_VCC")
		)
		(pad "2" smd circle
			(at 0.40005 0 90)
			(size 0 0)
			(layers "F.Cu" "F.Mask" "F.Paste")
			(net "GND")
		)
	)
	(footprint ""
		(layer "F.Cu")
		(at 28.829 -13.081)
		(property "Reference" "U9"
			(at -2.38633 -0.254 90)
			(unlocked yes)
			(layer "F.SilkS")
			(effects
				(font
					(size 0.7874 0.5842)
					(thickness 0.1524)
				)
			)
		)
		(property "Value" ""
			(at 0 0 0)
			(layer "F.Fab")
			(effects
				(font
					(size 1.27 1.27)
				)
			)
		)
		(duplicate_pad_numbers_are_jumpers no)
		(fp_line
			(start -1.834896 -1.575054)
			(end -0.508 -1.575054)
			(stroke
				(width 0.1524)
				(type default)
			)
			(layer "F.SilkS")
		)
		(fp_line
			(start -1.834896 1.575054)
			(end -1.834896 -1.575054)
			(stroke
				(width 0.1524)
				(type default)
			)
			(layer "F.SilkS")
		)
		(fp_line
			(start -0.508 -1.575054)
			(end 0 -1.016)
			(stroke
				(width 0.1524)
				(type default)
			)
			(layer "F.SilkS")
		)
		(fp_line
			(start 0 -1.016)
			(end 0.508 -1.575054)
			(stroke
				(width 0.1524)
				(type default)
			)
			(layer "F.SilkS")
		)
		(fp_line
			(start 0.508 -1.575054)
			(end 1.834896 -1.575054)
			(stroke
				(width 0.1524)
				(type default)
			)
			(layer "F.SilkS")
		)
		(fp_line
			(start 1.834896 -1.575054)
			(end 1.834896 1.575054)
			(stroke
				(width 0.1524)
				(type default)
			)
			(layer "F.SilkS")
		)
		(fp_line
			(start 1.834896 1.575054)
			(end -1.834896 1.575054)
			(stroke
				(width 0.1524)
				(type default)
			)
			(layer "F.SilkS")
		)
		(fp_poly
			(pts
				(xy -2.372614 -2.627884) (xy -3.09118 -1.909318) (xy -2.013458 -1.550162)
			)
			(stroke
				(width 0)
				(type default)
			)
			(fill yes)
			(layer "F.SilkS")
		)
		(fp_line
			(start -0.824992 -1.575054)
			(end 0.824992 -1.575054)
			(stroke
				(width 0.1)
				(type default)
			)
			(layer "F.Fab")
		)
		(fp_line
			(start -0.824992 1.575054)
			(end -0.824992 -1.575054)
			(stroke
				(width 0.1)
				(type default)
			)
			(layer "F.Fab")
		)
		(fp_line
			(start 0.824992 -1.575054)
			(end 0.824992 1.575054)
			(stroke
				(width 0.1)
				(type default)
			)
			(layer "F.Fab")
		)
		(fp_line
			(start 0.824992 1.575054)
			(end -0.824992 1.575054)
			(stroke
				(width 0.1)
				(type default)
			)
			(layer "F.Fab")
		)
		(fp_poly
			(pts
				(xy -3.003296 -1.45796) (xy -3.003296 -0.44196) (xy -1.987296 -0.94996)
			)
			(stroke
				(width 0)
				(type default)
			)
			(fill yes)
			(layer "F.Fab")
		)
		(pad "1" smd rect
			(at -1.199896 -0.94996 270)
			(size 0.7112 1.016)
			(layers "F.Cu" "F.Mask" "F.Paste")
			(net "BEEP_LED")
		)
		(pad "2" smd rect
			(at -1.199896 0 270)
			(size 0.7112 1.016)
			(layers "F.Cu" "F.Mask" "F.Paste")
			(net "FM_ID_R_LED")
		)
		(pad "3" smd rect
			(at -1.199896 0.94996 270)
			(size 0.7112 1.016)
			(layers "F.Cu" "F.Mask" "F.Paste")
			(net "GND")
		)
		(pad "4" smd rect
			(at 1.199896 0.94996 270)
			(size 0.7112 1.016)
			(layers "F.Cu" "F.Mask" "F.Paste")
			(net "ID_LED_BUF")
		)
		(pad "5" smd rect
			(at 1.199896 -0.94996 270)
			(size 0.7112 1.016)
			(layers "F.Cu" "F.Mask" "F.Paste")
			(net "P3V3_AUX")
		)
	)
	(footprint ""
		(layer "F.Cu")
		(at 38.989 -58.547 -90)
		(property "Reference" "R275"
			(at 0 0 270)
			(layer "F.SilkS")
			(hide yes)
			(effects
				(font
					(size 1.27 1.27)
				)
			)
		)
		(property "Value" ""
			(at 0 0 270)
			(layer "F.Fab")
			(effects
				(font
					(size 1.27 1.27)
				)
			)
		)
		(duplicate_pad_numbers_are_jumpers no)
		(fp_line
			(start -0.7874 0.4064)
			(end -0.7874 -0.4064)
			(stroke
				(width 0.1524)
				(type default)
			)
			(layer "F.SilkS")
		)
		(fp_line
			(start 0.7874 0.4064)
			(end -0.7874 0.4064)
			(stroke
				(width 0.1524)
				(type default)
			)
			(layer "F.SilkS")
		)
		(fp_line
			(start -0.7874 -0.4064)
			(end 0.7874 -0.4064)
			(stroke
				(width 0.1524)
				(type default)
			)
			(layer "F.SilkS")
		)
		(fp_line
			(start 0.7874 -0.4064)
			(end 0.7874 0.4064)
			(stroke
				(width 0.1524)
				(type default)
			)
			(layer "F.SilkS")
		)
		(fp_line
			(start -0.67945 0.3048)
			(end -0.67945 -0.305054)
			(stroke
				(width 0.1)
				(type default)
			)
			(layer "F.Fab")
		)
		(fp_line
			(start -0.12065 0.3048)
			(end -0.67945 0.3048)
			(stroke
				(width 0.1)
				(type default)
			)
			(layer "F.Fab")
		)
		(fp_line
			(start 0.120396 0.3048)
			(end 0.120396 0.2794)
			(stroke
				(width 0.1)
				(type default)
			)
			(layer "F.Fab")
		)
		(fp_line
			(start 0.67945 0.3048)
			(end 0.120396 0.3048)
			(stroke
				(width 0.1)
				(type default)
			)
			(layer "F.Fab")
		)
		(fp_line
			(start -0.12065 0.2794)
			(end -0.12065 0.3048)
			(stroke
				(width 0.1)
				(type default)
			)
			(layer "F.Fab")
		)
		(fp_line
			(start 0.120396 0.2794)
			(end -0.12065 0.2794)
			(stroke
				(width 0.1)
				(type default)
			)
			(layer "F.Fab")
		)
		(fp_line
			(start -0.12065 -0.2794)
			(end 0.12065 -0.2794)
			(stroke
				(width 0.1)
				(type default)
			)
			(layer "F.Fab")
		)
		(fp_line
			(start 0.12065 -0.2794)
			(end 0.12065 -0.3048)
			(stroke
				(width 0.1)
				(type default)
			)
			(layer "F.Fab")
		)
		(fp_line
			(start 0.12065 -0.3048)
			(end 0.67945 -0.3048)
			(stroke
				(width 0.1)
				(type default)
			)
			(layer "F.Fab")
		)
		(fp_line
			(start 0.67945 -0.3048)
			(end 0.67945 0.3048)
			(stroke
				(width 0.1)
				(type default)
			)
			(layer "F.Fab")
		)
		(fp_line
			(start -0.67945 -0.305054)
			(end -0.12065 -0.305054)
			(stroke
				(width 0.1)
				(type default)
			)
			(layer "F.Fab")
		)
		(fp_line
			(start -0.12065 -0.305054)
			(end -0.12065 -0.2794)
			(stroke
				(width 0.1)
				(type default)
			)
			(layer "F.Fab")
		)
		(pad "1" smd circle
			(at -0.40005 0 270)
			(size 0 0)
			(layers "F.Cu" "F.Mask" "F.Paste")
			(net "PWRGD_P1V8_AUX")
		)
		(pad "2" smd circle
			(at 0.40005 0 270)
			(size 0 0)
			(layers "F.Cu" "F.Mask" "F.Paste")
			(net "PWRGD_P1V8_AUX_R")
		)
	)
	(footprint ""
		(layer "F.Cu")
		(at 12.319 -87.376 180)
		(property "Reference" "R691"
			(at 0 0 180)
			(layer "F.SilkS")
			(hide yes)
			(effects
				(font
					(size 1.27 1.27)
				)
			)
		)
		(property "Value" ""
			(at 0 0 180)
			(layer "F.Fab")
			(effects
				(font
					(size 1.27 1.27)
				)
			)
		)
		(duplicate_pad_numbers_are_jumpers no)
		(fp_line
			(start 0.7874 0.4064)
			(end -0.7874 0.4064)
			(stroke
				(width 0.1524)
				(type default)
			)
			(layer "F.SilkS")
		)
		(fp_line
			(start 0.7874 -0.4064)
			(end 0.7874 0.4064)
			(stroke
				(width 0.1524)
				(type default)
			)
			(layer "F.SilkS")
		)
		(fp_line
			(start -0.7874 0.4064)
			(end -0.7874 -0.4064)
			(stroke
				(width 0.1524)
				(type default)
			)
			(layer "F.SilkS")
		)
		(fp_line
			(start -0.7874 -0.4064)
			(end 0.7874 -0.4064)
			(stroke
				(width 0.1524)
				(type default)
			)
			(layer "F.SilkS")
		)
		(fp_line
			(start 0.67945 0.3048)
			(end 0.120396 0.3048)
			(stroke
				(width 0.1)
				(type default)
			)
			(layer "F.Fab")
		)
		(fp_line
			(start 0.67945 -0.3048)
			(end 0.67945 0.3048)
			(stroke
				(width 0.1)
				(type default)
			)
			(layer "F.Fab")
		)
		(fp_line
			(start 0.12065 -0.2794)
			(end 0.12065 -0.3048)
			(stroke
				(width 0.1)
				(type default)
			)
			(layer "F.Fab")
		)
		(fp_line
			(start 0.12065 -0.3048)
			(end 0.67945 -0.3048)
			(stroke
				(width 0.1)
				(type default)
			)
			(layer "F.Fab")
		)
		(fp_line
			(start 0.120396 0.3048)
			(end 0.120396 0.2794)
			(stroke
				(width 0.1)
				(type default)
			)
			(layer "F.Fab")
		)
		(fp_line
			(start 0.120396 0.2794)
			(end -0.12065 0.2794)
			(stroke
				(width 0.1)
				(type default)
			)
			(layer "F.Fab")
		)
		(fp_line
			(start -0.12065 0.3048)
			(end -0.67945 0.3048)
			(stroke
				(width 0.1)
				(type default)
			)
			(layer "F.Fab")
		)
		(fp_line
			(start -0.12065 0.2794)
			(end -0.12065 0.3048)
			(stroke
				(width 0.1)
				(type default)
			)
			(layer "F.Fab")
		)
		(fp_line
			(start -0.12065 -0.2794)
			(end 0.12065 -0.2794)
			(stroke
				(width 0.1)
				(type default)
			)
			(layer "F.Fab")
		)
		(fp_line
			(start -0.12065 -0.305054)
			(end -0.12065 -0.2794)
			(stroke
				(width 0.1)
				(type default)
			)
			(layer "F.Fab")
		)
		(fp_line
			(start -0.67945 0.3048)
			(end -0.67945 -0.305054)
			(stroke
				(width 0.1)
				(type default)
			)
			(layer "F.Fab")
		)
		(fp_line
			(start -0.67945 -0.305054)
			(end -0.12065 -0.305054)
			(stroke
				(width 0.1)
				(type default)
			)
			(layer "F.Fab")
		)
		(pad "1" smd circle
			(at -0.40005 0 180)
			(size 0 0)
			(layers "F.Cu" "F.Mask" "F.Paste")
			(net "RST_SGPIO_RESET_R_N")
		)
		(pad "2" smd circle
			(at 0.40005 0 180)
			(size 0 0)
			(layers "F.Cu" "F.Mask" "F.Paste")
			(net "RST_SGPIO_RESET_N")
		)
	)
	(footprint ""
		(layer "F.Cu")
		(at 39.9288 -43.434)
		(property "Reference" "R266"
			(at 0 0 0)
			(layer "F.SilkS")
			(hide yes)
			(effects
				(font
					(size 1.27 1.27)
				)
			)
		)
		(property "Value" ""
			(at 0 0 0)
			(layer "F.Fab")
			(effects
				(font
					(size 1.27 1.27)
				)
			)
		)
		(duplicate_pad_numbers_are_jumpers no)
		(fp_line
			(start -0.7874 -0.4064)
			(end 0.7874 -0.4064)
			(stroke
				(width 0.1524)
				(type default)
			)
			(layer "F.SilkS")
		)
		(fp_line
			(start -0.7874 0.4064)
			(end -0.7874 -0.4064)
			(stroke
				(width 0.1524)
				(type default)
			)
			(layer "F.SilkS")
		)
		(fp_line
			(start 0.7874 -0.4064)
			(end 0.7874 0.4064)
			(stroke
				(width 0.1524)
				(type default)
			)
			(layer "F.SilkS")
		)
		(fp_line
			(start 0.7874 0.4064)
			(end -0.7874 0.4064)
			(stroke
				(width 0.1524)
				(type default)
			)
			(layer "F.SilkS")
		)
		(fp_line
			(start -0.67945 -0.305054)
			(end -0.12065 -0.305054)
			(stroke
				(width 0.1)
				(type default)
			)
			(layer "F.Fab")
		)
		(fp_line
			(start -0.67945 0.3048)
			(end -0.67945 -0.305054)
			(stroke
				(width 0.1)
				(type default)
			)
			(layer "F.Fab")
		)
		(fp_line
			(start -0.12065 -0.305054)
			(end -0.12065 -0.2794)
			(stroke
				(width 0.1)
				(type default)
			)
			(layer "F.Fab")
		)
		(fp_line
			(start -0.12065 -0.2794)
			(end 0.12065 -0.2794)
			(stroke
				(width 0.1)
				(type default)
			)
			(layer "F.Fab")
		)
		(fp_line
			(start -0.12065 0.2794)
			(end -0.12065 0.3048)
			(stroke
				(width 0.1)
				(type default)
			)
			(layer "F.Fab")
		)
		(fp_line
			(start -0.12065 0.3048)
			(end -0.67945 0.3048)
			(stroke
				(width 0.1)
				(type default)
			)
			(layer "F.Fab")
		)
		(fp_line
			(start 0.120396 0.2794)
			(end -0.12065 0.2794)
			(stroke
				(width 0.1)
				(type default)
			)
			(layer "F.Fab")
		)
		(fp_line
			(start 0.120396 0.3048)
			(end 0.120396 0.2794)
			(stroke
				(width 0.1)
				(type default)
			)
			(layer "F.Fab")
		)
		(fp_line
			(start 0.12065 -0.3048)
			(end 0.67945 -0.3048)
			(stroke
				(width 0.1)
				(type default)
			)
			(layer "F.Fab")
		)
		(fp_line
			(start 0.12065 -0.2794)
			(end 0.12065 -0.3048)
			(stroke
				(width 0.1)
				(type default)
			)
			(layer "F.Fab")
		)
		(fp_line
			(start 0.67945 -0.3048)
			(end 0.67945 0.3048)
			(stroke
				(width 0.1)
				(type default)
			)
			(layer "F.Fab")
		)
		(fp_line
			(start 0.67945 0.3048)
			(end 0.120396 0.3048)
			(stroke
				(width 0.1)
				(type default)
			)
			(layer "F.Fab")
		)
		(pad "1" smd circle
			(at -0.40005 0)
			(size 0 0)
			(layers "F.Cu" "F.Mask" "F.Paste")
			(net "P3V3_AUX")
		)
		(pad "2" smd circle
			(at 0.40005 0)
			(size 0 0)
			(layers "F.Cu" "F.Mask" "F.Paste")
			(net "FM_ME_BT_DONE")
		)
	)
	(footprint ""
		(layer "F.Cu")
		(at 31.70809 -16.503396 90)
		(property "Reference" "U38"
			(at -2.052066 1.69291 0)
			(unlocked yes)
			(layer "F.SilkS")
			(effects
				(font
					(size 0.7874 0.5842)
					(thickness 0.1524)
				)
				(justify left)
			)
		)
		(property "Value" ""
			(at 0 0 90)
			(layer "F.Fab")
			(effects
				(font
					(size 1.27 1.27)
				)
			)
		)
		(duplicate_pad_numbers_are_jumpers no)
		(fp_line
			(start 0.517398 -1.500124)
			(end 0.517398 0.122936)
			(stroke
				(width 0.1524)
				(type default)
			)
			(layer "F.SilkS")
		)
		(fp_line
			(start 0.374904 -1.500124)
			(end 0.517398 -1.500124)
			(stroke
				(width 0.1524)
				(type default)
			)
			(layer "F.SilkS")
		)
		(fp_line
			(start -0.517398 -1.500124)
			(end -0.336296 -1.500124)
			(stroke
				(width 0.1524)
				(type default)
			)
			(layer "F.SilkS")
		)
		(fp_line
			(start -0.517398 0.128016)
			(end -0.517398 -1.500124)
			(stroke
				(width 0.1524)
				(type default)
			)
			(layer "F.SilkS")
		)
		(fp_poly
			(pts
				(xy -1.5875 -0.621284) (xy -2.2225 -0.938784) (xy -2.2225 -0.303784)
			)
			(stroke
				(width 0)
				(type default)
			)
			(fill yes)
			(layer "F.SilkS")
		)
		(fp_line
			(start 0.700024 -1.500124)
			(end 0.700024 1.500124)
			(stroke
				(width 0.1)
				(type default)
			)
			(layer "F.Fab")
		)
		(fp_line
			(start -0.700024 -1.500124)
			(end 0.700024 -1.500124)
			(stroke
				(width 0.1)
				(type default)
			)
			(layer "F.Fab")
		)
		(fp_line
			(start 0.700024 1.500124)
			(end -0.700024 1.500124)
			(stroke
				(width 0.1)
				(type default)
			)
			(layer "F.Fab")
		)
		(fp_line
			(start -0.700024 1.500124)
			(end -0.700024 -1.500124)
			(stroke
				(width 0.1)
				(type default)
			)
			(layer "F.Fab")
		)
		(fp_poly
			(pts
				(xy -1.5113 -0.750062) (xy -2.1463 -1.067562) (xy -2.1463 -0.432562)
			)
			(stroke
				(width 0)
				(type default)
			)
			(fill yes)
			(layer "F.Fab")
		)
		(pad "1" smd rect
			(at -0.999998 -0.750062 90)
			(size 0.7112 1.016)
			(layers "F.Cu" "F.Mask" "F.Paste")
			(net "GND")
		)
		(pad "2" smd rect
			(at -0.999998 0.94996)
			(size 0.6096 0.7112)
			(layers "F.Cu" "F.Mask" "F.Paste")
			(net "USB2_01_F_DP")
		)
		(pad "3" smd rect
			(at 0.999998 0.94996)
			(size 0.6096 0.7112)
			(layers "F.Cu" "F.Mask" "F.Paste")
			(net "USB2_01_F_DN")
		)
		(pad "4" smd rect
			(at 0.999998 -0.94996)
			(size 0.6096 0.7112)
			(layers "F.Cu" "F.Mask" "F.Paste")
			(net "P5V_USB_REAR")
		)
	)
	(footprint ""
		(layer "F.Cu")
		(at 19.308826 -34.509964 180)
		(property "Reference" "PC263"
			(at 0 0 180)
			(layer "F.SilkS")
			(hide yes)
			(effects
				(font
					(size 1.27 1.27)
				)
			)
		)
		(property "Value" ""
			(at 0 0 180)
			(layer "F.Fab")
			(effects
				(font
					(size 1.27 1.27)
				)
			)
		)
		(duplicate_pad_numbers_are_jumpers no)
		(fp_line
			(start 0.7874 0.4064)
			(end -0.7874 0.4064)
			(stroke
				(width 0.1524)
				(type default)
			)
			(layer "F.SilkS")
		)
		(fp_line
			(start 0.7874 -0.4064)
			(end 0.7874 0.4064)
			(stroke
				(width 0.1524)
				(type default)
			)
			(layer "F.SilkS")
		)
		(fp_line
			(start -0.7874 0.4064)
			(end -0.7874 -0.4064)
			(stroke
				(width 0.1524)
				(type default)
			)
			(layer "F.SilkS")
		)
		(fp_line
			(start -0.7874 -0.4064)
			(end 0.7874 -0.4064)
			(stroke
				(width 0.1524)
				(type default)
			)
			(layer "F.SilkS")
		)
		(fp_line
			(start 0.67945 0.3048)
			(end 0.120396 0.3048)
			(stroke
				(width 0.1)
				(type default)
			)
			(layer "F.Fab")
		)
		(fp_line
			(start 0.67945 -0.3048)
			(end 0.67945 0.3048)
			(stroke
				(width 0.1)
				(type default)
			)
			(layer "F.Fab")
		)
		(fp_line
			(start 0.12065 -0.2794)
			(end 0.12065 -0.3048)
			(stroke
				(width 0.1)
				(type default)
			)
			(layer "F.Fab")
		)
		(fp_line
			(start 0.12065 -0.3048)
			(end 0.67945 -0.3048)
			(stroke
				(width 0.1)
				(type default)
			)
			(layer "F.Fab")
		)
		(fp_line
			(start 0.120396 0.3048)
			(end 0.120396 0.2794)
			(stroke
				(width 0.1)
				(type default)
			)
			(layer "F.Fab")
		)
		(fp_line
			(start 0.120396 0.2794)
			(end -0.12065 0.2794)
			(stroke
				(width 0.1)
				(type default)
			)
			(layer "F.Fab")
		)
		(fp_line
			(start -0.12065 0.3048)
			(end -0.67945 0.3048)
			(stroke
				(width 0.1)
				(type default)
			)
			(layer "F.Fab")
		)
		(fp_line
			(start -0.12065 0.2794)
			(end -0.12065 0.3048)
			(stroke
				(width 0.1)
				(type default)
			)
			(layer "F.Fab")
		)
		(fp_line
			(start -0.12065 -0.2794)
			(end 0.12065 -0.2794)
			(stroke
				(width 0.1)
				(type default)
			)
			(layer "F.Fab")
		)
		(fp_line
			(start -0.12065 -0.305054)
			(end -0.12065 -0.2794)
			(stroke
				(width 0.1)
				(type default)
			)
			(layer "F.Fab")
		)
		(fp_line
			(start -0.67945 0.3048)
			(end -0.67945 -0.305054)
			(stroke
				(width 0.1)
				(type default)
			)
			(layer "F.Fab")
		)
		(fp_line
			(start -0.67945 -0.305054)
			(end -0.12065 -0.305054)
			(stroke
				(width 0.1)
				(type default)
			)
			(layer "F.Fab")
		)
		(pad "1" smd circle
			(at -0.40005 0 180)
			(size 0 0)
			(layers "F.Cu" "F.Mask" "F.Paste")
			(net "SW_P1V0_AUX_FLT")
		)
		(pad "2" smd circle
			(at 0.40005 0 180)
			(size 0 0)
			(layers "F.Cu" "F.Mask" "F.Paste")
			(net "GND")
		)
	)
	(footprint ""
		(layer "F.Cu")
		(at 84.700364 -11.789918)
		(property "Reference" "H7"
			(at -4.842764 -2.280412 0)
			(unlocked yes)
			(layer "F.SilkS")
			(effects
				(font
					(size 0.7874 0.5842)
					(thickness 0.1524)
				)
				(justify left)
			)
		)
		(property "Value" ""
			(at 0 0 0)
			(layer "F.Fab")
			(effects
				(font
					(size 1.27 1.27)
				)
			)
		)
		(duplicate_pad_numbers_are_jumpers no)
		(pad "1" thru_hole circle
			(at 0 0)
			(size 6.5024 6.5024)
			(drill 3.2004)
			(layers "*.Cu" "*.Mask")
			(remove_unused_layers no)
			(net "GND")
			(clearance -1.397)
		)
	)
	(footprint ""
		(layer "F.Cu")
		(at 13.5001 -53.6448 180)
		(property "Reference" "C305"
			(at 0 0 180)
			(layer "F.SilkS")
			(hide yes)
			(effects
				(font
					(size 1.27 1.27)
				)
			)
		)
		(property "Value" ""
			(at 0 0 180)
			(layer "F.Fab")
			(effects
				(font
					(size 1.27 1.27)
				)
			)
		)
		(duplicate_pad_numbers_are_jumpers no)
		(fp_line
			(start 0.7874 0.4064)
			(end -0.7874 0.4064)
			(stroke
				(width 0.1524)
				(type default)
			)
			(layer "F.SilkS")
		)
		(fp_line
			(start 0.7874 -0.4064)
			(end 0.7874 0.4064)
			(stroke
				(width 0.1524)
				(type default)
			)
			(layer "F.SilkS")
		)
		(fp_line
			(start -0.7874 0.4064)
			(end -0.7874 -0.4064)
			(stroke
				(width 0.1524)
				(type default)
			)
			(layer "F.SilkS")
		)
		(fp_line
			(start -0.7874 -0.4064)
			(end 0.7874 -0.4064)
			(stroke
				(width 0.1524)
				(type default)
			)
			(layer "F.SilkS")
		)
		(fp_line
			(start 0.67945 0.3048)
			(end 0.120396 0.3048)
			(stroke
				(width 0.1)
				(type default)
			)
			(layer "F.Fab")
		)
		(fp_line
			(start 0.67945 -0.3048)
			(end 0.67945 0.3048)
			(stroke
				(width 0.1)
				(type default)
			)
			(layer "F.Fab")
		)
		(fp_line
			(start 0.12065 -0.2794)
			(end 0.12065 -0.3048)
			(stroke
				(width 0.1)
				(type default)
			)
			(layer "F.Fab")
		)
		(fp_line
			(start 0.12065 -0.3048)
			(end 0.67945 -0.3048)
			(stroke
				(width 0.1)
				(type default)
			)
			(layer "F.Fab")
		)
		(fp_line
			(start 0.120396 0.3048)
			(end 0.120396 0.2794)
			(stroke
				(width 0.1)
				(type default)
			)
			(layer "F.Fab")
		)
		(fp_line
			(start 0.120396 0.2794)
			(end -0.12065 0.2794)
			(stroke
				(width 0.1)
				(type default)
			)
			(layer "F.Fab")
		)
		(fp_line
			(start -0.12065 0.3048)
			(end -0.67945 0.3048)
			(stroke
				(width 0.1)
				(type default)
			)
			(layer "F.Fab")
		)
		(fp_line
			(start -0.12065 0.2794)
			(end -0.12065 0.3048)
			(stroke
				(width 0.1)
				(type default)
			)
			(layer "F.Fab")
		)
		(fp_line
			(start -0.12065 -0.2794)
			(end 0.12065 -0.2794)
			(stroke
				(width 0.1)
				(type default)
			)
			(layer "F.Fab")
		)
		(fp_line
			(start -0.12065 -0.305054)
			(end -0.12065 -0.2794)
			(stroke
				(width 0.1)
				(type default)
			)
			(layer "F.Fab")
		)
		(fp_line
			(start -0.67945 0.3048)
			(end -0.67945 -0.305054)
			(stroke
				(width 0.1)
				(type default)
			)
			(layer "F.Fab")
		)
		(fp_line
			(start -0.67945 -0.305054)
			(end -0.12065 -0.305054)
			(stroke
				(width 0.1)
				(type default)
			)
			(layer "F.Fab")
		)
		(pad "1" smd circle
			(at -0.40005 0 180)
			(size 0 0)
			(layers "F.Cu" "F.Mask" "F.Paste")
			(net "PWRGD_P1V8_AUX_R2")
		)
		(pad "2" smd circle
			(at 0.40005 0 180)
			(size 0 0)
			(layers "F.Cu" "F.Mask" "F.Paste")
			(net "GND")
		)
	)
	(footprint ""
		(layer "F.Cu")
		(at 57.073292 -28.062936 90)
		(property "Reference" "OSC1"
			(at -2.448306 1.397508 0)
			(unlocked yes)
			(layer "F.SilkS")
			(effects
				(font
					(size 0.7874 0.5842)
					(thickness 0.1524)
				)
				(justify left)
			)
		)
		(property "Value" ""
			(at 0 0 90)
			(layer "F.Fab")
			(effects
				(font
					(size 1.27 1.27)
				)
			)
		)
		(duplicate_pad_numbers_are_jumpers no)
		(fp_line
			(start 1.397 -1.761236)
			(end -1.397 -1.761236)
			(stroke
				(width 0.1524)
				(type default)
			)
			(layer "F.SilkS")
		)
		(fp_line
			(start -1.397 -1.761236)
			(end -1.397 1.761236)
			(stroke
				(width 0.1524)
				(type default)
			)
			(layer "F.SilkS")
		)
		(fp_line
			(start 1.397 1.761236)
			(end 1.397 -1.761236)
			(stroke
				(width 0.1524)
				(type default)
			)
			(layer "F.SilkS")
		)
		(fp_line
			(start -1.397 1.761236)
			(end 1.397 1.761236)
			(stroke
				(width 0.1524)
				(type default)
			)
			(layer "F.SilkS")
		)
		(fp_poly
			(pts
				(xy -1.69037 -0.799338) (xy -2.70637 -1.307592) (xy -2.706624 -0.291592)
			)
			(stroke
				(width 0)
				(type default)
			)
			(fill yes)
			(layer "F.SilkS")
		)
		(fp_line
			(start 1.299972 -1.649984)
			(end 1.299972 1.649984)
			(stroke
				(width 0.1)
				(type default)
			)
			(layer "F.Fab")
		)
		(fp_line
			(start -1.299972 -1.649984)
			(end 1.299972 -1.649984)
			(stroke
				(width 0.1)
				(type default)
			)
			(layer "F.Fab")
		)
		(fp_line
			(start 1.299972 1.649984)
			(end -1.299972 1.649984)
			(stroke
				(width 0.1)
				(type default)
			)
			(layer "F.Fab")
		)
		(fp_line
			(start -1.299972 1.649984)
			(end -1.299972 -1.649984)
			(stroke
				(width 0.1)
				(type default)
			)
			(layer "F.Fab")
		)
		(fp_poly
			(pts
				(xy -1.694688 -1.050036) (xy -2.710688 -1.558036) (xy -2.710688 -0.542036)
			)
			(stroke
				(width 0)
				(type default)
			)
			(fill yes)
			(layer "F.Fab")
		)
		(pad "1" smd rect
			(at -0.824992 -1.050036 90)
			(size 0.8636 1.1684)
			(layers "F.Cu" "F.Mask" "F.Paste")
			(net "PU_25M_BMC_CLK_EN")
		)
		(pad "2" smd rect
			(at -0.824992 1.050036 90)
			(size 0.8636 1.1684)
			(layers "F.Cu" "F.Mask" "F.Paste")
			(net "GND")
		)
		(pad "3" smd rect
			(at 0.824992 1.050036 90)
			(size 0.8636 1.1684)
			(layers "F.Cu" "F.Mask" "F.Paste")
			(net "BMC_CLK_25M_R")
		)
		(pad "4" smd rect
			(at 0.824992 -1.050036 90)
			(size 0.8636 1.1684)
			(layers "F.Cu" "F.Mask" "F.Paste")
			(net "P3V3_RGM")
		)
	)
	(footprint ""
		(layer "F.Cu")
		(at 54.84368 -25.911556 180)
		(property "Reference" "R376"
			(at 0 0 180)
			(layer "F.SilkS")
			(hide yes)
			(effects
				(font
					(size 1.27 1.27)
				)
			)
		)
		(property "Value" ""
			(at 0 0 180)
			(layer "F.Fab")
			(effects
				(font
					(size 1.27 1.27)
				)
			)
		)
		(duplicate_pad_numbers_are_jumpers no)
		(fp_line
			(start 0.7874 0.4064)
			(end -0.7874 0.4064)
			(stroke
				(width 0.1524)
				(type default)
			)
			(layer "F.SilkS")
		)
		(fp_line
			(start 0.7874 -0.4064)
			(end 0.7874 0.4064)
			(stroke
				(width 0.1524)
				(type default)
			)
			(layer "F.SilkS")
		)
		(fp_line
			(start -0.7874 0.4064)
			(end -0.7874 -0.4064)
			(stroke
				(width 0.1524)
				(type default)
			)
			(layer "F.SilkS")
		)
		(fp_line
			(start -0.7874 -0.4064)
			(end 0.7874 -0.4064)
			(stroke
				(width 0.1524)
				(type default)
			)
			(layer "F.SilkS")
		)
		(fp_line
			(start 0.67945 0.3048)
			(end 0.120396 0.3048)
			(stroke
				(width 0.1)
				(type default)
			)
			(layer "F.Fab")
		)
		(fp_line
			(start 0.67945 -0.3048)
			(end 0.67945 0.3048)
			(stroke
				(width 0.1)
				(type default)
			)
			(layer "F.Fab")
		)
		(fp_line
			(start 0.12065 -0.2794)
			(end 0.12065 -0.3048)
			(stroke
				(width 0.1)
				(type default)
			)
			(layer "F.Fab")
		)
		(fp_line
			(start 0.12065 -0.3048)
			(end 0.67945 -0.3048)
			(stroke
				(width 0.1)
				(type default)
			)
			(layer "F.Fab")
		)
		(fp_line
			(start 0.120396 0.3048)
			(end 0.120396 0.2794)
			(stroke
				(width 0.1)
				(type default)
			)
			(layer "F.Fab")
		)
		(fp_line
			(start 0.120396 0.2794)
			(end -0.12065 0.2794)
			(stroke
				(width 0.1)
				(type default)
			)
			(layer "F.Fab")
		)
		(fp_line
			(start -0.12065 0.3048)
			(end -0.67945 0.3048)
			(stroke
				(width 0.1)
				(type default)
			)
			(layer "F.Fab")
		)
		(fp_line
			(start -0.12065 0.2794)
			(end -0.12065 0.3048)
			(stroke
				(width 0.1)
				(type default)
			)
			(layer "F.Fab")
		)
		(fp_line
			(start -0.12065 -0.2794)
			(end 0.12065 -0.2794)
			(stroke
				(width 0.1)
				(type default)
			)
			(layer "F.Fab")
		)
		(fp_line
			(start -0.12065 -0.305054)
			(end -0.12065 -0.2794)
			(stroke
				(width 0.1)
				(type default)
			)
			(layer "F.Fab")
		)
		(fp_line
			(start -0.67945 0.3048)
			(end -0.67945 -0.305054)
			(stroke
				(width 0.1)
				(type default)
			)
			(layer "F.Fab")
		)
		(fp_line
			(start -0.67945 -0.305054)
			(end -0.12065 -0.305054)
			(stroke
				(width 0.1)
				(type default)
			)
			(layer "F.Fab")
		)
		(pad "1" smd circle
			(at -0.40005 0 180)
			(size 0 0)
			(layers "F.Cu" "F.Mask" "F.Paste")
			(net "P5V_AUX")
		)
		(pad "2" smd circle
			(at 0.40005 0 180)
			(size 0 0)
			(layers "F.Cu" "F.Mask" "F.Paste")
			(net "USB_OC0_EN")
		)
	)
	(footprint ""
		(layer "F.Cu")
		(at 32.766 -12.7 180)
		(property "Reference" "R390"
			(at 0 0 180)
			(layer "F.SilkS")
			(hide yes)
			(effects
				(font
					(size 1.27 1.27)
				)
			)
		)
		(property "Value" ""
			(at 0 0 180)
			(layer "F.Fab")
			(effects
				(font
					(size 1.27 1.27)
				)
			)
		)
		(duplicate_pad_numbers_are_jumpers no)
		(fp_line
			(start 0.7874 0.4064)
			(end -0.7874 0.4064)
			(stroke
				(width 0.1524)
				(type default)
			)
			(layer "F.SilkS")
		)
		(fp_line
			(start 0.7874 -0.4064)
			(end 0.7874 0.4064)
			(stroke
				(width 0.1524)
				(type default)
			)
			(layer "F.SilkS")
		)
		(fp_line
			(start -0.7874 0.4064)
			(end -0.7874 -0.4064)
			(stroke
				(width 0.1524)
				(type default)
			)
			(layer "F.SilkS")
		)
		(fp_line
			(start -0.7874 -0.4064)
			(end 0.7874 -0.4064)
			(stroke
				(width 0.1524)
				(type default)
			)
			(layer "F.SilkS")
		)
		(fp_line
			(start 0.67945 0.3048)
			(end 0.120396 0.3048)
			(stroke
				(width 0.1)
				(type default)
			)
			(layer "F.Fab")
		)
		(fp_line
			(start 0.67945 -0.3048)
			(end 0.67945 0.3048)
			(stroke
				(width 0.1)
				(type default)
			)
			(layer "F.Fab")
		)
		(fp_line
			(start 0.12065 -0.2794)
			(end 0.12065 -0.3048)
			(stroke
				(width 0.1)
				(type default)
			)
			(layer "F.Fab")
		)
		(fp_line
			(start 0.12065 -0.3048)
			(end 0.67945 -0.3048)
			(stroke
				(width 0.1)
				(type default)
			)
			(layer "F.Fab")
		)
		(fp_line
			(start 0.120396 0.3048)
			(end 0.120396 0.2794)
			(stroke
				(width 0.1)
				(type default)
			)
			(layer "F.Fab")
		)
		(fp_line
			(start 0.120396 0.2794)
			(end -0.12065 0.2794)
			(stroke
				(width 0.1)
				(type default)
			)
			(layer "F.Fab")
		)
		(fp_line
			(start -0.12065 0.3048)
			(end -0.67945 0.3048)
			(stroke
				(width 0.1)
				(type default)
			)
			(layer "F.Fab")
		)
		(fp_line
			(start -0.12065 0.2794)
			(end -0.12065 0.3048)
			(stroke
				(width 0.1)
				(type default)
			)
			(layer "F.Fab")
		)
		(fp_line
			(start -0.12065 -0.2794)
			(end 0.12065 -0.2794)
			(stroke
				(width 0.1)
				(type default)
			)
			(layer "F.Fab")
		)
		(fp_line
			(start -0.12065 -0.305054)
			(end -0.12065 -0.2794)
			(stroke
				(width 0.1)
				(type default)
			)
			(layer "F.Fab")
		)
		(fp_line
			(start -0.67945 0.3048)
			(end -0.67945 -0.305054)
			(stroke
				(width 0.1)
				(type default)
			)
			(layer "F.Fab")
		)
		(fp_line
			(start -0.67945 -0.305054)
			(end -0.12065 -0.305054)
			(stroke
				(width 0.1)
				(type default)
			)
			(layer "F.Fab")
		)
		(pad "1" smd circle
			(at -0.40005 0 180)
			(size 0 0)
			(layers "F.Cu" "F.Mask" "F.Paste")
			(net "FM_ID_LED")
		)
		(pad "2" smd circle
			(at 0.40005 0 180)
			(size 0 0)
			(layers "F.Cu" "F.Mask" "F.Paste")
			(net "FM_ID_R_LED")
		)
	)
	(footprint ""
		(layer "F.Cu")
		(at 10.287 -100.076 -90)
		(property "Reference" "R516"
			(at 0 0 270)
			(layer "F.SilkS")
			(hide yes)
			(effects
				(font
					(size 1.27 1.27)
				)
			)
		)
		(property "Value" ""
			(at 0 0 270)
			(layer "F.Fab")
			(effects
				(font
					(size 1.27 1.27)
				)
			)
		)
		(duplicate_pad_numbers_are_jumpers no)
		(fp_line
			(start -0.7874 0.4064)
			(end -0.7874 -0.4064)
			(stroke
				(width 0.1524)
				(type default)
			)
			(layer "F.SilkS")
		)
		(fp_line
			(start 0.7874 0.4064)
			(end -0.7874 0.4064)
			(stroke
				(width 0.1524)
				(type default)
			)
			(layer "F.SilkS")
		)
		(fp_line
			(start -0.7874 -0.4064)
			(end 0.7874 -0.4064)
			(stroke
				(width 0.1524)
				(type default)
			)
			(layer "F.SilkS")
		)
		(fp_line
			(start 0.7874 -0.4064)
			(end 0.7874 0.4064)
			(stroke
				(width 0.1524)
				(type default)
			)
			(layer "F.SilkS")
		)
		(fp_line
			(start -0.67945 0.3048)
			(end -0.67945 -0.305054)
			(stroke
				(width 0.1)
				(type default)
			)
			(layer "F.Fab")
		)
		(fp_line
			(start -0.12065 0.3048)
			(end -0.67945 0.3048)
			(stroke
				(width 0.1)
				(type default)
			)
			(layer "F.Fab")
		)
		(fp_line
			(start 0.120396 0.3048)
			(end 0.120396 0.2794)
			(stroke
				(width 0.1)
				(type default)
			)
			(layer "F.Fab")
		)
		(fp_line
			(start 0.67945 0.3048)
			(end 0.120396 0.3048)
			(stroke
				(width 0.1)
				(type default)
			)
			(layer "F.Fab")
		)
		(fp_line
			(start -0.12065 0.2794)
			(end -0.12065 0.3048)
			(stroke
				(width 0.1)
				(type default)
			)
			(layer "F.Fab")
		)
		(fp_line
			(start 0.120396 0.2794)
			(end -0.12065 0.2794)
			(stroke
				(width 0.1)
				(type default)
			)
			(layer "F.Fab")
		)
		(fp_line
			(start -0.12065 -0.2794)
			(end 0.12065 -0.2794)
			(stroke
				(width 0.1)
				(type default)
			)
			(layer "F.Fab")
		)
		(fp_line
			(start 0.12065 -0.2794)
			(end 0.12065 -0.3048)
			(stroke
				(width 0.1)
				(type default)
			)
			(layer "F.Fab")
		)
		(fp_line
			(start 0.12065 -0.3048)
			(end 0.67945 -0.3048)
			(stroke
				(width 0.1)
				(type default)
			)
			(layer "F.Fab")
		)
		(fp_line
			(start 0.67945 -0.3048)
			(end 0.67945 0.3048)
			(stroke
				(width 0.1)
				(type default)
			)
			(layer "F.Fab")
		)
		(fp_line
			(start -0.67945 -0.305054)
			(end -0.12065 -0.305054)
			(stroke
				(width 0.1)
				(type default)
			)
			(layer "F.Fab")
		)
		(fp_line
			(start -0.12065 -0.305054)
			(end -0.12065 -0.2794)
			(stroke
				(width 0.1)
				(type default)
			)
			(layer "F.Fab")
		)
		(pad "1" smd circle
			(at -0.40005 0 270)
			(size 0 0)
			(layers "F.Cu" "F.Mask" "F.Paste")
			(net "JTAG_SCM_PLD_TDI")
		)
		(pad "2" smd circle
			(at 0.40005 0 270)
			(size 0 0)
			(layers "F.Cu" "F.Mask" "F.Paste")
			(net "JTAG_SCM_CONN_TDI")
		)
	)
	(footprint ""
		(layer "F.Cu")
		(at 62.484 -30.861 90)
		(property "Reference" "R834"
			(at 0 0 90)
			(layer "F.SilkS")
			(hide yes)
			(effects
				(font
					(size 1.27 1.27)
				)
			)
		)
		(property "Value" ""
			(at 0 0 90)
			(layer "F.Fab")
			(effects
				(font
					(size 1.27 1.27)
				)
			)
		)
		(duplicate_pad_numbers_are_jumpers no)
		(fp_line
			(start 0.7874 -0.4064)
			(end 0.7874 0.4064)
			(stroke
				(width 0.1524)
				(type default)
			)
			(layer "F.SilkS")
		)
		(fp_line
			(start -0.7874 -0.4064)
			(end 0.7874 -0.4064)
			(stroke
				(width 0.1524)
				(type default)
			)
			(layer "F.SilkS")
		)
		(fp_line
			(start 0.7874 0.4064)
			(end -0.7874 0.4064)
			(stroke
				(width 0.1524)
				(type default)
			)
			(layer "F.SilkS")
		)
		(fp_line
			(start -0.7874 0.4064)
			(end -0.7874 -0.4064)
			(stroke
				(width 0.1524)
				(type default)
			)
			(layer "F.SilkS")
		)
		(fp_line
			(start -0.12065 -0.305054)
			(end -0.12065 -0.2794)
			(stroke
				(width 0.1)
				(type default)
			)
			(layer "F.Fab")
		)
		(fp_line
			(start -0.67945 -0.305054)
			(end -0.12065 -0.305054)
			(stroke
				(width 0.1)
				(type default)
			)
			(layer "F.Fab")
		)
		(fp_line
			(start 0.67945 -0.3048)
			(end 0.67945 0.3048)
			(stroke
				(width 0.1)
				(type default)
			)
			(layer "F.Fab")
		)
		(fp_line
			(start 0.12065 -0.3048)
			(end 0.67945 -0.3048)
			(stroke
				(width 0.1)
				(type default)
			)
			(layer "F.Fab")
		)
		(fp_line
			(start 0.12065 -0.2794)
			(end 0.12065 -0.3048)
			(stroke
				(width 0.1)
				(type default)
			)
			(layer "F.Fab")
		)
		(fp_line
			(start -0.12065 -0.2794)
			(end 0.12065 -0.2794)
			(stroke
				(width 0.1)
				(type default)
			)
			(layer "F.Fab")
		)
		(fp_line
			(start 0.120396 0.2794)
			(end -0.12065 0.2794)
			(stroke
				(width 0.1)
				(type default)
			)
			(layer "F.Fab")
		)
		(fp_line
			(start -0.12065 0.2794)
			(end -0.12065 0.3048)
			(stroke
				(width 0.1)
				(type default)
			)
			(layer "F.Fab")
		)
		(fp_line
			(start 0.67945 0.3048)
			(end 0.120396 0.3048)
			(stroke
				(width 0.1)
				(type default)
			)
			(layer "F.Fab")
		)
		(fp_line
			(start 0.120396 0.3048)
			(end 0.120396 0.2794)
			(stroke
				(width 0.1)
				(type default)
			)
			(layer "F.Fab")
		)
		(fp_line
			(start -0.12065 0.3048)
			(end -0.67945 0.3048)
			(stroke
				(width 0.1)
				(type default)
			)
			(layer "F.Fab")
		)
		(fp_line
			(start -0.67945 0.3048)
			(end -0.67945 -0.305054)
			(stroke
				(width 0.1)
				(type default)
			)
			(layer "F.Fab")
		)
		(pad "1" smd circle
			(at -0.40005 0 90)
			(size 0 0)
			(layers "F.Cu" "F.Mask" "F.Paste")
			(net "P3V3_RGM")
		)
		(pad "2" smd circle
			(at 0.40005 0 90)
			(size 0 0)
			(layers "F.Cu" "F.Mask" "F.Paste")
			(net "JTAG_SCM_TCK")
		)
	)
	(footprint ""
		(layer "F.Cu")
		(at 16.637 -46.3042 90)
		(property "Reference" "C304"
			(at 0 0 90)
			(layer "F.SilkS")
			(hide yes)
			(effects
				(font
					(size 1.27 1.27)
				)
			)
		)
		(property "Value" ""
			(at 0 0 90)
			(layer "F.Fab")
			(effects
				(font
					(size 1.27 1.27)
				)
			)
		)
		(duplicate_pad_numbers_are_jumpers no)
		(fp_line
			(start 0.7874 -0.4064)
			(end 0.7874 0.4064)
			(stroke
				(width 0.1524)
				(type default)
			)
			(layer "F.SilkS")
		)
		(fp_line
			(start -0.7874 -0.4064)
			(end 0.7874 -0.4064)
			(stroke
				(width 0.1524)
				(type default)
			)
			(layer "F.SilkS")
		)
		(fp_line
			(start 0.7874 0.4064)
			(end -0.7874 0.4064)
			(stroke
				(width 0.1524)
				(type default)
			)
			(layer "F.SilkS")
		)
		(fp_line
			(start -0.7874 0.4064)
			(end -0.7874 -0.4064)
			(stroke
				(width 0.1524)
				(type default)
			)
			(layer "F.SilkS")
		)
		(fp_line
			(start -0.12065 -0.305054)
			(end -0.12065 -0.2794)
			(stroke
				(width 0.1)
				(type default)
			)
			(layer "F.Fab")
		)
		(fp_line
			(start -0.67945 -0.305054)
			(end -0.12065 -0.305054)
			(stroke
				(width 0.1)
				(type default)
			)
			(layer "F.Fab")
		)
		(fp_line
			(start 0.67945 -0.3048)
			(end 0.67945 0.3048)
			(stroke
				(width 0.1)
				(type default)
			)
			(layer "F.Fab")
		)
		(fp_line
			(start 0.12065 -0.3048)
			(end 0.67945 -0.3048)
			(stroke
				(width 0.1)
				(type default)
			)
			(layer "F.Fab")
		)
		(fp_line
			(start 0.12065 -0.2794)
			(end 0.12065 -0.3048)
			(stroke
				(width 0.1)
				(type default)
			)
			(layer "F.Fab")
		)
		(fp_line
			(start -0.12065 -0.2794)
			(end 0.12065 -0.2794)
			(stroke
				(width 0.1)
				(type default)
			)
			(layer "F.Fab")
		)
		(fp_line
			(start 0.120396 0.2794)
			(end -0.12065 0.2794)
			(stroke
				(width 0.1)
				(type default)
			)
			(layer "F.Fab")
		)
		(fp_line
			(start -0.12065 0.2794)
			(end -0.12065 0.3048)
			(stroke
				(width 0.1)
				(type default)
			)
			(layer "F.Fab")
		)
		(fp_line
			(start 0.67945 0.3048)
			(end 0.120396 0.3048)
			(stroke
				(width 0.1)
				(type default)
			)
			(layer "F.Fab")
		)
		(fp_line
			(start 0.120396 0.3048)
			(end 0.120396 0.2794)
			(stroke
				(width 0.1)
				(type default)
			)
			(layer "F.Fab")
		)
		(fp_line
			(start -0.12065 0.3048)
			(end -0.67945 0.3048)
			(stroke
				(width 0.1)
				(type default)
			)
			(layer "F.Fab")
		)
		(fp_line
			(start -0.67945 0.3048)
			(end -0.67945 -0.305054)
			(stroke
				(width 0.1)
				(type default)
			)
			(layer "F.Fab")
		)
		(pad "1" smd circle
			(at -0.40005 0 90)
			(size 0 0)
			(layers "F.Cu" "F.Mask" "F.Paste")
			(net "P3V3_AUX")
		)
		(pad "2" smd circle
			(at 0.40005 0 90)
			(size 0 0)
			(layers "F.Cu" "F.Mask" "F.Paste")
			(net "GND")
		)
	)
	(footprint ""
		(layer "F.Cu")
		(at 37.063172 -83.816952 90)
		(property "Reference" "R648"
			(at 0 0 90)
			(layer "F.SilkS")
			(hide yes)
			(effects
				(font
					(size 1.27 1.27)
				)
			)
		)
		(property "Value" ""
			(at 0 0 90)
			(layer "F.Fab")
			(effects
				(font
					(size 1.27 1.27)
				)
			)
		)
		(duplicate_pad_numbers_are_jumpers no)
		(fp_line
			(start 0.7874 -0.4064)
			(end 0.7874 0.4064)
			(stroke
				(width 0.1524)
				(type default)
			)
			(layer "F.SilkS")
		)
		(fp_line
			(start -0.7874 -0.4064)
			(end 0.7874 -0.4064)
			(stroke
				(width 0.1524)
				(type default)
			)
			(layer "F.SilkS")
		)
		(fp_line
			(start 0.7874 0.4064)
			(end -0.7874 0.4064)
			(stroke
				(width 0.1524)
				(type default)
			)
			(layer "F.SilkS")
		)
		(fp_line
			(start -0.7874 0.4064)
			(end -0.7874 -0.4064)
			(stroke
				(width 0.1524)
				(type default)
			)
			(layer "F.SilkS")
		)
		(fp_line
			(start -0.12065 -0.305054)
			(end -0.12065 -0.2794)
			(stroke
				(width 0.1)
				(type default)
			)
			(layer "F.Fab")
		)
		(fp_line
			(start -0.67945 -0.305054)
			(end -0.12065 -0.305054)
			(stroke
				(width 0.1)
				(type default)
			)
			(layer "F.Fab")
		)
		(fp_line
			(start 0.67945 -0.3048)
			(end 0.67945 0.3048)
			(stroke
				(width 0.1)
				(type default)
			)
			(layer "F.Fab")
		)
		(fp_line
			(start 0.12065 -0.3048)
			(end 0.67945 -0.3048)
			(stroke
				(width 0.1)
				(type default)
			)
			(layer "F.Fab")
		)
		(fp_line
			(start 0.12065 -0.2794)
			(end 0.12065 -0.3048)
			(stroke
				(width 0.1)
				(type default)
			)
			(layer "F.Fab")
		)
		(fp_line
			(start -0.12065 -0.2794)
			(end 0.12065 -0.2794)
			(stroke
				(width 0.1)
				(type default)
			)
			(layer "F.Fab")
		)
		(fp_line
			(start 0.120396 0.2794)
			(end -0.12065 0.2794)
			(stroke
				(width 0.1)
				(type default)
			)
			(layer "F.Fab")
		)
		(fp_line
			(start -0.12065 0.2794)
			(end -0.12065 0.3048)
			(stroke
				(width 0.1)
				(type default)
			)
			(layer "F.Fab")
		)
		(fp_line
			(start 0.67945 0.3048)
			(end 0.120396 0.3048)
			(stroke
				(width 0.1)
				(type default)
			)
			(layer "F.Fab")
		)
		(fp_line
			(start 0.120396 0.3048)
			(end 0.120396 0.2794)
			(stroke
				(width 0.1)
				(type default)
			)
			(layer "F.Fab")
		)
		(fp_line
			(start -0.12065 0.3048)
			(end -0.67945 0.3048)
			(stroke
				(width 0.1)
				(type default)
			)
			(layer "F.Fab")
		)
		(fp_line
			(start -0.67945 0.3048)
			(end -0.67945 -0.305054)
			(stroke
				(width 0.1)
				(type default)
			)
			(layer "F.Fab")
		)
		(pad "1" smd circle
			(at -0.40005 0 90)
			(size 0 0)
			(layers "F.Cu" "F.Mask" "F.Paste")
			(net "EMMC_DT1_R")
		)
		(pad "2" smd circle
			(at 0.40005 0 90)
			(size 0 0)
			(layers "F.Cu" "F.Mask" "F.Paste")
			(net "BMC_EMMC_DT1")
		)
	)
	(footprint ""
		(layer "F.Cu")
		(at 69.005196 -37.288216 -90)
		(property "Reference" "C52"
			(at 0 0 270)
			(layer "F.SilkS")
			(hide yes)
			(effects
				(font
					(size 1.27 1.27)
				)
			)
		)
		(property "Value" ""
			(at 0 0 270)
			(layer "F.Fab")
			(effects
				(font
					(size 1.27 1.27)
				)
			)
		)
		(duplicate_pad_numbers_are_jumpers no)
		(fp_line
			(start -0.7874 0.4064)
			(end -0.7874 -0.4064)
			(stroke
				(width 0.1524)
				(type default)
			)
			(layer "F.SilkS")
		)
		(fp_line
			(start 0.7874 0.4064)
			(end -0.7874 0.4064)
			(stroke
				(width 0.1524)
				(type default)
			)
			(layer "F.SilkS")
		)
		(fp_line
			(start -0.7874 -0.4064)
			(end 0.7874 -0.4064)
			(stroke
				(width 0.1524)
				(type default)
			)
			(layer "F.SilkS")
		)
		(fp_line
			(start 0.7874 -0.4064)
			(end 0.7874 0.4064)
			(stroke
				(width 0.1524)
				(type default)
			)
			(layer "F.SilkS")
		)
		(fp_line
			(start -0.67945 0.3048)
			(end -0.67945 -0.305054)
			(stroke
				(width 0.1)
				(type default)
			)
			(layer "F.Fab")
		)
		(fp_line
			(start -0.12065 0.3048)
			(end -0.67945 0.3048)
			(stroke
				(width 0.1)
				(type default)
			)
			(layer "F.Fab")
		)
		(fp_line
			(start 0.120396 0.3048)
			(end 0.120396 0.2794)
			(stroke
				(width 0.1)
				(type default)
			)
			(layer "F.Fab")
		)
		(fp_line
			(start 0.67945 0.3048)
			(end 0.120396 0.3048)
			(stroke
				(width 0.1)
				(type default)
			)
			(layer "F.Fab")
		)
		(fp_line
			(start -0.12065 0.2794)
			(end -0.12065 0.3048)
			(stroke
				(width 0.1)
				(type default)
			)
			(layer "F.Fab")
		)
		(fp_line
			(start 0.120396 0.2794)
			(end -0.12065 0.2794)
			(stroke
				(width 0.1)
				(type default)
			)
			(layer "F.Fab")
		)
		(fp_line
			(start -0.12065 -0.2794)
			(end 0.12065 -0.2794)
			(stroke
				(width 0.1)
				(type default)
			)
			(layer "F.Fab")
		)
		(fp_line
			(start 0.12065 -0.2794)
			(end 0.12065 -0.3048)
			(stroke
				(width 0.1)
				(type default)
			)
			(layer "F.Fab")
		)
		(fp_line
			(start 0.12065 -0.3048)
			(end 0.67945 -0.3048)
			(stroke
				(width 0.1)
				(type default)
			)
			(layer "F.Fab")
		)
		(fp_line
			(start 0.67945 -0.3048)
			(end 0.67945 0.3048)
			(stroke
				(width 0.1)
				(type default)
			)
			(layer "F.Fab")
		)
		(fp_line
			(start -0.67945 -0.305054)
			(end -0.12065 -0.305054)
			(stroke
				(width 0.1)
				(type default)
			)
			(layer "F.Fab")
		)
		(fp_line
			(start -0.12065 -0.305054)
			(end -0.12065 -0.2794)
			(stroke
				(width 0.1)
				(type default)
			)
			(layer "F.Fab")
		)
		(pad "1" smd circle
			(at -0.40005 0 270)
			(size 0 0)
			(layers "F.Cu" "F.Mask" "F.Paste")
			(net "P1V0_STBY_PLAVDD")
		)
		(pad "2" smd circle
			(at 0.40005 0 270)
			(size 0 0)
			(layers "F.Cu" "F.Mask" "F.Paste")
			(net "GND")
		)
	)
	(footprint ""
		(layer "F.Cu")
		(at 12.319 -88.392 180)
		(property "Reference" "R526"
			(at 0 0 180)
			(layer "F.SilkS")
			(hide yes)
			(effects
				(font
					(size 1.27 1.27)
				)
			)
		)
		(property "Value" ""
			(at 0 0 180)
			(layer "F.Fab")
			(effects
				(font
					(size 1.27 1.27)
				)
			)
		)
		(duplicate_pad_numbers_are_jumpers no)
		(fp_line
			(start 0.7874 0.4064)
			(end -0.7874 0.4064)
			(stroke
				(width 0.1524)
				(type default)
			)
			(layer "F.SilkS")
		)
		(fp_line
			(start 0.7874 -0.4064)
			(end 0.7874 0.4064)
			(stroke
				(width 0.1524)
				(type default)
			)
			(layer "F.SilkS")
		)
		(fp_line
			(start -0.7874 0.4064)
			(end -0.7874 -0.4064)
			(stroke
				(width 0.1524)
				(type default)
			)
			(layer "F.SilkS")
		)
		(fp_line
			(start -0.7874 -0.4064)
			(end 0.7874 -0.4064)
			(stroke
				(width 0.1524)
				(type default)
			)
			(layer "F.SilkS")
		)
		(fp_line
			(start 0.67945 0.3048)
			(end 0.120396 0.3048)
			(stroke
				(width 0.1)
				(type default)
			)
			(layer "F.Fab")
		)
		(fp_line
			(start 0.67945 -0.3048)
			(end 0.67945 0.3048)
			(stroke
				(width 0.1)
				(type default)
			)
			(layer "F.Fab")
		)
		(fp_line
			(start 0.12065 -0.2794)
			(end 0.12065 -0.3048)
			(stroke
				(width 0.1)
				(type default)
			)
			(layer "F.Fab")
		)
		(fp_line
			(start 0.12065 -0.3048)
			(end 0.67945 -0.3048)
			(stroke
				(width 0.1)
				(type default)
			)
			(layer "F.Fab")
		)
		(fp_line
			(start 0.120396 0.3048)
			(end 0.120396 0.2794)
			(stroke
				(width 0.1)
				(type default)
			)
			(layer "F.Fab")
		)
		(fp_line
			(start 0.120396 0.2794)
			(end -0.12065 0.2794)
			(stroke
				(width 0.1)
				(type default)
			)
			(layer "F.Fab")
		)
		(fp_line
			(start -0.12065 0.3048)
			(end -0.67945 0.3048)
			(stroke
				(width 0.1)
				(type default)
			)
			(layer "F.Fab")
		)
		(fp_line
			(start -0.12065 0.2794)
			(end -0.12065 0.3048)
			(stroke
				(width 0.1)
				(type default)
			)
			(layer "F.Fab")
		)
		(fp_line
			(start -0.12065 -0.2794)
			(end 0.12065 -0.2794)
			(stroke
				(width 0.1)
				(type default)
			)
			(layer "F.Fab")
		)
		(fp_line
			(start -0.12065 -0.305054)
			(end -0.12065 -0.2794)
			(stroke
				(width 0.1)
				(type default)
			)
			(layer "F.Fab")
		)
		(fp_line
			(start -0.67945 0.3048)
			(end -0.67945 -0.305054)
			(stroke
				(width 0.1)
				(type default)
			)
			(layer "F.Fab")
		)
		(fp_line
			(start -0.67945 -0.305054)
			(end -0.12065 -0.305054)
			(stroke
				(width 0.1)
				(type default)
			)
			(layer "F.Fab")
		)
		(pad "1" smd circle
			(at -0.40005 0 180)
			(size 0 0)
			(layers "F.Cu" "F.Mask" "F.Paste")
			(net "BMC_CPLD_GPIO_7_R2")
		)
		(pad "2" smd circle
			(at 0.40005 0 180)
			(size 0 0)
			(layers "F.Cu" "F.Mask" "F.Paste")
			(net "BMC_CPLD_GPIO_7")
		)
	)
	(footprint ""
		(layer "F.Cu")
		(at 57.023 -76.3524 180)
		(property "Reference" "R182"
			(at 0 0 180)
			(layer "F.SilkS")
			(hide yes)
			(effects
				(font
					(size 1.27 1.27)
				)
			)
		)
		(property "Value" ""
			(at 0 0 180)
			(layer "F.Fab")
			(effects
				(font
					(size 1.27 1.27)
				)
			)
		)
		(duplicate_pad_numbers_are_jumpers no)
		(fp_line
			(start 0.7874 0.4064)
			(end -0.7874 0.4064)
			(stroke
				(width 0.1524)
				(type default)
			)
			(layer "F.SilkS")
		)
		(fp_line
			(start 0.7874 -0.4064)
			(end 0.7874 0.4064)
			(stroke
				(width 0.1524)
				(type default)
			)
			(layer "F.SilkS")
		)
		(fp_line
			(start -0.7874 0.4064)
			(end -0.7874 -0.4064)
			(stroke
				(width 0.1524)
				(type default)
			)
			(layer "F.SilkS")
		)
		(fp_line
			(start -0.7874 -0.4064)
			(end 0.7874 -0.4064)
			(stroke
				(width 0.1524)
				(type default)
			)
			(layer "F.SilkS")
		)
		(fp_line
			(start 0.67945 0.3048)
			(end 0.120396 0.3048)
			(stroke
				(width 0.1)
				(type default)
			)
			(layer "F.Fab")
		)
		(fp_line
			(start 0.67945 -0.3048)
			(end 0.67945 0.3048)
			(stroke
				(width 0.1)
				(type default)
			)
			(layer "F.Fab")
		)
		(fp_line
			(start 0.12065 -0.2794)
			(end 0.12065 -0.3048)
			(stroke
				(width 0.1)
				(type default)
			)
			(layer "F.Fab")
		)
		(fp_line
			(start 0.12065 -0.3048)
			(end 0.67945 -0.3048)
			(stroke
				(width 0.1)
				(type default)
			)
			(layer "F.Fab")
		)
		(fp_line
			(start 0.120396 0.3048)
			(end 0.120396 0.2794)
			(stroke
				(width 0.1)
				(type default)
			)
			(layer "F.Fab")
		)
		(fp_line
			(start 0.120396 0.2794)
			(end -0.12065 0.2794)
			(stroke
				(width 0.1)
				(type default)
			)
			(layer "F.Fab")
		)
		(fp_line
			(start -0.12065 0.3048)
			(end -0.67945 0.3048)
			(stroke
				(width 0.1)
				(type default)
			)
			(layer "F.Fab")
		)
		(fp_line
			(start -0.12065 0.2794)
			(end -0.12065 0.3048)
			(stroke
				(width 0.1)
				(type default)
			)
			(layer "F.Fab")
		)
		(fp_line
			(start -0.12065 -0.2794)
			(end 0.12065 -0.2794)
			(stroke
				(width 0.1)
				(type default)
			)
			(layer "F.Fab")
		)
		(fp_line
			(start -0.12065 -0.305054)
			(end -0.12065 -0.2794)
			(stroke
				(width 0.1)
				(type default)
			)
			(layer "F.Fab")
		)
		(fp_line
			(start -0.67945 0.3048)
			(end -0.67945 -0.305054)
			(stroke
				(width 0.1)
				(type default)
			)
			(layer "F.Fab")
		)
		(fp_line
			(start -0.67945 -0.305054)
			(end -0.12065 -0.305054)
			(stroke
				(width 0.1)
				(type default)
			)
			(layer "F.Fab")
		)
		(pad "1" smd circle
			(at -0.40005 0 180)
			(size 0 0)
			(layers "F.Cu" "F.Mask" "F.Paste")
			(net "GND")
		)
		(pad "2" smd circle
			(at 0.40005 0 180)
			(size 0 0)
			(layers "F.Cu" "F.Mask" "F.Paste")
			(net "FLASH_LATCH_D")
		)
	)
	(footprint ""
		(layer "F.Cu")
		(at 48.6156 -30.867604 90)
		(property "Reference" "R245"
			(at 0 0 90)
			(layer "F.SilkS")
			(hide yes)
			(effects
				(font
					(size 1.27 1.27)
				)
			)
		)
		(property "Value" ""
			(at 0 0 90)
			(layer "F.Fab")
			(effects
				(font
					(size 1.27 1.27)
				)
			)
		)
		(duplicate_pad_numbers_are_jumpers no)
		(fp_line
			(start 0.7874 -0.4064)
			(end 0.7874 0.4064)
			(stroke
				(width 0.1524)
				(type default)
			)
			(layer "F.SilkS")
		)
		(fp_line
			(start -0.7874 -0.4064)
			(end 0.7874 -0.4064)
			(stroke
				(width 0.1524)
				(type default)
			)
			(layer "F.SilkS")
		)
		(fp_line
			(start 0.7874 0.4064)
			(end -0.7874 0.4064)
			(stroke
				(width 0.1524)
				(type default)
			)
			(layer "F.SilkS")
		)
		(fp_line
			(start -0.7874 0.4064)
			(end -0.7874 -0.4064)
			(stroke
				(width 0.1524)
				(type default)
			)
			(layer "F.SilkS")
		)
		(fp_line
			(start -0.12065 -0.305054)
			(end -0.12065 -0.2794)
			(stroke
				(width 0.1)
				(type default)
			)
			(layer "F.Fab")
		)
		(fp_line
			(start -0.67945 -0.305054)
			(end -0.12065 -0.305054)
			(stroke
				(width 0.1)
				(type default)
			)
			(layer "F.Fab")
		)
		(fp_line
			(start 0.67945 -0.3048)
			(end 0.67945 0.3048)
			(stroke
				(width 0.1)
				(type default)
			)
			(layer "F.Fab")
		)
		(fp_line
			(start 0.12065 -0.3048)
			(end 0.67945 -0.3048)
			(stroke
				(width 0.1)
				(type default)
			)
			(layer "F.Fab")
		)
		(fp_line
			(start 0.12065 -0.2794)
			(end 0.12065 -0.3048)
			(stroke
				(width 0.1)
				(type default)
			)
			(layer "F.Fab")
		)
		(fp_line
			(start -0.12065 -0.2794)
			(end 0.12065 -0.2794)
			(stroke
				(width 0.1)
				(type default)
			)
			(layer "F.Fab")
		)
		(fp_line
			(start 0.120396 0.2794)
			(end -0.12065 0.2794)
			(stroke
				(width 0.1)
				(type default)
			)
			(layer "F.Fab")
		)
		(fp_line
			(start -0.12065 0.2794)
			(end -0.12065 0.3048)
			(stroke
				(width 0.1)
				(type default)
			)
			(layer "F.Fab")
		)
		(fp_line
			(start 0.67945 0.3048)
			(end 0.120396 0.3048)
			(stroke
				(width 0.1)
				(type default)
			)
			(layer "F.Fab")
		)
		(fp_line
			(start 0.120396 0.3048)
			(end 0.120396 0.2794)
			(stroke
				(width 0.1)
				(type default)
			)
			(layer "F.Fab")
		)
		(fp_line
			(start -0.12065 0.3048)
			(end -0.67945 0.3048)
			(stroke
				(width 0.1)
				(type default)
			)
			(layer "F.Fab")
		)
		(fp_line
			(start -0.67945 0.3048)
			(end -0.67945 -0.305054)
			(stroke
				(width 0.1)
				(type default)
			)
			(layer "F.Fab")
		)
		(pad "1" smd circle
			(at -0.40005 0 90)
			(size 0 0)
			(layers "F.Cu" "F.Mask" "F.Paste")
			(net "P3V3_AUX")
		)
		(pad "2" smd circle
			(at 0.40005 0 90)
			(size 0 0)
			(layers "F.Cu" "F.Mask" "F.Paste")
			(net "SMB_BMC_MM1_SDA")
		)
	)
	(footprint ""
		(layer "F.Cu")
		(at 24.892 -83.7438 90)
		(property "Reference" "R123"
			(at 0 0 90)
			(layer "F.SilkS")
			(hide yes)
			(effects
				(font
					(size 1.27 1.27)
				)
			)
		)
		(property "Value" ""
			(at 0 0 90)
			(layer "F.Fab")
			(effects
				(font
					(size 1.27 1.27)
				)
			)
		)
		(duplicate_pad_numbers_are_jumpers no)
		(fp_line
			(start 0.7874 -0.4064)
			(end 0.7874 0.4064)
			(stroke
				(width 0.1524)
				(type default)
			)
			(layer "F.SilkS")
		)
		(fp_line
			(start -0.7874 -0.4064)
			(end 0.7874 -0.4064)
			(stroke
				(width 0.1524)
				(type default)
			)
			(layer "F.SilkS")
		)
		(fp_line
			(start 0.7874 0.4064)
			(end -0.7874 0.4064)
			(stroke
				(width 0.1524)
				(type default)
			)
			(layer "F.SilkS")
		)
		(fp_line
			(start -0.7874 0.4064)
			(end -0.7874 -0.4064)
			(stroke
				(width 0.1524)
				(type default)
			)
			(layer "F.SilkS")
		)
		(fp_line
			(start -0.12065 -0.305054)
			(end -0.12065 -0.2794)
			(stroke
				(width 0.1)
				(type default)
			)
			(layer "F.Fab")
		)
		(fp_line
			(start -0.67945 -0.305054)
			(end -0.12065 -0.305054)
			(stroke
				(width 0.1)
				(type default)
			)
			(layer "F.Fab")
		)
		(fp_line
			(start 0.67945 -0.3048)
			(end 0.67945 0.3048)
			(stroke
				(width 0.1)
				(type default)
			)
			(layer "F.Fab")
		)
		(fp_line
			(start 0.12065 -0.3048)
			(end 0.67945 -0.3048)
			(stroke
				(width 0.1)
				(type default)
			)
			(layer "F.Fab")
		)
		(fp_line
			(start 0.12065 -0.2794)
			(end 0.12065 -0.3048)
			(stroke
				(width 0.1)
				(type default)
			)
			(layer "F.Fab")
		)
		(fp_line
			(start -0.12065 -0.2794)
			(end 0.12065 -0.2794)
			(stroke
				(width 0.1)
				(type default)
			)
			(layer "F.Fab")
		)
		(fp_line
			(start 0.120396 0.2794)
			(end -0.12065 0.2794)
			(stroke
				(width 0.1)
				(type default)
			)
			(layer "F.Fab")
		)
		(fp_line
			(start -0.12065 0.2794)
			(end -0.12065 0.3048)
			(stroke
				(width 0.1)
				(type default)
			)
			(layer "F.Fab")
		)
		(fp_line
			(start 0.67945 0.3048)
			(end 0.120396 0.3048)
			(stroke
				(width 0.1)
				(type default)
			)
			(layer "F.Fab")
		)
		(fp_line
			(start 0.120396 0.3048)
			(end 0.120396 0.2794)
			(stroke
				(width 0.1)
				(type default)
			)
			(layer "F.Fab")
		)
		(fp_line
			(start -0.12065 0.3048)
			(end -0.67945 0.3048)
			(stroke
				(width 0.1)
				(type default)
			)
			(layer "F.Fab")
		)
		(fp_line
			(start -0.67945 0.3048)
			(end -0.67945 -0.305054)
			(stroke
				(width 0.1)
				(type default)
			)
			(layer "F.Fab")
		)
		(pad "1" smd circle
			(at -0.40005 0 90)
			(size 0 0)
			(layers "F.Cu" "F.Mask" "F.Paste")
			(net "FM_TPM_PRSNT_1_N")
		)
		(pad "2" smd circle
			(at 0.40005 0 90)
			(size 0 0)
			(layers "F.Cu" "F.Mask" "F.Paste")
			(net "FM_TPM_PRSNT_1_R_N")
		)
	)
	(footprint ""
		(layer "F.Cu")
		(at 68.189094 -97.877122)
		(property "Reference" "R500"
			(at 0 0 0)
			(layer "F.SilkS")
			(hide yes)
			(effects
				(font
					(size 1.27 1.27)
				)
			)
		)
		(property "Value" ""
			(at 0 0 0)
			(layer "F.Fab")
			(effects
				(font
					(size 1.27 1.27)
				)
			)
		)
		(duplicate_pad_numbers_are_jumpers no)
		(fp_line
			(start -0.7874 -0.4064)
			(end 0.7874 -0.4064)
			(stroke
				(width 0.1524)
				(type default)
			)
			(layer "F.SilkS")
		)
		(fp_line
			(start -0.7874 0.4064)
			(end -0.7874 -0.4064)
			(stroke
				(width 0.1524)
				(type default)
			)
			(layer "F.SilkS")
		)
		(fp_line
			(start 0.7874 -0.4064)
			(end 0.7874 0.4064)
			(stroke
				(width 0.1524)
				(type default)
			)
			(layer "F.SilkS")
		)
		(fp_line
			(start 0.7874 0.4064)
			(end -0.7874 0.4064)
			(stroke
				(width 0.1524)
				(type default)
			)
			(layer "F.SilkS")
		)
		(fp_line
			(start -0.67945 -0.305054)
			(end -0.12065 -0.305054)
			(stroke
				(width 0.1)
				(type default)
			)
			(layer "F.Fab")
		)
		(fp_line
			(start -0.67945 0.3048)
			(end -0.67945 -0.305054)
			(stroke
				(width 0.1)
				(type default)
			)
			(layer "F.Fab")
		)
		(fp_line
			(start -0.12065 -0.305054)
			(end -0.12065 -0.2794)
			(stroke
				(width 0.1)
				(type default)
			)
			(layer "F.Fab")
		)
		(fp_line
			(start -0.12065 -0.2794)
			(end 0.12065 -0.2794)
			(stroke
				(width 0.1)
				(type default)
			)
			(layer "F.Fab")
		)
		(fp_line
			(start -0.12065 0.2794)
			(end -0.12065 0.3048)
			(stroke
				(width 0.1)
				(type default)
			)
			(layer "F.Fab")
		)
		(fp_line
			(start -0.12065 0.3048)
			(end -0.67945 0.3048)
			(stroke
				(width 0.1)
				(type default)
			)
			(layer "F.Fab")
		)
		(fp_line
			(start 0.120396 0.2794)
			(end -0.12065 0.2794)
			(stroke
				(width 0.1)
				(type default)
			)
			(layer "F.Fab")
		)
		(fp_line
			(start 0.120396 0.3048)
			(end 0.120396 0.2794)
			(stroke
				(width 0.1)
				(type default)
			)
			(layer "F.Fab")
		)
		(fp_line
			(start 0.12065 -0.3048)
			(end 0.67945 -0.3048)
			(stroke
				(width 0.1)
				(type default)
			)
			(layer "F.Fab")
		)
		(fp_line
			(start 0.12065 -0.2794)
			(end 0.12065 -0.3048)
			(stroke
				(width 0.1)
				(type default)
			)
			(layer "F.Fab")
		)
		(fp_line
			(start 0.67945 -0.3048)
			(end 0.67945 0.3048)
			(stroke
				(width 0.1)
				(type default)
			)
			(layer "F.Fab")
		)
		(fp_line
			(start 0.67945 0.3048)
			(end 0.120396 0.3048)
			(stroke
				(width 0.1)
				(type default)
			)
			(layer "F.Fab")
		)
		(pad "1" smd circle
			(at -0.40005 0)
			(size 0 0)
			(layers "F.Cu" "F.Mask" "F.Paste")
			(net "SPI_TPM_CS_N_R")
		)
		(pad "2" smd circle
			(at 0.40005 0)
			(size 0 0)
			(layers "F.Cu" "F.Mask" "F.Paste")
			(net "SPI_TPM_CS_R_N")
		)
	)
	(footprint ""
		(layer "F.Cu")
		(at 47.567088 -20.435062 90)
		(property "Reference" "C179"
			(at 0 0 90)
			(layer "F.SilkS")
			(hide yes)
			(effects
				(font
					(size 1.27 1.27)
				)
			)
		)
		(property "Value" ""
			(at 0 0 90)
			(layer "F.Fab")
			(effects
				(font
					(size 1.27 1.27)
				)
			)
		)
		(duplicate_pad_numbers_are_jumpers no)
		(fp_line
			(start 0.7874 -0.4064)
			(end 0.7874 0.4064)
			(stroke
				(width 0.1524)
				(type default)
			)
			(layer "F.SilkS")
		)
		(fp_line
			(start -0.7874 -0.4064)
			(end 0.7874 -0.4064)
			(stroke
				(width 0.1524)
				(type default)
			)
			(layer "F.SilkS")
		)
		(fp_line
			(start 0.7874 0.4064)
			(end -0.7874 0.4064)
			(stroke
				(width 0.1524)
				(type default)
			)
			(layer "F.SilkS")
		)
		(fp_line
			(start -0.7874 0.4064)
			(end -0.7874 -0.4064)
			(stroke
				(width 0.1524)
				(type default)
			)
			(layer "F.SilkS")
		)
		(fp_line
			(start -0.12065 -0.305054)
			(end -0.12065 -0.2794)
			(stroke
				(width 0.1)
				(type default)
			)
			(layer "F.Fab")
		)
		(fp_line
			(start -0.67945 -0.305054)
			(end -0.12065 -0.305054)
			(stroke
				(width 0.1)
				(type default)
			)
			(layer "F.Fab")
		)
		(fp_line
			(start 0.67945 -0.3048)
			(end 0.67945 0.3048)
			(stroke
				(width 0.1)
				(type default)
			)
			(layer "F.Fab")
		)
		(fp_line
			(start 0.12065 -0.3048)
			(end 0.67945 -0.3048)
			(stroke
				(width 0.1)
				(type default)
			)
			(layer "F.Fab")
		)
		(fp_line
			(start 0.12065 -0.2794)
			(end 0.12065 -0.3048)
			(stroke
				(width 0.1)
				(type default)
			)
			(layer "F.Fab")
		)
		(fp_line
			(start -0.12065 -0.2794)
			(end 0.12065 -0.2794)
			(stroke
				(width 0.1)
				(type default)
			)
			(layer "F.Fab")
		)
		(fp_line
			(start 0.120396 0.2794)
			(end -0.12065 0.2794)
			(stroke
				(width 0.1)
				(type default)
			)
			(layer "F.Fab")
		)
		(fp_line
			(start -0.12065 0.2794)
			(end -0.12065 0.3048)
			(stroke
				(width 0.1)
				(type default)
			)
			(layer "F.Fab")
		)
		(fp_line
			(start 0.67945 0.3048)
			(end 0.120396 0.3048)
			(stroke
				(width 0.1)
				(type default)
			)
			(layer "F.Fab")
		)
		(fp_line
			(start 0.120396 0.3048)
			(end 0.120396 0.2794)
			(stroke
				(width 0.1)
				(type default)
			)
			(layer "F.Fab")
		)
		(fp_line
			(start -0.12065 0.3048)
			(end -0.67945 0.3048)
			(stroke
				(width 0.1)
				(type default)
			)
			(layer "F.Fab")
		)
		(fp_line
			(start -0.67945 0.3048)
			(end -0.67945 -0.305054)
			(stroke
				(width 0.1)
				(type default)
			)
			(layer "F.Fab")
		)
		(pad "1" smd circle
			(at -0.40005 0 90)
			(size 0 0)
			(layers "F.Cu" "F.Mask" "F.Paste")
			(net "P5V_USB_REAR")
		)
		(pad "2" smd circle
			(at 0.40005 0 90)
			(size 0 0)
			(layers "F.Cu" "F.Mask" "F.Paste")
			(net "GND")
		)
	)
	(footprint ""
		(layer "F.Cu")
		(at 67.818 -106.2736 -90)
		(property "Reference" "R824"
			(at 0 0 270)
			(layer "F.SilkS")
			(hide yes)
			(effects
				(font
					(size 1.27 1.27)
				)
			)
		)
		(property "Value" ""
			(at 0 0 270)
			(layer "F.Fab")
			(effects
				(font
					(size 1.27 1.27)
				)
			)
		)
		(duplicate_pad_numbers_are_jumpers no)
		(fp_line
			(start -0.7874 0.4064)
			(end -0.7874 -0.4064)
			(stroke
				(width 0.1524)
				(type default)
			)
			(layer "F.SilkS")
		)
		(fp_line
			(start 0.7874 0.4064)
			(end -0.7874 0.4064)
			(stroke
				(width 0.1524)
				(type default)
			)
			(layer "F.SilkS")
		)
		(fp_line
			(start -0.7874 -0.4064)
			(end 0.7874 -0.4064)
			(stroke
				(width 0.1524)
				(type default)
			)
			(layer "F.SilkS")
		)
		(fp_line
			(start 0.7874 -0.4064)
			(end 0.7874 0.4064)
			(stroke
				(width 0.1524)
				(type default)
			)
			(layer "F.SilkS")
		)
		(fp_line
			(start -0.67945 0.3048)
			(end -0.67945 -0.305054)
			(stroke
				(width 0.1)
				(type default)
			)
			(layer "F.Fab")
		)
		(fp_line
			(start -0.12065 0.3048)
			(end -0.67945 0.3048)
			(stroke
				(width 0.1)
				(type default)
			)
			(layer "F.Fab")
		)
		(fp_line
			(start 0.120396 0.3048)
			(end 0.120396 0.2794)
			(stroke
				(width 0.1)
				(type default)
			)
			(layer "F.Fab")
		)
		(fp_line
			(start 0.67945 0.3048)
			(end 0.120396 0.3048)
			(stroke
				(width 0.1)
				(type default)
			)
			(layer "F.Fab")
		)
		(fp_line
			(start -0.12065 0.2794)
			(end -0.12065 0.3048)
			(stroke
				(width 0.1)
				(type default)
			)
			(layer "F.Fab")
		)
		(fp_line
			(start 0.120396 0.2794)
			(end -0.12065 0.2794)
			(stroke
				(width 0.1)
				(type default)
			)
			(layer "F.Fab")
		)
		(fp_line
			(start -0.12065 -0.2794)
			(end 0.12065 -0.2794)
			(stroke
				(width 0.1)
				(type default)
			)
			(layer "F.Fab")
		)
		(fp_line
			(start 0.12065 -0.2794)
			(end 0.12065 -0.3048)
			(stroke
				(width 0.1)
				(type default)
			)
			(layer "F.Fab")
		)
		(fp_line
			(start 0.12065 -0.3048)
			(end 0.67945 -0.3048)
			(stroke
				(width 0.1)
				(type default)
			)
			(layer "F.Fab")
		)
		(fp_line
			(start 0.67945 -0.3048)
			(end 0.67945 0.3048)
			(stroke
				(width 0.1)
				(type default)
			)
			(layer "F.Fab")
		)
		(fp_line
			(start -0.67945 -0.305054)
			(end -0.12065 -0.305054)
			(stroke
				(width 0.1)
				(type default)
			)
			(layer "F.Fab")
		)
		(fp_line
			(start -0.12065 -0.305054)
			(end -0.12065 -0.2794)
			(stroke
				(width 0.1)
				(type default)
			)
			(layer "F.Fab")
		)
		(pad "1" smd circle
			(at -0.40005 0 270)
			(size 0 0)
			(layers "F.Cu" "F.Mask" "F.Paste")
			(net "FM_VIRTUAL_RESEAT")
		)
		(pad "2" smd circle
			(at 0.40005 0 270)
			(size 0 0)
			(layers "F.Cu" "F.Mask" "F.Paste")
			(net "FM_VIRTUAL_RESEAT_BMC")
		)
	)
	(footprint ""
		(layer "F.Cu")
		(at 60.7314 -64.0588 90)
		(property "Reference" "R174"
			(at 0 0 90)
			(layer "F.SilkS")
			(hide yes)
			(effects
				(font
					(size 1.27 1.27)
				)
			)
		)
		(property "Value" ""
			(at 0 0 90)
			(layer "F.Fab")
			(effects
				(font
					(size 1.27 1.27)
				)
			)
		)
		(duplicate_pad_numbers_are_jumpers no)
		(fp_line
			(start 0.7874 -0.4064)
			(end 0.7874 0.4064)
			(stroke
				(width 0.1524)
				(type default)
			)
			(layer "F.SilkS")
		)
		(fp_line
			(start -0.7874 -0.4064)
			(end 0.7874 -0.4064)
			(stroke
				(width 0.1524)
				(type default)
			)
			(layer "F.SilkS")
		)
		(fp_line
			(start 0.7874 0.4064)
			(end -0.7874 0.4064)
			(stroke
				(width 0.1524)
				(type default)
			)
			(layer "F.SilkS")
		)
		(fp_line
			(start -0.7874 0.4064)
			(end -0.7874 -0.4064)
			(stroke
				(width 0.1524)
				(type default)
			)
			(layer "F.SilkS")
		)
		(fp_line
			(start -0.12065 -0.305054)
			(end -0.12065 -0.2794)
			(stroke
				(width 0.1)
				(type default)
			)
			(layer "F.Fab")
		)
		(fp_line
			(start -0.67945 -0.305054)
			(end -0.12065 -0.305054)
			(stroke
				(width 0.1)
				(type default)
			)
			(layer "F.Fab")
		)
		(fp_line
			(start 0.67945 -0.3048)
			(end 0.67945 0.3048)
			(stroke
				(width 0.1)
				(type default)
			)
			(layer "F.Fab")
		)
		(fp_line
			(start 0.12065 -0.3048)
			(end 0.67945 -0.3048)
			(stroke
				(width 0.1)
				(type default)
			)
			(layer "F.Fab")
		)
		(fp_line
			(start 0.12065 -0.2794)
			(end 0.12065 -0.3048)
			(stroke
				(width 0.1)
				(type default)
			)
			(layer "F.Fab")
		)
		(fp_line
			(start -0.12065 -0.2794)
			(end 0.12065 -0.2794)
			(stroke
				(width 0.1)
				(type default)
			)
			(layer "F.Fab")
		)
		(fp_line
			(start 0.120396 0.2794)
			(end -0.12065 0.2794)
			(stroke
				(width 0.1)
				(type default)
			)
			(layer "F.Fab")
		)
		(fp_line
			(start -0.12065 0.2794)
			(end -0.12065 0.3048)
			(stroke
				(width 0.1)
				(type default)
			)
			(layer "F.Fab")
		)
		(fp_line
			(start 0.67945 0.3048)
			(end 0.120396 0.3048)
			(stroke
				(width 0.1)
				(type default)
			)
			(layer "F.Fab")
		)
		(fp_line
			(start 0.120396 0.3048)
			(end 0.120396 0.2794)
			(stroke
				(width 0.1)
				(type default)
			)
			(layer "F.Fab")
		)
		(fp_line
			(start -0.12065 0.3048)
			(end -0.67945 0.3048)
			(stroke
				(width 0.1)
				(type default)
			)
			(layer "F.Fab")
		)
		(fp_line
			(start -0.67945 0.3048)
			(end -0.67945 -0.305054)
			(stroke
				(width 0.1)
				(type default)
			)
			(layer "F.Fab")
		)
		(pad "1" smd circle
			(at -0.40005 0 90)
			(size 0 0)
			(layers "F.Cu" "F.Mask" "F.Paste")
			(net "SPI_BMC_BIOS_ROM_CLK")
		)
		(pad "2" smd circle
			(at 0.40005 0 90)
			(size 0 0)
			(layers "F.Cu" "F.Mask" "F.Paste")
			(net "SPI_BMC_BIOS_ROM_R_CLK")
		)
	)
	(footprint ""
		(layer "F.Cu")
		(at 40.41648 -30.63748 -90)
		(property "Reference" "C38"
			(at 0 0 270)
			(layer "F.SilkS")
			(hide yes)
			(effects
				(font
					(size 1.27 1.27)
				)
			)
		)
		(property "Value" ""
			(at 0 0 270)
			(layer "F.Fab")
			(effects
				(font
					(size 1.27 1.27)
				)
			)
		)
		(duplicate_pad_numbers_are_jumpers no)
		(fp_line
			(start -0.7874 0.4064)
			(end -0.7874 -0.4064)
			(stroke
				(width 0.1524)
				(type default)
			)
			(layer "F.SilkS")
		)
		(fp_line
			(start 0.7874 0.4064)
			(end -0.7874 0.4064)
			(stroke
				(width 0.1524)
				(type default)
			)
			(layer "F.SilkS")
		)
		(fp_line
			(start -0.7874 -0.4064)
			(end 0.7874 -0.4064)
			(stroke
				(width 0.1524)
				(type default)
			)
			(layer "F.SilkS")
		)
		(fp_line
			(start 0.7874 -0.4064)
			(end 0.7874 0.4064)
			(stroke
				(width 0.1524)
				(type default)
			)
			(layer "F.SilkS")
		)
		(fp_line
			(start -0.67945 0.3048)
			(end -0.67945 -0.305054)
			(stroke
				(width 0.1)
				(type default)
			)
			(layer "F.Fab")
		)
		(fp_line
			(start -0.12065 0.3048)
			(end -0.67945 0.3048)
			(stroke
				(width 0.1)
				(type default)
			)
			(layer "F.Fab")
		)
		(fp_line
			(start 0.120396 0.3048)
			(end 0.120396 0.2794)
			(stroke
				(width 0.1)
				(type default)
			)
			(layer "F.Fab")
		)
		(fp_line
			(start 0.67945 0.3048)
			(end 0.120396 0.3048)
			(stroke
				(width 0.1)
				(type default)
			)
			(layer "F.Fab")
		)
		(fp_line
			(start -0.12065 0.2794)
			(end -0.12065 0.3048)
			(stroke
				(width 0.1)
				(type default)
			)
			(layer "F.Fab")
		)
		(fp_line
			(start 0.120396 0.2794)
			(end -0.12065 0.2794)
			(stroke
				(width 0.1)
				(type default)
			)
			(layer "F.Fab")
		)
		(fp_line
			(start -0.12065 -0.2794)
			(end 0.12065 -0.2794)
			(stroke
				(width 0.1)
				(type default)
			)
			(layer "F.Fab")
		)
		(fp_line
			(start 0.12065 -0.2794)
			(end 0.12065 -0.3048)
			(stroke
				(width 0.1)
				(type default)
			)
			(layer "F.Fab")
		)
		(fp_line
			(start 0.12065 -0.3048)
			(end 0.67945 -0.3048)
			(stroke
				(width 0.1)
				(type default)
			)
			(layer "F.Fab")
		)
		(fp_line
			(start 0.67945 -0.3048)
			(end 0.67945 0.3048)
			(stroke
				(width 0.1)
				(type default)
			)
			(layer "F.Fab")
		)
		(fp_line
			(start -0.67945 -0.305054)
			(end -0.12065 -0.305054)
			(stroke
				(width 0.1)
				(type default)
			)
			(layer "F.Fab")
		)
		(fp_line
			(start -0.12065 -0.305054)
			(end -0.12065 -0.2794)
			(stroke
				(width 0.1)
				(type default)
			)
			(layer "F.Fab")
		)
		(pad "1" smd circle
			(at -0.40005 0 270)
			(size 0 0)
			(layers "F.Cu" "F.Mask" "F.Paste")
			(net "P3V3_P1V8_SD2VDD")
		)
		(pad "2" smd circle
			(at 0.40005 0 270)
			(size 0 0)
			(layers "F.Cu" "F.Mask" "F.Paste")
			(net "GND")
		)
	)
	(footprint ""
		(layer "F.Cu")
		(at 25.5016 -33.909 90)
		(property "Reference" "R277"
			(at 0 0 90)
			(layer "F.SilkS")
			(hide yes)
			(effects
				(font
					(size 1.27 1.27)
				)
			)
		)
		(property "Value" ""
			(at 0 0 90)
			(layer "F.Fab")
			(effects
				(font
					(size 1.27 1.27)
				)
			)
		)
		(duplicate_pad_numbers_are_jumpers no)
		(fp_line
			(start 0.7874 -0.4064)
			(end 0.7874 0.4064)
			(stroke
				(width 0.1524)
				(type default)
			)
			(layer "F.SilkS")
		)
		(fp_line
			(start -0.7874 -0.4064)
			(end 0.7874 -0.4064)
			(stroke
				(width 0.1524)
				(type default)
			)
			(layer "F.SilkS")
		)
		(fp_line
			(start 0.7874 0.4064)
			(end -0.7874 0.4064)
			(stroke
				(width 0.1524)
				(type default)
			)
			(layer "F.SilkS")
		)
		(fp_line
			(start -0.7874 0.4064)
			(end -0.7874 -0.4064)
			(stroke
				(width 0.1524)
				(type default)
			)
			(layer "F.SilkS")
		)
		(fp_line
			(start -0.12065 -0.305054)
			(end -0.12065 -0.2794)
			(stroke
				(width 0.1)
				(type default)
			)
			(layer "F.Fab")
		)
		(fp_line
			(start -0.67945 -0.305054)
			(end -0.12065 -0.305054)
			(stroke
				(width 0.1)
				(type default)
			)
			(layer "F.Fab")
		)
		(fp_line
			(start 0.67945 -0.3048)
			(end 0.67945 0.3048)
			(stroke
				(width 0.1)
				(type default)
			)
			(layer "F.Fab")
		)
		(fp_line
			(start 0.12065 -0.3048)
			(end 0.67945 -0.3048)
			(stroke
				(width 0.1)
				(type default)
			)
			(layer "F.Fab")
		)
		(fp_line
			(start 0.12065 -0.2794)
			(end 0.12065 -0.3048)
			(stroke
				(width 0.1)
				(type default)
			)
			(layer "F.Fab")
		)
		(fp_line
			(start -0.12065 -0.2794)
			(end 0.12065 -0.2794)
			(stroke
				(width 0.1)
				(type default)
			)
			(layer "F.Fab")
		)
		(fp_line
			(start 0.120396 0.2794)
			(end -0.12065 0.2794)
			(stroke
				(width 0.1)
				(type default)
			)
			(layer "F.Fab")
		)
		(fp_line
			(start -0.12065 0.2794)
			(end -0.12065 0.3048)
			(stroke
				(width 0.1)
				(type default)
			)
			(layer "F.Fab")
		)
		(fp_line
			(start 0.67945 0.3048)
			(end 0.120396 0.3048)
			(stroke
				(width 0.1)
				(type default)
			)
			(layer "F.Fab")
		)
		(fp_line
			(start 0.120396 0.3048)
			(end 0.120396 0.2794)
			(stroke
				(width 0.1)
				(type default)
			)
			(layer "F.Fab")
		)
		(fp_line
			(start -0.12065 0.3048)
			(end -0.67945 0.3048)
			(stroke
				(width 0.1)
				(type default)
			)
			(layer "F.Fab")
		)
		(fp_line
			(start -0.67945 0.3048)
			(end -0.67945 -0.305054)
			(stroke
				(width 0.1)
				(type default)
			)
			(layer "F.Fab")
		)
		(pad "1" smd circle
			(at -0.40005 0 90)
			(size 0 0)
			(layers "F.Cu" "F.Mask" "F.Paste")
			(net "PWRGD_P1V0_AUX_R")
		)
		(pad "2" smd circle
			(at 0.40005 0 90)
			(size 0 0)
			(layers "F.Cu" "F.Mask" "F.Paste")
			(net "PWRGD_P1V0_AUX")
		)
	)
	(footprint ""
		(layer "F.Cu")
		(at 41.859454 -65.776094 -90)
		(property "Reference" "R184"
			(at 0 0 270)
			(layer "F.SilkS")
			(hide yes)
			(effects
				(font
					(size 1.27 1.27)
				)
			)
		)
		(property "Value" ""
			(at 0 0 270)
			(layer "F.Fab")
			(effects
				(font
					(size 1.27 1.27)
				)
			)
		)
		(duplicate_pad_numbers_are_jumpers no)
		(fp_line
			(start -0.7874 0.4064)
			(end -0.7874 -0.4064)
			(stroke
				(width 0.1524)
				(type default)
			)
			(layer "F.SilkS")
		)
		(fp_line
			(start 0.7874 0.4064)
			(end -0.7874 0.4064)
			(stroke
				(width 0.1524)
				(type default)
			)
			(layer "F.SilkS")
		)
		(fp_line
			(start -0.7874 -0.4064)
			(end 0.7874 -0.4064)
			(stroke
				(width 0.1524)
				(type default)
			)
			(layer "F.SilkS")
		)
		(fp_line
			(start 0.7874 -0.4064)
			(end 0.7874 0.4064)
			(stroke
				(width 0.1524)
				(type default)
			)
			(layer "F.SilkS")
		)
		(fp_line
			(start -0.67945 0.3048)
			(end -0.67945 -0.305054)
			(stroke
				(width 0.1)
				(type default)
			)
			(layer "F.Fab")
		)
		(fp_line
			(start -0.12065 0.3048)
			(end -0.67945 0.3048)
			(stroke
				(width 0.1)
				(type default)
			)
			(layer "F.Fab")
		)
		(fp_line
			(start 0.120396 0.3048)
			(end 0.120396 0.2794)
			(stroke
				(width 0.1)
				(type default)
			)
			(layer "F.Fab")
		)
		(fp_line
			(start 0.67945 0.3048)
			(end 0.120396 0.3048)
			(stroke
				(width 0.1)
				(type default)
			)
			(layer "F.Fab")
		)
		(fp_line
			(start -0.12065 0.2794)
			(end -0.12065 0.3048)
			(stroke
				(width 0.1)
				(type default)
			)
			(layer "F.Fab")
		)
		(fp_line
			(start 0.120396 0.2794)
			(end -0.12065 0.2794)
			(stroke
				(width 0.1)
				(type default)
			)
			(layer "F.Fab")
		)
		(fp_line
			(start -0.12065 -0.2794)
			(end 0.12065 -0.2794)
			(stroke
				(width 0.1)
				(type default)
			)
			(layer "F.Fab")
		)
		(fp_line
			(start 0.12065 -0.2794)
			(end 0.12065 -0.3048)
			(stroke
				(width 0.1)
				(type default)
			)
			(layer "F.Fab")
		)
		(fp_line
			(start 0.12065 -0.3048)
			(end 0.67945 -0.3048)
			(stroke
				(width 0.1)
				(type default)
			)
			(layer "F.Fab")
		)
		(fp_line
			(start 0.67945 -0.3048)
			(end 0.67945 0.3048)
			(stroke
				(width 0.1)
				(type default)
			)
			(layer "F.Fab")
		)
		(fp_line
			(start -0.67945 -0.305054)
			(end -0.12065 -0.305054)
			(stroke
				(width 0.1)
				(type default)
			)
			(layer "F.Fab")
		)
		(fp_line
			(start -0.12065 -0.305054)
			(end -0.12065 -0.2794)
			(stroke
				(width 0.1)
				(type default)
			)
			(layer "F.Fab")
		)
		(pad "1" smd circle
			(at -0.40005 0 270)
			(size 0 0)
			(layers "F.Cu" "F.Mask" "F.Paste")
			(net "I3C1_SPD_SCL")
		)
		(pad "2" smd circle
			(at 0.40005 0 270)
			(size 0 0)
			(layers "F.Cu" "F.Mask" "F.Paste")
			(net "I3C1_SCL_R")
		)
	)
	(footprint ""
		(layer "F.Cu")
		(at 63.654432 -66.926968 180)
		(property "Reference" "L17"
			(at 0 0 180)
			(layer "F.SilkS")
			(hide yes)
			(effects
				(font
					(size 1.27 1.27)
				)
			)
		)
		(property "Value" ""
			(at 0 0 180)
			(layer "F.Fab")
			(effects
				(font
					(size 1.27 1.27)
				)
			)
		)
		(duplicate_pad_numbers_are_jumpers no)
		(fp_line
			(start 1.27 0.5842)
			(end 1.27 -0.5842)
			(stroke
				(width 0.1524)
				(type default)
			)
			(layer "F.SilkS")
		)
		(fp_line
			(start 1.27 0.5842)
			(end -1.27 0.5842)
			(stroke
				(width 0.1524)
				(type default)
			)
			(layer "F.SilkS")
		)
		(fp_line
			(start 0.127 0.5842)
			(end 0.127 -0.5842)
			(stroke
				(width 0.1524)
				(type default)
			)
			(layer "F.SilkS")
		)
		(fp_line
			(start -0.127 0.5842)
			(end -0.127 -0.5842)
			(stroke
				(width 0.1524)
				(type default)
			)
			(layer "F.SilkS")
		)
		(fp_line
			(start -1.27 0.5842)
			(end -1.27 -0.5842)
			(stroke
				(width 0.1524)
				(type default)
			)
			(layer "F.SilkS")
		)
		(fp_line
			(start -1.27 -0.5588)
			(end -1.27 -0.5842)
			(stroke
				(width 0.1524)
				(type default)
			)
			(layer "F.SilkS")
		)
		(fp_line
			(start -1.27 -0.5842)
			(end 1.27 -0.5842)
			(stroke
				(width 0.1524)
				(type default)
			)
			(layer "F.SilkS")
		)
		(fp_line
			(start 1.1938 0.4064)
			(end 0.9144 0.4064)
			(stroke
				(width 0.1)
				(type default)
			)
			(layer "F.Fab")
		)
		(fp_line
			(start 1.1938 -0.406654)
			(end 1.1938 0.4064)
			(stroke
				(width 0.1)
				(type default)
			)
			(layer "F.Fab")
		)
		(fp_line
			(start 0.9144 0.508)
			(end -0.9144 0.508)
			(stroke
				(width 0.1)
				(type default)
			)
			(layer "F.Fab")
		)
		(fp_line
			(start 0.9144 0.4064)
			(end 0.9144 0.508)
			(stroke
				(width 0.1)
				(type default)
			)
			(layer "F.Fab")
		)
		(fp_line
			(start 0.9144 -0.406654)
			(end 1.1938 -0.406654)
			(stroke
				(width 0.1)
				(type default)
			)
			(layer "F.Fab")
		)
		(fp_line
			(start 0.9144 -0.508)
			(end 0.9144 -0.406654)
			(stroke
				(width 0.1)
				(type default)
			)
			(layer "F.Fab")
		)
		(fp_line
			(start -0.9144 0.508)
			(end -0.9144 0.406654)
			(stroke
				(width 0.1)
				(type default)
			)
			(layer "F.Fab")
		)
		(fp_line
			(start -0.9144 0.406654)
			(end -1.194308 0.406654)
			(stroke
				(width 0.1)
				(type default)
			)
			(layer "F.Fab")
		)
		(fp_line
			(start -0.9144 -0.406654)
			(end -0.9144 -0.508)
			(stroke
				(width 0.1)
				(type default)
			)
			(layer "F.Fab")
		)
		(fp_line
			(start -0.9144 -0.508)
			(end 0.9144 -0.508)
			(stroke
				(width 0.1)
				(type default)
			)
			(layer "F.Fab")
		)
		(fp_line
			(start -1.194308 0.406654)
			(end -1.194308 -0.406654)
			(stroke
				(width 0.1)
				(type default)
			)
			(layer "F.Fab")
		)
		(fp_line
			(start -1.194308 -0.406654)
			(end -0.9144 -0.406654)
			(stroke
				(width 0.1)
				(type default)
			)
			(layer "F.Fab")
		)
		(pad "1" smd rect
			(at -0.7366 0 90)
			(size 0.7112 0.8128)
			(layers "F.Cu" "F.Mask" "F.Paste")
			(net "PGPPA_BMC_AUX_L")
		)
		(pad "2" smd rect
			(at 0.7366 0 90)
			(size 0.7112 0.8128)
			(layers "F.Cu" "F.Mask" "F.Paste")
			(net "PGPPA_BMC_AUX")
		)
	)
	(footprint ""
		(layer "F.Cu")
		(at 47.6377 -66.35496 -90)
		(property "Reference" "R461"
			(at 0 0 270)
			(layer "F.SilkS")
			(hide yes)
			(effects
				(font
					(size 1.27 1.27)
				)
			)
		)
		(property "Value" ""
			(at 0 0 270)
			(layer "F.Fab")
			(effects
				(font
					(size 1.27 1.27)
				)
			)
		)
		(duplicate_pad_numbers_are_jumpers no)
		(fp_line
			(start -0.7874 0.4064)
			(end -0.7874 -0.4064)
			(stroke
				(width 0.1524)
				(type default)
			)
			(layer "F.SilkS")
		)
		(fp_line
			(start 0.7874 0.4064)
			(end -0.7874 0.4064)
			(stroke
				(width 0.1524)
				(type default)
			)
			(layer "F.SilkS")
		)
		(fp_line
			(start -0.7874 -0.4064)
			(end 0.7874 -0.4064)
			(stroke
				(width 0.1524)
				(type default)
			)
			(layer "F.SilkS")
		)
		(fp_line
			(start 0.7874 -0.4064)
			(end 0.7874 0.4064)
			(stroke
				(width 0.1524)
				(type default)
			)
			(layer "F.SilkS")
		)
		(fp_line
			(start -0.67945 0.3048)
			(end -0.67945 -0.305054)
			(stroke
				(width 0.1)
				(type default)
			)
			(layer "F.Fab")
		)
		(fp_line
			(start -0.12065 0.3048)
			(end -0.67945 0.3048)
			(stroke
				(width 0.1)
				(type default)
			)
			(layer "F.Fab")
		)
		(fp_line
			(start 0.120396 0.3048)
			(end 0.120396 0.2794)
			(stroke
				(width 0.1)
				(type default)
			)
			(layer "F.Fab")
		)
		(fp_line
			(start 0.67945 0.3048)
			(end 0.120396 0.3048)
			(stroke
				(width 0.1)
				(type default)
			)
			(layer "F.Fab")
		)
		(fp_line
			(start -0.12065 0.2794)
			(end -0.12065 0.3048)
			(stroke
				(width 0.1)
				(type default)
			)
			(layer "F.Fab")
		)
		(fp_line
			(start 0.120396 0.2794)
			(end -0.12065 0.2794)
			(stroke
				(width 0.1)
				(type default)
			)
			(layer "F.Fab")
		)
		(fp_line
			(start -0.12065 -0.2794)
			(end 0.12065 -0.2794)
			(stroke
				(width 0.1)
				(type default)
			)
			(layer "F.Fab")
		)
		(fp_line
			(start 0.12065 -0.2794)
			(end 0.12065 -0.3048)
			(stroke
				(width 0.1)
				(type default)
			)
			(layer "F.Fab")
		)
		(fp_line
			(start 0.12065 -0.3048)
			(end 0.67945 -0.3048)
			(stroke
				(width 0.1)
				(type default)
			)
			(layer "F.Fab")
		)
		(fp_line
			(start 0.67945 -0.3048)
			(end 0.67945 0.3048)
			(stroke
				(width 0.1)
				(type default)
			)
			(layer "F.Fab")
		)
		(fp_line
			(start -0.67945 -0.305054)
			(end -0.12065 -0.305054)
			(stroke
				(width 0.1)
				(type default)
			)
			(layer "F.Fab")
		)
		(fp_line
			(start -0.12065 -0.305054)
			(end -0.12065 -0.2794)
			(stroke
				(width 0.1)
				(type default)
			)
			(layer "F.Fab")
		)
		(pad "1" smd circle
			(at -0.40005 0 270)
			(size 0 0)
			(layers "F.Cu" "F.Mask" "F.Paste")
			(net "BMC_ID_BEEP_SEL")
		)
		(pad "2" smd circle
			(at 0.40005 0 270)
			(size 0 0)
			(layers "F.Cu" "F.Mask" "F.Paste")
			(net "BMC_ID_BEEP_SEL_R1")
		)
	)
	(footprint ""
		(layer "F.Cu")
		(at 73.787 -25.5016 180)
		(property "Reference" "R601"
			(at 0 0 180)
			(layer "F.SilkS")
			(hide yes)
			(effects
				(font
					(size 1.27 1.27)
				)
			)
		)
		(property "Value" ""
			(at 0 0 180)
			(layer "F.Fab")
			(effects
				(font
					(size 1.27 1.27)
				)
			)
		)
		(duplicate_pad_numbers_are_jumpers no)
		(fp_line
			(start 0.7874 0.4064)
			(end -0.7874 0.4064)
			(stroke
				(width 0.1524)
				(type default)
			)
			(layer "F.SilkS")
		)
		(fp_line
			(start 0.7874 -0.4064)
			(end 0.7874 0.4064)
			(stroke
				(width 0.1524)
				(type default)
			)
			(layer "F.SilkS")
		)
		(fp_line
			(start -0.7874 0.4064)
			(end -0.7874 -0.4064)
			(stroke
				(width 0.1524)
				(type default)
			)
			(layer "F.SilkS")
		)
		(fp_line
			(start -0.7874 -0.4064)
			(end 0.7874 -0.4064)
			(stroke
				(width 0.1524)
				(type default)
			)
			(layer "F.SilkS")
		)
		(fp_line
			(start 0.67945 0.3048)
			(end 0.120396 0.3048)
			(stroke
				(width 0.1)
				(type default)
			)
			(layer "F.Fab")
		)
		(fp_line
			(start 0.67945 -0.3048)
			(end 0.67945 0.3048)
			(stroke
				(width 0.1)
				(type default)
			)
			(layer "F.Fab")
		)
		(fp_line
			(start 0.12065 -0.2794)
			(end 0.12065 -0.3048)
			(stroke
				(width 0.1)
				(type default)
			)
			(layer "F.Fab")
		)
		(fp_line
			(start 0.12065 -0.3048)
			(end 0.67945 -0.3048)
			(stroke
				(width 0.1)
				(type default)
			)
			(layer "F.Fab")
		)
		(fp_line
			(start 0.120396 0.3048)
			(end 0.120396 0.2794)
			(stroke
				(width 0.1)
				(type default)
			)
			(layer "F.Fab")
		)
		(fp_line
			(start 0.120396 0.2794)
			(end -0.12065 0.2794)
			(stroke
				(width 0.1)
				(type default)
			)
			(layer "F.Fab")
		)
		(fp_line
			(start -0.12065 0.3048)
			(end -0.67945 0.3048)
			(stroke
				(width 0.1)
				(type default)
			)
			(layer "F.Fab")
		)
		(fp_line
			(start -0.12065 0.2794)
			(end -0.12065 0.3048)
			(stroke
				(width 0.1)
				(type default)
			)
			(layer "F.Fab")
		)
		(fp_line
			(start -0.12065 -0.2794)
			(end 0.12065 -0.2794)
			(stroke
				(width 0.1)
				(type default)
			)
			(layer "F.Fab")
		)
		(fp_line
			(start -0.12065 -0.305054)
			(end -0.12065 -0.2794)
			(stroke
				(width 0.1)
				(type default)
			)
			(layer "F.Fab")
		)
		(fp_line
			(start -0.67945 0.3048)
			(end -0.67945 -0.305054)
			(stroke
				(width 0.1)
				(type default)
			)
			(layer "F.Fab")
		)
		(fp_line
			(start -0.67945 -0.305054)
			(end -0.12065 -0.305054)
			(stroke
				(width 0.1)
				(type default)
			)
			(layer "F.Fab")
		)
		(pad "1" smd circle
			(at -0.40005 0 180)
			(size 0 0)
			(layers "F.Cu" "F.Mask" "F.Paste")
			(net "LED_POSTCODE_3")
		)
		(pad "2" smd circle
			(at 0.40005 0 180)
			(size 0 0)
			(layers "F.Cu" "F.Mask" "F.Paste")
			(net "LED_POSTCODE_3_R")
		)
	)
	(footprint ""
		(layer "F.Cu")
		(at 33.909 -36.195 90)
		(property "Reference" "R751"
			(at 0 0 90)
			(layer "F.SilkS")
			(hide yes)
			(effects
				(font
					(size 1.27 1.27)
				)
			)
		)
		(property "Value" ""
			(at 0 0 90)
			(layer "F.Fab")
			(effects
				(font
					(size 1.27 1.27)
				)
			)
		)
		(duplicate_pad_numbers_are_jumpers no)
		(fp_line
			(start 0.7874 -0.4064)
			(end 0.7874 0.4064)
			(stroke
				(width 0.1524)
				(type default)
			)
			(layer "F.SilkS")
		)
		(fp_line
			(start -0.7874 -0.4064)
			(end 0.7874 -0.4064)
			(stroke
				(width 0.1524)
				(type default)
			)
			(layer "F.SilkS")
		)
		(fp_line
			(start 0.7874 0.4064)
			(end -0.7874 0.4064)
			(stroke
				(width 0.1524)
				(type default)
			)
			(layer "F.SilkS")
		)
		(fp_line
			(start -0.7874 0.4064)
			(end -0.7874 -0.4064)
			(stroke
				(width 0.1524)
				(type default)
			)
			(layer "F.SilkS")
		)
		(fp_line
			(start -0.12065 -0.305054)
			(end -0.12065 -0.2794)
			(stroke
				(width 0.1)
				(type default)
			)
			(layer "F.Fab")
		)
		(fp_line
			(start -0.67945 -0.305054)
			(end -0.12065 -0.305054)
			(stroke
				(width 0.1)
				(type default)
			)
			(layer "F.Fab")
		)
		(fp_line
			(start 0.67945 -0.3048)
			(end 0.67945 0.3048)
			(stroke
				(width 0.1)
				(type default)
			)
			(layer "F.Fab")
		)
		(fp_line
			(start 0.12065 -0.3048)
			(end 0.67945 -0.3048)
			(stroke
				(width 0.1)
				(type default)
			)
			(layer "F.Fab")
		)
		(fp_line
			(start 0.12065 -0.2794)
			(end 0.12065 -0.3048)
			(stroke
				(width 0.1)
				(type default)
			)
			(layer "F.Fab")
		)
		(fp_line
			(start -0.12065 -0.2794)
			(end 0.12065 -0.2794)
			(stroke
				(width 0.1)
				(type default)
			)
			(layer "F.Fab")
		)
		(fp_line
			(start 0.120396 0.2794)
			(end -0.12065 0.2794)
			(stroke
				(width 0.1)
				(type default)
			)
			(layer "F.Fab")
		)
		(fp_line
			(start -0.12065 0.2794)
			(end -0.12065 0.3048)
			(stroke
				(width 0.1)
				(type default)
			)
			(layer "F.Fab")
		)
		(fp_line
			(start 0.67945 0.3048)
			(end 0.120396 0.3048)
			(stroke
				(width 0.1)
				(type default)
			)
			(layer "F.Fab")
		)
		(fp_line
			(start 0.120396 0.3048)
			(end 0.120396 0.2794)
			(stroke
				(width 0.1)
				(type default)
			)
			(layer "F.Fab")
		)
		(fp_line
			(start -0.12065 0.3048)
			(end -0.67945 0.3048)
			(stroke
				(width 0.1)
				(type default)
			)
			(layer "F.Fab")
		)
		(fp_line
			(start -0.67945 0.3048)
			(end -0.67945 -0.305054)
			(stroke
				(width 0.1)
				(type default)
			)
			(layer "F.Fab")
		)
		(pad "1" smd circle
			(at -0.40005 0 90)
			(size 0 0)
			(layers "F.Cu" "F.Mask" "F.Paste")
			(net "P3V3_AUX")
		)
		(pad "2" smd circle
			(at 0.40005 0 90)
			(size 0 0)
			(layers "F.Cu" "F.Mask" "F.Paste")
			(net "PWRGD_P1V0_AUX_DELAY_R1")
		)
	)
	(footprint ""
		(layer "F.Cu")
		(at 35.5346 -109.347 90)
		(property "Reference" "R69"
			(at 0 0 90)
			(layer "F.SilkS")
			(hide yes)
			(effects
				(font
					(size 1.27 1.27)
				)
			)
		)
		(property "Value" ""
			(at 0 0 90)
			(layer "F.Fab")
			(effects
				(font
					(size 1.27 1.27)
				)
			)
		)
		(duplicate_pad_numbers_are_jumpers no)
		(fp_line
			(start 0.7874 -0.4064)
			(end 0.7874 0.4064)
			(stroke
				(width 0.1524)
				(type default)
			)
			(layer "F.SilkS")
		)
		(fp_line
			(start -0.7874 -0.4064)
			(end 0.7874 -0.4064)
			(stroke
				(width 0.1524)
				(type default)
			)
			(layer "F.SilkS")
		)
		(fp_line
			(start 0.7874 0.4064)
			(end -0.7874 0.4064)
			(stroke
				(width 0.1524)
				(type default)
			)
			(layer "F.SilkS")
		)
		(fp_line
			(start -0.7874 0.4064)
			(end -0.7874 -0.4064)
			(stroke
				(width 0.1524)
				(type default)
			)
			(layer "F.SilkS")
		)
		(fp_line
			(start -0.12065 -0.305054)
			(end -0.12065 -0.2794)
			(stroke
				(width 0.1)
				(type default)
			)
			(layer "F.Fab")
		)
		(fp_line
			(start -0.67945 -0.305054)
			(end -0.12065 -0.305054)
			(stroke
				(width 0.1)
				(type default)
			)
			(layer "F.Fab")
		)
		(fp_line
			(start 0.67945 -0.3048)
			(end 0.67945 0.3048)
			(stroke
				(width 0.1)
				(type default)
			)
			(layer "F.Fab")
		)
		(fp_line
			(start 0.12065 -0.3048)
			(end 0.67945 -0.3048)
			(stroke
				(width 0.1)
				(type default)
			)
			(layer "F.Fab")
		)
		(fp_line
			(start 0.12065 -0.2794)
			(end 0.12065 -0.3048)
			(stroke
				(width 0.1)
				(type default)
			)
			(layer "F.Fab")
		)
		(fp_line
			(start -0.12065 -0.2794)
			(end 0.12065 -0.2794)
			(stroke
				(width 0.1)
				(type default)
			)
			(layer "F.Fab")
		)
		(fp_line
			(start 0.120396 0.2794)
			(end -0.12065 0.2794)
			(stroke
				(width 0.1)
				(type default)
			)
			(layer "F.Fab")
		)
		(fp_line
			(start -0.12065 0.2794)
			(end -0.12065 0.3048)
			(stroke
				(width 0.1)
				(type default)
			)
			(layer "F.Fab")
		)
		(fp_line
			(start 0.67945 0.3048)
			(end 0.120396 0.3048)
			(stroke
				(width 0.1)
				(type default)
			)
			(layer "F.Fab")
		)
		(fp_line
			(start 0.120396 0.3048)
			(end 0.120396 0.2794)
			(stroke
				(width 0.1)
				(type default)
			)
			(layer "F.Fab")
		)
		(fp_line
			(start -0.12065 0.3048)
			(end -0.67945 0.3048)
			(stroke
				(width 0.1)
				(type default)
			)
			(layer "F.Fab")
		)
		(fp_line
			(start -0.67945 0.3048)
			(end -0.67945 -0.305054)
			(stroke
				(width 0.1)
				(type default)
			)
			(layer "F.Fab")
		)
		(pad "1" smd circle
			(at -0.40005 0 90)
			(size 0 0)
			(layers "F.Cu" "F.Mask" "F.Paste")
			(net "P3V3_AUX")
		)
		(pad "2" smd circle
			(at 0.40005 0 90)
			(size 0 0)
			(layers "F.Cu" "F.Mask" "F.Paste")
			(net "RST_SGPIO_RESET_N")
		)
	)
	(footprint ""
		(layer "F.Cu")
		(at 80.6704 -15.9258)
		(property "Reference" "C201"
			(at 0 0 0)
			(layer "F.SilkS")
			(hide yes)
			(effects
				(font
					(size 1.27 1.27)
				)
			)
		)
		(property "Value" ""
			(at 0 0 0)
			(layer "F.Fab")
			(effects
				(font
					(size 1.27 1.27)
				)
			)
		)
		(duplicate_pad_numbers_are_jumpers no)
		(fp_line
			(start -0.7874 -0.4064)
			(end 0.7874 -0.4064)
			(stroke
				(width 0.1524)
				(type default)
			)
			(layer "F.SilkS")
		)
		(fp_line
			(start -0.7874 0.4064)
			(end -0.7874 -0.4064)
			(stroke
				(width 0.1524)
				(type default)
			)
			(layer "F.SilkS")
		)
		(fp_line
			(start 0.7874 -0.4064)
			(end 0.7874 0.4064)
			(stroke
				(width 0.1524)
				(type default)
			)
			(layer "F.SilkS")
		)
		(fp_line
			(start 0.7874 0.4064)
			(end -0.7874 0.4064)
			(stroke
				(width 0.1524)
				(type default)
			)
			(layer "F.SilkS")
		)
		(fp_line
			(start -0.67945 -0.305054)
			(end -0.12065 -0.305054)
			(stroke
				(width 0.1)
				(type default)
			)
			(layer "F.Fab")
		)
		(fp_line
			(start -0.67945 0.3048)
			(end -0.67945 -0.305054)
			(stroke
				(width 0.1)
				(type default)
			)
			(layer "F.Fab")
		)
		(fp_line
			(start -0.12065 -0.305054)
			(end -0.12065 -0.2794)
			(stroke
				(width 0.1)
				(type default)
			)
			(layer "F.Fab")
		)
		(fp_line
			(start -0.12065 -0.2794)
			(end 0.12065 -0.2794)
			(stroke
				(width 0.1)
				(type default)
			)
			(layer "F.Fab")
		)
		(fp_line
			(start -0.12065 0.2794)
			(end -0.12065 0.3048)
			(stroke
				(width 0.1)
				(type default)
			)
			(layer "F.Fab")
		)
		(fp_line
			(start -0.12065 0.3048)
			(end -0.67945 0.3048)
			(stroke
				(width 0.1)
				(type default)
			)
			(layer "F.Fab")
		)
		(fp_line
			(start 0.120396 0.2794)
			(end -0.12065 0.2794)
			(stroke
				(width 0.1)
				(type default)
			)
			(layer "F.Fab")
		)
		(fp_line
			(start 0.120396 0.3048)
			(end 0.120396 0.2794)
			(stroke
				(width 0.1)
				(type default)
			)
			(layer "F.Fab")
		)
		(fp_line
			(start 0.12065 -0.3048)
			(end 0.67945 -0.3048)
			(stroke
				(width 0.1)
				(type default)
			)
			(layer "F.Fab")
		)
		(fp_line
			(start 0.12065 -0.2794)
			(end 0.12065 -0.3048)
			(stroke
				(width 0.1)
				(type default)
			)
			(layer "F.Fab")
		)
		(fp_line
			(start 0.67945 -0.3048)
			(end 0.67945 0.3048)
			(stroke
				(width 0.1)
				(type default)
			)
			(layer "F.Fab")
		)
		(fp_line
			(start 0.67945 0.3048)
			(end 0.120396 0.3048)
			(stroke
				(width 0.1)
				(type default)
			)
			(layer "F.Fab")
		)
		(pad "1" smd circle
			(at -0.40005 0)
			(size 0 0)
			(layers "F.Cu" "F.Mask" "F.Paste")
			(net "P3V3_AUX")
		)
		(pad "2" smd circle
			(at 0.40005 0)
			(size 0 0)
			(layers "F.Cu" "F.Mask" "F.Paste")
			(net "GND")
		)
	)
	(footprint ""
		(layer "F.Cu")
		(at 20.701 -56.1848 90)
		(property "Reference" "R538"
			(at 0 0 90)
			(layer "F.SilkS")
			(hide yes)
			(effects
				(font
					(size 1.27 1.27)
				)
			)
		)
		(property "Value" ""
			(at 0 0 90)
			(layer "F.Fab")
			(effects
				(font
					(size 1.27 1.27)
				)
			)
		)
		(duplicate_pad_numbers_are_jumpers no)
		(fp_line
			(start 0.7874 -0.4064)
			(end 0.7874 0.4064)
			(stroke
				(width 0.1524)
				(type default)
			)
			(layer "F.SilkS")
		)
		(fp_line
			(start -0.7874 -0.4064)
			(end 0.7874 -0.4064)
			(stroke
				(width 0.1524)
				(type default)
			)
			(layer "F.SilkS")
		)
		(fp_line
			(start 0.7874 0.4064)
			(end -0.7874 0.4064)
			(stroke
				(width 0.1524)
				(type default)
			)
			(layer "F.SilkS")
		)
		(fp_line
			(start -0.7874 0.4064)
			(end -0.7874 -0.4064)
			(stroke
				(width 0.1524)
				(type default)
			)
			(layer "F.SilkS")
		)
		(fp_line
			(start -0.12065 -0.305054)
			(end -0.12065 -0.2794)
			(stroke
				(width 0.1)
				(type default)
			)
			(layer "F.Fab")
		)
		(fp_line
			(start -0.67945 -0.305054)
			(end -0.12065 -0.305054)
			(stroke
				(width 0.1)
				(type default)
			)
			(layer "F.Fab")
		)
		(fp_line
			(start 0.67945 -0.3048)
			(end 0.67945 0.3048)
			(stroke
				(width 0.1)
				(type default)
			)
			(layer "F.Fab")
		)
		(fp_line
			(start 0.12065 -0.3048)
			(end 0.67945 -0.3048)
			(stroke
				(width 0.1)
				(type default)
			)
			(layer "F.Fab")
		)
		(fp_line
			(start 0.12065 -0.2794)
			(end 0.12065 -0.3048)
			(stroke
				(width 0.1)
				(type default)
			)
			(layer "F.Fab")
		)
		(fp_line
			(start -0.12065 -0.2794)
			(end 0.12065 -0.2794)
			(stroke
				(width 0.1)
				(type default)
			)
			(layer "F.Fab")
		)
		(fp_line
			(start 0.120396 0.2794)
			(end -0.12065 0.2794)
			(stroke
				(width 0.1)
				(type default)
			)
			(layer "F.Fab")
		)
		(fp_line
			(start -0.12065 0.2794)
			(end -0.12065 0.3048)
			(stroke
				(width 0.1)
				(type default)
			)
			(layer "F.Fab")
		)
		(fp_line
			(start 0.67945 0.3048)
			(end 0.120396 0.3048)
			(stroke
				(width 0.1)
				(type default)
			)
			(layer "F.Fab")
		)
		(fp_line
			(start 0.120396 0.3048)
			(end 0.120396 0.2794)
			(stroke
				(width 0.1)
				(type default)
			)
			(layer "F.Fab")
		)
		(fp_line
			(start -0.12065 0.3048)
			(end -0.67945 0.3048)
			(stroke
				(width 0.1)
				(type default)
			)
			(layer "F.Fab")
		)
		(fp_line
			(start -0.67945 0.3048)
			(end -0.67945 -0.305054)
			(stroke
				(width 0.1)
				(type default)
			)
			(layer "F.Fab")
		)
		(pad "1" smd circle
			(at -0.40005 0 90)
			(size 0 0)
			(layers "F.Cu" "F.Mask" "F.Paste")
			(net "P3V3_AUX")
		)
		(pad "2" smd circle
			(at 0.40005 0 90)
			(size 0 0)
			(layers "F.Cu" "F.Mask" "F.Paste")
			(net "UART_6_BMC_RXD_R")
		)
	)
	(footprint ""
		(layer "F.Cu")
		(at 19.3421 -35.967162 180)
		(property "Reference" "PC261"
			(at 0 0 180)
			(layer "F.SilkS")
			(hide yes)
			(effects
				(font
					(size 1.27 1.27)
				)
			)
		)
		(property "Value" ""
			(at 0 0 180)
			(layer "F.Fab")
			(effects
				(font
					(size 1.27 1.27)
				)
			)
		)
		(duplicate_pad_numbers_are_jumpers no)
		(fp_line
			(start 1.651 0.8382)
			(end -1.651 0.8382)
			(stroke
				(width 0.1524)
				(type default)
			)
			(layer "F.SilkS")
		)
		(fp_line
			(start 1.651 -0.8382)
			(end 1.651 0.8382)
			(stroke
				(width 0.1524)
				(type default)
			)
			(layer "F.SilkS")
		)
		(fp_line
			(start 0 0.8382)
			(end 0 -0.8382)
			(stroke
				(width 0.1524)
				(type default)
			)
			(layer "F.SilkS")
		)
		(fp_line
			(start -1.651 0.8382)
			(end -1.651 -0.8382)
			(stroke
				(width 0.1524)
				(type default)
			)
			(layer "F.SilkS")
		)
		(fp_line
			(start -1.651 -0.8382)
			(end 1.651 -0.8382)
			(stroke
				(width 0.1524)
				(type default)
			)
			(layer "F.SilkS")
		)
		(fp_line
			(start 1.55956 0.7366)
			(end 1.55956 -0.7366)
			(stroke
				(width 0.1)
				(type default)
			)
			(layer "F.Fab")
		)
		(fp_line
			(start 1.55956 -0.7366)
			(end 1.524 -0.7366)
			(stroke
				(width 0.1)
				(type default)
			)
			(layer "F.Fab")
		)
		(fp_line
			(start 1.524 0.7366)
			(end 1.55956 0.7366)
			(stroke
				(width 0.1)
				(type default)
			)
			(layer "F.Fab")
		)
		(fp_line
			(start 1.524 -0.7366)
			(end -1.524 -0.7366)
			(stroke
				(width 0.1)
				(type default)
			)
			(layer "F.Fab")
		)
		(fp_line
			(start -1.524 0.7366)
			(end 1.524 0.7366)
			(stroke
				(width 0.1)
				(type default)
			)
			(layer "F.Fab")
		)
		(fp_line
			(start -1.524 -0.7366)
			(end -1.55956 -0.7366)
			(stroke
				(width 0.1)
				(type default)
			)
			(layer "F.Fab")
		)
		(fp_line
			(start -1.55956 0.7366)
			(end -1.524 0.7366)
			(stroke
				(width 0.1)
				(type default)
			)
			(layer "F.Fab")
		)
		(fp_line
			(start -1.55956 -0.7366)
			(end -1.55956 0.7366)
			(stroke
				(width 0.1)
				(type default)
			)
			(layer "F.Fab")
		)
		(pad "1" smd rect
			(at -0.94996 0)
			(size 1.1176 1.3716)
			(layers "F.Cu" "F.Mask" "F.Paste")
			(net "SW_P1V0_AUX_FLT")
		)
		(pad "2" smd rect
			(at 0.94996 0)
			(size 1.1176 1.3716)
			(layers "F.Cu" "F.Mask" "F.Paste")
			(net "GND")
		)
	)
	(footprint ""
		(layer "F.Cu")
		(at 28.935172 -83.816952 90)
		(property "Reference" "R654"
			(at 0 0 90)
			(layer "F.SilkS")
			(hide yes)
			(effects
				(font
					(size 1.27 1.27)
				)
			)
		)
		(property "Value" ""
			(at 0 0 90)
			(layer "F.Fab")
			(effects
				(font
					(size 1.27 1.27)
				)
			)
		)
		(duplicate_pad_numbers_are_jumpers no)
		(fp_line
			(start 0.7874 -0.4064)
			(end 0.7874 0.4064)
			(stroke
				(width 0.1524)
				(type default)
			)
			(layer "F.SilkS")
		)
		(fp_line
			(start -0.7874 -0.4064)
			(end 0.7874 -0.4064)
			(stroke
				(width 0.1524)
				(type default)
			)
			(layer "F.SilkS")
		)
		(fp_line
			(start 0.7874 0.4064)
			(end -0.7874 0.4064)
			(stroke
				(width 0.1524)
				(type default)
			)
			(layer "F.SilkS")
		)
		(fp_line
			(start -0.7874 0.4064)
			(end -0.7874 -0.4064)
			(stroke
				(width 0.1524)
				(type default)
			)
			(layer "F.SilkS")
		)
		(fp_line
			(start -0.12065 -0.305054)
			(end -0.12065 -0.2794)
			(stroke
				(width 0.1)
				(type default)
			)
			(layer "F.Fab")
		)
		(fp_line
			(start -0.67945 -0.305054)
			(end -0.12065 -0.305054)
			(stroke
				(width 0.1)
				(type default)
			)
			(layer "F.Fab")
		)
		(fp_line
			(start 0.67945 -0.3048)
			(end 0.67945 0.3048)
			(stroke
				(width 0.1)
				(type default)
			)
			(layer "F.Fab")
		)
		(fp_line
			(start 0.12065 -0.3048)
			(end 0.67945 -0.3048)
			(stroke
				(width 0.1)
				(type default)
			)
			(layer "F.Fab")
		)
		(fp_line
			(start 0.12065 -0.2794)
			(end 0.12065 -0.3048)
			(stroke
				(width 0.1)
				(type default)
			)
			(layer "F.Fab")
		)
		(fp_line
			(start -0.12065 -0.2794)
			(end 0.12065 -0.2794)
			(stroke
				(width 0.1)
				(type default)
			)
			(layer "F.Fab")
		)
		(fp_line
			(start 0.120396 0.2794)
			(end -0.12065 0.2794)
			(stroke
				(width 0.1)
				(type default)
			)
			(layer "F.Fab")
		)
		(fp_line
			(start -0.12065 0.2794)
			(end -0.12065 0.3048)
			(stroke
				(width 0.1)
				(type default)
			)
			(layer "F.Fab")
		)
		(fp_line
			(start 0.67945 0.3048)
			(end 0.120396 0.3048)
			(stroke
				(width 0.1)
				(type default)
			)
			(layer "F.Fab")
		)
		(fp_line
			(start 0.120396 0.3048)
			(end 0.120396 0.2794)
			(stroke
				(width 0.1)
				(type default)
			)
			(layer "F.Fab")
		)
		(fp_line
			(start -0.12065 0.3048)
			(end -0.67945 0.3048)
			(stroke
				(width 0.1)
				(type default)
			)
			(layer "F.Fab")
		)
		(fp_line
			(start -0.67945 0.3048)
			(end -0.67945 -0.305054)
			(stroke
				(width 0.1)
				(type default)
			)
			(layer "F.Fab")
		)
		(pad "1" smd circle
			(at -0.40005 0 90)
			(size 0 0)
			(layers "F.Cu" "F.Mask" "F.Paste")
			(net "EMMC_CLK_R")
		)
		(pad "2" smd circle
			(at 0.40005 0 90)
			(size 0 0)
			(layers "F.Cu" "F.Mask" "F.Paste")
			(net "BMC_EMMC_CLK")
		)
	)
	(footprint ""
		(layer "F.Cu")
		(at 55.4228 -63.6524 90)
		(property "Reference" "R681"
			(at 0 0 90)
			(layer "F.SilkS")
			(hide yes)
			(effects
				(font
					(size 1.27 1.27)
				)
			)
		)
		(property "Value" ""
			(at 0 0 90)
			(layer "F.Fab")
			(effects
				(font
					(size 1.27 1.27)
				)
			)
		)
		(duplicate_pad_numbers_are_jumpers no)
		(fp_line
			(start 0.7874 -0.4064)
			(end 0.7874 0.4064)
			(stroke
				(width 0.1524)
				(type default)
			)
			(layer "F.SilkS")
		)
		(fp_line
			(start -0.7874 -0.4064)
			(end 0.7874 -0.4064)
			(stroke
				(width 0.1524)
				(type default)
			)
			(layer "F.SilkS")
		)
		(fp_line
			(start 0.7874 0.4064)
			(end -0.7874 0.4064)
			(stroke
				(width 0.1524)
				(type default)
			)
			(layer "F.SilkS")
		)
		(fp_line
			(start -0.7874 0.4064)
			(end -0.7874 -0.4064)
			(stroke
				(width 0.1524)
				(type default)
			)
			(layer "F.SilkS")
		)
		(fp_line
			(start -0.12065 -0.305054)
			(end -0.12065 -0.2794)
			(stroke
				(width 0.1)
				(type default)
			)
			(layer "F.Fab")
		)
		(fp_line
			(start -0.67945 -0.305054)
			(end -0.12065 -0.305054)
			(stroke
				(width 0.1)
				(type default)
			)
			(layer "F.Fab")
		)
		(fp_line
			(start 0.67945 -0.3048)
			(end 0.67945 0.3048)
			(stroke
				(width 0.1)
				(type default)
			)
			(layer "F.Fab")
		)
		(fp_line
			(start 0.12065 -0.3048)
			(end 0.67945 -0.3048)
			(stroke
				(width 0.1)
				(type default)
			)
			(layer "F.Fab")
		)
		(fp_line
			(start 0.12065 -0.2794)
			(end 0.12065 -0.3048)
			(stroke
				(width 0.1)
				(type default)
			)
			(layer "F.Fab")
		)
		(fp_line
			(start -0.12065 -0.2794)
			(end 0.12065 -0.2794)
			(stroke
				(width 0.1)
				(type default)
			)
			(layer "F.Fab")
		)
		(fp_line
			(start 0.120396 0.2794)
			(end -0.12065 0.2794)
			(stroke
				(width 0.1)
				(type default)
			)
			(layer "F.Fab")
		)
		(fp_line
			(start -0.12065 0.2794)
			(end -0.12065 0.3048)
			(stroke
				(width 0.1)
				(type default)
			)
			(layer "F.Fab")
		)
		(fp_line
			(start 0.67945 0.3048)
			(end 0.120396 0.3048)
			(stroke
				(width 0.1)
				(type default)
			)
			(layer "F.Fab")
		)
		(fp_line
			(start 0.120396 0.3048)
			(end 0.120396 0.2794)
			(stroke
				(width 0.1)
				(type default)
			)
			(layer "F.Fab")
		)
		(fp_line
			(start -0.12065 0.3048)
			(end -0.67945 0.3048)
			(stroke
				(width 0.1)
				(type default)
			)
			(layer "F.Fab")
		)
		(fp_line
			(start -0.67945 0.3048)
			(end -0.67945 -0.305054)
			(stroke
				(width 0.1)
				(type default)
			)
			(layer "F.Fab")
		)
		(pad "1" smd circle
			(at -0.40005 0 90)
			(size 0 0)
			(layers "F.Cu" "F.Mask" "F.Paste")
			(net "SPI_BMC_IO2_R")
		)
		(pad "2" smd circle
			(at 0.40005 0 90)
			(size 0 0)
			(layers "F.Cu" "F.Mask" "F.Paste")
			(net "QSPI_2_PLD_IO2")
		)
	)
	(footprint ""
		(layer "F.Cu")
		(at 16.564864 -57.7342 90)
		(property "Reference" "R903"
			(at 0 0 90)
			(layer "F.SilkS")
			(hide yes)
			(effects
				(font
					(size 1.27 1.27)
				)
			)
		)
		(property "Value" ""
			(at 0 0 90)
			(layer "F.Fab")
			(effects
				(font
					(size 1.27 1.27)
				)
			)
		)
		(duplicate_pad_numbers_are_jumpers no)
		(fp_line
			(start 0.7874 -0.4064)
			(end 0.7874 0.4064)
			(stroke
				(width 0.1524)
				(type default)
			)
			(layer "F.SilkS")
		)
		(fp_line
			(start -0.7874 -0.4064)
			(end 0.7874 -0.4064)
			(stroke
				(width 0.1524)
				(type default)
			)
			(layer "F.SilkS")
		)
		(fp_line
			(start 0.7874 0.4064)
			(end -0.7874 0.4064)
			(stroke
				(width 0.1524)
				(type default)
			)
			(layer "F.SilkS")
		)
		(fp_line
			(start -0.7874 0.4064)
			(end -0.7874 -0.4064)
			(stroke
				(width 0.1524)
				(type default)
			)
			(layer "F.SilkS")
		)
		(fp_line
			(start -0.12065 -0.305054)
			(end -0.12065 -0.2794)
			(stroke
				(width 0.1)
				(type default)
			)
			(layer "F.Fab")
		)
		(fp_line
			(start -0.67945 -0.305054)
			(end -0.12065 -0.305054)
			(stroke
				(width 0.1)
				(type default)
			)
			(layer "F.Fab")
		)
		(fp_line
			(start 0.67945 -0.3048)
			(end 0.67945 0.3048)
			(stroke
				(width 0.1)
				(type default)
			)
			(layer "F.Fab")
		)
		(fp_line
			(start 0.12065 -0.3048)
			(end 0.67945 -0.3048)
			(stroke
				(width 0.1)
				(type default)
			)
			(layer "F.Fab")
		)
		(fp_line
			(start 0.12065 -0.2794)
			(end 0.12065 -0.3048)
			(stroke
				(width 0.1)
				(type default)
			)
			(layer "F.Fab")
		)
		(fp_line
			(start -0.12065 -0.2794)
			(end 0.12065 -0.2794)
			(stroke
				(width 0.1)
				(type default)
			)
			(layer "F.Fab")
		)
		(fp_line
			(start 0.120396 0.2794)
			(end -0.12065 0.2794)
			(stroke
				(width 0.1)
				(type default)
			)
			(layer "F.Fab")
		)
		(fp_line
			(start -0.12065 0.2794)
			(end -0.12065 0.3048)
			(stroke
				(width 0.1)
				(type default)
			)
			(layer "F.Fab")
		)
		(fp_line
			(start 0.67945 0.3048)
			(end 0.120396 0.3048)
			(stroke
				(width 0.1)
				(type default)
			)
			(layer "F.Fab")
		)
		(fp_line
			(start 0.120396 0.3048)
			(end 0.120396 0.2794)
			(stroke
				(width 0.1)
				(type default)
			)
			(layer "F.Fab")
		)
		(fp_line
			(start -0.12065 0.3048)
			(end -0.67945 0.3048)
			(stroke
				(width 0.1)
				(type default)
			)
			(layer "F.Fab")
		)
		(fp_line
			(start -0.67945 0.3048)
			(end -0.67945 -0.305054)
			(stroke
				(width 0.1)
				(type default)
			)
			(layer "F.Fab")
		)
		(pad "1" smd circle
			(at -0.40005 0 90)
			(size 0 0)
			(layers "F.Cu" "F.Mask" "F.Paste")
			(net "UART_6_BMC_TXD")
		)
		(pad "2" smd circle
			(at 0.40005 0 90)
			(size 0 0)
			(layers "F.Cu" "F.Mask" "F.Paste")
			(net "UART_6_BMC_TXD_R")
		)
	)
	(footprint ""
		(layer "F.Cu")
		(at 68.5292 -26.3906 -90)
		(property "Reference" "R510"
			(at 0 0 270)
			(layer "F.SilkS")
			(hide yes)
			(effects
				(font
					(size 1.27 1.27)
				)
			)
		)
		(property "Value" ""
			(at 0 0 270)
			(layer "F.Fab")
			(effects
				(font
					(size 1.27 1.27)
				)
			)
		)
		(duplicate_pad_numbers_are_jumpers no)
		(fp_line
			(start -0.7874 0.4064)
			(end -0.7874 -0.4064)
			(stroke
				(width 0.1524)
				(type default)
			)
			(layer "F.SilkS")
		)
		(fp_line
			(start 0.7874 0.4064)
			(end -0.7874 0.4064)
			(stroke
				(width 0.1524)
				(type default)
			)
			(layer "F.SilkS")
		)
		(fp_line
			(start -0.7874 -0.4064)
			(end 0.7874 -0.4064)
			(stroke
				(width 0.1524)
				(type default)
			)
			(layer "F.SilkS")
		)
		(fp_line
			(start 0.7874 -0.4064)
			(end 0.7874 0.4064)
			(stroke
				(width 0.1524)
				(type default)
			)
			(layer "F.SilkS")
		)
		(fp_line
			(start -0.67945 0.3048)
			(end -0.67945 -0.305054)
			(stroke
				(width 0.1)
				(type default)
			)
			(layer "F.Fab")
		)
		(fp_line
			(start -0.12065 0.3048)
			(end -0.67945 0.3048)
			(stroke
				(width 0.1)
				(type default)
			)
			(layer "F.Fab")
		)
		(fp_line
			(start 0.120396 0.3048)
			(end 0.120396 0.2794)
			(stroke
				(width 0.1)
				(type default)
			)
			(layer "F.Fab")
		)
		(fp_line
			(start 0.67945 0.3048)
			(end 0.120396 0.3048)
			(stroke
				(width 0.1)
				(type default)
			)
			(layer "F.Fab")
		)
		(fp_line
			(start -0.12065 0.2794)
			(end -0.12065 0.3048)
			(stroke
				(width 0.1)
				(type default)
			)
			(layer "F.Fab")
		)
		(fp_line
			(start 0.120396 0.2794)
			(end -0.12065 0.2794)
			(stroke
				(width 0.1)
				(type default)
			)
			(layer "F.Fab")
		)
		(fp_line
			(start -0.12065 -0.2794)
			(end 0.12065 -0.2794)
			(stroke
				(width 0.1)
				(type default)
			)
			(layer "F.Fab")
		)
		(fp_line
			(start 0.12065 -0.2794)
			(end 0.12065 -0.3048)
			(stroke
				(width 0.1)
				(type default)
			)
			(layer "F.Fab")
		)
		(fp_line
			(start 0.12065 -0.3048)
			(end 0.67945 -0.3048)
			(stroke
				(width 0.1)
				(type default)
			)
			(layer "F.Fab")
		)
		(fp_line
			(start 0.67945 -0.3048)
			(end 0.67945 0.3048)
			(stroke
				(width 0.1)
				(type default)
			)
			(layer "F.Fab")
		)
		(fp_line
			(start -0.67945 -0.305054)
			(end -0.12065 -0.305054)
			(stroke
				(width 0.1)
				(type default)
			)
			(layer "F.Fab")
		)
		(fp_line
			(start -0.12065 -0.305054)
			(end -0.12065 -0.2794)
			(stroke
				(width 0.1)
				(type default)
			)
			(layer "F.Fab")
		)
		(pad "1" smd circle
			(at -0.40005 0 270)
			(size 0 0)
			(layers "F.Cu" "F.Mask" "F.Paste")
			(net "JTAG_SCM_TCK")
		)
		(pad "2" smd circle
			(at 0.40005 0 270)
			(size 0 0)
			(layers "F.Cu" "F.Mask" "F.Paste")
			(net "JTAG_SCM_PLD_TCK")
		)
	)
	(footprint ""
		(layer "F.Cu")
		(at 76.691744 -35.502088 90)
		(property "Reference" "R328"
			(at 0 0 90)
			(layer "F.SilkS")
			(hide yes)
			(effects
				(font
					(size 1.27 1.27)
				)
			)
		)
		(property "Value" ""
			(at 0 0 90)
			(layer "F.Fab")
			(effects
				(font
					(size 1.27 1.27)
				)
			)
		)
		(duplicate_pad_numbers_are_jumpers no)
		(fp_line
			(start 0.7874 -0.4064)
			(end 0.7874 0.4064)
			(stroke
				(width 0.1524)
				(type default)
			)
			(layer "F.SilkS")
		)
		(fp_line
			(start -0.7874 -0.4064)
			(end 0.7874 -0.4064)
			(stroke
				(width 0.1524)
				(type default)
			)
			(layer "F.SilkS")
		)
		(fp_line
			(start 0.7874 0.4064)
			(end -0.7874 0.4064)
			(stroke
				(width 0.1524)
				(type default)
			)
			(layer "F.SilkS")
		)
		(fp_line
			(start -0.7874 0.4064)
			(end -0.7874 -0.4064)
			(stroke
				(width 0.1524)
				(type default)
			)
			(layer "F.SilkS")
		)
		(fp_line
			(start -0.12065 -0.305054)
			(end -0.12065 -0.2794)
			(stroke
				(width 0.1)
				(type default)
			)
			(layer "F.Fab")
		)
		(fp_line
			(start -0.67945 -0.305054)
			(end -0.12065 -0.305054)
			(stroke
				(width 0.1)
				(type default)
			)
			(layer "F.Fab")
		)
		(fp_line
			(start 0.67945 -0.3048)
			(end 0.67945 0.3048)
			(stroke
				(width 0.1)
				(type default)
			)
			(layer "F.Fab")
		)
		(fp_line
			(start 0.12065 -0.3048)
			(end 0.67945 -0.3048)
			(stroke
				(width 0.1)
				(type default)
			)
			(layer "F.Fab")
		)
		(fp_line
			(start 0.12065 -0.2794)
			(end 0.12065 -0.3048)
			(stroke
				(width 0.1)
				(type default)
			)
			(layer "F.Fab")
		)
		(fp_line
			(start -0.12065 -0.2794)
			(end 0.12065 -0.2794)
			(stroke
				(width 0.1)
				(type default)
			)
			(layer "F.Fab")
		)
		(fp_line
			(start 0.120396 0.2794)
			(end -0.12065 0.2794)
			(stroke
				(width 0.1)
				(type default)
			)
			(layer "F.Fab")
		)
		(fp_line
			(start -0.12065 0.2794)
			(end -0.12065 0.3048)
			(stroke
				(width 0.1)
				(type default)
			)
			(layer "F.Fab")
		)
		(fp_line
			(start 0.67945 0.3048)
			(end 0.120396 0.3048)
			(stroke
				(width 0.1)
				(type default)
			)
			(layer "F.Fab")
		)
		(fp_line
			(start 0.120396 0.3048)
			(end 0.120396 0.2794)
			(stroke
				(width 0.1)
				(type default)
			)
			(layer "F.Fab")
		)
		(fp_line
			(start -0.12065 0.3048)
			(end -0.67945 0.3048)
			(stroke
				(width 0.1)
				(type default)
			)
			(layer "F.Fab")
		)
		(fp_line
			(start -0.67945 0.3048)
			(end -0.67945 -0.305054)
			(stroke
				(width 0.1)
				(type default)
			)
			(layer "F.Fab")
		)
		(pad "1" smd circle
			(at -0.40005 0 90)
			(size 0 0)
			(layers "F.Cu" "F.Mask" "F.Paste")
			(net "GND")
		)
		(pad "2" smd circle
			(at 0.40005 0 90)
			(size 0 0)
			(layers "F.Cu" "F.Mask" "F.Paste")
			(net "M_BMC_DDR4_MA<2>")
		)
	)
	(footprint ""
		(layer "F.Cu")
		(at 48.593248 -20.435062 90)
		(property "Reference" "C178"
			(at 0 0 90)
			(layer "F.SilkS")
			(hide yes)
			(effects
				(font
					(size 1.27 1.27)
				)
			)
		)
		(property "Value" ""
			(at 0 0 90)
			(layer "F.Fab")
			(effects
				(font
					(size 1.27 1.27)
				)
			)
		)
		(duplicate_pad_numbers_are_jumpers no)
		(fp_line
			(start 0.7874 -0.4064)
			(end 0.7874 0.4064)
			(stroke
				(width 0.1524)
				(type default)
			)
			(layer "F.SilkS")
		)
		(fp_line
			(start -0.7874 -0.4064)
			(end 0.7874 -0.4064)
			(stroke
				(width 0.1524)
				(type default)
			)
			(layer "F.SilkS")
		)
		(fp_line
			(start 0.7874 0.4064)
			(end -0.7874 0.4064)
			(stroke
				(width 0.1524)
				(type default)
			)
			(layer "F.SilkS")
		)
		(fp_line
			(start -0.7874 0.4064)
			(end -0.7874 -0.4064)
			(stroke
				(width 0.1524)
				(type default)
			)
			(layer "F.SilkS")
		)
		(fp_line
			(start -0.12065 -0.305054)
			(end -0.12065 -0.2794)
			(stroke
				(width 0.1)
				(type default)
			)
			(layer "F.Fab")
		)
		(fp_line
			(start -0.67945 -0.305054)
			(end -0.12065 -0.305054)
			(stroke
				(width 0.1)
				(type default)
			)
			(layer "F.Fab")
		)
		(fp_line
			(start 0.67945 -0.3048)
			(end 0.67945 0.3048)
			(stroke
				(width 0.1)
				(type default)
			)
			(layer "F.Fab")
		)
		(fp_line
			(start 0.12065 -0.3048)
			(end 0.67945 -0.3048)
			(stroke
				(width 0.1)
				(type default)
			)
			(layer "F.Fab")
		)
		(fp_line
			(start 0.12065 -0.2794)
			(end 0.12065 -0.3048)
			(stroke
				(width 0.1)
				(type default)
			)
			(layer "F.Fab")
		)
		(fp_line
			(start -0.12065 -0.2794)
			(end 0.12065 -0.2794)
			(stroke
				(width 0.1)
				(type default)
			)
			(layer "F.Fab")
		)
		(fp_line
			(start 0.120396 0.2794)
			(end -0.12065 0.2794)
			(stroke
				(width 0.1)
				(type default)
			)
			(layer "F.Fab")
		)
		(fp_line
			(start -0.12065 0.2794)
			(end -0.12065 0.3048)
			(stroke
				(width 0.1)
				(type default)
			)
			(layer "F.Fab")
		)
		(fp_line
			(start 0.67945 0.3048)
			(end 0.120396 0.3048)
			(stroke
				(width 0.1)
				(type default)
			)
			(layer "F.Fab")
		)
		(fp_line
			(start 0.120396 0.3048)
			(end 0.120396 0.2794)
			(stroke
				(width 0.1)
				(type default)
			)
			(layer "F.Fab")
		)
		(fp_line
			(start -0.12065 0.3048)
			(end -0.67945 0.3048)
			(stroke
				(width 0.1)
				(type default)
			)
			(layer "F.Fab")
		)
		(fp_line
			(start -0.67945 0.3048)
			(end -0.67945 -0.305054)
			(stroke
				(width 0.1)
				(type default)
			)
			(layer "F.Fab")
		)
		(pad "1" smd circle
			(at -0.40005 0 90)
			(size 0 0)
			(layers "F.Cu" "F.Mask" "F.Paste")
			(net "P5V_USB_REAR")
		)
		(pad "2" smd circle
			(at 0.40005 0 90)
			(size 0 0)
			(layers "F.Cu" "F.Mask" "F.Paste")
			(net "GND")
		)
	)
	(footprint ""
		(layer "F.Cu")
		(at 36.047172 -83.816952 -90)
		(property "Reference" "R656"
			(at 0 0 270)
			(layer "F.SilkS")
			(hide yes)
			(effects
				(font
					(size 1.27 1.27)
				)
			)
		)
		(property "Value" ""
			(at 0 0 270)
			(layer "F.Fab")
			(effects
				(font
					(size 1.27 1.27)
				)
			)
		)
		(duplicate_pad_numbers_are_jumpers no)
		(fp_line
			(start -0.7874 0.4064)
			(end -0.7874 -0.4064)
			(stroke
				(width 0.1524)
				(type default)
			)
			(layer "F.SilkS")
		)
		(fp_line
			(start 0.7874 0.4064)
			(end -0.7874 0.4064)
			(stroke
				(width 0.1524)
				(type default)
			)
			(layer "F.SilkS")
		)
		(fp_line
			(start -0.7874 -0.4064)
			(end 0.7874 -0.4064)
			(stroke
				(width 0.1524)
				(type default)
			)
			(layer "F.SilkS")
		)
		(fp_line
			(start 0.7874 -0.4064)
			(end 0.7874 0.4064)
			(stroke
				(width 0.1524)
				(type default)
			)
			(layer "F.SilkS")
		)
		(fp_line
			(start -0.67945 0.3048)
			(end -0.67945 -0.305054)
			(stroke
				(width 0.1)
				(type default)
			)
			(layer "F.Fab")
		)
		(fp_line
			(start -0.12065 0.3048)
			(end -0.67945 0.3048)
			(stroke
				(width 0.1)
				(type default)
			)
			(layer "F.Fab")
		)
		(fp_line
			(start 0.120396 0.3048)
			(end 0.120396 0.2794)
			(stroke
				(width 0.1)
				(type default)
			)
			(layer "F.Fab")
		)
		(fp_line
			(start 0.67945 0.3048)
			(end 0.120396 0.3048)
			(stroke
				(width 0.1)
				(type default)
			)
			(layer "F.Fab")
		)
		(fp_line
			(start -0.12065 0.2794)
			(end -0.12065 0.3048)
			(stroke
				(width 0.1)
				(type default)
			)
			(layer "F.Fab")
		)
		(fp_line
			(start 0.120396 0.2794)
			(end -0.12065 0.2794)
			(stroke
				(width 0.1)
				(type default)
			)
			(layer "F.Fab")
		)
		(fp_line
			(start -0.12065 -0.2794)
			(end 0.12065 -0.2794)
			(stroke
				(width 0.1)
				(type default)
			)
			(layer "F.Fab")
		)
		(fp_line
			(start 0.12065 -0.2794)
			(end 0.12065 -0.3048)
			(stroke
				(width 0.1)
				(type default)
			)
			(layer "F.Fab")
		)
		(fp_line
			(start 0.12065 -0.3048)
			(end 0.67945 -0.3048)
			(stroke
				(width 0.1)
				(type default)
			)
			(layer "F.Fab")
		)
		(fp_line
			(start 0.67945 -0.3048)
			(end 0.67945 0.3048)
			(stroke
				(width 0.1)
				(type default)
			)
			(layer "F.Fab")
		)
		(fp_line
			(start -0.67945 -0.305054)
			(end -0.12065 -0.305054)
			(stroke
				(width 0.1)
				(type default)
			)
			(layer "F.Fab")
		)
		(fp_line
			(start -0.12065 -0.305054)
			(end -0.12065 -0.2794)
			(stroke
				(width 0.1)
				(type default)
			)
			(layer "F.Fab")
		)
		(pad "1" smd circle
			(at -0.40005 0 270)
			(size 0 0)
			(layers "F.Cu" "F.Mask" "F.Paste")
			(net "P3V3_AUX")
		)
		(pad "2" smd circle
			(at 0.40005 0 270)
			(size 0 0)
			(layers "F.Cu" "F.Mask" "F.Paste")
			(net "EMMC_DT1_R")
		)
	)
	(footprint ""
		(layer "F.Cu")
		(at 68.189094 -93.62694 180)
		(property "Reference" "R498"
			(at 0 0 180)
			(layer "F.SilkS")
			(hide yes)
			(effects
				(font
					(size 1.27 1.27)
				)
			)
		)
		(property "Value" ""
			(at 0 0 180)
			(layer "F.Fab")
			(effects
				(font
					(size 1.27 1.27)
				)
			)
		)
		(duplicate_pad_numbers_are_jumpers no)
		(fp_line
			(start 0.7874 0.4064)
			(end -0.7874 0.4064)
			(stroke
				(width 0.1524)
				(type default)
			)
			(layer "F.SilkS")
		)
		(fp_line
			(start 0.7874 -0.4064)
			(end 0.7874 0.4064)
			(stroke
				(width 0.1524)
				(type default)
			)
			(layer "F.SilkS")
		)
		(fp_line
			(start -0.7874 0.4064)
			(end -0.7874 -0.4064)
			(stroke
				(width 0.1524)
				(type default)
			)
			(layer "F.SilkS")
		)
		(fp_line
			(start -0.7874 -0.4064)
			(end 0.7874 -0.4064)
			(stroke
				(width 0.1524)
				(type default)
			)
			(layer "F.SilkS")
		)
		(fp_line
			(start 0.67945 0.3048)
			(end 0.120396 0.3048)
			(stroke
				(width 0.1)
				(type default)
			)
			(layer "F.Fab")
		)
		(fp_line
			(start 0.67945 -0.3048)
			(end 0.67945 0.3048)
			(stroke
				(width 0.1)
				(type default)
			)
			(layer "F.Fab")
		)
		(fp_line
			(start 0.12065 -0.2794)
			(end 0.12065 -0.3048)
			(stroke
				(width 0.1)
				(type default)
			)
			(layer "F.Fab")
		)
		(fp_line
			(start 0.12065 -0.3048)
			(end 0.67945 -0.3048)
			(stroke
				(width 0.1)
				(type default)
			)
			(layer "F.Fab")
		)
		(fp_line
			(start 0.120396 0.3048)
			(end 0.120396 0.2794)
			(stroke
				(width 0.1)
				(type default)
			)
			(layer "F.Fab")
		)
		(fp_line
			(start 0.120396 0.2794)
			(end -0.12065 0.2794)
			(stroke
				(width 0.1)
				(type default)
			)
			(layer "F.Fab")
		)
		(fp_line
			(start -0.12065 0.3048)
			(end -0.67945 0.3048)
			(stroke
				(width 0.1)
				(type default)
			)
			(layer "F.Fab")
		)
		(fp_line
			(start -0.12065 0.2794)
			(end -0.12065 0.3048)
			(stroke
				(width 0.1)
				(type default)
			)
			(layer "F.Fab")
		)
		(fp_line
			(start -0.12065 -0.2794)
			(end 0.12065 -0.2794)
			(stroke
				(width 0.1)
				(type default)
			)
			(layer "F.Fab")
		)
		(fp_line
			(start -0.12065 -0.305054)
			(end -0.12065 -0.2794)
			(stroke
				(width 0.1)
				(type default)
			)
			(layer "F.Fab")
		)
		(fp_line
			(start -0.67945 0.3048)
			(end -0.67945 -0.305054)
			(stroke
				(width 0.1)
				(type default)
			)
			(layer "F.Fab")
		)
		(fp_line
			(start -0.67945 -0.305054)
			(end -0.12065 -0.305054)
			(stroke
				(width 0.1)
				(type default)
			)
			(layer "F.Fab")
		)
		(pad "1" smd circle
			(at -0.40005 0 180)
			(size 0 0)
			(layers "F.Cu" "F.Mask" "F.Paste")
			(net "SPI_SYS_R_MOSI")
		)
		(pad "2" smd circle
			(at 0.40005 0 180)
			(size 0 0)
			(layers "F.Cu" "F.Mask" "F.Paste")
			(net "SPI_SYS_R1_MOSI")
		)
	)
	(footprint ""
		(layer "F.Cu")
		(at 49.2125 -96.012 90)
		(property "Reference" "R289"
			(at 0 0 90)
			(layer "F.SilkS")
			(hide yes)
			(effects
				(font
					(size 1.27 1.27)
				)
			)
		)
		(property "Value" ""
			(at 0 0 90)
			(layer "F.Fab")
			(effects
				(font
					(size 1.27 1.27)
				)
			)
		)
		(duplicate_pad_numbers_are_jumpers no)
		(fp_line
			(start 0.7874 -0.4064)
			(end 0.7874 0.4064)
			(stroke
				(width 0.1524)
				(type default)
			)
			(layer "F.SilkS")
		)
		(fp_line
			(start -0.7874 -0.4064)
			(end 0.7874 -0.4064)
			(stroke
				(width 0.1524)
				(type default)
			)
			(layer "F.SilkS")
		)
		(fp_line
			(start 0.7874 0.4064)
			(end -0.7874 0.4064)
			(stroke
				(width 0.1524)
				(type default)
			)
			(layer "F.SilkS")
		)
		(fp_line
			(start -0.7874 0.4064)
			(end -0.7874 -0.4064)
			(stroke
				(width 0.1524)
				(type default)
			)
			(layer "F.SilkS")
		)
		(fp_line
			(start -0.12065 -0.305054)
			(end -0.12065 -0.2794)
			(stroke
				(width 0.1)
				(type default)
			)
			(layer "F.Fab")
		)
		(fp_line
			(start -0.67945 -0.305054)
			(end -0.12065 -0.305054)
			(stroke
				(width 0.1)
				(type default)
			)
			(layer "F.Fab")
		)
		(fp_line
			(start 0.67945 -0.3048)
			(end 0.67945 0.3048)
			(stroke
				(width 0.1)
				(type default)
			)
			(layer "F.Fab")
		)
		(fp_line
			(start 0.12065 -0.3048)
			(end 0.67945 -0.3048)
			(stroke
				(width 0.1)
				(type default)
			)
			(layer "F.Fab")
		)
		(fp_line
			(start 0.12065 -0.2794)
			(end 0.12065 -0.3048)
			(stroke
				(width 0.1)
				(type default)
			)
			(layer "F.Fab")
		)
		(fp_line
			(start -0.12065 -0.2794)
			(end 0.12065 -0.2794)
			(stroke
				(width 0.1)
				(type default)
			)
			(layer "F.Fab")
		)
		(fp_line
			(start 0.120396 0.2794)
			(end -0.12065 0.2794)
			(stroke
				(width 0.1)
				(type default)
			)
			(layer "F.Fab")
		)
		(fp_line
			(start -0.12065 0.2794)
			(end -0.12065 0.3048)
			(stroke
				(width 0.1)
				(type default)
			)
			(layer "F.Fab")
		)
		(fp_line
			(start 0.67945 0.3048)
			(end 0.120396 0.3048)
			(stroke
				(width 0.1)
				(type default)
			)
			(layer "F.Fab")
		)
		(fp_line
			(start 0.120396 0.3048)
			(end 0.120396 0.2794)
			(stroke
				(width 0.1)
				(type default)
			)
			(layer "F.Fab")
		)
		(fp_line
			(start -0.12065 0.3048)
			(end -0.67945 0.3048)
			(stroke
				(width 0.1)
				(type default)
			)
			(layer "F.Fab")
		)
		(fp_line
			(start -0.67945 0.3048)
			(end -0.67945 -0.305054)
			(stroke
				(width 0.1)
				(type default)
			)
			(layer "F.Fab")
		)
		(pad "1" smd circle
			(at -0.40005 0 90)
			(size 0 0)
			(layers "F.Cu" "F.Mask" "F.Paste")
			(net "P3V3_RGM")
		)
		(pad "2" smd circle
			(at 0.40005 0 90)
			(size 0 0)
			(layers "F.Cu" "F.Mask" "F.Paste")
			(net "BJT_Q3_C")
		)
	)
	(footprint ""
		(layer "F.Cu")
		(at 42.828464 -30.867604 90)
		(property "Reference" "R706"
			(at 0 0 90)
			(layer "F.SilkS")
			(hide yes)
			(effects
				(font
					(size 1.27 1.27)
				)
			)
		)
		(property "Value" ""
			(at 0 0 90)
			(layer "F.Fab")
			(effects
				(font
					(size 1.27 1.27)
				)
			)
		)
		(duplicate_pad_numbers_are_jumpers no)
		(fp_line
			(start 0.7874 -0.4064)
			(end 0.7874 0.4064)
			(stroke
				(width 0.1524)
				(type default)
			)
			(layer "F.SilkS")
		)
		(fp_line
			(start -0.7874 -0.4064)
			(end 0.7874 -0.4064)
			(stroke
				(width 0.1524)
				(type default)
			)
			(layer "F.SilkS")
		)
		(fp_line
			(start 0.7874 0.4064)
			(end -0.7874 0.4064)
			(stroke
				(width 0.1524)
				(type default)
			)
			(layer "F.SilkS")
		)
		(fp_line
			(start -0.7874 0.4064)
			(end -0.7874 -0.4064)
			(stroke
				(width 0.1524)
				(type default)
			)
			(layer "F.SilkS")
		)
		(fp_line
			(start -0.12065 -0.305054)
			(end -0.12065 -0.2794)
			(stroke
				(width 0.1)
				(type default)
			)
			(layer "F.Fab")
		)
		(fp_line
			(start -0.67945 -0.305054)
			(end -0.12065 -0.305054)
			(stroke
				(width 0.1)
				(type default)
			)
			(layer "F.Fab")
		)
		(fp_line
			(start 0.67945 -0.3048)
			(end 0.67945 0.3048)
			(stroke
				(width 0.1)
				(type default)
			)
			(layer "F.Fab")
		)
		(fp_line
			(start 0.12065 -0.3048)
			(end 0.67945 -0.3048)
			(stroke
				(width 0.1)
				(type default)
			)
			(layer "F.Fab")
		)
		(fp_line
			(start 0.12065 -0.2794)
			(end 0.12065 -0.3048)
			(stroke
				(width 0.1)
				(type default)
			)
			(layer "F.Fab")
		)
		(fp_line
			(start -0.12065 -0.2794)
			(end 0.12065 -0.2794)
			(stroke
				(width 0.1)
				(type default)
			)
			(layer "F.Fab")
		)
		(fp_line
			(start 0.120396 0.2794)
			(end -0.12065 0.2794)
			(stroke
				(width 0.1)
				(type default)
			)
			(layer "F.Fab")
		)
		(fp_line
			(start -0.12065 0.2794)
			(end -0.12065 0.3048)
			(stroke
				(width 0.1)
				(type default)
			)
			(layer "F.Fab")
		)
		(fp_line
			(start 0.67945 0.3048)
			(end 0.120396 0.3048)
			(stroke
				(width 0.1)
				(type default)
			)
			(layer "F.Fab")
		)
		(fp_line
			(start 0.120396 0.3048)
			(end 0.120396 0.2794)
			(stroke
				(width 0.1)
				(type default)
			)
			(layer "F.Fab")
		)
		(fp_line
			(start -0.12065 0.3048)
			(end -0.67945 0.3048)
			(stroke
				(width 0.1)
				(type default)
			)
			(layer "F.Fab")
		)
		(fp_line
			(start -0.67945 0.3048)
			(end -0.67945 -0.305054)
			(stroke
				(width 0.1)
				(type default)
			)
			(layer "F.Fab")
		)
		(pad "1" smd circle
			(at -0.40005 0 90)
			(size 0 0)
			(layers "F.Cu" "F.Mask" "F.Paste")
			(net "P3V3_AUX")
		)
		(pad "2" smd circle
			(at 0.40005 0 90)
			(size 0 0)
			(layers "F.Cu" "F.Mask" "F.Paste")
			(net "FM_BMC_DBP_PRESENT_N")
		)
	)
	(footprint ""
		(layer "F.Cu")
		(at 58.039 -84.709 90)
		(property "Reference" "R753"
			(at 0 0 90)
			(layer "F.SilkS")
			(hide yes)
			(effects
				(font
					(size 1.27 1.27)
				)
			)
		)
		(property "Value" ""
			(at 0 0 90)
			(layer "F.Fab")
			(effects
				(font
					(size 1.27 1.27)
				)
			)
		)
		(duplicate_pad_numbers_are_jumpers no)
		(fp_line
			(start 0.7874 -0.4064)
			(end 0.7874 0.4064)
			(stroke
				(width 0.1524)
				(type default)
			)
			(layer "F.SilkS")
		)
		(fp_line
			(start -0.7874 -0.4064)
			(end 0.7874 -0.4064)
			(stroke
				(width 0.1524)
				(type default)
			)
			(layer "F.SilkS")
		)
		(fp_line
			(start 0.7874 0.4064)
			(end -0.7874 0.4064)
			(stroke
				(width 0.1524)
				(type default)
			)
			(layer "F.SilkS")
		)
		(fp_line
			(start -0.7874 0.4064)
			(end -0.7874 -0.4064)
			(stroke
				(width 0.1524)
				(type default)
			)
			(layer "F.SilkS")
		)
		(fp_line
			(start -0.12065 -0.305054)
			(end -0.12065 -0.2794)
			(stroke
				(width 0.1)
				(type default)
			)
			(layer "F.Fab")
		)
		(fp_line
			(start -0.67945 -0.305054)
			(end -0.12065 -0.305054)
			(stroke
				(width 0.1)
				(type default)
			)
			(layer "F.Fab")
		)
		(fp_line
			(start 0.67945 -0.3048)
			(end 0.67945 0.3048)
			(stroke
				(width 0.1)
				(type default)
			)
			(layer "F.Fab")
		)
		(fp_line
			(start 0.12065 -0.3048)
			(end 0.67945 -0.3048)
			(stroke
				(width 0.1)
				(type default)
			)
			(layer "F.Fab")
		)
		(fp_line
			(start 0.12065 -0.2794)
			(end 0.12065 -0.3048)
			(stroke
				(width 0.1)
				(type default)
			)
			(layer "F.Fab")
		)
		(fp_line
			(start -0.12065 -0.2794)
			(end 0.12065 -0.2794)
			(stroke
				(width 0.1)
				(type default)
			)
			(layer "F.Fab")
		)
		(fp_line
			(start 0.120396 0.2794)
			(end -0.12065 0.2794)
			(stroke
				(width 0.1)
				(type default)
			)
			(layer "F.Fab")
		)
		(fp_line
			(start -0.12065 0.2794)
			(end -0.12065 0.3048)
			(stroke
				(width 0.1)
				(type default)
			)
			(layer "F.Fab")
		)
		(fp_line
			(start 0.67945 0.3048)
			(end 0.120396 0.3048)
			(stroke
				(width 0.1)
				(type default)
			)
			(layer "F.Fab")
		)
		(fp_line
			(start 0.120396 0.3048)
			(end 0.120396 0.2794)
			(stroke
				(width 0.1)
				(type default)
			)
			(layer "F.Fab")
		)
		(fp_line
			(start -0.12065 0.3048)
			(end -0.67945 0.3048)
			(stroke
				(width 0.1)
				(type default)
			)
			(layer "F.Fab")
		)
		(fp_line
			(start -0.67945 0.3048)
			(end -0.67945 -0.305054)
			(stroke
				(width 0.1)
				(type default)
			)
			(layer "F.Fab")
		)
		(pad "1" smd circle
			(at -0.40005 0 90)
			(size 0 0)
			(layers "F.Cu" "F.Mask" "F.Paste")
			(net "P3V3_AUX")
		)
		(pad "2" smd circle
			(at 0.40005 0 90)
			(size 0 0)
			(layers "F.Cu" "F.Mask" "F.Paste")
			(net "SPI_BMC_BOOT_MISO")
		)
	)
	(footprint ""
		(layer "F.Cu")
		(at 55.7784 -109.3978 -90)
		(property "Reference" "R864"
			(at 0 0 270)
			(layer "F.SilkS")
			(hide yes)
			(effects
				(font
					(size 1.27 1.27)
				)
			)
		)
		(property "Value" ""
			(at 0 0 270)
			(layer "F.Fab")
			(effects
				(font
					(size 1.27 1.27)
				)
			)
		)
		(duplicate_pad_numbers_are_jumpers no)
		(fp_line
			(start -0.7874 0.4064)
			(end -0.7874 -0.4064)
			(stroke
				(width 0.1524)
				(type default)
			)
			(layer "F.SilkS")
		)
		(fp_line
			(start 0.7874 0.4064)
			(end -0.7874 0.4064)
			(stroke
				(width 0.1524)
				(type default)
			)
			(layer "F.SilkS")
		)
		(fp_line
			(start -0.7874 -0.4064)
			(end 0.7874 -0.4064)
			(stroke
				(width 0.1524)
				(type default)
			)
			(layer "F.SilkS")
		)
		(fp_line
			(start 0.7874 -0.4064)
			(end 0.7874 0.4064)
			(stroke
				(width 0.1524)
				(type default)
			)
			(layer "F.SilkS")
		)
		(fp_line
			(start -0.67945 0.3048)
			(end -0.67945 -0.305054)
			(stroke
				(width 0.1)
				(type default)
			)
			(layer "F.Fab")
		)
		(fp_line
			(start -0.12065 0.3048)
			(end -0.67945 0.3048)
			(stroke
				(width 0.1)
				(type default)
			)
			(layer "F.Fab")
		)
		(fp_line
			(start 0.120396 0.3048)
			(end 0.120396 0.2794)
			(stroke
				(width 0.1)
				(type default)
			)
			(layer "F.Fab")
		)
		(fp_line
			(start 0.67945 0.3048)
			(end 0.120396 0.3048)
			(stroke
				(width 0.1)
				(type default)
			)
			(layer "F.Fab")
		)
		(fp_line
			(start -0.12065 0.2794)
			(end -0.12065 0.3048)
			(stroke
				(width 0.1)
				(type default)
			)
			(layer "F.Fab")
		)
		(fp_line
			(start 0.120396 0.2794)
			(end -0.12065 0.2794)
			(stroke
				(width 0.1)
				(type default)
			)
			(layer "F.Fab")
		)
		(fp_line
			(start -0.12065 -0.2794)
			(end 0.12065 -0.2794)
			(stroke
				(width 0.1)
				(type default)
			)
			(layer "F.Fab")
		)
		(fp_line
			(start 0.12065 -0.2794)
			(end 0.12065 -0.3048)
			(stroke
				(width 0.1)
				(type default)
			)
			(layer "F.Fab")
		)
		(fp_line
			(start 0.12065 -0.3048)
			(end 0.67945 -0.3048)
			(stroke
				(width 0.1)
				(type default)
			)
			(layer "F.Fab")
		)
		(fp_line
			(start 0.67945 -0.3048)
			(end 0.67945 0.3048)
			(stroke
				(width 0.1)
				(type default)
			)
			(layer "F.Fab")
		)
		(fp_line
			(start -0.67945 -0.305054)
			(end -0.12065 -0.305054)
			(stroke
				(width 0.1)
				(type default)
			)
			(layer "F.Fab")
		)
		(fp_line
			(start -0.12065 -0.305054)
			(end -0.12065 -0.2794)
			(stroke
				(width 0.1)
				(type default)
			)
			(layer "F.Fab")
		)
		(pad "1" smd circle
			(at -0.40005 0 270)
			(size 0 0)
			(layers "F.Cu" "F.Mask" "F.Paste")
			(net "SPI_SYS_CS0_N")
		)
		(pad "2" smd circle
			(at 0.40005 0 270)
			(size 0 0)
			(layers "F.Cu" "F.Mask" "F.Paste")
			(net "SPI_PCH_SECURE_CS0_N")
		)
	)
	(footprint ""
		(layer "F.Cu")
		(at 72.1614 -106.2482 90)
		(property "Reference" "R822"
			(at 0 0 90)
			(layer "F.SilkS")
			(hide yes)
			(effects
				(font
					(size 1.27 1.27)
				)
			)
		)
		(property "Value" ""
			(at 0 0 90)
			(layer "F.Fab")
			(effects
				(font
					(size 1.27 1.27)
				)
			)
		)
		(duplicate_pad_numbers_are_jumpers no)
		(fp_line
			(start 0.7874 -0.4064)
			(end 0.7874 0.4064)
			(stroke
				(width 0.1524)
				(type default)
			)
			(layer "F.SilkS")
		)
		(fp_line
			(start -0.7874 -0.4064)
			(end 0.7874 -0.4064)
			(stroke
				(width 0.1524)
				(type default)
			)
			(layer "F.SilkS")
		)
		(fp_line
			(start 0.7874 0.4064)
			(end -0.7874 0.4064)
			(stroke
				(width 0.1524)
				(type default)
			)
			(layer "F.SilkS")
		)
		(fp_line
			(start -0.7874 0.4064)
			(end -0.7874 -0.4064)
			(stroke
				(width 0.1524)
				(type default)
			)
			(layer "F.SilkS")
		)
		(fp_line
			(start -0.12065 -0.305054)
			(end -0.12065 -0.2794)
			(stroke
				(width 0.1)
				(type default)
			)
			(layer "F.Fab")
		)
		(fp_line
			(start -0.67945 -0.305054)
			(end -0.12065 -0.305054)
			(stroke
				(width 0.1)
				(type default)
			)
			(layer "F.Fab")
		)
		(fp_line
			(start 0.67945 -0.3048)
			(end 0.67945 0.3048)
			(stroke
				(width 0.1)
				(type default)
			)
			(layer "F.Fab")
		)
		(fp_line
			(start 0.12065 -0.3048)
			(end 0.67945 -0.3048)
			(stroke
				(width 0.1)
				(type default)
			)
			(layer "F.Fab")
		)
		(fp_line
			(start 0.12065 -0.2794)
			(end 0.12065 -0.3048)
			(stroke
				(width 0.1)
				(type default)
			)
			(layer "F.Fab")
		)
		(fp_line
			(start -0.12065 -0.2794)
			(end 0.12065 -0.2794)
			(stroke
				(width 0.1)
				(type default)
			)
			(layer "F.Fab")
		)
		(fp_line
			(start 0.120396 0.2794)
			(end -0.12065 0.2794)
			(stroke
				(width 0.1)
				(type default)
			)
			(layer "F.Fab")
		)
		(fp_line
			(start -0.12065 0.2794)
			(end -0.12065 0.3048)
			(stroke
				(width 0.1)
				(type default)
			)
			(layer "F.Fab")
		)
		(fp_line
			(start 0.67945 0.3048)
			(end 0.120396 0.3048)
			(stroke
				(width 0.1)
				(type default)
			)
			(layer "F.Fab")
		)
		(fp_line
			(start 0.120396 0.3048)
			(end 0.120396 0.2794)
			(stroke
				(width 0.1)
				(type default)
			)
			(layer "F.Fab")
		)
		(fp_line
			(start -0.12065 0.3048)
			(end -0.67945 0.3048)
			(stroke
				(width 0.1)
				(type default)
			)
			(layer "F.Fab")
		)
		(fp_line
			(start -0.67945 0.3048)
			(end -0.67945 -0.305054)
			(stroke
				(width 0.1)
				(type default)
			)
			(layer "F.Fab")
		)
		(pad "1" smd circle
			(at -0.40005 0 90)
			(size 0 0)
			(layers "F.Cu" "F.Mask" "F.Paste")
			(net "FM_PRSNT_1_N")
		)
		(pad "2" smd circle
			(at 0.40005 0 90)
			(size 0 0)
			(layers "F.Cu" "F.Mask" "F.Paste")
			(net "FM_PRSNT_0_R_N")
		)
	)
	(footprint ""
		(layer "F.Cu")
		(at 84.201 -96.774)
		(property "Reference" "R414"
			(at 0 0 0)
			(layer "F.SilkS")
			(hide yes)
			(effects
				(font
					(size 1.27 1.27)
				)
			)
		)
		(property "Value" ""
			(at 0 0 0)
			(layer "F.Fab")
			(effects
				(font
					(size 1.27 1.27)
				)
			)
		)
		(duplicate_pad_numbers_are_jumpers no)
		(fp_line
			(start -0.7874 -0.4064)
			(end 0.7874 -0.4064)
			(stroke
				(width 0.1524)
				(type default)
			)
			(layer "F.SilkS")
		)
		(fp_line
			(start -0.7874 0.4064)
			(end -0.7874 -0.4064)
			(stroke
				(width 0.1524)
				(type default)
			)
			(layer "F.SilkS")
		)
		(fp_line
			(start 0.7874 -0.4064)
			(end 0.7874 0.4064)
			(stroke
				(width 0.1524)
				(type default)
			)
			(layer "F.SilkS")
		)
		(fp_line
			(start 0.7874 0.4064)
			(end -0.7874 0.4064)
			(stroke
				(width 0.1524)
				(type default)
			)
			(layer "F.SilkS")
		)
		(fp_line
			(start -0.67945 -0.305054)
			(end -0.12065 -0.305054)
			(stroke
				(width 0.1)
				(type default)
			)
			(layer "F.Fab")
		)
		(fp_line
			(start -0.67945 0.3048)
			(end -0.67945 -0.305054)
			(stroke
				(width 0.1)
				(type default)
			)
			(layer "F.Fab")
		)
		(fp_line
			(start -0.12065 -0.305054)
			(end -0.12065 -0.2794)
			(stroke
				(width 0.1)
				(type default)
			)
			(layer "F.Fab")
		)
		(fp_line
			(start -0.12065 -0.2794)
			(end 0.12065 -0.2794)
			(stroke
				(width 0.1)
				(type default)
			)
			(layer "F.Fab")
		)
		(fp_line
			(start -0.12065 0.2794)
			(end -0.12065 0.3048)
			(stroke
				(width 0.1)
				(type default)
			)
			(layer "F.Fab")
		)
		(fp_line
			(start -0.12065 0.3048)
			(end -0.67945 0.3048)
			(stroke
				(width 0.1)
				(type default)
			)
			(layer "F.Fab")
		)
		(fp_line
			(start 0.120396 0.2794)
			(end -0.12065 0.2794)
			(stroke
				(width 0.1)
				(type default)
			)
			(layer "F.Fab")
		)
		(fp_line
			(start 0.120396 0.3048)
			(end 0.120396 0.2794)
			(stroke
				(width 0.1)
				(type default)
			)
			(layer "F.Fab")
		)
		(fp_line
			(start 0.12065 -0.3048)
			(end 0.67945 -0.3048)
			(stroke
				(width 0.1)
				(type default)
			)
			(layer "F.Fab")
		)
		(fp_line
			(start 0.12065 -0.2794)
			(end 0.12065 -0.3048)
			(stroke
				(width 0.1)
				(type default)
			)
			(layer "F.Fab")
		)
		(fp_line
			(start 0.67945 -0.3048)
			(end 0.67945 0.3048)
			(stroke
				(width 0.1)
				(type default)
			)
			(layer "F.Fab")
		)
		(fp_line
			(start 0.67945 0.3048)
			(end 0.120396 0.3048)
			(stroke
				(width 0.1)
				(type default)
			)
			(layer "F.Fab")
		)
		(pad "1" smd circle
			(at -0.40005 0)
			(size 0 0)
			(layers "F.Cu" "F.Mask" "F.Paste")
			(net "P3V3_AUX")
		)
		(pad "2" smd circle
			(at 0.40005 0)
			(size 0 0)
			(layers "F.Cu" "F.Mask" "F.Paste")
			(net "SPI_BMC_TPM_MISO")
		)
	)
	(footprint ""
		(layer "F.Cu")
		(at 11.557 -9.652)
		(property "Reference" "R768"
			(at 0 0 0)
			(layer "F.SilkS")
			(hide yes)
			(effects
				(font
					(size 1.27 1.27)
				)
			)
		)
		(property "Value" ""
			(at 0 0 0)
			(layer "F.Fab")
			(effects
				(font
					(size 1.27 1.27)
				)
			)
		)
		(duplicate_pad_numbers_are_jumpers no)
		(fp_line
			(start -0.7874 -0.4064)
			(end 0.7874 -0.4064)
			(stroke
				(width 0.1524)
				(type default)
			)
			(layer "F.SilkS")
		)
		(fp_line
			(start -0.7874 0.4064)
			(end -0.7874 -0.4064)
			(stroke
				(width 0.1524)
				(type default)
			)
			(layer "F.SilkS")
		)
		(fp_line
			(start 0.7874 -0.4064)
			(end 0.7874 0.4064)
			(stroke
				(width 0.1524)
				(type default)
			)
			(layer "F.SilkS")
		)
		(fp_line
			(start 0.7874 0.4064)
			(end -0.7874 0.4064)
			(stroke
				(width 0.1524)
				(type default)
			)
			(layer "F.SilkS")
		)
		(fp_line
			(start -0.67945 -0.305054)
			(end -0.12065 -0.305054)
			(stroke
				(width 0.1)
				(type default)
			)
			(layer "F.Fab")
		)
		(fp_line
			(start -0.67945 0.3048)
			(end -0.67945 -0.305054)
			(stroke
				(width 0.1)
				(type default)
			)
			(layer "F.Fab")
		)
		(fp_line
			(start -0.12065 -0.305054)
			(end -0.12065 -0.2794)
			(stroke
				(width 0.1)
				(type default)
			)
			(layer "F.Fab")
		)
		(fp_line
			(start -0.12065 -0.2794)
			(end 0.12065 -0.2794)
			(stroke
				(width 0.1)
				(type default)
			)
			(layer "F.Fab")
		)
		(fp_line
			(start -0.12065 0.2794)
			(end -0.12065 0.3048)
			(stroke
				(width 0.1)
				(type default)
			)
			(layer "F.Fab")
		)
		(fp_line
			(start -0.12065 0.3048)
			(end -0.67945 0.3048)
			(stroke
				(width 0.1)
				(type default)
			)
			(layer "F.Fab")
		)
		(fp_line
			(start 0.120396 0.2794)
			(end -0.12065 0.2794)
			(stroke
				(width 0.1)
				(type default)
			)
			(layer "F.Fab")
		)
		(fp_line
			(start 0.120396 0.3048)
			(end 0.120396 0.2794)
			(stroke
				(width 0.1)
				(type default)
			)
			(layer "F.Fab")
		)
		(fp_line
			(start 0.12065 -0.3048)
			(end 0.67945 -0.3048)
			(stroke
				(width 0.1)
				(type default)
			)
			(layer "F.Fab")
		)
		(fp_line
			(start 0.12065 -0.2794)
			(end 0.12065 -0.3048)
			(stroke
				(width 0.1)
				(type default)
			)
			(layer "F.Fab")
		)
		(fp_line
			(start 0.67945 -0.3048)
			(end 0.67945 0.3048)
			(stroke
				(width 0.1)
				(type default)
			)
			(layer "F.Fab")
		)
		(fp_line
			(start 0.67945 0.3048)
			(end 0.120396 0.3048)
			(stroke
				(width 0.1)
				(type default)
			)
			(layer "F.Fab")
		)
		(pad "1" smd circle
			(at -0.40005 0)
			(size 0 0)
			(layers "F.Cu" "F.Mask" "F.Paste")
			(net "P3V3_AUX")
		)
		(pad "2" smd circle
			(at 0.40005 0)
			(size 0 0)
			(layers "F.Cu" "F.Mask" "F.Paste")
			(net "REAR_PWR_BTN_N")
		)
	)
	(footprint ""
		(layer "F.Cu")
		(at 37.690298 -38.53561 -90)
		(property "Reference" "R155"
			(at 0 0 270)
			(layer "F.SilkS")
			(hide yes)
			(effects
				(font
					(size 1.27 1.27)
				)
			)
		)
		(property "Value" ""
			(at 0 0 270)
			(layer "F.Fab")
			(effects
				(font
					(size 1.27 1.27)
				)
			)
		)
		(duplicate_pad_numbers_are_jumpers no)
		(fp_line
			(start -0.7874 0.4064)
			(end -0.7874 -0.4064)
			(stroke
				(width 0.1524)
				(type default)
			)
			(layer "F.SilkS")
		)
		(fp_line
			(start 0.7874 0.4064)
			(end -0.7874 0.4064)
			(stroke
				(width 0.1524)
				(type default)
			)
			(layer "F.SilkS")
		)
		(fp_line
			(start -0.7874 -0.4064)
			(end 0.7874 -0.4064)
			(stroke
				(width 0.1524)
				(type default)
			)
			(layer "F.SilkS")
		)
		(fp_line
			(start 0.7874 -0.4064)
			(end 0.7874 0.4064)
			(stroke
				(width 0.1524)
				(type default)
			)
			(layer "F.SilkS")
		)
		(fp_line
			(start -0.67945 0.3048)
			(end -0.67945 -0.305054)
			(stroke
				(width 0.1)
				(type default)
			)
			(layer "F.Fab")
		)
		(fp_line
			(start -0.12065 0.3048)
			(end -0.67945 0.3048)
			(stroke
				(width 0.1)
				(type default)
			)
			(layer "F.Fab")
		)
		(fp_line
			(start 0.120396 0.3048)
			(end 0.120396 0.2794)
			(stroke
				(width 0.1)
				(type default)
			)
			(layer "F.Fab")
		)
		(fp_line
			(start 0.67945 0.3048)
			(end 0.120396 0.3048)
			(stroke
				(width 0.1)
				(type default)
			)
			(layer "F.Fab")
		)
		(fp_line
			(start -0.12065 0.2794)
			(end -0.12065 0.3048)
			(stroke
				(width 0.1)
				(type default)
			)
			(layer "F.Fab")
		)
		(fp_line
			(start 0.120396 0.2794)
			(end -0.12065 0.2794)
			(stroke
				(width 0.1)
				(type default)
			)
			(layer "F.Fab")
		)
		(fp_line
			(start -0.12065 -0.2794)
			(end 0.12065 -0.2794)
			(stroke
				(width 0.1)
				(type default)
			)
			(layer "F.Fab")
		)
		(fp_line
			(start 0.12065 -0.2794)
			(end 0.12065 -0.3048)
			(stroke
				(width 0.1)
				(type default)
			)
			(layer "F.Fab")
		)
		(fp_line
			(start 0.12065 -0.3048)
			(end 0.67945 -0.3048)
			(stroke
				(width 0.1)
				(type default)
			)
			(layer "F.Fab")
		)
		(fp_line
			(start 0.67945 -0.3048)
			(end 0.67945 0.3048)
			(stroke
				(width 0.1)
				(type default)
			)
			(layer "F.Fab")
		)
		(fp_line
			(start -0.67945 -0.305054)
			(end -0.12065 -0.305054)
			(stroke
				(width 0.1)
				(type default)
			)
			(layer "F.Fab")
		)
		(fp_line
			(start -0.12065 -0.305054)
			(end -0.12065 -0.2794)
			(stroke
				(width 0.1)
				(type default)
			)
			(layer "F.Fab")
		)
		(pad "1" smd circle
			(at -0.40005 0 270)
			(size 0 0)
			(layers "F.Cu" "F.Mask" "F.Paste")
			(net "P3V3_AUX")
		)
		(pad "2" smd circle
			(at 0.40005 0 270)
			(size 0 0)
			(layers "F.Cu" "F.Mask" "F.Paste")
			(net "P3V3_P2V5_P1V8_RVDD")
		)
	)
	(footprint ""
		(layer "F.Cu")
		(at 11.27125 -64.54394 -90)
		(property "Reference" "PR530"
			(at 0 0 270)
			(layer "F.SilkS")
			(hide yes)
			(effects
				(font
					(size 1.27 1.27)
				)
			)
		)
		(property "Value" ""
			(at 0 0 270)
			(layer "F.Fab")
			(effects
				(font
					(size 1.27 1.27)
				)
			)
		)
		(duplicate_pad_numbers_are_jumpers no)
		(fp_line
			(start -0.7874 0.4064)
			(end -0.7874 -0.4064)
			(stroke
				(width 0.1524)
				(type default)
			)
			(layer "F.SilkS")
		)
		(fp_line
			(start 0.7874 0.4064)
			(end -0.7874 0.4064)
			(stroke
				(width 0.1524)
				(type default)
			)
			(layer "F.SilkS")
		)
		(fp_line
			(start -0.7874 -0.4064)
			(end 0.7874 -0.4064)
			(stroke
				(width 0.1524)
				(type default)
			)
			(layer "F.SilkS")
		)
		(fp_line
			(start 0.7874 -0.4064)
			(end 0.7874 0.4064)
			(stroke
				(width 0.1524)
				(type default)
			)
			(layer "F.SilkS")
		)
		(fp_line
			(start -0.67945 0.3048)
			(end -0.67945 -0.305054)
			(stroke
				(width 0.1)
				(type default)
			)
			(layer "F.Fab")
		)
		(fp_line
			(start -0.12065 0.3048)
			(end -0.67945 0.3048)
			(stroke
				(width 0.1)
				(type default)
			)
			(layer "F.Fab")
		)
		(fp_line
			(start 0.120396 0.3048)
			(end 0.120396 0.2794)
			(stroke
				(width 0.1)
				(type default)
			)
			(layer "F.Fab")
		)
		(fp_line
			(start 0.67945 0.3048)
			(end 0.120396 0.3048)
			(stroke
				(width 0.1)
				(type default)
			)
			(layer "F.Fab")
		)
		(fp_line
			(start -0.12065 0.2794)
			(end -0.12065 0.3048)
			(stroke
				(width 0.1)
				(type default)
			)
			(layer "F.Fab")
		)
		(fp_line
			(start 0.120396 0.2794)
			(end -0.12065 0.2794)
			(stroke
				(width 0.1)
				(type default)
			)
			(layer "F.Fab")
		)
		(fp_line
			(start -0.12065 -0.2794)
			(end 0.12065 -0.2794)
			(stroke
				(width 0.1)
				(type default)
			)
			(layer "F.Fab")
		)
		(fp_line
			(start 0.12065 -0.2794)
			(end 0.12065 -0.3048)
			(stroke
				(width 0.1)
				(type default)
			)
			(layer "F.Fab")
		)
		(fp_line
			(start 0.12065 -0.3048)
			(end 0.67945 -0.3048)
			(stroke
				(width 0.1)
				(type default)
			)
			(layer "F.Fab")
		)
		(fp_line
			(start 0.67945 -0.3048)
			(end 0.67945 0.3048)
			(stroke
				(width 0.1)
				(type default)
			)
			(layer "F.Fab")
		)
		(fp_line
			(start -0.67945 -0.305054)
			(end -0.12065 -0.305054)
			(stroke
				(width 0.1)
				(type default)
			)
			(layer "F.Fab")
		)
		(fp_line
			(start -0.12065 -0.305054)
			(end -0.12065 -0.2794)
			(stroke
				(width 0.1)
				(type default)
			)
			(layer "F.Fab")
		)
		(pad "1" smd circle
			(at -0.40005 0 270)
			(size 0 0)
			(layers "F.Cu" "F.Mask" "F.Paste")
			(net "GND")
		)
		(pad "2" smd circle
			(at 0.40005 0 270)
			(size 0 0)
			(layers "F.Cu" "F.Mask" "F.Paste")
			(net "P3V3_AUX_FB_RC")
		)
	)
	(footprint ""
		(layer "F.Cu")
		(at 64.600328 -29.377132 -90)
		(property "Reference" "R217"
			(at 0 0 270)
			(layer "F.SilkS")
			(hide yes)
			(effects
				(font
					(size 1.27 1.27)
				)
			)
		)
		(property "Value" ""
			(at 0 0 270)
			(layer "F.Fab")
			(effects
				(font
					(size 1.27 1.27)
				)
			)
		)
		(duplicate_pad_numbers_are_jumpers no)
		(fp_line
			(start -0.7874 0.4064)
			(end -0.7874 -0.167132)
			(stroke
				(width 0.1524)
				(type default)
			)
			(layer "F.SilkS")
		)
		(fp_line
			(start 0.7874 0.4064)
			(end -0.7874 0.4064)
			(stroke
				(width 0.1524)
				(type default)
			)
			(layer "F.SilkS")
		)
		(fp_line
			(start 0.7874 -0.062992)
			(end 0.7874 0.4064)
			(stroke
				(width 0.1524)
				(type default)
			)
			(layer "F.SilkS")
		)
		(fp_line
			(start -0.397002 -0.4064)
			(end 0.277368 -0.4064)
			(stroke
				(width 0.1524)
				(type default)
			)
			(layer "F.SilkS")
		)
		(fp_line
			(start -0.67945 0.3048)
			(end -0.67945 -0.305054)
			(stroke
				(width 0.1)
				(type default)
			)
			(layer "F.Fab")
		)
		(fp_line
			(start -0.12065 0.3048)
			(end -0.67945 0.3048)
			(stroke
				(width 0.1)
				(type default)
			)
			(layer "F.Fab")
		)
		(fp_line
			(start 0.120396 0.3048)
			(end 0.120396 0.2794)
			(stroke
				(width 0.1)
				(type default)
			)
			(layer "F.Fab")
		)
		(fp_line
			(start 0.67945 0.3048)
			(end 0.120396 0.3048)
			(stroke
				(width 0.1)
				(type default)
			)
			(layer "F.Fab")
		)
		(fp_line
			(start -0.12065 0.2794)
			(end -0.12065 0.3048)
			(stroke
				(width 0.1)
				(type default)
			)
			(layer "F.Fab")
		)
		(fp_line
			(start 0.120396 0.2794)
			(end -0.12065 0.2794)
			(stroke
				(width 0.1)
				(type default)
			)
			(layer "F.Fab")
		)
		(fp_line
			(start -0.12065 -0.2794)
			(end 0.12065 -0.2794)
			(stroke
				(width 0.1)
				(type default)
			)
			(layer "F.Fab")
		)
		(fp_line
			(start 0.12065 -0.2794)
			(end 0.12065 -0.3048)
			(stroke
				(width 0.1)
				(type default)
			)
			(layer "F.Fab")
		)
		(fp_line
			(start 0.12065 -0.3048)
			(end 0.67945 -0.3048)
			(stroke
				(width 0.1)
				(type default)
			)
			(layer "F.Fab")
		)
		(fp_line
			(start 0.67945 -0.3048)
			(end 0.67945 0.3048)
			(stroke
				(width 0.1)
				(type default)
			)
			(layer "F.Fab")
		)
		(fp_line
			(start -0.67945 -0.305054)
			(end -0.12065 -0.305054)
			(stroke
				(width 0.1)
				(type default)
			)
			(layer "F.Fab")
		)
		(fp_line
			(start -0.12065 -0.305054)
			(end -0.12065 -0.2794)
			(stroke
				(width 0.1)
				(type default)
			)
			(layer "F.Fab")
		)
		(pad "1" smd circle
			(at -0.40005 0 270)
			(size 0 0)
			(layers "F.Cu" "F.Mask" "F.Paste")
			(net "USB_HOST_BMC_A_R_DP")
		)
		(pad "2" smd circle
			(at 0.40005 0 270)
			(size 0 0)
			(layers "F.Cu" "F.Mask" "F.Paste")
			(net "USB_HOST_BMC_A_DP")
		)
	)
	(footprint ""
		(layer "F.Cu")
		(at 18.415 -66.04 90)
		(property "Reference" "C20"
			(at 0 0 90)
			(layer "F.SilkS")
			(hide yes)
			(effects
				(font
					(size 1.27 1.27)
				)
			)
		)
		(property "Value" ""
			(at 0 0 90)
			(layer "F.Fab")
			(effects
				(font
					(size 1.27 1.27)
				)
			)
		)
		(duplicate_pad_numbers_are_jumpers no)
		(fp_line
			(start 0.7874 -0.4064)
			(end 0.7874 0.4064)
			(stroke
				(width 0.1524)
				(type default)
			)
			(layer "F.SilkS")
		)
		(fp_line
			(start -0.7874 -0.4064)
			(end 0.7874 -0.4064)
			(stroke
				(width 0.1524)
				(type default)
			)
			(layer "F.SilkS")
		)
		(fp_line
			(start 0.7874 0.4064)
			(end -0.7874 0.4064)
			(stroke
				(width 0.1524)
				(type default)
			)
			(layer "F.SilkS")
		)
		(fp_line
			(start -0.7874 0.4064)
			(end -0.7874 -0.4064)
			(stroke
				(width 0.1524)
				(type default)
			)
			(layer "F.SilkS")
		)
		(fp_line
			(start -0.12065 -0.305054)
			(end -0.12065 -0.2794)
			(stroke
				(width 0.1)
				(type default)
			)
			(layer "F.Fab")
		)
		(fp_line
			(start -0.67945 -0.305054)
			(end -0.12065 -0.305054)
			(stroke
				(width 0.1)
				(type default)
			)
			(layer "F.Fab")
		)
		(fp_line
			(start 0.67945 -0.3048)
			(end 0.67945 0.3048)
			(stroke
				(width 0.1)
				(type default)
			)
			(layer "F.Fab")
		)
		(fp_line
			(start 0.12065 -0.3048)
			(end 0.67945 -0.3048)
			(stroke
				(width 0.1)
				(type default)
			)
			(layer "F.Fab")
		)
		(fp_line
			(start 0.12065 -0.2794)
			(end 0.12065 -0.3048)
			(stroke
				(width 0.1)
				(type default)
			)
			(layer "F.Fab")
		)
		(fp_line
			(start -0.12065 -0.2794)
			(end 0.12065 -0.2794)
			(stroke
				(width 0.1)
				(type default)
			)
			(layer "F.Fab")
		)
		(fp_line
			(start 0.120396 0.2794)
			(end -0.12065 0.2794)
			(stroke
				(width 0.1)
				(type default)
			)
			(layer "F.Fab")
		)
		(fp_line
			(start -0.12065 0.2794)
			(end -0.12065 0.3048)
			(stroke
				(width 0.1)
				(type default)
			)
			(layer "F.Fab")
		)
		(fp_line
			(start 0.67945 0.3048)
			(end 0.120396 0.3048)
			(stroke
				(width 0.1)
				(type default)
			)
			(layer "F.Fab")
		)
		(fp_line
			(start 0.120396 0.3048)
			(end 0.120396 0.2794)
			(stroke
				(width 0.1)
				(type default)
			)
			(layer "F.Fab")
		)
		(fp_line
			(start -0.12065 0.3048)
			(end -0.67945 0.3048)
			(stroke
				(width 0.1)
				(type default)
			)
			(layer "F.Fab")
		)
		(fp_line
			(start -0.67945 0.3048)
			(end -0.67945 -0.305054)
			(stroke
				(width 0.1)
				(type default)
			)
			(layer "F.Fab")
		)
		(pad "1" smd circle
			(at -0.40005 0 90)
			(size 0 0)
			(layers "F.Cu" "F.Mask" "F.Paste")
			(net "P3V3_AUX")
		)
		(pad "2" smd circle
			(at 0.40005 0 90)
			(size 0 0)
			(layers "F.Cu" "F.Mask" "F.Paste")
			(net "GND")
		)
	)
	(footprint ""
		(layer "F.Cu")
		(at 39.73322 -36.571174 90)
		(property "Reference" "R154"
			(at 0 0 90)
			(layer "F.SilkS")
			(hide yes)
			(effects
				(font
					(size 1.27 1.27)
				)
			)
		)
		(property "Value" ""
			(at 0 0 90)
			(layer "F.Fab")
			(effects
				(font
					(size 1.27 1.27)
				)
			)
		)
		(duplicate_pad_numbers_are_jumpers no)
		(fp_line
			(start 0.7874 -0.4064)
			(end 0.7874 0.4064)
			(stroke
				(width 0.1524)
				(type default)
			)
			(layer "F.SilkS")
		)
		(fp_line
			(start -0.7874 -0.4064)
			(end 0.7874 -0.4064)
			(stroke
				(width 0.1524)
				(type default)
			)
			(layer "F.SilkS")
		)
		(fp_line
			(start 0.7874 0.4064)
			(end -0.7874 0.4064)
			(stroke
				(width 0.1524)
				(type default)
			)
			(layer "F.SilkS")
		)
		(fp_line
			(start -0.7874 0.4064)
			(end -0.7874 -0.4064)
			(stroke
				(width 0.1524)
				(type default)
			)
			(layer "F.SilkS")
		)
		(fp_line
			(start -0.12065 -0.305054)
			(end -0.12065 -0.2794)
			(stroke
				(width 0.1)
				(type default)
			)
			(layer "F.Fab")
		)
		(fp_line
			(start -0.67945 -0.305054)
			(end -0.12065 -0.305054)
			(stroke
				(width 0.1)
				(type default)
			)
			(layer "F.Fab")
		)
		(fp_line
			(start 0.67945 -0.3048)
			(end 0.67945 0.3048)
			(stroke
				(width 0.1)
				(type default)
			)
			(layer "F.Fab")
		)
		(fp_line
			(start 0.12065 -0.3048)
			(end 0.67945 -0.3048)
			(stroke
				(width 0.1)
				(type default)
			)
			(layer "F.Fab")
		)
		(fp_line
			(start 0.12065 -0.2794)
			(end 0.12065 -0.3048)
			(stroke
				(width 0.1)
				(type default)
			)
			(layer "F.Fab")
		)
		(fp_line
			(start -0.12065 -0.2794)
			(end 0.12065 -0.2794)
			(stroke
				(width 0.1)
				(type default)
			)
			(layer "F.Fab")
		)
		(fp_line
			(start 0.120396 0.2794)
			(end -0.12065 0.2794)
			(stroke
				(width 0.1)
				(type default)
			)
			(layer "F.Fab")
		)
		(fp_line
			(start -0.12065 0.2794)
			(end -0.12065 0.3048)
			(stroke
				(width 0.1)
				(type default)
			)
			(layer "F.Fab")
		)
		(fp_line
			(start 0.67945 0.3048)
			(end 0.120396 0.3048)
			(stroke
				(width 0.1)
				(type default)
			)
			(layer "F.Fab")
		)
		(fp_line
			(start 0.120396 0.3048)
			(end 0.120396 0.2794)
			(stroke
				(width 0.1)
				(type default)
			)
			(layer "F.Fab")
		)
		(fp_line
			(start -0.12065 0.3048)
			(end -0.67945 0.3048)
			(stroke
				(width 0.1)
				(type default)
			)
			(layer "F.Fab")
		)
		(fp_line
			(start -0.67945 0.3048)
			(end -0.67945 -0.305054)
			(stroke
				(width 0.1)
				(type default)
			)
			(layer "F.Fab")
		)
		(pad "1" smd circle
			(at -0.40005 0 90)
			(size 0 0)
			(layers "F.Cu" "F.Mask" "F.Paste")
			(net "P1V8_AUX")
		)
		(pad "2" smd circle
			(at 0.40005 0 90)
			(size 0 0)
			(layers "F.Cu" "F.Mask" "F.Paste")
			(net "P3V3_P2V5_P1V8_RVDD")
		)
	)
	(footprint ""
		(layer "F.Cu")
		(at 38.079172 -83.816952 90)
		(property "Reference" "R649"
			(at 0 0 90)
			(layer "F.SilkS")
			(hide yes)
			(effects
				(font
					(size 1.27 1.27)
				)
			)
		)
		(property "Value" ""
			(at 0 0 90)
			(layer "F.Fab")
			(effects
				(font
					(size 1.27 1.27)
				)
			)
		)
		(duplicate_pad_numbers_are_jumpers no)
		(fp_line
			(start 0.7874 -0.4064)
			(end 0.7874 0.4064)
			(stroke
				(width 0.1524)
				(type default)
			)
			(layer "F.SilkS")
		)
		(fp_line
			(start -0.7874 -0.4064)
			(end 0.7874 -0.4064)
			(stroke
				(width 0.1524)
				(type default)
			)
			(layer "F.SilkS")
		)
		(fp_line
			(start 0.7874 0.4064)
			(end -0.7874 0.4064)
			(stroke
				(width 0.1524)
				(type default)
			)
			(layer "F.SilkS")
		)
		(fp_line
			(start -0.7874 0.4064)
			(end -0.7874 -0.4064)
			(stroke
				(width 0.1524)
				(type default)
			)
			(layer "F.SilkS")
		)
		(fp_line
			(start -0.12065 -0.305054)
			(end -0.12065 -0.2794)
			(stroke
				(width 0.1)
				(type default)
			)
			(layer "F.Fab")
		)
		(fp_line
			(start -0.67945 -0.305054)
			(end -0.12065 -0.305054)
			(stroke
				(width 0.1)
				(type default)
			)
			(layer "F.Fab")
		)
		(fp_line
			(start 0.67945 -0.3048)
			(end 0.67945 0.3048)
			(stroke
				(width 0.1)
				(type default)
			)
			(layer "F.Fab")
		)
		(fp_line
			(start 0.12065 -0.3048)
			(end 0.67945 -0.3048)
			(stroke
				(width 0.1)
				(type default)
			)
			(layer "F.Fab")
		)
		(fp_line
			(start 0.12065 -0.2794)
			(end 0.12065 -0.3048)
			(stroke
				(width 0.1)
				(type default)
			)
			(layer "F.Fab")
		)
		(fp_line
			(start -0.12065 -0.2794)
			(end 0.12065 -0.2794)
			(stroke
				(width 0.1)
				(type default)
			)
			(layer "F.Fab")
		)
		(fp_line
			(start 0.120396 0.2794)
			(end -0.12065 0.2794)
			(stroke
				(width 0.1)
				(type default)
			)
			(layer "F.Fab")
		)
		(fp_line
			(start -0.12065 0.2794)
			(end -0.12065 0.3048)
			(stroke
				(width 0.1)
				(type default)
			)
			(layer "F.Fab")
		)
		(fp_line
			(start 0.67945 0.3048)
			(end 0.120396 0.3048)
			(stroke
				(width 0.1)
				(type default)
			)
			(layer "F.Fab")
		)
		(fp_line
			(start 0.120396 0.3048)
			(end 0.120396 0.2794)
			(stroke
				(width 0.1)
				(type default)
			)
			(layer "F.Fab")
		)
		(fp_line
			(start -0.12065 0.3048)
			(end -0.67945 0.3048)
			(stroke
				(width 0.1)
				(type default)
			)
			(layer "F.Fab")
		)
		(fp_line
			(start -0.67945 0.3048)
			(end -0.67945 -0.305054)
			(stroke
				(width 0.1)
				(type default)
			)
			(layer "F.Fab")
		)
		(pad "1" smd circle
			(at -0.40005 0 90)
			(size 0 0)
			(layers "F.Cu" "F.Mask" "F.Paste")
			(net "EMMC_DT0_R")
		)
		(pad "2" smd circle
			(at 0.40005 0 90)
			(size 0 0)
			(layers "F.Cu" "F.Mask" "F.Paste")
			(net "BMC_EMMC_DT0")
		)
	)
	(footprint ""
		(layer "F.Cu")
		(at 85.471 -34.544 -90)
		(property "Reference" "C289"
			(at 0 0 270)
			(layer "F.SilkS")
			(hide yes)
			(effects
				(font
					(size 1.27 1.27)
				)
			)
		)
		(property "Value" ""
			(at 0 0 270)
			(layer "F.Fab")
			(effects
				(font
					(size 1.27 1.27)
				)
			)
		)
		(duplicate_pad_numbers_are_jumpers no)
		(fp_line
			(start -1.651 0.8382)
			(end -1.651 -0.8382)
			(stroke
				(width 0.1524)
				(type default)
			)
			(layer "F.SilkS")
		)
		(fp_line
			(start 0 0.8382)
			(end 0 -0.8382)
			(stroke
				(width 0.1524)
				(type default)
			)
			(layer "F.SilkS")
		)
		(fp_line
			(start 1.651 0.8382)
			(end -1.651 0.8382)
			(stroke
				(width 0.1524)
				(type default)
			)
			(layer "F.SilkS")
		)
		(fp_line
			(start -1.651 -0.8382)
			(end 1.651 -0.8382)
			(stroke
				(width 0.1524)
				(type default)
			)
			(layer "F.SilkS")
		)
		(fp_line
			(start 1.651 -0.8382)
			(end 1.651 0.8382)
			(stroke
				(width 0.1524)
				(type default)
			)
			(layer "F.SilkS")
		)
		(fp_line
			(start -1.55956 0.7366)
			(end -1.524 0.7366)
			(stroke
				(width 0.1)
				(type default)
			)
			(layer "F.Fab")
		)
		(fp_line
			(start -1.524 0.7366)
			(end 1.524 0.7366)
			(stroke
				(width 0.1)
				(type default)
			)
			(layer "F.Fab")
		)
		(fp_line
			(start 1.524 0.7366)
			(end 1.55956 0.7366)
			(stroke
				(width 0.1)
				(type default)
			)
			(layer "F.Fab")
		)
		(fp_line
			(start 1.55956 0.7366)
			(end 1.55956 -0.7366)
			(stroke
				(width 0.1)
				(type default)
			)
			(layer "F.Fab")
		)
		(fp_line
			(start -1.55956 -0.7366)
			(end -1.55956 0.7366)
			(stroke
				(width 0.1)
				(type default)
			)
			(layer "F.Fab")
		)
		(fp_line
			(start -1.524 -0.7366)
			(end -1.55956 -0.7366)
			(stroke
				(width 0.1)
				(type default)
			)
			(layer "F.Fab")
		)
		(fp_line
			(start 1.524 -0.7366)
			(end -1.524 -0.7366)
			(stroke
				(width 0.1)
				(type default)
			)
			(layer "F.Fab")
		)
		(fp_line
			(start 1.55956 -0.7366)
			(end 1.524 -0.7366)
			(stroke
				(width 0.1)
				(type default)
			)
			(layer "F.Fab")
		)
		(pad "1" smd rect
			(at -0.94996 0 90)
			(size 1.1176 1.3716)
			(layers "F.Cu" "F.Mask" "F.Paste")
			(net "P2V5_AUX")
		)
		(pad "2" smd rect
			(at 0.94996 0 90)
			(size 1.1176 1.3716)
			(layers "F.Cu" "F.Mask" "F.Paste")
			(net "GND")
		)
	)
	(footprint ""
		(layer "F.Cu")
		(at 57.222136 -34.637726 -90)
		(property "Reference" "R584"
			(at 0 0 270)
			(layer "F.SilkS")
			(hide yes)
			(effects
				(font
					(size 1.27 1.27)
				)
			)
		)
		(property "Value" ""
			(at 0 0 270)
			(layer "F.Fab")
			(effects
				(font
					(size 1.27 1.27)
				)
			)
		)
		(duplicate_pad_numbers_are_jumpers no)
		(fp_line
			(start -0.7874 0.4064)
			(end -0.7874 -0.4064)
			(stroke
				(width 0.1524)
				(type default)
			)
			(layer "F.SilkS")
		)
		(fp_line
			(start 0.7874 0.4064)
			(end -0.7874 0.4064)
			(stroke
				(width 0.1524)
				(type default)
			)
			(layer "F.SilkS")
		)
		(fp_line
			(start -0.7874 -0.4064)
			(end 0.7874 -0.4064)
			(stroke
				(width 0.1524)
				(type default)
			)
			(layer "F.SilkS")
		)
		(fp_line
			(start 0.7874 -0.4064)
			(end 0.7874 0.4064)
			(stroke
				(width 0.1524)
				(type default)
			)
			(layer "F.SilkS")
		)
		(fp_line
			(start -0.67945 0.3048)
			(end -0.67945 -0.305054)
			(stroke
				(width 0.1)
				(type default)
			)
			(layer "F.Fab")
		)
		(fp_line
			(start -0.12065 0.3048)
			(end -0.67945 0.3048)
			(stroke
				(width 0.1)
				(type default)
			)
			(layer "F.Fab")
		)
		(fp_line
			(start 0.120396 0.3048)
			(end 0.120396 0.2794)
			(stroke
				(width 0.1)
				(type default)
			)
			(layer "F.Fab")
		)
		(fp_line
			(start 0.67945 0.3048)
			(end 0.120396 0.3048)
			(stroke
				(width 0.1)
				(type default)
			)
			(layer "F.Fab")
		)
		(fp_line
			(start -0.12065 0.2794)
			(end -0.12065 0.3048)
			(stroke
				(width 0.1)
				(type default)
			)
			(layer "F.Fab")
		)
		(fp_line
			(start 0.120396 0.2794)
			(end -0.12065 0.2794)
			(stroke
				(width 0.1)
				(type default)
			)
			(layer "F.Fab")
		)
		(fp_line
			(start -0.12065 -0.2794)
			(end 0.12065 -0.2794)
			(stroke
				(width 0.1)
				(type default)
			)
			(layer "F.Fab")
		)
		(fp_line
			(start 0.12065 -0.2794)
			(end 0.12065 -0.3048)
			(stroke
				(width 0.1)
				(type default)
			)
			(layer "F.Fab")
		)
		(fp_line
			(start 0.12065 -0.3048)
			(end 0.67945 -0.3048)
			(stroke
				(width 0.1)
				(type default)
			)
			(layer "F.Fab")
		)
		(fp_line
			(start 0.67945 -0.3048)
			(end 0.67945 0.3048)
			(stroke
				(width 0.1)
				(type default)
			)
			(layer "F.Fab")
		)
		(fp_line
			(start -0.67945 -0.305054)
			(end -0.12065 -0.305054)
			(stroke
				(width 0.1)
				(type default)
			)
			(layer "F.Fab")
		)
		(fp_line
			(start -0.12065 -0.305054)
			(end -0.12065 -0.2794)
			(stroke
				(width 0.1)
				(type default)
			)
			(layer "F.Fab")
		)
		(pad "1" smd circle
			(at -0.40005 0 270)
			(size 0 0)
			(layers "F.Cu" "F.Mask" "F.Paste")
			(net "SMB_BMC_MM10_R_SDA")
		)
		(pad "2" smd circle
			(at 0.40005 0 270)
			(size 0 0)
			(layers "F.Cu" "F.Mask" "F.Paste")
			(net "SMB_BMC_MM10_SDA")
		)
	)
	(footprint ""
		(layer "F.Cu")
		(at 35.1536 -89.3826 180)
		(property "Reference" "R486"
			(at 0 0 180)
			(layer "F.SilkS")
			(hide yes)
			(effects
				(font
					(size 1.27 1.27)
				)
			)
		)
		(property "Value" ""
			(at 0 0 180)
			(layer "F.Fab")
			(effects
				(font
					(size 1.27 1.27)
				)
			)
		)
		(duplicate_pad_numbers_are_jumpers no)
		(fp_line
			(start 0.7874 0.4064)
			(end -0.7874 0.4064)
			(stroke
				(width 0.1524)
				(type default)
			)
			(layer "F.SilkS")
		)
		(fp_line
			(start 0.7874 -0.4064)
			(end 0.7874 0.4064)
			(stroke
				(width 0.1524)
				(type default)
			)
			(layer "F.SilkS")
		)
		(fp_line
			(start -0.7874 0.4064)
			(end -0.7874 -0.4064)
			(stroke
				(width 0.1524)
				(type default)
			)
			(layer "F.SilkS")
		)
		(fp_line
			(start -0.7874 -0.4064)
			(end 0.7874 -0.4064)
			(stroke
				(width 0.1524)
				(type default)
			)
			(layer "F.SilkS")
		)
		(fp_line
			(start 0.67945 0.3048)
			(end 0.120396 0.3048)
			(stroke
				(width 0.1)
				(type default)
			)
			(layer "F.Fab")
		)
		(fp_line
			(start 0.67945 -0.3048)
			(end 0.67945 0.3048)
			(stroke
				(width 0.1)
				(type default)
			)
			(layer "F.Fab")
		)
		(fp_line
			(start 0.12065 -0.2794)
			(end 0.12065 -0.3048)
			(stroke
				(width 0.1)
				(type default)
			)
			(layer "F.Fab")
		)
		(fp_line
			(start 0.12065 -0.3048)
			(end 0.67945 -0.3048)
			(stroke
				(width 0.1)
				(type default)
			)
			(layer "F.Fab")
		)
		(fp_line
			(start 0.120396 0.3048)
			(end 0.120396 0.2794)
			(stroke
				(width 0.1)
				(type default)
			)
			(layer "F.Fab")
		)
		(fp_line
			(start 0.120396 0.2794)
			(end -0.12065 0.2794)
			(stroke
				(width 0.1)
				(type default)
			)
			(layer "F.Fab")
		)
		(fp_line
			(start -0.12065 0.3048)
			(end -0.67945 0.3048)
			(stroke
				(width 0.1)
				(type default)
			)
			(layer "F.Fab")
		)
		(fp_line
			(start -0.12065 0.2794)
			(end -0.12065 0.3048)
			(stroke
				(width 0.1)
				(type default)
			)
			(layer "F.Fab")
		)
		(fp_line
			(start -0.12065 -0.2794)
			(end 0.12065 -0.2794)
			(stroke
				(width 0.1)
				(type default)
			)
			(layer "F.Fab")
		)
		(fp_line
			(start -0.12065 -0.305054)
			(end -0.12065 -0.2794)
			(stroke
				(width 0.1)
				(type default)
			)
			(layer "F.Fab")
		)
		(fp_line
			(start -0.67945 0.3048)
			(end -0.67945 -0.305054)
			(stroke
				(width 0.1)
				(type default)
			)
			(layer "F.Fab")
		)
		(fp_line
			(start -0.67945 -0.305054)
			(end -0.12065 -0.305054)
			(stroke
				(width 0.1)
				(type default)
			)
			(layer "F.Fab")
		)
		(pad "1" smd circle
			(at -0.40005 0 180)
			(size 0 0)
			(layers "F.Cu" "F.Mask" "F.Paste")
			(net "SPI_PCH_MUXED_IO3")
		)
		(pad "2" smd circle
			(at 0.40005 0 180)
			(size 0 0)
			(layers "F.Cu" "F.Mask" "F.Paste")
			(net "SPI_PCH_IO3_FLASH_R1")
		)
	)
	(footprint ""
		(layer "F.Cu")
		(at 30.5562 -87.9856 180)
		(property "Reference" "R81"
			(at 0 0 180)
			(layer "F.SilkS")
			(hide yes)
			(effects
				(font
					(size 1.27 1.27)
				)
			)
		)
		(property "Value" ""
			(at 0 0 180)
			(layer "F.Fab")
			(effects
				(font
					(size 1.27 1.27)
				)
			)
		)
		(duplicate_pad_numbers_are_jumpers no)
		(fp_line
			(start 0.7874 0.4064)
			(end -0.7874 0.4064)
			(stroke
				(width 0.1524)
				(type default)
			)
			(layer "F.SilkS")
		)
		(fp_line
			(start 0.7874 -0.4064)
			(end 0.7874 0.4064)
			(stroke
				(width 0.1524)
				(type default)
			)
			(layer "F.SilkS")
		)
		(fp_line
			(start -0.7874 0.4064)
			(end -0.7874 -0.4064)
			(stroke
				(width 0.1524)
				(type default)
			)
			(layer "F.SilkS")
		)
		(fp_line
			(start -0.7874 -0.4064)
			(end 0.7874 -0.4064)
			(stroke
				(width 0.1524)
				(type default)
			)
			(layer "F.SilkS")
		)
		(fp_line
			(start 0.67945 0.3048)
			(end 0.120396 0.3048)
			(stroke
				(width 0.1)
				(type default)
			)
			(layer "F.Fab")
		)
		(fp_line
			(start 0.67945 -0.3048)
			(end 0.67945 0.3048)
			(stroke
				(width 0.1)
				(type default)
			)
			(layer "F.Fab")
		)
		(fp_line
			(start 0.12065 -0.2794)
			(end 0.12065 -0.3048)
			(stroke
				(width 0.1)
				(type default)
			)
			(layer "F.Fab")
		)
		(fp_line
			(start 0.12065 -0.3048)
			(end 0.67945 -0.3048)
			(stroke
				(width 0.1)
				(type default)
			)
			(layer "F.Fab")
		)
		(fp_line
			(start 0.120396 0.3048)
			(end 0.120396 0.2794)
			(stroke
				(width 0.1)
				(type default)
			)
			(layer "F.Fab")
		)
		(fp_line
			(start 0.120396 0.2794)
			(end -0.12065 0.2794)
			(stroke
				(width 0.1)
				(type default)
			)
			(layer "F.Fab")
		)
		(fp_line
			(start -0.12065 0.3048)
			(end -0.67945 0.3048)
			(stroke
				(width 0.1)
				(type default)
			)
			(layer "F.Fab")
		)
		(fp_line
			(start -0.12065 0.2794)
			(end -0.12065 0.3048)
			(stroke
				(width 0.1)
				(type default)
			)
			(layer "F.Fab")
		)
		(fp_line
			(start -0.12065 -0.2794)
			(end 0.12065 -0.2794)
			(stroke
				(width 0.1)
				(type default)
			)
			(layer "F.Fab")
		)
		(fp_line
			(start -0.12065 -0.305054)
			(end -0.12065 -0.2794)
			(stroke
				(width 0.1)
				(type default)
			)
			(layer "F.Fab")
		)
		(fp_line
			(start -0.67945 0.3048)
			(end -0.67945 -0.305054)
			(stroke
				(width 0.1)
				(type default)
			)
			(layer "F.Fab")
		)
		(fp_line
			(start -0.67945 -0.305054)
			(end -0.12065 -0.305054)
			(stroke
				(width 0.1)
				(type default)
			)
			(layer "F.Fab")
		)
		(pad "1" smd circle
			(at -0.40005 0 180)
			(size 0 0)
			(layers "F.Cu" "F.Mask" "F.Paste")
			(net "P3V3_AUX")
		)
		(pad "2" smd circle
			(at 0.40005 0 180)
			(size 0 0)
			(layers "F.Cu" "F.Mask" "F.Paste")
			(net "PWR_BTN_BMC_N")
		)
	)
	(footprint ""
		(layer "F.Cu")
		(at 16.5354 -70.739 -90)
		(property "Reference" "R665"
			(at 0 0 270)
			(layer "F.SilkS")
			(hide yes)
			(effects
				(font
					(size 1.27 1.27)
				)
			)
		)
		(property "Value" ""
			(at 0 0 270)
			(layer "F.Fab")
			(effects
				(font
					(size 1.27 1.27)
				)
			)
		)
		(duplicate_pad_numbers_are_jumpers no)
		(fp_line
			(start -0.7874 0.4064)
			(end -0.7874 -0.4064)
			(stroke
				(width 0.1524)
				(type default)
			)
			(layer "F.SilkS")
		)
		(fp_line
			(start 0.7874 0.4064)
			(end -0.7874 0.4064)
			(stroke
				(width 0.1524)
				(type default)
			)
			(layer "F.SilkS")
		)
		(fp_line
			(start -0.7874 -0.4064)
			(end 0.7874 -0.4064)
			(stroke
				(width 0.1524)
				(type default)
			)
			(layer "F.SilkS")
		)
		(fp_line
			(start 0.7874 -0.4064)
			(end 0.7874 0.4064)
			(stroke
				(width 0.1524)
				(type default)
			)
			(layer "F.SilkS")
		)
		(fp_line
			(start -0.67945 0.3048)
			(end -0.67945 -0.305054)
			(stroke
				(width 0.1)
				(type default)
			)
			(layer "F.Fab")
		)
		(fp_line
			(start -0.12065 0.3048)
			(end -0.67945 0.3048)
			(stroke
				(width 0.1)
				(type default)
			)
			(layer "F.Fab")
		)
		(fp_line
			(start 0.120396 0.3048)
			(end 0.120396 0.2794)
			(stroke
				(width 0.1)
				(type default)
			)
			(layer "F.Fab")
		)
		(fp_line
			(start 0.67945 0.3048)
			(end 0.120396 0.3048)
			(stroke
				(width 0.1)
				(type default)
			)
			(layer "F.Fab")
		)
		(fp_line
			(start -0.12065 0.2794)
			(end -0.12065 0.3048)
			(stroke
				(width 0.1)
				(type default)
			)
			(layer "F.Fab")
		)
		(fp_line
			(start 0.120396 0.2794)
			(end -0.12065 0.2794)
			(stroke
				(width 0.1)
				(type default)
			)
			(layer "F.Fab")
		)
		(fp_line
			(start -0.12065 -0.2794)
			(end 0.12065 -0.2794)
			(stroke
				(width 0.1)
				(type default)
			)
			(layer "F.Fab")
		)
		(fp_line
			(start 0.12065 -0.2794)
			(end 0.12065 -0.3048)
			(stroke
				(width 0.1)
				(type default)
			)
			(layer "F.Fab")
		)
		(fp_line
			(start 0.12065 -0.3048)
			(end 0.67945 -0.3048)
			(stroke
				(width 0.1)
				(type default)
			)
			(layer "F.Fab")
		)
		(fp_line
			(start 0.67945 -0.3048)
			(end 0.67945 0.3048)
			(stroke
				(width 0.1)
				(type default)
			)
			(layer "F.Fab")
		)
		(fp_line
			(start -0.67945 -0.305054)
			(end -0.12065 -0.305054)
			(stroke
				(width 0.1)
				(type default)
			)
			(layer "F.Fab")
		)
		(fp_line
			(start -0.12065 -0.305054)
			(end -0.12065 -0.2794)
			(stroke
				(width 0.1)
				(type default)
			)
			(layer "F.Fab")
		)
		(pad "1" smd circle
			(at -0.40005 0 270)
			(size 0 0)
			(layers "F.Cu" "F.Mask" "F.Paste")
			(net "SPI_BMC_BT_WP0_N_R")
		)
		(pad "2" smd circle
			(at 0.40005 0 270)
			(size 0 0)
			(layers "F.Cu" "F.Mask" "F.Paste")
			(net "GND")
		)
	)
	(footprint ""
		(layer "F.Cu")
		(at 79.685134 -59.059826 -90)
		(property "Reference" "PC258"
			(at 0 0 270)
			(layer "F.SilkS")
			(hide yes)
			(effects
				(font
					(size 1.27 1.27)
				)
			)
		)
		(property "Value" ""
			(at 0 0 270)
			(layer "F.Fab")
			(effects
				(font
					(size 1.27 1.27)
				)
			)
		)
		(duplicate_pad_numbers_are_jumpers no)
		(fp_line
			(start -1.651 0.8382)
			(end -1.651 -0.8382)
			(stroke
				(width 0.1524)
				(type default)
			)
			(layer "F.SilkS")
		)
		(fp_line
			(start 0 0.8382)
			(end 0 -0.8382)
			(stroke
				(width 0.1524)
				(type default)
			)
			(layer "F.SilkS")
		)
		(fp_line
			(start 1.651 0.8382)
			(end -1.651 0.8382)
			(stroke
				(width 0.1524)
				(type default)
			)
			(layer "F.SilkS")
		)
		(fp_line
			(start -1.651 -0.8382)
			(end 1.651 -0.8382)
			(stroke
				(width 0.1524)
				(type default)
			)
			(layer "F.SilkS")
		)
		(fp_line
			(start 1.651 -0.8382)
			(end 1.651 0.8382)
			(stroke
				(width 0.1524)
				(type default)
			)
			(layer "F.SilkS")
		)
		(fp_line
			(start -1.55956 0.7366)
			(end -1.524 0.7366)
			(stroke
				(width 0.1)
				(type default)
			)
			(layer "F.Fab")
		)
		(fp_line
			(start -1.524 0.7366)
			(end 1.524 0.7366)
			(stroke
				(width 0.1)
				(type default)
			)
			(layer "F.Fab")
		)
		(fp_line
			(start 1.524 0.7366)
			(end 1.55956 0.7366)
			(stroke
				(width 0.1)
				(type default)
			)
			(layer "F.Fab")
		)
		(fp_line
			(start 1.55956 0.7366)
			(end 1.55956 -0.7366)
			(stroke
				(width 0.1)
				(type default)
			)
			(layer "F.Fab")
		)
		(fp_line
			(start -1.55956 -0.7366)
			(end -1.55956 0.7366)
			(stroke
				(width 0.1)
				(type default)
			)
			(layer "F.Fab")
		)
		(fp_line
			(start -1.524 -0.7366)
			(end -1.55956 -0.7366)
			(stroke
				(width 0.1)
				(type default)
			)
			(layer "F.Fab")
		)
		(fp_line
			(start 1.524 -0.7366)
			(end -1.524 -0.7366)
			(stroke
				(width 0.1)
				(type default)
			)
			(layer "F.Fab")
		)
		(fp_line
			(start 1.55956 -0.7366)
			(end 1.524 -0.7366)
			(stroke
				(width 0.1)
				(type default)
			)
			(layer "F.Fab")
		)
		(pad "1" smd rect
			(at -0.94996 0 90)
			(size 1.1176 1.3716)
			(layers "F.Cu" "F.Mask" "F.Paste")
			(net "P1V2_AUX")
		)
		(pad "2" smd rect
			(at 0.94996 0 90)
			(size 1.1176 1.3716)
			(layers "F.Cu" "F.Mask" "F.Paste")
			(net "GND")
		)
	)
	(footprint ""
		(layer "F.Cu")
		(at 36.068 -44.5008 180)
		(property "Reference" "R710"
			(at 0 0 180)
			(layer "F.SilkS")
			(hide yes)
			(effects
				(font
					(size 1.27 1.27)
				)
			)
		)
		(property "Value" ""
			(at 0 0 180)
			(layer "F.Fab")
			(effects
				(font
					(size 1.27 1.27)
				)
			)
		)
		(duplicate_pad_numbers_are_jumpers no)
		(fp_line
			(start 0.7874 0.4064)
			(end -0.7874 0.4064)
			(stroke
				(width 0.1524)
				(type default)
			)
			(layer "F.SilkS")
		)
		(fp_line
			(start 0.7874 -0.4064)
			(end 0.7874 0.4064)
			(stroke
				(width 0.1524)
				(type default)
			)
			(layer "F.SilkS")
		)
		(fp_line
			(start -0.7874 0.4064)
			(end -0.7874 -0.4064)
			(stroke
				(width 0.1524)
				(type default)
			)
			(layer "F.SilkS")
		)
		(fp_line
			(start -0.7874 -0.4064)
			(end 0.7874 -0.4064)
			(stroke
				(width 0.1524)
				(type default)
			)
			(layer "F.SilkS")
		)
		(fp_line
			(start 0.67945 0.3048)
			(end 0.120396 0.3048)
			(stroke
				(width 0.1)
				(type default)
			)
			(layer "F.Fab")
		)
		(fp_line
			(start 0.67945 -0.3048)
			(end 0.67945 0.3048)
			(stroke
				(width 0.1)
				(type default)
			)
			(layer "F.Fab")
		)
		(fp_line
			(start 0.12065 -0.2794)
			(end 0.12065 -0.3048)
			(stroke
				(width 0.1)
				(type default)
			)
			(layer "F.Fab")
		)
		(fp_line
			(start 0.12065 -0.3048)
			(end 0.67945 -0.3048)
			(stroke
				(width 0.1)
				(type default)
			)
			(layer "F.Fab")
		)
		(fp_line
			(start 0.120396 0.3048)
			(end 0.120396 0.2794)
			(stroke
				(width 0.1)
				(type default)
			)
			(layer "F.Fab")
		)
		(fp_line
			(start 0.120396 0.2794)
			(end -0.12065 0.2794)
			(stroke
				(width 0.1)
				(type default)
			)
			(layer "F.Fab")
		)
		(fp_line
			(start -0.12065 0.3048)
			(end -0.67945 0.3048)
			(stroke
				(width 0.1)
				(type default)
			)
			(layer "F.Fab")
		)
		(fp_line
			(start -0.12065 0.2794)
			(end -0.12065 0.3048)
			(stroke
				(width 0.1)
				(type default)
			)
			(layer "F.Fab")
		)
		(fp_line
			(start -0.12065 -0.2794)
			(end 0.12065 -0.2794)
			(stroke
				(width 0.1)
				(type default)
			)
			(layer "F.Fab")
		)
		(fp_line
			(start -0.12065 -0.305054)
			(end -0.12065 -0.2794)
			(stroke
				(width 0.1)
				(type default)
			)
			(layer "F.Fab")
		)
		(fp_line
			(start -0.67945 0.3048)
			(end -0.67945 -0.305054)
			(stroke
				(width 0.1)
				(type default)
			)
			(layer "F.Fab")
		)
		(fp_line
			(start -0.67945 -0.305054)
			(end -0.12065 -0.305054)
			(stroke
				(width 0.1)
				(type default)
			)
			(layer "F.Fab")
		)
		(pad "1" smd circle
			(at -0.40005 0 180)
			(size 0 0)
			(layers "F.Cu" "F.Mask" "F.Paste")
			(net "P3V3_AUX")
		)
		(pad "2" smd circle
			(at 0.40005 0 180)
			(size 0 0)
			(layers "F.Cu" "F.Mask" "F.Paste")
			(net "U43_CT")
		)
	)
	(footprint ""
		(layer "F.Cu")
		(at 84.201 -95.631)
		(property "Reference" "R98"
			(at 0 0 0)
			(layer "F.SilkS")
			(hide yes)
			(effects
				(font
					(size 1.27 1.27)
				)
			)
		)
		(property "Value" ""
			(at 0 0 0)
			(layer "F.Fab")
			(effects
				(font
					(size 1.27 1.27)
				)
			)
		)
		(duplicate_pad_numbers_are_jumpers no)
		(fp_line
			(start -0.7874 -0.4064)
			(end 0.7874 -0.4064)
			(stroke
				(width 0.1524)
				(type default)
			)
			(layer "F.SilkS")
		)
		(fp_line
			(start -0.7874 0.4064)
			(end -0.7874 -0.4064)
			(stroke
				(width 0.1524)
				(type default)
			)
			(layer "F.SilkS")
		)
		(fp_line
			(start 0.7874 -0.4064)
			(end 0.7874 0.4064)
			(stroke
				(width 0.1524)
				(type default)
			)
			(layer "F.SilkS")
		)
		(fp_line
			(start 0.7874 0.4064)
			(end -0.7874 0.4064)
			(stroke
				(width 0.1524)
				(type default)
			)
			(layer "F.SilkS")
		)
		(fp_line
			(start -0.67945 -0.305054)
			(end -0.12065 -0.305054)
			(stroke
				(width 0.1)
				(type default)
			)
			(layer "F.Fab")
		)
		(fp_line
			(start -0.67945 0.3048)
			(end -0.67945 -0.305054)
			(stroke
				(width 0.1)
				(type default)
			)
			(layer "F.Fab")
		)
		(fp_line
			(start -0.12065 -0.305054)
			(end -0.12065 -0.2794)
			(stroke
				(width 0.1)
				(type default)
			)
			(layer "F.Fab")
		)
		(fp_line
			(start -0.12065 -0.2794)
			(end 0.12065 -0.2794)
			(stroke
				(width 0.1)
				(type default)
			)
			(layer "F.Fab")
		)
		(fp_line
			(start -0.12065 0.2794)
			(end -0.12065 0.3048)
			(stroke
				(width 0.1)
				(type default)
			)
			(layer "F.Fab")
		)
		(fp_line
			(start -0.12065 0.3048)
			(end -0.67945 0.3048)
			(stroke
				(width 0.1)
				(type default)
			)
			(layer "F.Fab")
		)
		(fp_line
			(start 0.120396 0.2794)
			(end -0.12065 0.2794)
			(stroke
				(width 0.1)
				(type default)
			)
			(layer "F.Fab")
		)
		(fp_line
			(start 0.120396 0.3048)
			(end 0.120396 0.2794)
			(stroke
				(width 0.1)
				(type default)
			)
			(layer "F.Fab")
		)
		(fp_line
			(start 0.12065 -0.3048)
			(end 0.67945 -0.3048)
			(stroke
				(width 0.1)
				(type default)
			)
			(layer "F.Fab")
		)
		(fp_line
			(start 0.12065 -0.2794)
			(end 0.12065 -0.3048)
			(stroke
				(width 0.1)
				(type default)
			)
			(layer "F.Fab")
		)
		(fp_line
			(start 0.67945 -0.3048)
			(end 0.67945 0.3048)
			(stroke
				(width 0.1)
				(type default)
			)
			(layer "F.Fab")
		)
		(fp_line
			(start 0.67945 0.3048)
			(end 0.120396 0.3048)
			(stroke
				(width 0.1)
				(type default)
			)
			(layer "F.Fab")
		)
		(pad "1" smd circle
			(at -0.40005 0)
			(size 0 0)
			(layers "F.Cu" "F.Mask" "F.Paste")
			(net "SPI_BMC_TPM_MISO_R")
		)
		(pad "2" smd circle
			(at 0.40005 0)
			(size 0 0)
			(layers "F.Cu" "F.Mask" "F.Paste")
			(net "SPI_BMC_TPM_MISO")
		)
	)
	(footprint ""
		(layer "F.Cu")
		(at 16.8275 -106.6165 -90)
		(property "Reference" "C147"
			(at 0 0 270)
			(layer "F.SilkS")
			(hide yes)
			(effects
				(font
					(size 1.27 1.27)
				)
			)
		)
		(property "Value" ""
			(at 0 0 270)
			(layer "F.Fab")
			(effects
				(font
					(size 1.27 1.27)
				)
			)
		)
		(duplicate_pad_numbers_are_jumpers no)
		(fp_line
			(start -0.7874 0.4064)
			(end -0.7874 -0.4064)
			(stroke
				(width 0.1524)
				(type default)
			)
			(layer "F.SilkS")
		)
		(fp_line
			(start 0.7874 0.4064)
			(end -0.7874 0.4064)
			(stroke
				(width 0.1524)
				(type default)
			)
			(layer "F.SilkS")
		)
		(fp_line
			(start -0.7874 -0.4064)
			(end 0.7874 -0.4064)
			(stroke
				(width 0.1524)
				(type default)
			)
			(layer "F.SilkS")
		)
		(fp_line
			(start 0.7874 -0.4064)
			(end 0.7874 0.4064)
			(stroke
				(width 0.1524)
				(type default)
			)
			(layer "F.SilkS")
		)
		(fp_line
			(start -0.67945 0.3048)
			(end -0.67945 -0.305054)
			(stroke
				(width 0.1)
				(type default)
			)
			(layer "F.Fab")
		)
		(fp_line
			(start -0.12065 0.3048)
			(end -0.67945 0.3048)
			(stroke
				(width 0.1)
				(type default)
			)
			(layer "F.Fab")
		)
		(fp_line
			(start 0.120396 0.3048)
			(end 0.120396 0.2794)
			(stroke
				(width 0.1)
				(type default)
			)
			(layer "F.Fab")
		)
		(fp_line
			(start 0.67945 0.3048)
			(end 0.120396 0.3048)
			(stroke
				(width 0.1)
				(type default)
			)
			(layer "F.Fab")
		)
		(fp_line
			(start -0.12065 0.2794)
			(end -0.12065 0.3048)
			(stroke
				(width 0.1)
				(type default)
			)
			(layer "F.Fab")
		)
		(fp_line
			(start 0.120396 0.2794)
			(end -0.12065 0.2794)
			(stroke
				(width 0.1)
				(type default)
			)
			(layer "F.Fab")
		)
		(fp_line
			(start -0.12065 -0.2794)
			(end 0.12065 -0.2794)
			(stroke
				(width 0.1)
				(type default)
			)
			(layer "F.Fab")
		)
		(fp_line
			(start 0.12065 -0.2794)
			(end 0.12065 -0.3048)
			(stroke
				(width 0.1)
				(type default)
			)
			(layer "F.Fab")
		)
		(fp_line
			(start 0.12065 -0.3048)
			(end 0.67945 -0.3048)
			(stroke
				(width 0.1)
				(type default)
			)
			(layer "F.Fab")
		)
		(fp_line
			(start 0.67945 -0.3048)
			(end 0.67945 0.3048)
			(stroke
				(width 0.1)
				(type default)
			)
			(layer "F.Fab")
		)
		(fp_line
			(start -0.67945 -0.305054)
			(end -0.12065 -0.305054)
			(stroke
				(width 0.1)
				(type default)
			)
			(layer "F.Fab")
		)
		(fp_line
			(start -0.12065 -0.305054)
			(end -0.12065 -0.2794)
			(stroke
				(width 0.1)
				(type default)
			)
			(layer "F.Fab")
		)
		(pad "1" smd circle
			(at -0.40005 0 270)
			(size 0 0)
			(layers "F.Cu" "F.Mask" "F.Paste")
			(net "P3V3_AUX")
		)
		(pad "2" smd circle
			(at 0.40005 0 270)
			(size 0 0)
			(layers "F.Cu" "F.Mask" "F.Paste")
			(net "GND")
		)
	)
	(footprint ""
		(layer "F.Cu")
		(at 59.6392 -81.1276 180)
		(property "Reference" "R509"
			(at 0 0 180)
			(layer "F.SilkS")
			(hide yes)
			(effects
				(font
					(size 1.27 1.27)
				)
			)
		)
		(property "Value" ""
			(at 0 0 180)
			(layer "F.Fab")
			(effects
				(font
					(size 1.27 1.27)
				)
			)
		)
		(duplicate_pad_numbers_are_jumpers no)
		(fp_line
			(start 0.7874 0.4064)
			(end -0.7874 0.4064)
			(stroke
				(width 0.1524)
				(type default)
			)
			(layer "F.SilkS")
		)
		(fp_line
			(start 0.7874 -0.4064)
			(end 0.7874 0.4064)
			(stroke
				(width 0.1524)
				(type default)
			)
			(layer "F.SilkS")
		)
		(fp_line
			(start -0.7874 0.4064)
			(end -0.7874 -0.4064)
			(stroke
				(width 0.1524)
				(type default)
			)
			(layer "F.SilkS")
		)
		(fp_line
			(start -0.7874 -0.4064)
			(end 0.7874 -0.4064)
			(stroke
				(width 0.1524)
				(type default)
			)
			(layer "F.SilkS")
		)
		(fp_line
			(start 0.67945 0.3048)
			(end 0.120396 0.3048)
			(stroke
				(width 0.1)
				(type default)
			)
			(layer "F.Fab")
		)
		(fp_line
			(start 0.67945 -0.3048)
			(end 0.67945 0.3048)
			(stroke
				(width 0.1)
				(type default)
			)
			(layer "F.Fab")
		)
		(fp_line
			(start 0.12065 -0.2794)
			(end 0.12065 -0.3048)
			(stroke
				(width 0.1)
				(type default)
			)
			(layer "F.Fab")
		)
		(fp_line
			(start 0.12065 -0.3048)
			(end 0.67945 -0.3048)
			(stroke
				(width 0.1)
				(type default)
			)
			(layer "F.Fab")
		)
		(fp_line
			(start 0.120396 0.3048)
			(end 0.120396 0.2794)
			(stroke
				(width 0.1)
				(type default)
			)
			(layer "F.Fab")
		)
		(fp_line
			(start 0.120396 0.2794)
			(end -0.12065 0.2794)
			(stroke
				(width 0.1)
				(type default)
			)
			(layer "F.Fab")
		)
		(fp_line
			(start -0.12065 0.3048)
			(end -0.67945 0.3048)
			(stroke
				(width 0.1)
				(type default)
			)
			(layer "F.Fab")
		)
		(fp_line
			(start -0.12065 0.2794)
			(end -0.12065 0.3048)
			(stroke
				(width 0.1)
				(type default)
			)
			(layer "F.Fab")
		)
		(fp_line
			(start -0.12065 -0.2794)
			(end 0.12065 -0.2794)
			(stroke
				(width 0.1)
				(type default)
			)
			(layer "F.Fab")
		)
		(fp_line
			(start -0.12065 -0.305054)
			(end -0.12065 -0.2794)
			(stroke
				(width 0.1)
				(type default)
			)
			(layer "F.Fab")
		)
		(fp_line
			(start -0.67945 0.3048)
			(end -0.67945 -0.305054)
			(stroke
				(width 0.1)
				(type default)
			)
			(layer "F.Fab")
		)
		(fp_line
			(start -0.67945 -0.305054)
			(end -0.12065 -0.305054)
			(stroke
				(width 0.1)
				(type default)
			)
			(layer "F.Fab")
		)
		(pad "1" smd circle
			(at -0.40005 0 180)
			(size 0 0)
			(layers "F.Cu" "F.Mask" "F.Paste")
			(net "MB_JTAG_PLD_R_JTAGEN")
		)
		(pad "2" smd circle
			(at 0.40005 0 180)
			(size 0 0)
			(layers "F.Cu" "F.Mask" "F.Paste")
			(net "JTAG_SCM_PLD_JTAGEN")
		)
	)
	(footprint ""
		(layer "F.Cu")
		(at 38.6334 -109.8804)
		(property "Reference" "R76"
			(at 0 0 0)
			(layer "F.SilkS")
			(hide yes)
			(effects
				(font
					(size 1.27 1.27)
				)
			)
		)
		(property "Value" ""
			(at 0 0 0)
			(layer "F.Fab")
			(effects
				(font
					(size 1.27 1.27)
				)
			)
		)
		(duplicate_pad_numbers_are_jumpers no)
		(fp_line
			(start -0.7874 -0.4064)
			(end 0.7874 -0.4064)
			(stroke
				(width 0.1524)
				(type default)
			)
			(layer "F.SilkS")
		)
		(fp_line
			(start -0.7874 0.4064)
			(end -0.7874 -0.4064)
			(stroke
				(width 0.1524)
				(type default)
			)
			(layer "F.SilkS")
		)
		(fp_line
			(start 0.7874 -0.4064)
			(end 0.7874 0.4064)
			(stroke
				(width 0.1524)
				(type default)
			)
			(layer "F.SilkS")
		)
		(fp_line
			(start 0.7874 0.4064)
			(end -0.7874 0.4064)
			(stroke
				(width 0.1524)
				(type default)
			)
			(layer "F.SilkS")
		)
		(fp_line
			(start -0.67945 -0.305054)
			(end -0.12065 -0.305054)
			(stroke
				(width 0.1)
				(type default)
			)
			(layer "F.Fab")
		)
		(fp_line
			(start -0.67945 0.3048)
			(end -0.67945 -0.305054)
			(stroke
				(width 0.1)
				(type default)
			)
			(layer "F.Fab")
		)
		(fp_line
			(start -0.12065 -0.305054)
			(end -0.12065 -0.2794)
			(stroke
				(width 0.1)
				(type default)
			)
			(layer "F.Fab")
		)
		(fp_line
			(start -0.12065 -0.2794)
			(end 0.12065 -0.2794)
			(stroke
				(width 0.1)
				(type default)
			)
			(layer "F.Fab")
		)
		(fp_line
			(start -0.12065 0.2794)
			(end -0.12065 0.3048)
			(stroke
				(width 0.1)
				(type default)
			)
			(layer "F.Fab")
		)
		(fp_line
			(start -0.12065 0.3048)
			(end -0.67945 0.3048)
			(stroke
				(width 0.1)
				(type default)
			)
			(layer "F.Fab")
		)
		(fp_line
			(start 0.120396 0.2794)
			(end -0.12065 0.2794)
			(stroke
				(width 0.1)
				(type default)
			)
			(layer "F.Fab")
		)
		(fp_line
			(start 0.120396 0.3048)
			(end 0.120396 0.2794)
			(stroke
				(width 0.1)
				(type default)
			)
			(layer "F.Fab")
		)
		(fp_line
			(start 0.12065 -0.3048)
			(end 0.67945 -0.3048)
			(stroke
				(width 0.1)
				(type default)
			)
			(layer "F.Fab")
		)
		(fp_line
			(start 0.12065 -0.2794)
			(end 0.12065 -0.3048)
			(stroke
				(width 0.1)
				(type default)
			)
			(layer "F.Fab")
		)
		(fp_line
			(start 0.67945 -0.3048)
			(end 0.67945 0.3048)
			(stroke
				(width 0.1)
				(type default)
			)
			(layer "F.Fab")
		)
		(fp_line
			(start 0.67945 0.3048)
			(end 0.120396 0.3048)
			(stroke
				(width 0.1)
				(type default)
			)
			(layer "F.Fab")
		)
		(pad "1" smd circle
			(at -0.40005 0)
			(size 0 0)
			(layers "F.Cu" "F.Mask" "F.Paste")
			(net "P3V3_AUX")
		)
		(pad "2" smd circle
			(at 0.40005 0)
			(size 0 0)
			(layers "F.Cu" "F.Mask" "F.Paste")
			(net "SGPIO_CLK_1")
		)
	)
	(footprint ""
		(layer "F.Cu")
		(at 50.64887 -109.411008 90)
		(property "Reference" "R103"
			(at 0 0 90)
			(layer "F.SilkS")
			(hide yes)
			(effects
				(font
					(size 1.27 1.27)
				)
			)
		)
		(property "Value" ""
			(at 0 0 90)
			(layer "F.Fab")
			(effects
				(font
					(size 1.27 1.27)
				)
			)
		)
		(duplicate_pad_numbers_are_jumpers no)
		(fp_line
			(start 0.7874 -0.4064)
			(end 0.7874 0.4064)
			(stroke
				(width 0.1524)
				(type default)
			)
			(layer "F.SilkS")
		)
		(fp_line
			(start -0.7874 -0.4064)
			(end 0.7874 -0.4064)
			(stroke
				(width 0.1524)
				(type default)
			)
			(layer "F.SilkS")
		)
		(fp_line
			(start 0.7874 0.4064)
			(end -0.7874 0.4064)
			(stroke
				(width 0.1524)
				(type default)
			)
			(layer "F.SilkS")
		)
		(fp_line
			(start -0.7874 0.4064)
			(end -0.7874 -0.4064)
			(stroke
				(width 0.1524)
				(type default)
			)
			(layer "F.SilkS")
		)
		(fp_line
			(start -0.12065 -0.305054)
			(end -0.12065 -0.2794)
			(stroke
				(width 0.1)
				(type default)
			)
			(layer "F.Fab")
		)
		(fp_line
			(start -0.67945 -0.305054)
			(end -0.12065 -0.305054)
			(stroke
				(width 0.1)
				(type default)
			)
			(layer "F.Fab")
		)
		(fp_line
			(start 0.67945 -0.3048)
			(end 0.67945 0.3048)
			(stroke
				(width 0.1)
				(type default)
			)
			(layer "F.Fab")
		)
		(fp_line
			(start 0.12065 -0.3048)
			(end 0.67945 -0.3048)
			(stroke
				(width 0.1)
				(type default)
			)
			(layer "F.Fab")
		)
		(fp_line
			(start 0.12065 -0.2794)
			(end 0.12065 -0.3048)
			(stroke
				(width 0.1)
				(type default)
			)
			(layer "F.Fab")
		)
		(fp_line
			(start -0.12065 -0.2794)
			(end 0.12065 -0.2794)
			(stroke
				(width 0.1)
				(type default)
			)
			(layer "F.Fab")
		)
		(fp_line
			(start 0.120396 0.2794)
			(end -0.12065 0.2794)
			(stroke
				(width 0.1)
				(type default)
			)
			(layer "F.Fab")
		)
		(fp_line
			(start -0.12065 0.2794)
			(end -0.12065 0.3048)
			(stroke
				(width 0.1)
				(type default)
			)
			(layer "F.Fab")
		)
		(fp_line
			(start 0.67945 0.3048)
			(end 0.120396 0.3048)
			(stroke
				(width 0.1)
				(type default)
			)
			(layer "F.Fab")
		)
		(fp_line
			(start 0.120396 0.3048)
			(end 0.120396 0.2794)
			(stroke
				(width 0.1)
				(type default)
			)
			(layer "F.Fab")
		)
		(fp_line
			(start -0.12065 0.3048)
			(end -0.67945 0.3048)
			(stroke
				(width 0.1)
				(type default)
			)
			(layer "F.Fab")
		)
		(fp_line
			(start -0.67945 0.3048)
			(end -0.67945 -0.305054)
			(stroke
				(width 0.1)
				(type default)
			)
			(layer "F.Fab")
		)
		(pad "1" smd circle
			(at -0.40005 0 90)
			(size 0 0)
			(layers "F.Cu" "F.Mask" "F.Paste")
			(net "P3V3_AUX")
		)
		(pad "2" smd circle
			(at 0.40005 0 90)
			(size 0 0)
			(layers "F.Cu" "F.Mask" "F.Paste")
			(net "RMII_TXEN")
		)
	)
	(footprint ""
		(layer "F.Cu")
		(at 53.630068 -6.290056)
		(property "Reference" "D21"
			(at -1.143 -2.708148 0)
			(unlocked yes)
			(layer "F.SilkS")
			(effects
				(font
					(size 0.7874 0.5842)
					(thickness 0.1524)
				)
				(justify left)
			)
		)
		(property "Value" ""
			(at 0 0 0)
			(layer "F.Fab")
			(effects
				(font
					(size 1.27 1.27)
				)
			)
		)
		(duplicate_pad_numbers_are_jumpers no)
		(fp_line
			(start -1.080008 -1.999996)
			(end 3.620008 -1.999996)
			(stroke
				(width 0.1524)
				(type default)
			)
			(layer "F.SilkS")
		)
		(fp_line
			(start -1.080008 3.999992)
			(end -1.080008 -1.999996)
			(stroke
				(width 0.1524)
				(type default)
			)
			(layer "F.SilkS")
		)
		(fp_line
			(start -0.230124 3.999992)
			(end -1.080008 3.999992)
			(stroke
				(width 0.1524)
				(type default)
			)
			(layer "F.SilkS")
		)
		(fp_line
			(start -0.230124 5.199888)
			(end -0.230124 3.999992)
			(stroke
				(width 0.1524)
				(type default)
			)
			(layer "F.SilkS")
		)
		(fp_line
			(start 2.770124 3.999992)
			(end 2.770124 5.199888)
			(stroke
				(width 0.1524)
				(type default)
			)
			(layer "F.SilkS")
		)
		(fp_line
			(start 3.620008 -1.999996)
			(end 3.620008 3.999992)
			(stroke
				(width 0.1524)
				(type default)
			)
			(layer "F.SilkS")
		)
		(fp_line
			(start 3.620008 3.999992)
			(end 2.770124 3.999992)
			(stroke
				(width 0.1524)
				(type default)
			)
			(layer "F.SilkS")
		)
		(fp_arc
			(start 1.27 6.700012)
			(mid 0.209252 6.260636)
			(end -0.230124 5.199888)
			(stroke
				(width 0.1524)
				(type default)
			)
			(layer "F.SilkS")
		)
		(fp_arc
			(start 2.770124 5.199888)
			(mid 2.330748 6.260636)
			(end 1.27 6.700012)
			(stroke
				(width 0.1524)
				(type default)
			)
			(layer "F.SilkS")
		)
		(fp_line
			(start -1.080008 -1.999996)
			(end 3.620008 -1.999996)
			(stroke
				(width 0.1)
				(type default)
			)
			(layer "F.Fab")
		)
		(fp_line
			(start -1.080008 3.999992)
			(end -1.080008 -1.999996)
			(stroke
				(width 0.1)
				(type default)
			)
			(layer "F.Fab")
		)
		(fp_line
			(start -0.230124 3.999992)
			(end -1.080008 3.999992)
			(stroke
				(width 0.1)
				(type default)
			)
			(layer "F.Fab")
		)
		(fp_line
			(start -0.230124 5.199888)
			(end -0.230124 3.999992)
			(stroke
				(width 0.1)
				(type default)
			)
			(layer "F.Fab")
		)
		(fp_line
			(start 2.770124 3.999992)
			(end 2.770124 5.199888)
			(stroke
				(width 0.1)
				(type default)
			)
			(layer "F.Fab")
		)
		(fp_line
			(start 3.620008 -1.999996)
			(end 3.620008 3.999992)
			(stroke
				(width 0.1)
				(type default)
			)
			(layer "F.Fab")
		)
		(fp_line
			(start 3.620008 3.999992)
			(end 2.770124 3.999992)
			(stroke
				(width 0.1)
				(type default)
			)
			(layer "F.Fab")
		)
		(fp_arc
			(start 1.27 6.700012)
			(mid 0.209252 6.260636)
			(end -0.230124 5.199888)
			(stroke
				(width 0.1)
				(type default)
			)
			(layer "F.Fab")
		)
		(fp_arc
			(start 2.770124 5.199888)
			(mid 2.330748 6.260636)
			(end 1.27 6.700012)
			(stroke
				(width 0.1)
				(type default)
			)
			(layer "F.Fab")
		)
		(pad "A" thru_hole rect
			(at 0 0)
			(size 1.2192 1.2192)
			(drill 0.8128)
			(layers "*.Cu" "*.Mask")
			(remove_unused_layers no)
			(net "LED_D21_R3")
			(clearance 0.0508)
			(thermal_gap 0.0508)
			(padstack
				(mode front_inner_back)
				(layer "Inner"
					(shape circle)
					(size 1.2192 1.2192)
					(clearance 0.0508)
				)
				(layer "B.Cu"
					(shape rect)
					(size 1.2192 1.2192)
					(clearance 0.0508)
				)
			)
		)
		(pad "C" thru_hole circle
			(at 2.54 0)
			(size 1.2192 1.2192)
			(drill 0.8128)
			(layers "*.Cu" "*.Mask")
			(remove_unused_layers no)
			(net "GND")
			(clearance 0.0508)
			(thermal_gap 0.0508)
		)
	)
	(footprint ""
		(layer "F.Cu")
		(at 56.4642 -71.2724 90)
		(property "Reference" "R466"
			(at 0 0 90)
			(layer "F.SilkS")
			(hide yes)
			(effects
				(font
					(size 1.27 1.27)
				)
			)
		)
		(property "Value" ""
			(at 0 0 90)
			(layer "F.Fab")
			(effects
				(font
					(size 1.27 1.27)
				)
			)
		)
		(duplicate_pad_numbers_are_jumpers no)
		(fp_line
			(start 0.7874 -0.4064)
			(end 0.7874 0.4064)
			(stroke
				(width 0.1524)
				(type default)
			)
			(layer "F.SilkS")
		)
		(fp_line
			(start -0.7874 -0.4064)
			(end 0.7874 -0.4064)
			(stroke
				(width 0.1524)
				(type default)
			)
			(layer "F.SilkS")
		)
		(fp_line
			(start 0.7874 0.4064)
			(end -0.7874 0.4064)
			(stroke
				(width 0.1524)
				(type default)
			)
			(layer "F.SilkS")
		)
		(fp_line
			(start -0.7874 0.4064)
			(end -0.7874 -0.4064)
			(stroke
				(width 0.1524)
				(type default)
			)
			(layer "F.SilkS")
		)
		(fp_line
			(start -0.12065 -0.305054)
			(end -0.12065 -0.2794)
			(stroke
				(width 0.1)
				(type default)
			)
			(layer "F.Fab")
		)
		(fp_line
			(start -0.67945 -0.305054)
			(end -0.12065 -0.305054)
			(stroke
				(width 0.1)
				(type default)
			)
			(layer "F.Fab")
		)
		(fp_line
			(start 0.67945 -0.3048)
			(end 0.67945 0.3048)
			(stroke
				(width 0.1)
				(type default)
			)
			(layer "F.Fab")
		)
		(fp_line
			(start 0.12065 -0.3048)
			(end 0.67945 -0.3048)
			(stroke
				(width 0.1)
				(type default)
			)
			(layer "F.Fab")
		)
		(fp_line
			(start 0.12065 -0.2794)
			(end 0.12065 -0.3048)
			(stroke
				(width 0.1)
				(type default)
			)
			(layer "F.Fab")
		)
		(fp_line
			(start -0.12065 -0.2794)
			(end 0.12065 -0.2794)
			(stroke
				(width 0.1)
				(type default)
			)
			(layer "F.Fab")
		)
		(fp_line
			(start 0.120396 0.2794)
			(end -0.12065 0.2794)
			(stroke
				(width 0.1)
				(type default)
			)
			(layer "F.Fab")
		)
		(fp_line
			(start -0.12065 0.2794)
			(end -0.12065 0.3048)
			(stroke
				(width 0.1)
				(type default)
			)
			(layer "F.Fab")
		)
		(fp_line
			(start 0.67945 0.3048)
			(end 0.120396 0.3048)
			(stroke
				(width 0.1)
				(type default)
			)
			(layer "F.Fab")
		)
		(fp_line
			(start 0.120396 0.3048)
			(end 0.120396 0.2794)
			(stroke
				(width 0.1)
				(type default)
			)
			(layer "F.Fab")
		)
		(fp_line
			(start -0.12065 0.3048)
			(end -0.67945 0.3048)
			(stroke
				(width 0.1)
				(type default)
			)
			(layer "F.Fab")
		)
		(fp_line
			(start -0.67945 0.3048)
			(end -0.67945 -0.305054)
			(stroke
				(width 0.1)
				(type default)
			)
			(layer "F.Fab")
		)
		(pad "1" smd circle
			(at -0.40005 0 90)
			(size 0 0)
			(layers "F.Cu" "F.Mask" "F.Paste")
			(net "FLASH_WP_STATUS_R1")
		)
		(pad "2" smd circle
			(at 0.40005 0 90)
			(size 0 0)
			(layers "F.Cu" "F.Mask" "F.Paste")
			(net "FLASH_WP_STATUS")
		)
	)
	(footprint ""
		(layer "F.Cu")
		(at 12.319 -84.328)
		(property "Reference" "R446"
			(at 0 0 0)
			(layer "F.SilkS")
			(hide yes)
			(effects
				(font
					(size 1.27 1.27)
				)
			)
		)
		(property "Value" ""
			(at 0 0 0)
			(layer "F.Fab")
			(effects
				(font
					(size 1.27 1.27)
				)
			)
		)
		(duplicate_pad_numbers_are_jumpers no)
		(fp_line
			(start -0.7874 -0.4064)
			(end 0.7874 -0.4064)
			(stroke
				(width 0.1524)
				(type default)
			)
			(layer "F.SilkS")
		)
		(fp_line
			(start -0.7874 0.4064)
			(end -0.7874 -0.4064)
			(stroke
				(width 0.1524)
				(type default)
			)
			(layer "F.SilkS")
		)
		(fp_line
			(start 0.7874 -0.4064)
			(end 0.7874 0.4064)
			(stroke
				(width 0.1524)
				(type default)
			)
			(layer "F.SilkS")
		)
		(fp_line
			(start 0.7874 0.4064)
			(end -0.7874 0.4064)
			(stroke
				(width 0.1524)
				(type default)
			)
			(layer "F.SilkS")
		)
		(fp_line
			(start -0.67945 -0.305054)
			(end -0.12065 -0.305054)
			(stroke
				(width 0.1)
				(type default)
			)
			(layer "F.Fab")
		)
		(fp_line
			(start -0.67945 0.3048)
			(end -0.67945 -0.305054)
			(stroke
				(width 0.1)
				(type default)
			)
			(layer "F.Fab")
		)
		(fp_line
			(start -0.12065 -0.305054)
			(end -0.12065 -0.2794)
			(stroke
				(width 0.1)
				(type default)
			)
			(layer "F.Fab")
		)
		(fp_line
			(start -0.12065 -0.2794)
			(end 0.12065 -0.2794)
			(stroke
				(width 0.1)
				(type default)
			)
			(layer "F.Fab")
		)
		(fp_line
			(start -0.12065 0.2794)
			(end -0.12065 0.3048)
			(stroke
				(width 0.1)
				(type default)
			)
			(layer "F.Fab")
		)
		(fp_line
			(start -0.12065 0.3048)
			(end -0.67945 0.3048)
			(stroke
				(width 0.1)
				(type default)
			)
			(layer "F.Fab")
		)
		(fp_line
			(start 0.120396 0.2794)
			(end -0.12065 0.2794)
			(stroke
				(width 0.1)
				(type default)
			)
			(layer "F.Fab")
		)
		(fp_line
			(start 0.120396 0.3048)
			(end 0.120396 0.2794)
			(stroke
				(width 0.1)
				(type default)
			)
			(layer "F.Fab")
		)
		(fp_line
			(start 0.12065 -0.3048)
			(end 0.67945 -0.3048)
			(stroke
				(width 0.1)
				(type default)
			)
			(layer "F.Fab")
		)
		(fp_line
			(start 0.12065 -0.2794)
			(end 0.12065 -0.3048)
			(stroke
				(width 0.1)
				(type default)
			)
			(layer "F.Fab")
		)
		(fp_line
			(start 0.67945 -0.3048)
			(end 0.67945 0.3048)
			(stroke
				(width 0.1)
				(type default)
			)
			(layer "F.Fab")
		)
		(fp_line
			(start 0.67945 0.3048)
			(end 0.120396 0.3048)
			(stroke
				(width 0.1)
				(type default)
			)
			(layer "F.Fab")
		)
		(pad "1" smd circle
			(at -0.40005 0)
			(size 0 0)
			(layers "F.Cu" "F.Mask" "F.Paste")
			(net "P3V3_AUX")
		)
		(pad "2" smd circle
			(at 0.40005 0)
			(size 0 0)
			(layers "F.Cu" "F.Mask" "F.Paste")
			(net "FM_PECI_SEL_N")
		)
	)
	(footprint ""
		(layer "F.Cu")
		(at 83.90001 -22.690074)
		(property "Reference" "H9"
			(at 3.474212 0.323596 0)
			(unlocked yes)
			(layer "F.SilkS")
			(effects
				(font
					(size 0.7874 0.5842)
					(thickness 0.1524)
				)
				(justify left)
			)
		)
		(property "Value" ""
			(at 0 0 0)
			(layer "F.Fab")
			(effects
				(font
					(size 1.27 1.27)
				)
			)
		)
		(duplicate_pad_numbers_are_jumpers no)
		(pad "1" thru_hole circle
			(at 0 0)
			(size 6.0452 6.0452)
			(drill 3.1496)
			(layers "*.Cu" "*.Mask")
			(remove_unused_layers no)
			(net "GND")
			(clearance -1.1938)
		)
	)
	(footprint ""
		(layer "F.Cu")
		(at 56.0324 -81.153 90)
		(property "Reference" "R551"
			(at 0 0 90)
			(layer "F.SilkS")
			(hide yes)
			(effects
				(font
					(size 1.27 1.27)
				)
			)
		)
		(property "Value" ""
			(at 0 0 90)
			(layer "F.Fab")
			(effects
				(font
					(size 1.27 1.27)
				)
			)
		)
		(duplicate_pad_numbers_are_jumpers no)
		(fp_line
			(start 0.7874 -0.4064)
			(end 0.7874 0.4064)
			(stroke
				(width 0.1524)
				(type default)
			)
			(layer "F.SilkS")
		)
		(fp_line
			(start -0.7874 -0.4064)
			(end 0.7874 -0.4064)
			(stroke
				(width 0.1524)
				(type default)
			)
			(layer "F.SilkS")
		)
		(fp_line
			(start 0.7874 0.4064)
			(end -0.7874 0.4064)
			(stroke
				(width 0.1524)
				(type default)
			)
			(layer "F.SilkS")
		)
		(fp_line
			(start -0.7874 0.4064)
			(end -0.7874 -0.4064)
			(stroke
				(width 0.1524)
				(type default)
			)
			(layer "F.SilkS")
		)
		(fp_line
			(start -0.12065 -0.305054)
			(end -0.12065 -0.2794)
			(stroke
				(width 0.1)
				(type default)
			)
			(layer "F.Fab")
		)
		(fp_line
			(start -0.67945 -0.305054)
			(end -0.12065 -0.305054)
			(stroke
				(width 0.1)
				(type default)
			)
			(layer "F.Fab")
		)
		(fp_line
			(start 0.67945 -0.3048)
			(end 0.67945 0.3048)
			(stroke
				(width 0.1)
				(type default)
			)
			(layer "F.Fab")
		)
		(fp_line
			(start 0.12065 -0.3048)
			(end 0.67945 -0.3048)
			(stroke
				(width 0.1)
				(type default)
			)
			(layer "F.Fab")
		)
		(fp_line
			(start 0.12065 -0.2794)
			(end 0.12065 -0.3048)
			(stroke
				(width 0.1)
				(type default)
			)
			(layer "F.Fab")
		)
		(fp_line
			(start -0.12065 -0.2794)
			(end 0.12065 -0.2794)
			(stroke
				(width 0.1)
				(type default)
			)
			(layer "F.Fab")
		)
		(fp_line
			(start 0.120396 0.2794)
			(end -0.12065 0.2794)
			(stroke
				(width 0.1)
				(type default)
			)
			(layer "F.Fab")
		)
		(fp_line
			(start -0.12065 0.2794)
			(end -0.12065 0.3048)
			(stroke
				(width 0.1)
				(type default)
			)
			(layer "F.Fab")
		)
		(fp_line
			(start 0.67945 0.3048)
			(end 0.120396 0.3048)
			(stroke
				(width 0.1)
				(type default)
			)
			(layer "F.Fab")
		)
		(fp_line
			(start 0.120396 0.3048)
			(end 0.120396 0.2794)
			(stroke
				(width 0.1)
				(type default)
			)
			(layer "F.Fab")
		)
		(fp_line
			(start -0.12065 0.3048)
			(end -0.67945 0.3048)
			(stroke
				(width 0.1)
				(type default)
			)
			(layer "F.Fab")
		)
		(fp_line
			(start -0.67945 0.3048)
			(end -0.67945 -0.305054)
			(stroke
				(width 0.1)
				(type default)
			)
			(layer "F.Fab")
		)
		(pad "1" smd circle
			(at -0.40005 0 90)
			(size 0 0)
			(layers "F.Cu" "F.Mask" "F.Paste")
			(net "FLASH_WP_STATUS")
		)
		(pad "2" smd circle
			(at 0.40005 0 90)
			(size 0 0)
			(layers "F.Cu" "F.Mask" "F.Paste")
			(net "FLASH_R_WP_STATUS")
		)
	)
	(footprint ""
		(layer "F.Cu")
		(at 36.1061 -47.13605 -90)
		(property "Reference" "R438"
			(at 0 0 270)
			(layer "F.SilkS")
			(hide yes)
			(effects
				(font
					(size 1.27 1.27)
				)
			)
		)
		(property "Value" ""
			(at 0 0 270)
			(layer "F.Fab")
			(effects
				(font
					(size 1.27 1.27)
				)
			)
		)
		(duplicate_pad_numbers_are_jumpers no)
		(fp_line
			(start -0.7874 0.4064)
			(end -0.7874 -0.4064)
			(stroke
				(width 0.1524)
				(type default)
			)
			(layer "F.SilkS")
		)
		(fp_line
			(start 0.7874 0.4064)
			(end -0.7874 0.4064)
			(stroke
				(width 0.1524)
				(type default)
			)
			(layer "F.SilkS")
		)
		(fp_line
			(start -0.7874 -0.4064)
			(end 0.7874 -0.4064)
			(stroke
				(width 0.1524)
				(type default)
			)
			(layer "F.SilkS")
		)
		(fp_line
			(start 0.7874 -0.4064)
			(end 0.7874 0.4064)
			(stroke
				(width 0.1524)
				(type default)
			)
			(layer "F.SilkS")
		)
		(fp_line
			(start -0.67945 0.3048)
			(end -0.67945 -0.305054)
			(stroke
				(width 0.1)
				(type default)
			)
			(layer "F.Fab")
		)
		(fp_line
			(start -0.12065 0.3048)
			(end -0.67945 0.3048)
			(stroke
				(width 0.1)
				(type default)
			)
			(layer "F.Fab")
		)
		(fp_line
			(start 0.120396 0.3048)
			(end 0.120396 0.2794)
			(stroke
				(width 0.1)
				(type default)
			)
			(layer "F.Fab")
		)
		(fp_line
			(start 0.67945 0.3048)
			(end 0.120396 0.3048)
			(stroke
				(width 0.1)
				(type default)
			)
			(layer "F.Fab")
		)
		(fp_line
			(start -0.12065 0.2794)
			(end -0.12065 0.3048)
			(stroke
				(width 0.1)
				(type default)
			)
			(layer "F.Fab")
		)
		(fp_line
			(start 0.120396 0.2794)
			(end -0.12065 0.2794)
			(stroke
				(width 0.1)
				(type default)
			)
			(layer "F.Fab")
		)
		(fp_line
			(start -0.12065 -0.2794)
			(end 0.12065 -0.2794)
			(stroke
				(width 0.1)
				(type default)
			)
			(layer "F.Fab")
		)
		(fp_line
			(start 0.12065 -0.2794)
			(end 0.12065 -0.3048)
			(stroke
				(width 0.1)
				(type default)
			)
			(layer "F.Fab")
		)
		(fp_line
			(start 0.12065 -0.3048)
			(end 0.67945 -0.3048)
			(stroke
				(width 0.1)
				(type default)
			)
			(layer "F.Fab")
		)
		(fp_line
			(start 0.67945 -0.3048)
			(end 0.67945 0.3048)
			(stroke
				(width 0.1)
				(type default)
			)
			(layer "F.Fab")
		)
		(fp_line
			(start -0.67945 -0.305054)
			(end -0.12065 -0.305054)
			(stroke
				(width 0.1)
				(type default)
			)
			(layer "F.Fab")
		)
		(fp_line
			(start -0.12065 -0.305054)
			(end -0.12065 -0.2794)
			(stroke
				(width 0.1)
				(type default)
			)
			(layer "F.Fab")
		)
		(pad "1" smd circle
			(at -0.40005 0 270)
			(size 0 0)
			(layers "F.Cu" "F.Mask" "F.Paste")
			(net "P3V3_AUX")
		)
		(pad "2" smd circle
			(at 0.40005 0 270)
			(size 0 0)
			(layers "F.Cu" "F.Mask" "F.Paste")
			(net "SMB_BMC_MM14_SDA")
		)
	)
	(footprint ""
		(layer "F.Cu")
		(at 82.639662 -33.580324 -90)
		(property "Reference" "U39"
			(at 0.409448 2.049272 90)
			(unlocked yes)
			(layer "F.SilkS")
			(effects
				(font
					(size 0.7874 0.5842)
					(thickness 0.1524)
				)
				(justify left)
			)
		)
		(property "Value" ""
			(at 0 0 270)
			(layer "F.Fab")
			(effects
				(font
					(size 1.27 1.27)
				)
			)
		)
		(duplicate_pad_numbers_are_jumpers no)
		(fp_line
			(start -1.525016 1.525016)
			(end -0.889 1.525016)
			(stroke
				(width 0.1524)
				(type default)
			)
			(layer "F.SilkS")
		)
		(fp_line
			(start 0.9906 1.525016)
			(end 1.525016 1.525016)
			(stroke
				(width 0.1524)
				(type default)
			)
			(layer "F.SilkS")
		)
		(fp_line
			(start 1.525016 1.525016)
			(end -1.525016 1.525016)
			(stroke
				(width 0.1524)
				(type default)
			)
			(layer "F.SilkS")
		)
		(fp_line
			(start 1.525016 1.525016)
			(end 1.525016 1.3208)
			(stroke
				(width 0.1524)
				(type default)
			)
			(layer "F.SilkS")
		)
		(fp_line
			(start -1.525016 1.3208)
			(end -1.525016 1.525016)
			(stroke
				(width 0.1524)
				(type default)
			)
			(layer "F.SilkS")
		)
		(fp_line
			(start 1.525016 -1.3208)
			(end 1.525016 -1.525016)
			(stroke
				(width 0.1524)
				(type default)
			)
			(layer "F.SilkS")
		)
		(fp_line
			(start -1.525016 -1.525016)
			(end -1.525016 -1.3208)
			(stroke
				(width 0.1524)
				(type default)
			)
			(layer "F.SilkS")
		)
		(fp_line
			(start -0.8636 -1.525016)
			(end -1.525016 -1.525016)
			(stroke
				(width 0.1524)
				(type default)
			)
			(layer "F.SilkS")
		)
		(fp_line
			(start 1.525016 -1.525016)
			(end -1.525016 -1.525016)
			(stroke
				(width 0.1524)
				(type default)
			)
			(layer "F.SilkS")
		)
		(fp_line
			(start 1.525016 -1.525016)
			(end 0.9398 -1.525016)
			(stroke
				(width 0.1524)
				(type default)
			)
			(layer "F.SilkS")
		)
		(fp_poly
			(pts
				(xy -2.089404 -1.1684) (xy -2.513838 -2.017014) (xy -2.938272 -1.592834)
			)
			(stroke
				(width 0)
				(type default)
			)
			(fill yes)
			(layer "F.SilkS")
		)
		(fp_line
			(start -1.525016 1.525016)
			(end -1.525016 -1.525016)
			(stroke
				(width 0.1)
				(type default)
			)
			(layer "F.Fab")
		)
		(fp_line
			(start 1.525016 1.525016)
			(end -1.525016 1.525016)
			(stroke
				(width 0.1)
				(type default)
			)
			(layer "F.Fab")
		)
		(fp_line
			(start -1.525016 -1.525016)
			(end 1.525016 -1.525016)
			(stroke
				(width 0.1)
				(type default)
			)
			(layer "F.Fab")
		)
		(fp_line
			(start 1.525016 -1.525016)
			(end 1.525016 1.525016)
			(stroke
				(width 0.1)
				(type default)
			)
			(layer "F.Fab")
		)
		(fp_poly
			(pts
				(xy -2.0701 -0.999998) (xy -2.977896 -1.302512) (xy -2.977896 -0.697484)
			)
			(stroke
				(width 0)
				(type default)
			)
			(fill yes)
			(layer "F.Fab")
		)
		(pad "1" smd rect
			(at -1.550162 -0.999998 180)
			(size 0.2794 0.9144)
			(layers "F.Cu" "F.Mask" "F.Paste")
			(net "P2V5_AUX")
		)
		(pad "2" smd rect
			(at -1.550162 -0.500126 180)
			(size 0.2794 0.9144)
			(layers "F.Cu" "F.Mask" "F.Paste")
			(net "P2V5_AUX")
		)
		(pad "3" smd rect
			(at -1.550162 0 180)
			(size 0.2794 0.9144)
			(layers "F.Cu" "F.Mask" "F.Paste")
			(net "P2V5_AUX")
		)
		(pad "4" smd rect
			(at -1.550162 0.500126 180)
			(size 0.2794 0.9144)
			(layers "F.Cu" "F.Mask" "F.Paste")
			(net "U39_ADJ")
		)
		(pad "5" smd rect
			(at -1.550162 0.999998)
			(size 0.2794 0.9144)
			(layers "F.Cu" "F.Mask" "F.Paste")
			(net "PWRGD_P2V5_AUX_R")
		)
		(pad "6" smd rect
			(at 1.550162 0.999998)
			(size 0.2794 0.9144)
			(layers "F.Cu" "F.Mask" "F.Paste")
			(net "PWRGD_P3V3_AUX_R2")
		)
		(pad "7" smd rect
			(at 1.550162 0.500126 180)
			(size 0.2794 0.9144)
			(layers "F.Cu" "F.Mask" "F.Paste")
			(net "P3V3_AUX")
		)
		(pad "8" smd rect
			(at 1.550162 0 180)
			(size 0.2794 0.9144)
			(layers "F.Cu" "F.Mask" "F.Paste")
			(net "P3V3_AUX")
		)
		(pad "9" smd rect
			(at 1.550162 -0.500126 180)
			(size 0.2794 0.9144)
			(layers "F.Cu" "F.Mask" "F.Paste")
			(net "P3V3_AUX")
		)
		(pad "10" smd rect
			(at 1.550162 -0.999998 180)
			(size 0.2794 0.9144)
			(layers "F.Cu" "F.Mask" "F.Paste")
			(net "P5V_AUX")
		)
		(pad "TH" smd rect
			(at 0 0 270)
			(size 1.7526 2.667)
			(layers "F.Cu" "F.Mask" "F.Paste")
			(net "GND")
		)
		(zone
			(layer "F.Cu")
			(hatch none 0.5)
			(connect_pads
				(clearance 0)
			)
			(min_thickness 0.25)
			(keepout
				(tracks not_allowed)
				(vias allowed)
				(pads allowed)
				(copperpour not_allowed)
				(footprints allowed)
			)
			(placement
				(enabled no)
				(sheetname "")
			)
			(fill
				(thermal_gap 0.5)
				(thermal_bridge_width 0.5)
				(island_removal_mode 0)
			)
			(polygon
				(pts
					(xy 84.17306 -34.597086) (xy 81.12506 -34.597086) (xy 81.12506 -32.565086) (xy 84.17306 -32.565086)
					(xy 84.17306 -34.495486) (xy 84.04606 -34.495486) (xy 84.04606 -32.641286) (xy 81.22666 -32.641286)
					(xy 81.22666 -34.520886) (xy 84.17306 -34.520886)
				)
			)
		)
	)
	(footprint ""
		(layer "F.Cu")
		(at 20.193 -68.834 -90)
		(property "Reference" "R90"
			(at 0 0 270)
			(layer "F.SilkS")
			(hide yes)
			(effects
				(font
					(size 1.27 1.27)
				)
			)
		)
		(property "Value" ""
			(at 0 0 270)
			(layer "F.Fab")
			(effects
				(font
					(size 1.27 1.27)
				)
			)
		)
		(duplicate_pad_numbers_are_jumpers no)
		(fp_line
			(start -0.7874 0.4064)
			(end -0.7874 -0.4064)
			(stroke
				(width 0.1524)
				(type default)
			)
			(layer "F.SilkS")
		)
		(fp_line
			(start 0.7874 0.4064)
			(end -0.7874 0.4064)
			(stroke
				(width 0.1524)
				(type default)
			)
			(layer "F.SilkS")
		)
		(fp_line
			(start -0.7874 -0.4064)
			(end 0.7874 -0.4064)
			(stroke
				(width 0.1524)
				(type default)
			)
			(layer "F.SilkS")
		)
		(fp_line
			(start 0.7874 -0.4064)
			(end 0.7874 0.4064)
			(stroke
				(width 0.1524)
				(type default)
			)
			(layer "F.SilkS")
		)
		(fp_line
			(start -0.67945 0.3048)
			(end -0.67945 -0.305054)
			(stroke
				(width 0.1)
				(type default)
			)
			(layer "F.Fab")
		)
		(fp_line
			(start -0.12065 0.3048)
			(end -0.67945 0.3048)
			(stroke
				(width 0.1)
				(type default)
			)
			(layer "F.Fab")
		)
		(fp_line
			(start 0.120396 0.3048)
			(end 0.120396 0.2794)
			(stroke
				(width 0.1)
				(type default)
			)
			(layer "F.Fab")
		)
		(fp_line
			(start 0.67945 0.3048)
			(end 0.120396 0.3048)
			(stroke
				(width 0.1)
				(type default)
			)
			(layer "F.Fab")
		)
		(fp_line
			(start -0.12065 0.2794)
			(end -0.12065 0.3048)
			(stroke
				(width 0.1)
				(type default)
			)
			(layer "F.Fab")
		)
		(fp_line
			(start 0.120396 0.2794)
			(end -0.12065 0.2794)
			(stroke
				(width 0.1)
				(type default)
			)
			(layer "F.Fab")
		)
		(fp_line
			(start -0.12065 -0.2794)
			(end 0.12065 -0.2794)
			(stroke
				(width 0.1)
				(type default)
			)
			(layer "F.Fab")
		)
		(fp_line
			(start 0.12065 -0.2794)
			(end 0.12065 -0.3048)
			(stroke
				(width 0.1)
				(type default)
			)
			(layer "F.Fab")
		)
		(fp_line
			(start 0.12065 -0.3048)
			(end 0.67945 -0.3048)
			(stroke
				(width 0.1)
				(type default)
			)
			(layer "F.Fab")
		)
		(fp_line
			(start 0.67945 -0.3048)
			(end 0.67945 0.3048)
			(stroke
				(width 0.1)
				(type default)
			)
			(layer "F.Fab")
		)
		(fp_line
			(start -0.67945 -0.305054)
			(end -0.12065 -0.305054)
			(stroke
				(width 0.1)
				(type default)
			)
			(layer "F.Fab")
		)
		(fp_line
			(start -0.12065 -0.305054)
			(end -0.12065 -0.2794)
			(stroke
				(width 0.1)
				(type default)
			)
			(layer "F.Fab")
		)
		(pad "1" smd circle
			(at -0.40005 0 270)
			(size 0 0)
			(layers "F.Cu" "F.Mask" "F.Paste")
			(net "P3V3_AUX")
		)
		(pad "2" smd circle
			(at 0.40005 0 270)
			(size 0 0)
			(layers "F.Cu" "F.Mask" "F.Paste")
			(net "RST_SPI_BMC_FLASH_R2_N")
		)
	)
	(footprint ""
		(layer "F.Cu")
		(at 27.813 -25.908 180)
		(property "Reference" "C214"
			(at 0 0 180)
			(layer "F.SilkS")
			(hide yes)
			(effects
				(font
					(size 1.27 1.27)
				)
			)
		)
		(property "Value" ""
			(at 0 0 180)
			(layer "F.Fab")
			(effects
				(font
					(size 1.27 1.27)
				)
			)
		)
		(duplicate_pad_numbers_are_jumpers no)
		(fp_line
			(start 0.7874 0.4064)
			(end -0.7874 0.4064)
			(stroke
				(width 0.1524)
				(type default)
			)
			(layer "F.SilkS")
		)
		(fp_line
			(start 0.7874 -0.4064)
			(end 0.7874 0.4064)
			(stroke
				(width 0.1524)
				(type default)
			)
			(layer "F.SilkS")
		)
		(fp_line
			(start -0.7874 0.4064)
			(end -0.7874 -0.4064)
			(stroke
				(width 0.1524)
				(type default)
			)
			(layer "F.SilkS")
		)
		(fp_line
			(start -0.7874 -0.4064)
			(end 0.7874 -0.4064)
			(stroke
				(width 0.1524)
				(type default)
			)
			(layer "F.SilkS")
		)
		(fp_line
			(start 0.67945 0.3048)
			(end 0.120396 0.3048)
			(stroke
				(width 0.1)
				(type default)
			)
			(layer "F.Fab")
		)
		(fp_line
			(start 0.67945 -0.3048)
			(end 0.67945 0.3048)
			(stroke
				(width 0.1)
				(type default)
			)
			(layer "F.Fab")
		)
		(fp_line
			(start 0.12065 -0.2794)
			(end 0.12065 -0.3048)
			(stroke
				(width 0.1)
				(type default)
			)
			(layer "F.Fab")
		)
		(fp_line
			(start 0.12065 -0.3048)
			(end 0.67945 -0.3048)
			(stroke
				(width 0.1)
				(type default)
			)
			(layer "F.Fab")
		)
		(fp_line
			(start 0.120396 0.3048)
			(end 0.120396 0.2794)
			(stroke
				(width 0.1)
				(type default)
			)
			(layer "F.Fab")
		)
		(fp_line
			(start 0.120396 0.2794)
			(end -0.12065 0.2794)
			(stroke
				(width 0.1)
				(type default)
			)
			(layer "F.Fab")
		)
		(fp_line
			(start -0.12065 0.3048)
			(end -0.67945 0.3048)
			(stroke
				(width 0.1)
				(type default)
			)
			(layer "F.Fab")
		)
		(fp_line
			(start -0.12065 0.2794)
			(end -0.12065 0.3048)
			(stroke
				(width 0.1)
				(type default)
			)
			(layer "F.Fab")
		)
		(fp_line
			(start -0.12065 -0.2794)
			(end 0.12065 -0.2794)
			(stroke
				(width 0.1)
				(type default)
			)
			(layer "F.Fab")
		)
		(fp_line
			(start -0.12065 -0.305054)
			(end -0.12065 -0.2794)
			(stroke
				(width 0.1)
				(type default)
			)
			(layer "F.Fab")
		)
		(fp_line
			(start -0.67945 0.3048)
			(end -0.67945 -0.305054)
			(stroke
				(width 0.1)
				(type default)
			)
			(layer "F.Fab")
		)
		(fp_line
			(start -0.67945 -0.305054)
			(end -0.12065 -0.305054)
			(stroke
				(width 0.1)
				(type default)
			)
			(layer "F.Fab")
		)
		(pad "1" smd circle
			(at -0.40005 0 180)
			(size 0 0)
			(layers "F.Cu" "F.Mask" "F.Paste")
			(net "V_BMC_LS_DDC_SCL_R")
		)
		(pad "2" smd circle
			(at 0.40005 0 180)
			(size 0 0)
			(layers "F.Cu" "F.Mask" "F.Paste")
			(net "GND")
		)
	)
	(footprint ""
		(layer "F.Cu")
		(at 59.311794 -34.688526 90)
		(property "Reference" "R623"
			(at 0 0 90)
			(layer "F.SilkS")
			(hide yes)
			(effects
				(font
					(size 1.27 1.27)
				)
			)
		)
		(property "Value" ""
			(at 0 0 90)
			(layer "F.Fab")
			(effects
				(font
					(size 1.27 1.27)
				)
			)
		)
		(duplicate_pad_numbers_are_jumpers no)
		(fp_line
			(start 0.7874 -0.4064)
			(end 0.7874 0.4064)
			(stroke
				(width 0.1524)
				(type default)
			)
			(layer "F.SilkS")
		)
		(fp_line
			(start -0.7874 -0.4064)
			(end 0.7874 -0.4064)
			(stroke
				(width 0.1524)
				(type default)
			)
			(layer "F.SilkS")
		)
		(fp_line
			(start 0.7874 0.4064)
			(end -0.7874 0.4064)
			(stroke
				(width 0.1524)
				(type default)
			)
			(layer "F.SilkS")
		)
		(fp_line
			(start -0.7874 0.4064)
			(end -0.7874 -0.4064)
			(stroke
				(width 0.1524)
				(type default)
			)
			(layer "F.SilkS")
		)
		(fp_line
			(start -0.12065 -0.305054)
			(end -0.12065 -0.2794)
			(stroke
				(width 0.1)
				(type default)
			)
			(layer "F.Fab")
		)
		(fp_line
			(start -0.67945 -0.305054)
			(end -0.12065 -0.305054)
			(stroke
				(width 0.1)
				(type default)
			)
			(layer "F.Fab")
		)
		(fp_line
			(start 0.67945 -0.3048)
			(end 0.67945 0.3048)
			(stroke
				(width 0.1)
				(type default)
			)
			(layer "F.Fab")
		)
		(fp_line
			(start 0.12065 -0.3048)
			(end 0.67945 -0.3048)
			(stroke
				(width 0.1)
				(type default)
			)
			(layer "F.Fab")
		)
		(fp_line
			(start 0.12065 -0.2794)
			(end 0.12065 -0.3048)
			(stroke
				(width 0.1)
				(type default)
			)
			(layer "F.Fab")
		)
		(fp_line
			(start -0.12065 -0.2794)
			(end 0.12065 -0.2794)
			(stroke
				(width 0.1)
				(type default)
			)
			(layer "F.Fab")
		)
		(fp_line
			(start 0.120396 0.2794)
			(end -0.12065 0.2794)
			(stroke
				(width 0.1)
				(type default)
			)
			(layer "F.Fab")
		)
		(fp_line
			(start -0.12065 0.2794)
			(end -0.12065 0.3048)
			(stroke
				(width 0.1)
				(type default)
			)
			(layer "F.Fab")
		)
		(fp_line
			(start 0.67945 0.3048)
			(end 0.120396 0.3048)
			(stroke
				(width 0.1)
				(type default)
			)
			(layer "F.Fab")
		)
		(fp_line
			(start 0.120396 0.3048)
			(end 0.120396 0.2794)
			(stroke
				(width 0.1)
				(type default)
			)
			(layer "F.Fab")
		)
		(fp_line
			(start -0.12065 0.3048)
			(end -0.67945 0.3048)
			(stroke
				(width 0.1)
				(type default)
			)
			(layer "F.Fab")
		)
		(fp_line
			(start -0.67945 0.3048)
			(end -0.67945 -0.305054)
			(stroke
				(width 0.1)
				(type default)
			)
			(layer "F.Fab")
		)
		(pad "1" smd circle
			(at -0.40005 0 90)
			(size 0 0)
			(layers "F.Cu" "F.Mask" "F.Paste")
			(net "P3V3_RGM")
		)
		(pad "2" smd circle
			(at 0.40005 0 90)
			(size 0 0)
			(layers "F.Cu" "F.Mask" "F.Paste")
			(net "RST_EXTRST_N")
		)
	)
	(footprint ""
		(layer "F.Cu")
		(at 12.3444 -109.347 90)
		(property "Reference" "R564"
			(at 0 0 90)
			(layer "F.SilkS")
			(hide yes)
			(effects
				(font
					(size 1.27 1.27)
				)
			)
		)
		(property "Value" ""
			(at 0 0 90)
			(layer "F.Fab")
			(effects
				(font
					(size 1.27 1.27)
				)
			)
		)
		(duplicate_pad_numbers_are_jumpers no)
		(fp_line
			(start 0.7874 -0.4064)
			(end 0.7874 0.4064)
			(stroke
				(width 0.1524)
				(type default)
			)
			(layer "F.SilkS")
		)
		(fp_line
			(start -0.7874 -0.4064)
			(end 0.7874 -0.4064)
			(stroke
				(width 0.1524)
				(type default)
			)
			(layer "F.SilkS")
		)
		(fp_line
			(start 0.7874 0.4064)
			(end -0.7874 0.4064)
			(stroke
				(width 0.1524)
				(type default)
			)
			(layer "F.SilkS")
		)
		(fp_line
			(start -0.7874 0.4064)
			(end -0.7874 -0.4064)
			(stroke
				(width 0.1524)
				(type default)
			)
			(layer "F.SilkS")
		)
		(fp_line
			(start -0.12065 -0.305054)
			(end -0.12065 -0.2794)
			(stroke
				(width 0.1)
				(type default)
			)
			(layer "F.Fab")
		)
		(fp_line
			(start -0.67945 -0.305054)
			(end -0.12065 -0.305054)
			(stroke
				(width 0.1)
				(type default)
			)
			(layer "F.Fab")
		)
		(fp_line
			(start 0.67945 -0.3048)
			(end 0.67945 0.3048)
			(stroke
				(width 0.1)
				(type default)
			)
			(layer "F.Fab")
		)
		(fp_line
			(start 0.12065 -0.3048)
			(end 0.67945 -0.3048)
			(stroke
				(width 0.1)
				(type default)
			)
			(layer "F.Fab")
		)
		(fp_line
			(start 0.12065 -0.2794)
			(end 0.12065 -0.3048)
			(stroke
				(width 0.1)
				(type default)
			)
			(layer "F.Fab")
		)
		(fp_line
			(start -0.12065 -0.2794)
			(end 0.12065 -0.2794)
			(stroke
				(width 0.1)
				(type default)
			)
			(layer "F.Fab")
		)
		(fp_line
			(start 0.120396 0.2794)
			(end -0.12065 0.2794)
			(stroke
				(width 0.1)
				(type default)
			)
			(layer "F.Fab")
		)
		(fp_line
			(start -0.12065 0.2794)
			(end -0.12065 0.3048)
			(stroke
				(width 0.1)
				(type default)
			)
			(layer "F.Fab")
		)
		(fp_line
			(start 0.67945 0.3048)
			(end 0.120396 0.3048)
			(stroke
				(width 0.1)
				(type default)
			)
			(layer "F.Fab")
		)
		(fp_line
			(start 0.120396 0.3048)
			(end 0.120396 0.2794)
			(stroke
				(width 0.1)
				(type default)
			)
			(layer "F.Fab")
		)
		(fp_line
			(start -0.12065 0.3048)
			(end -0.67945 0.3048)
			(stroke
				(width 0.1)
				(type default)
			)
			(layer "F.Fab")
		)
		(fp_line
			(start -0.67945 0.3048)
			(end -0.67945 -0.305054)
			(stroke
				(width 0.1)
				(type default)
			)
			(layer "F.Fab")
		)
		(pad "1" smd circle
			(at -0.40005 0 90)
			(size 0 0)
			(layers "F.Cu" "F.Mask" "F.Paste")
			(net "HDD_LED_N")
		)
		(pad "2" smd circle
			(at 0.40005 0 90)
			(size 0 0)
			(layers "F.Cu" "F.Mask" "F.Paste")
			(net "HDD_LED_R_N")
		)
	)
	(footprint ""
		(layer "F.Cu")
		(at 10.922 -106.6038)
		(property "Reference" "R125"
			(at 0 0 0)
			(layer "F.SilkS")
			(hide yes)
			(effects
				(font
					(size 1.27 1.27)
				)
			)
		)
		(property "Value" ""
			(at 0 0 0)
			(layer "F.Fab")
			(effects
				(font
					(size 1.27 1.27)
				)
			)
		)
		(duplicate_pad_numbers_are_jumpers no)
		(fp_line
			(start -0.7874 -0.4064)
			(end 0.7874 -0.4064)
			(stroke
				(width 0.1524)
				(type default)
			)
			(layer "F.SilkS")
		)
		(fp_line
			(start -0.7874 0.4064)
			(end -0.7874 -0.4064)
			(stroke
				(width 0.1524)
				(type default)
			)
			(layer "F.SilkS")
		)
		(fp_line
			(start 0.7874 -0.4064)
			(end 0.7874 0.4064)
			(stroke
				(width 0.1524)
				(type default)
			)
			(layer "F.SilkS")
		)
		(fp_line
			(start 0.7874 0.4064)
			(end -0.7874 0.4064)
			(stroke
				(width 0.1524)
				(type default)
			)
			(layer "F.SilkS")
		)
		(fp_line
			(start -0.67945 -0.305054)
			(end -0.12065 -0.305054)
			(stroke
				(width 0.1)
				(type default)
			)
			(layer "F.Fab")
		)
		(fp_line
			(start -0.67945 0.3048)
			(end -0.67945 -0.305054)
			(stroke
				(width 0.1)
				(type default)
			)
			(layer "F.Fab")
		)
		(fp_line
			(start -0.12065 -0.305054)
			(end -0.12065 -0.2794)
			(stroke
				(width 0.1)
				(type default)
			)
			(layer "F.Fab")
		)
		(fp_line
			(start -0.12065 -0.2794)
			(end 0.12065 -0.2794)
			(stroke
				(width 0.1)
				(type default)
			)
			(layer "F.Fab")
		)
		(fp_line
			(start -0.12065 0.2794)
			(end -0.12065 0.3048)
			(stroke
				(width 0.1)
				(type default)
			)
			(layer "F.Fab")
		)
		(fp_line
			(start -0.12065 0.3048)
			(end -0.67945 0.3048)
			(stroke
				(width 0.1)
				(type default)
			)
			(layer "F.Fab")
		)
		(fp_line
			(start 0.120396 0.2794)
			(end -0.12065 0.2794)
			(stroke
				(width 0.1)
				(type default)
			)
			(layer "F.Fab")
		)
		(fp_line
			(start 0.120396 0.3048)
			(end 0.120396 0.2794)
			(stroke
				(width 0.1)
				(type default)
			)
			(layer "F.Fab")
		)
		(fp_line
			(start 0.12065 -0.3048)
			(end 0.67945 -0.3048)
			(stroke
				(width 0.1)
				(type default)
			)
			(layer "F.Fab")
		)
		(fp_line
			(start 0.12065 -0.2794)
			(end 0.12065 -0.3048)
			(stroke
				(width 0.1)
				(type default)
			)
			(layer "F.Fab")
		)
		(fp_line
			(start 0.67945 -0.3048)
			(end 0.67945 0.3048)
			(stroke
				(width 0.1)
				(type default)
			)
			(layer "F.Fab")
		)
		(fp_line
			(start 0.67945 0.3048)
			(end 0.120396 0.3048)
			(stroke
				(width 0.1)
				(type default)
			)
			(layer "F.Fab")
		)
		(pad "1" smd circle
			(at -0.40005 0)
			(size 0 0)
			(layers "F.Cu" "F.Mask" "F.Paste")
			(net "RST_BMC_SRST_BUF_R_N")
		)
		(pad "2" smd circle
			(at 0.40005 0)
			(size 0 0)
			(layers "F.Cu" "F.Mask" "F.Paste")
			(net "RST_BMC_SRST_N")
		)
	)
	(footprint ""
		(layer "F.Cu")
		(at 15.5448 -70.7136 -90)
		(property "Reference" "R664"
			(at 0 0 270)
			(layer "F.SilkS")
			(hide yes)
			(effects
				(font
					(size 1.27 1.27)
				)
			)
		)
		(property "Value" ""
			(at 0 0 270)
			(layer "F.Fab")
			(effects
				(font
					(size 1.27 1.27)
				)
			)
		)
		(duplicate_pad_numbers_are_jumpers no)
		(fp_line
			(start -0.7874 0.4064)
			(end -0.7874 -0.4064)
			(stroke
				(width 0.1524)
				(type default)
			)
			(layer "F.SilkS")
		)
		(fp_line
			(start 0.7874 0.4064)
			(end -0.7874 0.4064)
			(stroke
				(width 0.1524)
				(type default)
			)
			(layer "F.SilkS")
		)
		(fp_line
			(start -0.7874 -0.4064)
			(end 0.7874 -0.4064)
			(stroke
				(width 0.1524)
				(type default)
			)
			(layer "F.SilkS")
		)
		(fp_line
			(start 0.7874 -0.4064)
			(end 0.7874 0.4064)
			(stroke
				(width 0.1524)
				(type default)
			)
			(layer "F.SilkS")
		)
		(fp_line
			(start -0.67945 0.3048)
			(end -0.67945 -0.305054)
			(stroke
				(width 0.1)
				(type default)
			)
			(layer "F.Fab")
		)
		(fp_line
			(start -0.12065 0.3048)
			(end -0.67945 0.3048)
			(stroke
				(width 0.1)
				(type default)
			)
			(layer "F.Fab")
		)
		(fp_line
			(start 0.120396 0.3048)
			(end 0.120396 0.2794)
			(stroke
				(width 0.1)
				(type default)
			)
			(layer "F.Fab")
		)
		(fp_line
			(start 0.67945 0.3048)
			(end 0.120396 0.3048)
			(stroke
				(width 0.1)
				(type default)
			)
			(layer "F.Fab")
		)
		(fp_line
			(start -0.12065 0.2794)
			(end -0.12065 0.3048)
			(stroke
				(width 0.1)
				(type default)
			)
			(layer "F.Fab")
		)
		(fp_line
			(start 0.120396 0.2794)
			(end -0.12065 0.2794)
			(stroke
				(width 0.1)
				(type default)
			)
			(layer "F.Fab")
		)
		(fp_line
			(start -0.12065 -0.2794)
			(end 0.12065 -0.2794)
			(stroke
				(width 0.1)
				(type default)
			)
			(layer "F.Fab")
		)
		(fp_line
			(start 0.12065 -0.2794)
			(end 0.12065 -0.3048)
			(stroke
				(width 0.1)
				(type default)
			)
			(layer "F.Fab")
		)
		(fp_line
			(start 0.12065 -0.3048)
			(end 0.67945 -0.3048)
			(stroke
				(width 0.1)
				(type default)
			)
			(layer "F.Fab")
		)
		(fp_line
			(start 0.67945 -0.3048)
			(end 0.67945 0.3048)
			(stroke
				(width 0.1)
				(type default)
			)
			(layer "F.Fab")
		)
		(fp_line
			(start -0.67945 -0.305054)
			(end -0.12065 -0.305054)
			(stroke
				(width 0.1)
				(type default)
			)
			(layer "F.Fab")
		)
		(fp_line
			(start -0.12065 -0.305054)
			(end -0.12065 -0.2794)
			(stroke
				(width 0.1)
				(type default)
			)
			(layer "F.Fab")
		)
		(pad "1" smd circle
			(at -0.40005 0 270)
			(size 0 0)
			(layers "F.Cu" "F.Mask" "F.Paste")
			(net "SPI_BMC_BT_WP1_N_R")
		)
		(pad "2" smd circle
			(at 0.40005 0 270)
			(size 0 0)
			(layers "F.Cu" "F.Mask" "F.Paste")
			(net "GND")
		)
	)
	(footprint ""
		(layer "F.Cu")
		(at 33.2994 -61.976)
		(property "Reference" "U49"
			(at -2.794 3.55727 0)
			(unlocked yes)
			(layer "F.SilkS")
			(effects
				(font
					(size 0.7874 0.5842)
					(thickness 0.1524)
				)
			)
		)
		(property "Value" ""
			(at 0 0 0)
			(layer "F.Fab")
			(effects
				(font
					(size 1.27 1.27)
				)
			)
		)
		(duplicate_pad_numbers_are_jumpers no)
		(fp_line
			(start -1.834896 -1.575054)
			(end -0.508 -1.575054)
			(stroke
				(width 0.1524)
				(type default)
			)
			(layer "F.SilkS")
		)
		(fp_line
			(start -1.834896 1.575054)
			(end -1.834896 -1.575054)
			(stroke
				(width 0.1524)
				(type default)
			)
			(layer "F.SilkS")
		)
		(fp_line
			(start -0.508 -1.575054)
			(end 0 -1.016)
			(stroke
				(width 0.1524)
				(type default)
			)
			(layer "F.SilkS")
		)
		(fp_line
			(start 0 -1.016)
			(end 0.508 -1.575054)
			(stroke
				(width 0.1524)
				(type default)
			)
			(layer "F.SilkS")
		)
		(fp_line
			(start 0.508 -1.575054)
			(end 1.834896 -1.575054)
			(stroke
				(width 0.1524)
				(type default)
			)
			(layer "F.SilkS")
		)
		(fp_line
			(start 1.834896 -1.575054)
			(end 1.834896 1.575054)
			(stroke
				(width 0.1524)
				(type default)
			)
			(layer "F.SilkS")
		)
		(fp_line
			(start 1.834896 1.575054)
			(end -1.834896 1.575054)
			(stroke
				(width 0.1524)
				(type default)
			)
			(layer "F.SilkS")
		)
		(fp_poly
			(pts
				(xy -3.028696 -1.73736) (xy -3.028696 -0.72136) (xy -2.012696 -1.22936)
			)
			(stroke
				(width 0)
				(type default)
			)
			(fill yes)
			(layer "F.SilkS")
		)
		(fp_line
			(start -0.824992 -1.575054)
			(end 0.824992 -1.575054)
			(stroke
				(width 0.1)
				(type default)
			)
			(layer "F.Fab")
		)
		(fp_line
			(start -0.824992 1.575054)
			(end -0.824992 -1.575054)
			(stroke
				(width 0.1)
				(type default)
			)
			(layer "F.Fab")
		)
		(fp_line
			(start 0.824992 -1.575054)
			(end 0.824992 1.575054)
			(stroke
				(width 0.1)
				(type default)
			)
			(layer "F.Fab")
		)
		(fp_line
			(start 0.824992 1.575054)
			(end -0.824992 1.575054)
			(stroke
				(width 0.1)
				(type default)
			)
			(layer "F.Fab")
		)
		(fp_poly
			(pts
				(xy -3.003296 -1.45796) (xy -3.003296 -0.44196) (xy -1.987296 -0.94996)
			)
			(stroke
				(width 0)
				(type default)
			)
			(fill yes)
			(layer "F.Fab")
		)
		(pad "1" smd rect
			(at -1.199896 -0.94996 270)
			(size 0.7112 1.016)
			(layers "F.Cu" "F.Mask" "F.Paste")
			(net "PWRGD_P5V_AUX")
		)
		(pad "2" smd rect
			(at -1.199896 0 270)
			(size 0.7112 1.016)
			(layers "F.Cu" "F.Mask" "F.Paste")
			(net "PWRGD_P3V3_RGM_R2")
		)
		(pad "3" smd rect
			(at -1.199896 0.94996 270)
			(size 0.7112 1.016)
			(layers "F.Cu" "F.Mask" "F.Paste")
			(net "GND")
		)
		(pad "4" smd rect
			(at 1.199896 0.94996 270)
			(size 0.7112 1.016)
			(layers "F.Cu" "F.Mask" "F.Paste")
			(net "EN_P1V8")
		)
		(pad "5" smd rect
			(at 1.199896 -0.94996 270)
			(size 0.7112 1.016)
			(layers "F.Cu" "F.Mask" "F.Paste")
			(net "P3V3_LDO")
		)
	)
	(footprint ""
		(layer "F.Cu")
		(at 71.4502 -27.9146 -90)
		(property "Reference" "R872"
			(at 0 0 270)
			(layer "F.SilkS")
			(hide yes)
			(effects
				(font
					(size 1.27 1.27)
				)
			)
		)
		(property "Value" ""
			(at 0 0 270)
			(layer "F.Fab")
			(effects
				(font
					(size 1.27 1.27)
				)
			)
		)
		(duplicate_pad_numbers_are_jumpers no)
		(fp_line
			(start -0.7874 0.4064)
			(end -0.7874 -0.4064)
			(stroke
				(width 0.1524)
				(type default)
			)
			(layer "F.SilkS")
		)
		(fp_line
			(start 0.7874 0.4064)
			(end -0.7874 0.4064)
			(stroke
				(width 0.1524)
				(type default)
			)
			(layer "F.SilkS")
		)
		(fp_line
			(start -0.7874 -0.4064)
			(end 0.7874 -0.4064)
			(stroke
				(width 0.1524)
				(type default)
			)
			(layer "F.SilkS")
		)
		(fp_line
			(start 0.7874 -0.4064)
			(end 0.7874 0.4064)
			(stroke
				(width 0.1524)
				(type default)
			)
			(layer "F.SilkS")
		)
		(fp_line
			(start -0.67945 0.3048)
			(end -0.67945 -0.305054)
			(stroke
				(width 0.1)
				(type default)
			)
			(layer "F.Fab")
		)
		(fp_line
			(start -0.12065 0.3048)
			(end -0.67945 0.3048)
			(stroke
				(width 0.1)
				(type default)
			)
			(layer "F.Fab")
		)
		(fp_line
			(start 0.120396 0.3048)
			(end 0.120396 0.2794)
			(stroke
				(width 0.1)
				(type default)
			)
			(layer "F.Fab")
		)
		(fp_line
			(start 0.67945 0.3048)
			(end 0.120396 0.3048)
			(stroke
				(width 0.1)
				(type default)
			)
			(layer "F.Fab")
		)
		(fp_line
			(start -0.12065 0.2794)
			(end -0.12065 0.3048)
			(stroke
				(width 0.1)
				(type default)
			)
			(layer "F.Fab")
		)
		(fp_line
			(start 0.120396 0.2794)
			(end -0.12065 0.2794)
			(stroke
				(width 0.1)
				(type default)
			)
			(layer "F.Fab")
		)
		(fp_line
			(start -0.12065 -0.2794)
			(end 0.12065 -0.2794)
			(stroke
				(width 0.1)
				(type default)
			)
			(layer "F.Fab")
		)
		(fp_line
			(start 0.12065 -0.2794)
			(end 0.12065 -0.3048)
			(stroke
				(width 0.1)
				(type default)
			)
			(layer "F.Fab")
		)
		(fp_line
			(start 0.12065 -0.3048)
			(end 0.67945 -0.3048)
			(stroke
				(width 0.1)
				(type default)
			)
			(layer "F.Fab")
		)
		(fp_line
			(start 0.67945 -0.3048)
			(end 0.67945 0.3048)
			(stroke
				(width 0.1)
				(type default)
			)
			(layer "F.Fab")
		)
		(fp_line
			(start -0.67945 -0.305054)
			(end -0.12065 -0.305054)
			(stroke
				(width 0.1)
				(type default)
			)
			(layer "F.Fab")
		)
		(fp_line
			(start -0.12065 -0.305054)
			(end -0.12065 -0.2794)
			(stroke
				(width 0.1)
				(type default)
			)
			(layer "F.Fab")
		)
		(pad "1" smd circle
			(at -0.40005 0 270)
			(size 0 0)
			(layers "F.Cu" "F.Mask" "F.Paste")
			(net "PWRGD_P3V3_RGM_R")
		)
		(pad "2" smd circle
			(at 0.40005 0 270)
			(size 0 0)
			(layers "F.Cu" "F.Mask" "F.Paste")
			(net "PWRGD_P3V3_RGM_R3")
		)
	)
	(footprint ""
		(layer "F.Cu")
		(at 40.756078 -36.578286 90)
		(property "Reference" "R156"
			(at 0 0 90)
			(layer "F.SilkS")
			(hide yes)
			(effects
				(font
					(size 1.27 1.27)
				)
			)
		)
		(property "Value" ""
			(at 0 0 90)
			(layer "F.Fab")
			(effects
				(font
					(size 1.27 1.27)
				)
			)
		)
		(duplicate_pad_numbers_are_jumpers no)
		(fp_line
			(start 0.7874 -0.4064)
			(end 0.7874 0.4064)
			(stroke
				(width 0.1524)
				(type default)
			)
			(layer "F.SilkS")
		)
		(fp_line
			(start -0.7874 -0.4064)
			(end 0.7874 -0.4064)
			(stroke
				(width 0.1524)
				(type default)
			)
			(layer "F.SilkS")
		)
		(fp_line
			(start 0.7874 0.4064)
			(end -0.7874 0.4064)
			(stroke
				(width 0.1524)
				(type default)
			)
			(layer "F.SilkS")
		)
		(fp_line
			(start -0.7874 0.4064)
			(end -0.7874 -0.4064)
			(stroke
				(width 0.1524)
				(type default)
			)
			(layer "F.SilkS")
		)
		(fp_line
			(start -0.12065 -0.305054)
			(end -0.12065 -0.2794)
			(stroke
				(width 0.1)
				(type default)
			)
			(layer "F.Fab")
		)
		(fp_line
			(start -0.67945 -0.305054)
			(end -0.12065 -0.305054)
			(stroke
				(width 0.1)
				(type default)
			)
			(layer "F.Fab")
		)
		(fp_line
			(start 0.67945 -0.3048)
			(end 0.67945 0.3048)
			(stroke
				(width 0.1)
				(type default)
			)
			(layer "F.Fab")
		)
		(fp_line
			(start 0.12065 -0.3048)
			(end 0.67945 -0.3048)
			(stroke
				(width 0.1)
				(type default)
			)
			(layer "F.Fab")
		)
		(fp_line
			(start 0.12065 -0.2794)
			(end 0.12065 -0.3048)
			(stroke
				(width 0.1)
				(type default)
			)
			(layer "F.Fab")
		)
		(fp_line
			(start -0.12065 -0.2794)
			(end 0.12065 -0.2794)
			(stroke
				(width 0.1)
				(type default)
			)
			(layer "F.Fab")
		)
		(fp_line
			(start 0.120396 0.2794)
			(end -0.12065 0.2794)
			(stroke
				(width 0.1)
				(type default)
			)
			(layer "F.Fab")
		)
		(fp_line
			(start -0.12065 0.2794)
			(end -0.12065 0.3048)
			(stroke
				(width 0.1)
				(type default)
			)
			(layer "F.Fab")
		)
		(fp_line
			(start 0.67945 0.3048)
			(end 0.120396 0.3048)
			(stroke
				(width 0.1)
				(type default)
			)
			(layer "F.Fab")
		)
		(fp_line
			(start 0.120396 0.3048)
			(end 0.120396 0.2794)
			(stroke
				(width 0.1)
				(type default)
			)
			(layer "F.Fab")
		)
		(fp_line
			(start -0.12065 0.3048)
			(end -0.67945 0.3048)
			(stroke
				(width 0.1)
				(type default)
			)
			(layer "F.Fab")
		)
		(fp_line
			(start -0.67945 0.3048)
			(end -0.67945 -0.305054)
			(stroke
				(width 0.1)
				(type default)
			)
			(layer "F.Fab")
		)
		(pad "1" smd circle
			(at -0.40005 0 90)
			(size 0 0)
			(layers "F.Cu" "F.Mask" "F.Paste")
			(net "P2V5_AUX")
		)
		(pad "2" smd circle
			(at 0.40005 0 90)
			(size 0 0)
			(layers "F.Cu" "F.Mask" "F.Paste")
			(net "P3V3_P2V5_P1V8_RVDD")
		)
	)
	(footprint ""
		(layer "F.Cu")
		(at 33.528 -64.4398 180)
		(property "Reference" "C298"
			(at 0 0 180)
			(layer "F.SilkS")
			(hide yes)
			(effects
				(font
					(size 1.27 1.27)
				)
			)
		)
		(property "Value" ""
			(at 0 0 180)
			(layer "F.Fab")
			(effects
				(font
					(size 1.27 1.27)
				)
			)
		)
		(duplicate_pad_numbers_are_jumpers no)
		(fp_line
			(start 0.7874 0.4064)
			(end -0.7874 0.4064)
			(stroke
				(width 0.1524)
				(type default)
			)
			(layer "F.SilkS")
		)
		(fp_line
			(start 0.7874 -0.4064)
			(end 0.7874 0.4064)
			(stroke
				(width 0.1524)
				(type default)
			)
			(layer "F.SilkS")
		)
		(fp_line
			(start -0.7874 0.4064)
			(end -0.7874 -0.4064)
			(stroke
				(width 0.1524)
				(type default)
			)
			(layer "F.SilkS")
		)
		(fp_line
			(start -0.7874 -0.4064)
			(end 0.7874 -0.4064)
			(stroke
				(width 0.1524)
				(type default)
			)
			(layer "F.SilkS")
		)
		(fp_line
			(start 0.67945 0.3048)
			(end 0.120396 0.3048)
			(stroke
				(width 0.1)
				(type default)
			)
			(layer "F.Fab")
		)
		(fp_line
			(start 0.67945 -0.3048)
			(end 0.67945 0.3048)
			(stroke
				(width 0.1)
				(type default)
			)
			(layer "F.Fab")
		)
		(fp_line
			(start 0.12065 -0.2794)
			(end 0.12065 -0.3048)
			(stroke
				(width 0.1)
				(type default)
			)
			(layer "F.Fab")
		)
		(fp_line
			(start 0.12065 -0.3048)
			(end 0.67945 -0.3048)
			(stroke
				(width 0.1)
				(type default)
			)
			(layer "F.Fab")
		)
		(fp_line
			(start 0.120396 0.3048)
			(end 0.120396 0.2794)
			(stroke
				(width 0.1)
				(type default)
			)
			(layer "F.Fab")
		)
		(fp_line
			(start 0.120396 0.2794)
			(end -0.12065 0.2794)
			(stroke
				(width 0.1)
				(type default)
			)
			(layer "F.Fab")
		)
		(fp_line
			(start -0.12065 0.3048)
			(end -0.67945 0.3048)
			(stroke
				(width 0.1)
				(type default)
			)
			(layer "F.Fab")
		)
		(fp_line
			(start -0.12065 0.2794)
			(end -0.12065 0.3048)
			(stroke
				(width 0.1)
				(type default)
			)
			(layer "F.Fab")
		)
		(fp_line
			(start -0.12065 -0.2794)
			(end 0.12065 -0.2794)
			(stroke
				(width 0.1)
				(type default)
			)
			(layer "F.Fab")
		)
		(fp_line
			(start -0.12065 -0.305054)
			(end -0.12065 -0.2794)
			(stroke
				(width 0.1)
				(type default)
			)
			(layer "F.Fab")
		)
		(fp_line
			(start -0.67945 0.3048)
			(end -0.67945 -0.305054)
			(stroke
				(width 0.1)
				(type default)
			)
			(layer "F.Fab")
		)
		(fp_line
			(start -0.67945 -0.305054)
			(end -0.12065 -0.305054)
			(stroke
				(width 0.1)
				(type default)
			)
			(layer "F.Fab")
		)
		(pad "1" smd circle
			(at -0.40005 0 180)
			(size 0 0)
			(layers "F.Cu" "F.Mask" "F.Paste")
			(net "P3V3_LDO")
		)
		(pad "2" smd circle
			(at 0.40005 0 180)
			(size 0 0)
			(layers "F.Cu" "F.Mask" "F.Paste")
			(net "GND")
		)
	)
	(footprint ""
		(layer "F.Cu")
		(at 57.18302 -97.34804)
		(property "Reference" "R136"
			(at 0 0 0)
			(layer "F.SilkS")
			(hide yes)
			(effects
				(font
					(size 1.27 1.27)
				)
			)
		)
		(property "Value" ""
			(at 0 0 0)
			(layer "F.Fab")
			(effects
				(font
					(size 1.27 1.27)
				)
			)
		)
		(duplicate_pad_numbers_are_jumpers no)
		(fp_line
			(start -0.7874 -0.4064)
			(end 0.7874 -0.4064)
			(stroke
				(width 0.1524)
				(type default)
			)
			(layer "F.SilkS")
		)
		(fp_line
			(start -0.7874 0.4064)
			(end -0.7874 -0.4064)
			(stroke
				(width 0.1524)
				(type default)
			)
			(layer "F.SilkS")
		)
		(fp_line
			(start 0.7874 -0.4064)
			(end 0.7874 0.4064)
			(stroke
				(width 0.1524)
				(type default)
			)
			(layer "F.SilkS")
		)
		(fp_line
			(start 0.7874 0.4064)
			(end -0.7874 0.4064)
			(stroke
				(width 0.1524)
				(type default)
			)
			(layer "F.SilkS")
		)
		(fp_line
			(start -0.67945 -0.305054)
			(end -0.12065 -0.305054)
			(stroke
				(width 0.1)
				(type default)
			)
			(layer "F.Fab")
		)
		(fp_line
			(start -0.67945 0.3048)
			(end -0.67945 -0.305054)
			(stroke
				(width 0.1)
				(type default)
			)
			(layer "F.Fab")
		)
		(fp_line
			(start -0.12065 -0.305054)
			(end -0.12065 -0.2794)
			(stroke
				(width 0.1)
				(type default)
			)
			(layer "F.Fab")
		)
		(fp_line
			(start -0.12065 -0.2794)
			(end 0.12065 -0.2794)
			(stroke
				(width 0.1)
				(type default)
			)
			(layer "F.Fab")
		)
		(fp_line
			(start -0.12065 0.2794)
			(end -0.12065 0.3048)
			(stroke
				(width 0.1)
				(type default)
			)
			(layer "F.Fab")
		)
		(fp_line
			(start -0.12065 0.3048)
			(end -0.67945 0.3048)
			(stroke
				(width 0.1)
				(type default)
			)
			(layer "F.Fab")
		)
		(fp_line
			(start 0.120396 0.2794)
			(end -0.12065 0.2794)
			(stroke
				(width 0.1)
				(type default)
			)
			(layer "F.Fab")
		)
		(fp_line
			(start 0.120396 0.3048)
			(end 0.120396 0.2794)
			(stroke
				(width 0.1)
				(type default)
			)
			(layer "F.Fab")
		)
		(fp_line
			(start 0.12065 -0.3048)
			(end 0.67945 -0.3048)
			(stroke
				(width 0.1)
				(type default)
			)
			(layer "F.Fab")
		)
		(fp_line
			(start 0.12065 -0.2794)
			(end 0.12065 -0.3048)
			(stroke
				(width 0.1)
				(type default)
			)
			(layer "F.Fab")
		)
		(fp_line
			(start 0.67945 -0.3048)
			(end 0.67945 0.3048)
			(stroke
				(width 0.1)
				(type default)
			)
			(layer "F.Fab")
		)
		(fp_line
			(start 0.67945 0.3048)
			(end 0.120396 0.3048)
			(stroke
				(width 0.1)
				(type default)
			)
			(layer "F.Fab")
		)
		(pad "1" smd circle
			(at -0.40005 0)
			(size 0 0)
			(layers "F.Cu" "F.Mask" "F.Paste")
			(net "P3V3_AUX")
		)
		(pad "2" smd circle
			(at 0.40005 0)
			(size 0 0)
			(layers "F.Cu" "F.Mask" "F.Paste")
			(net "SMB_PCH_TPM_SCL")
		)
	)
	(footprint ""
		(layer "F.Cu")
		(at 43.171618 -65.776094 -90)
		(property "Reference" "R187"
			(at 0 0 270)
			(layer "F.SilkS")
			(hide yes)
			(effects
				(font
					(size 1.27 1.27)
				)
			)
		)
		(property "Value" ""
			(at 0 0 270)
			(layer "F.Fab")
			(effects
				(font
					(size 1.27 1.27)
				)
			)
		)
		(duplicate_pad_numbers_are_jumpers no)
		(fp_line
			(start -0.7874 0.4064)
			(end -0.7874 -0.4064)
			(stroke
				(width 0.1524)
				(type default)
			)
			(layer "F.SilkS")
		)
		(fp_line
			(start 0.7874 0.4064)
			(end -0.7874 0.4064)
			(stroke
				(width 0.1524)
				(type default)
			)
			(layer "F.SilkS")
		)
		(fp_line
			(start -0.7874 -0.4064)
			(end 0.7874 -0.4064)
			(stroke
				(width 0.1524)
				(type default)
			)
			(layer "F.SilkS")
		)
		(fp_line
			(start 0.7874 -0.4064)
			(end 0.7874 0.4064)
			(stroke
				(width 0.1524)
				(type default)
			)
			(layer "F.SilkS")
		)
		(fp_line
			(start -0.67945 0.3048)
			(end -0.67945 -0.305054)
			(stroke
				(width 0.1)
				(type default)
			)
			(layer "F.Fab")
		)
		(fp_line
			(start -0.12065 0.3048)
			(end -0.67945 0.3048)
			(stroke
				(width 0.1)
				(type default)
			)
			(layer "F.Fab")
		)
		(fp_line
			(start 0.120396 0.3048)
			(end 0.120396 0.2794)
			(stroke
				(width 0.1)
				(type default)
			)
			(layer "F.Fab")
		)
		(fp_line
			(start 0.67945 0.3048)
			(end 0.120396 0.3048)
			(stroke
				(width 0.1)
				(type default)
			)
			(layer "F.Fab")
		)
		(fp_line
			(start -0.12065 0.2794)
			(end -0.12065 0.3048)
			(stroke
				(width 0.1)
				(type default)
			)
			(layer "F.Fab")
		)
		(fp_line
			(start 0.120396 0.2794)
			(end -0.12065 0.2794)
			(stroke
				(width 0.1)
				(type default)
			)
			(layer "F.Fab")
		)
		(fp_line
			(start -0.12065 -0.2794)
			(end 0.12065 -0.2794)
			(stroke
				(width 0.1)
				(type default)
			)
			(layer "F.Fab")
		)
		(fp_line
			(start 0.12065 -0.2794)
			(end 0.12065 -0.3048)
			(stroke
				(width 0.1)
				(type default)
			)
			(layer "F.Fab")
		)
		(fp_line
			(start 0.12065 -0.3048)
			(end 0.67945 -0.3048)
			(stroke
				(width 0.1)
				(type default)
			)
			(layer "F.Fab")
		)
		(fp_line
			(start 0.67945 -0.3048)
			(end 0.67945 0.3048)
			(stroke
				(width 0.1)
				(type default)
			)
			(layer "F.Fab")
		)
		(fp_line
			(start -0.67945 -0.305054)
			(end -0.12065 -0.305054)
			(stroke
				(width 0.1)
				(type default)
			)
			(layer "F.Fab")
		)
		(fp_line
			(start -0.12065 -0.305054)
			(end -0.12065 -0.2794)
			(stroke
				(width 0.1)
				(type default)
			)
			(layer "F.Fab")
		)
		(pad "1" smd circle
			(at -0.40005 0 270)
			(size 0 0)
			(layers "F.Cu" "F.Mask" "F.Paste")
			(net "I3C2_SPD_SDA")
		)
		(pad "2" smd circle
			(at 0.40005 0 270)
			(size 0 0)
			(layers "F.Cu" "F.Mask" "F.Paste")
			(net "I3C2_SDA_R")
		)
	)
	(footprint ""
		(layer "F.Cu")
		(at 6.715252 -78.19009 90)
		(property "Reference" "PC227"
			(at 0 0 90)
			(layer "F.SilkS")
			(hide yes)
			(effects
				(font
					(size 1.27 1.27)
				)
			)
		)
		(property "Value" ""
			(at 0 0 90)
			(layer "F.Fab")
			(effects
				(font
					(size 1.27 1.27)
				)
			)
		)
		(duplicate_pad_numbers_are_jumpers no)
		(fp_line
			(start 1.651 -0.8382)
			(end 1.651 0.8382)
			(stroke
				(width 0.1524)
				(type default)
			)
			(layer "F.SilkS")
		)
		(fp_line
			(start -1.651 -0.8382)
			(end 1.651 -0.8382)
			(stroke
				(width 0.1524)
				(type default)
			)
			(layer "F.SilkS")
		)
		(fp_line
			(start 1.651 0.8382)
			(end -1.651 0.8382)
			(stroke
				(width 0.1524)
				(type default)
			)
			(layer "F.SilkS")
		)
		(fp_line
			(start 0 0.8382)
			(end 0 -0.8382)
			(stroke
				(width 0.1524)
				(type default)
			)
			(layer "F.SilkS")
		)
		(fp_line
			(start -1.651 0.8382)
			(end -1.651 -0.8382)
			(stroke
				(width 0.1524)
				(type default)
			)
			(layer "F.SilkS")
		)
		(fp_line
			(start 1.55956 -0.7366)
			(end 1.524 -0.7366)
			(stroke
				(width 0.1)
				(type default)
			)
			(layer "F.Fab")
		)
		(fp_line
			(start 1.524 -0.7366)
			(end -1.524 -0.7366)
			(stroke
				(width 0.1)
				(type default)
			)
			(layer "F.Fab")
		)
		(fp_line
			(start -1.524 -0.7366)
			(end -1.55956 -0.7366)
			(stroke
				(width 0.1)
				(type default)
			)
			(layer "F.Fab")
		)
		(fp_line
			(start -1.55956 -0.7366)
			(end -1.55956 0.7366)
			(stroke
				(width 0.1)
				(type default)
			)
			(layer "F.Fab")
		)
		(fp_line
			(start 1.55956 0.7366)
			(end 1.55956 -0.7366)
			(stroke
				(width 0.1)
				(type default)
			)
			(layer "F.Fab")
		)
		(fp_line
			(start 1.524 0.7366)
			(end 1.55956 0.7366)
			(stroke
				(width 0.1)
				(type default)
			)
			(layer "F.Fab")
		)
		(fp_line
			(start -1.524 0.7366)
			(end 1.524 0.7366)
			(stroke
				(width 0.1)
				(type default)
			)
			(layer "F.Fab")
		)
		(fp_line
			(start -1.55956 0.7366)
			(end -1.524 0.7366)
			(stroke
				(width 0.1)
				(type default)
			)
			(layer "F.Fab")
		)
		(pad "1" smd rect
			(at -0.94996 0 270)
			(size 1.1176 1.3716)
			(layers "F.Cu" "F.Mask" "F.Paste")
			(net "P3V3_AUX")
		)
		(pad "2" smd rect
			(at 0.94996 0 270)
			(size 1.1176 1.3716)
			(layers "F.Cu" "F.Mask" "F.Paste")
			(net "GND")
		)
	)
	(footprint ""
		(layer "F.Cu")
		(at 34.015172 -83.816952 90)
		(property "Reference" "R647"
			(at 0 0 90)
			(layer "F.SilkS")
			(hide yes)
			(effects
				(font
					(size 1.27 1.27)
				)
			)
		)
		(property "Value" ""
			(at 0 0 90)
			(layer "F.Fab")
			(effects
				(font
					(size 1.27 1.27)
				)
			)
		)
		(duplicate_pad_numbers_are_jumpers no)
		(fp_line
			(start 0.7874 -0.4064)
			(end 0.7874 0.4064)
			(stroke
				(width 0.1524)
				(type default)
			)
			(layer "F.SilkS")
		)
		(fp_line
			(start -0.7874 -0.4064)
			(end 0.7874 -0.4064)
			(stroke
				(width 0.1524)
				(type default)
			)
			(layer "F.SilkS")
		)
		(fp_line
			(start 0.7874 0.4064)
			(end -0.7874 0.4064)
			(stroke
				(width 0.1524)
				(type default)
			)
			(layer "F.SilkS")
		)
		(fp_line
			(start -0.7874 0.4064)
			(end -0.7874 -0.4064)
			(stroke
				(width 0.1524)
				(type default)
			)
			(layer "F.SilkS")
		)
		(fp_line
			(start -0.12065 -0.305054)
			(end -0.12065 -0.2794)
			(stroke
				(width 0.1)
				(type default)
			)
			(layer "F.Fab")
		)
		(fp_line
			(start -0.67945 -0.305054)
			(end -0.12065 -0.305054)
			(stroke
				(width 0.1)
				(type default)
			)
			(layer "F.Fab")
		)
		(fp_line
			(start 0.67945 -0.3048)
			(end 0.67945 0.3048)
			(stroke
				(width 0.1)
				(type default)
			)
			(layer "F.Fab")
		)
		(fp_line
			(start 0.12065 -0.3048)
			(end 0.67945 -0.3048)
			(stroke
				(width 0.1)
				(type default)
			)
			(layer "F.Fab")
		)
		(fp_line
			(start 0.12065 -0.2794)
			(end 0.12065 -0.3048)
			(stroke
				(width 0.1)
				(type default)
			)
			(layer "F.Fab")
		)
		(fp_line
			(start -0.12065 -0.2794)
			(end 0.12065 -0.2794)
			(stroke
				(width 0.1)
				(type default)
			)
			(layer "F.Fab")
		)
		(fp_line
			(start 0.120396 0.2794)
			(end -0.12065 0.2794)
			(stroke
				(width 0.1)
				(type default)
			)
			(layer "F.Fab")
		)
		(fp_line
			(start -0.12065 0.2794)
			(end -0.12065 0.3048)
			(stroke
				(width 0.1)
				(type default)
			)
			(layer "F.Fab")
		)
		(fp_line
			(start 0.67945 0.3048)
			(end 0.120396 0.3048)
			(stroke
				(width 0.1)
				(type default)
			)
			(layer "F.Fab")
		)
		(fp_line
			(start 0.120396 0.3048)
			(end 0.120396 0.2794)
			(stroke
				(width 0.1)
				(type default)
			)
			(layer "F.Fab")
		)
		(fp_line
			(start -0.12065 0.3048)
			(end -0.67945 0.3048)
			(stroke
				(width 0.1)
				(type default)
			)
			(layer "F.Fab")
		)
		(fp_line
			(start -0.67945 0.3048)
			(end -0.67945 -0.305054)
			(stroke
				(width 0.1)
				(type default)
			)
			(layer "F.Fab")
		)
		(pad "1" smd circle
			(at -0.40005 0 90)
			(size 0 0)
			(layers "F.Cu" "F.Mask" "F.Paste")
			(net "EMMC_DT2_R")
		)
		(pad "2" smd circle
			(at 0.40005 0 90)
			(size 0 0)
			(layers "F.Cu" "F.Mask" "F.Paste")
			(net "BMC_EMMC_DT2")
		)
	)
	(footprint ""
		(layer "F.Cu")
		(at 71.4375 -29.845 -90)
		(property "Reference" "R99"
			(at 0 0 270)
			(layer "F.SilkS")
			(hide yes)
			(effects
				(font
					(size 1.27 1.27)
				)
			)
		)
		(property "Value" ""
			(at 0 0 270)
			(layer "F.Fab")
			(effects
				(font
					(size 1.27 1.27)
				)
			)
		)
		(duplicate_pad_numbers_are_jumpers no)
		(fp_line
			(start -0.7874 0.4064)
			(end -0.7874 -0.4064)
			(stroke
				(width 0.1524)
				(type default)
			)
			(layer "F.SilkS")
		)
		(fp_line
			(start 0.7874 0.4064)
			(end -0.7874 0.4064)
			(stroke
				(width 0.1524)
				(type default)
			)
			(layer "F.SilkS")
		)
		(fp_line
			(start -0.7874 -0.4064)
			(end 0.7874 -0.4064)
			(stroke
				(width 0.1524)
				(type default)
			)
			(layer "F.SilkS")
		)
		(fp_line
			(start 0.7874 -0.4064)
			(end 0.7874 0.4064)
			(stroke
				(width 0.1524)
				(type default)
			)
			(layer "F.SilkS")
		)
		(fp_line
			(start -0.67945 0.3048)
			(end -0.67945 -0.305054)
			(stroke
				(width 0.1)
				(type default)
			)
			(layer "F.Fab")
		)
		(fp_line
			(start -0.12065 0.3048)
			(end -0.67945 0.3048)
			(stroke
				(width 0.1)
				(type default)
			)
			(layer "F.Fab")
		)
		(fp_line
			(start 0.120396 0.3048)
			(end 0.120396 0.2794)
			(stroke
				(width 0.1)
				(type default)
			)
			(layer "F.Fab")
		)
		(fp_line
			(start 0.67945 0.3048)
			(end 0.120396 0.3048)
			(stroke
				(width 0.1)
				(type default)
			)
			(layer "F.Fab")
		)
		(fp_line
			(start -0.12065 0.2794)
			(end -0.12065 0.3048)
			(stroke
				(width 0.1)
				(type default)
			)
			(layer "F.Fab")
		)
		(fp_line
			(start 0.120396 0.2794)
			(end -0.12065 0.2794)
			(stroke
				(width 0.1)
				(type default)
			)
			(layer "F.Fab")
		)
		(fp_line
			(start -0.12065 -0.2794)
			(end 0.12065 -0.2794)
			(stroke
				(width 0.1)
				(type default)
			)
			(layer "F.Fab")
		)
		(fp_line
			(start 0.12065 -0.2794)
			(end 0.12065 -0.3048)
			(stroke
				(width 0.1)
				(type default)
			)
			(layer "F.Fab")
		)
		(fp_line
			(start 0.12065 -0.3048)
			(end 0.67945 -0.3048)
			(stroke
				(width 0.1)
				(type default)
			)
			(layer "F.Fab")
		)
		(fp_line
			(start 0.67945 -0.3048)
			(end 0.67945 0.3048)
			(stroke
				(width 0.1)
				(type default)
			)
			(layer "F.Fab")
		)
		(fp_line
			(start -0.67945 -0.305054)
			(end -0.12065 -0.305054)
			(stroke
				(width 0.1)
				(type default)
			)
			(layer "F.Fab")
		)
		(fp_line
			(start -0.12065 -0.305054)
			(end -0.12065 -0.2794)
			(stroke
				(width 0.1)
				(type default)
			)
			(layer "F.Fab")
		)
		(pad "1" smd circle
			(at -0.40005 0 270)
			(size 0 0)
			(layers "F.Cu" "F.Mask" "F.Paste")
			(net "PWRGD_P3V3_RGM_R")
		)
		(pad "2" smd circle
			(at 0.40005 0 270)
			(size 0 0)
			(layers "F.Cu" "F.Mask" "F.Paste")
			(net "PWRGD_P3V3_RGM")
		)
	)
	(footprint ""
		(layer "F.Cu")
		(at 39.22776 -61.6585)
		(property "Reference" "R479"
			(at 0 0 0)
			(layer "F.SilkS")
			(hide yes)
			(effects
				(font
					(size 1.27 1.27)
				)
			)
		)
		(property "Value" ""
			(at 0 0 0)
			(layer "F.Fab")
			(effects
				(font
					(size 1.27 1.27)
				)
			)
		)
		(duplicate_pad_numbers_are_jumpers no)
		(fp_line
			(start -0.7874 -0.4064)
			(end 0.7874 -0.4064)
			(stroke
				(width 0.1524)
				(type default)
			)
			(layer "F.SilkS")
		)
		(fp_line
			(start -0.7874 0.4064)
			(end -0.7874 -0.4064)
			(stroke
				(width 0.1524)
				(type default)
			)
			(layer "F.SilkS")
		)
		(fp_line
			(start 0.7874 -0.4064)
			(end 0.7874 0.4064)
			(stroke
				(width 0.1524)
				(type default)
			)
			(layer "F.SilkS")
		)
		(fp_line
			(start 0.7874 0.4064)
			(end -0.7874 0.4064)
			(stroke
				(width 0.1524)
				(type default)
			)
			(layer "F.SilkS")
		)
		(fp_line
			(start -0.67945 -0.305054)
			(end -0.12065 -0.305054)
			(stroke
				(width 0.1)
				(type default)
			)
			(layer "F.Fab")
		)
		(fp_line
			(start -0.67945 0.3048)
			(end -0.67945 -0.305054)
			(stroke
				(width 0.1)
				(type default)
			)
			(layer "F.Fab")
		)
		(fp_line
			(start -0.12065 -0.305054)
			(end -0.12065 -0.2794)
			(stroke
				(width 0.1)
				(type default)
			)
			(layer "F.Fab")
		)
		(fp_line
			(start -0.12065 -0.2794)
			(end 0.12065 -0.2794)
			(stroke
				(width 0.1)
				(type default)
			)
			(layer "F.Fab")
		)
		(fp_line
			(start -0.12065 0.2794)
			(end -0.12065 0.3048)
			(stroke
				(width 0.1)
				(type default)
			)
			(layer "F.Fab")
		)
		(fp_line
			(start -0.12065 0.3048)
			(end -0.67945 0.3048)
			(stroke
				(width 0.1)
				(type default)
			)
			(layer "F.Fab")
		)
		(fp_line
			(start 0.120396 0.2794)
			(end -0.12065 0.2794)
			(stroke
				(width 0.1)
				(type default)
			)
			(layer "F.Fab")
		)
		(fp_line
			(start 0.120396 0.3048)
			(end 0.120396 0.2794)
			(stroke
				(width 0.1)
				(type default)
			)
			(layer "F.Fab")
		)
		(fp_line
			(start 0.12065 -0.3048)
			(end 0.67945 -0.3048)
			(stroke
				(width 0.1)
				(type default)
			)
			(layer "F.Fab")
		)
		(fp_line
			(start 0.12065 -0.2794)
			(end 0.12065 -0.3048)
			(stroke
				(width 0.1)
				(type default)
			)
			(layer "F.Fab")
		)
		(fp_line
			(start 0.67945 -0.3048)
			(end 0.67945 0.3048)
			(stroke
				(width 0.1)
				(type default)
			)
			(layer "F.Fab")
		)
		(fp_line
			(start 0.67945 0.3048)
			(end 0.120396 0.3048)
			(stroke
				(width 0.1)
				(type default)
			)
			(layer "F.Fab")
		)
		(pad "1" smd circle
			(at -0.40005 0)
			(size 0 0)
			(layers "F.Cu" "F.Mask" "F.Paste")
			(net "FM_P12V_HSC_ENABLE")
		)
		(pad "2" smd circle
			(at 0.40005 0)
			(size 0 0)
			(layers "F.Cu" "F.Mask" "F.Paste")
			(net "FM_P12V_HSC_ENABLE_R1")
		)
	)
	(footprint ""
		(layer "F.Cu")
		(at 33.782 -44.45 90)
		(property "Reference" "C264"
			(at 0 0 90)
			(layer "F.SilkS")
			(hide yes)
			(effects
				(font
					(size 1.27 1.27)
				)
			)
		)
		(property "Value" ""
			(at 0 0 90)
			(layer "F.Fab")
			(effects
				(font
					(size 1.27 1.27)
				)
			)
		)
		(duplicate_pad_numbers_are_jumpers no)
		(fp_line
			(start 0.7874 -0.4064)
			(end 0.7874 0.4064)
			(stroke
				(width 0.1524)
				(type default)
			)
			(layer "F.SilkS")
		)
		(fp_line
			(start -0.7874 -0.4064)
			(end 0.7874 -0.4064)
			(stroke
				(width 0.1524)
				(type default)
			)
			(layer "F.SilkS")
		)
		(fp_line
			(start 0.7874 0.4064)
			(end -0.7874 0.4064)
			(stroke
				(width 0.1524)
				(type default)
			)
			(layer "F.SilkS")
		)
		(fp_line
			(start -0.7874 0.4064)
			(end -0.7874 -0.4064)
			(stroke
				(width 0.1524)
				(type default)
			)
			(layer "F.SilkS")
		)
		(fp_line
			(start -0.12065 -0.305054)
			(end -0.12065 -0.2794)
			(stroke
				(width 0.1)
				(type default)
			)
			(layer "F.Fab")
		)
		(fp_line
			(start -0.67945 -0.305054)
			(end -0.12065 -0.305054)
			(stroke
				(width 0.1)
				(type default)
			)
			(layer "F.Fab")
		)
		(fp_line
			(start 0.67945 -0.3048)
			(end 0.67945 0.3048)
			(stroke
				(width 0.1)
				(type default)
			)
			(layer "F.Fab")
		)
		(fp_line
			(start 0.12065 -0.3048)
			(end 0.67945 -0.3048)
			(stroke
				(width 0.1)
				(type default)
			)
			(layer "F.Fab")
		)
		(fp_line
			(start 0.12065 -0.2794)
			(end 0.12065 -0.3048)
			(stroke
				(width 0.1)
				(type default)
			)
			(layer "F.Fab")
		)
		(fp_line
			(start -0.12065 -0.2794)
			(end 0.12065 -0.2794)
			(stroke
				(width 0.1)
				(type default)
			)
			(layer "F.Fab")
		)
		(fp_line
			(start 0.120396 0.2794)
			(end -0.12065 0.2794)
			(stroke
				(width 0.1)
				(type default)
			)
			(layer "F.Fab")
		)
		(fp_line
			(start -0.12065 0.2794)
			(end -0.12065 0.3048)
			(stroke
				(width 0.1)
				(type default)
			)
			(layer "F.Fab")
		)
		(fp_line
			(start 0.67945 0.3048)
			(end 0.120396 0.3048)
			(stroke
				(width 0.1)
				(type default)
			)
			(layer "F.Fab")
		)
		(fp_line
			(start 0.120396 0.3048)
			(end 0.120396 0.2794)
			(stroke
				(width 0.1)
				(type default)
			)
			(layer "F.Fab")
		)
		(fp_line
			(start -0.12065 0.3048)
			(end -0.67945 0.3048)
			(stroke
				(width 0.1)
				(type default)
			)
			(layer "F.Fab")
		)
		(fp_line
			(start -0.67945 0.3048)
			(end -0.67945 -0.305054)
			(stroke
				(width 0.1)
				(type default)
			)
			(layer "F.Fab")
		)
		(pad "1" smd circle
			(at -0.40005 0 90)
			(size 0 0)
			(layers "F.Cu" "F.Mask" "F.Paste")
			(net "U43_CT")
		)
		(pad "2" smd circle
			(at 0.40005 0 90)
			(size 0 0)
			(layers "F.Cu" "F.Mask" "F.Paste")
			(net "GND")
		)
	)
	(footprint ""
		(layer "F.Cu")
		(at 29.729938 -6.290056)
		(property "Reference" "D13"
			(at 1.512062 -2.624074 0)
			(unlocked yes)
			(layer "F.SilkS")
			(effects
				(font
					(size 0.7874 0.5842)
					(thickness 0.1524)
				)
				(justify left)
			)
		)
		(property "Value" ""
			(at 0 0 0)
			(layer "F.Fab")
			(effects
				(font
					(size 1.27 1.27)
				)
			)
		)
		(duplicate_pad_numbers_are_jumpers no)
		(fp_line
			(start -0.979932 -2.100072)
			(end 3.519932 -2.100072)
			(stroke
				(width 0.1524)
				(type default)
			)
			(layer "F.SilkS")
		)
		(fp_line
			(start -0.979932 3.899916)
			(end -0.979932 -2.100072)
			(stroke
				(width 0.1524)
				(type default)
			)
			(layer "F.SilkS")
		)
		(fp_line
			(start -0.130048 3.899916)
			(end -0.979932 3.899916)
			(stroke
				(width 0.1524)
				(type default)
			)
			(layer "F.SilkS")
		)
		(fp_line
			(start -0.130048 4.800092)
			(end -0.130048 3.899916)
			(stroke
				(width 0.1524)
				(type default)
			)
			(layer "F.SilkS")
		)
		(fp_line
			(start 2.670048 3.899916)
			(end 2.670048 4.800092)
			(stroke
				(width 0.1524)
				(type default)
			)
			(layer "F.SilkS")
		)
		(fp_line
			(start 3.519932 -2.100072)
			(end 3.519932 3.899916)
			(stroke
				(width 0.1524)
				(type default)
			)
			(layer "F.SilkS")
		)
		(fp_line
			(start 3.519932 3.899916)
			(end 2.670048 3.899916)
			(stroke
				(width 0.1524)
				(type default)
			)
			(layer "F.SilkS")
		)
		(fp_arc
			(start 1.27 6.199886)
			(mid 0.280106 5.789911)
			(end -0.130048 4.800092)
			(stroke
				(width 0.1524)
				(type default)
			)
			(layer "F.SilkS")
		)
		(fp_arc
			(start 2.670048 4.800092)
			(mid 2.259894 5.789911)
			(end 1.27 6.199886)
			(stroke
				(width 0.1524)
				(type default)
			)
			(layer "F.SilkS")
		)
		(fp_line
			(start -0.979932 -2.100072)
			(end 3.519932 -2.100072)
			(stroke
				(width 0.1)
				(type default)
			)
			(layer "F.Fab")
		)
		(fp_line
			(start -0.979932 3.899916)
			(end -0.979932 -2.100072)
			(stroke
				(width 0.1)
				(type default)
			)
			(layer "F.Fab")
		)
		(fp_line
			(start -0.130048 3.899916)
			(end -0.979932 3.899916)
			(stroke
				(width 0.1)
				(type default)
			)
			(layer "F.Fab")
		)
		(fp_line
			(start -0.130048 4.800092)
			(end -0.130048 3.899916)
			(stroke
				(width 0.1)
				(type default)
			)
			(layer "F.Fab")
		)
		(fp_line
			(start 2.670048 3.899916)
			(end 2.670048 4.800092)
			(stroke
				(width 0.1)
				(type default)
			)
			(layer "F.Fab")
		)
		(fp_line
			(start 3.519932 -2.100072)
			(end 3.519932 3.899916)
			(stroke
				(width 0.1)
				(type default)
			)
			(layer "F.Fab")
		)
		(fp_line
			(start 3.519932 3.899916)
			(end 2.670048 3.899916)
			(stroke
				(width 0.1)
				(type default)
			)
			(layer "F.Fab")
		)
		(fp_arc
			(start 1.27 6.199886)
			(mid 0.280106 5.789911)
			(end -0.130048 4.800092)
			(stroke
				(width 0.1)
				(type default)
			)
			(layer "F.Fab")
		)
		(fp_arc
			(start 2.670048 4.800092)
			(mid 2.259894 5.789911)
			(end 1.27 6.199886)
			(stroke
				(width 0.1)
				(type default)
			)
			(layer "F.Fab")
		)
		(pad "A" thru_hole rect
			(at 0 0)
			(size 1.2192 1.2192)
			(drill 0.8128)
			(layers "*.Cu" "*.Mask")
			(remove_unused_layers no)
			(net "ID_LED_P3V3_AUX")
			(clearance 0.0508)
			(thermal_gap 0.0508)
			(padstack
				(mode front_inner_back)
				(layer "Inner"
					(shape circle)
					(size 1.2192 1.2192)
					(clearance 0.0508)
				)
				(layer "B.Cu"
					(shape rect)
					(size 1.2192 1.2192)
					(clearance 0.0508)
				)
			)
		)
		(pad "C" thru_hole circle
			(at 2.54 0)
			(size 1.2192 1.2192)
			(drill 0.8128)
			(layers "*.Cu" "*.Mask")
			(remove_unused_layers no)
			(net "ID_LED_D_P3V3_AUX")
			(clearance 0.0508)
			(thermal_gap 0.0508)
		)
	)
	(footprint ""
		(layer "F.Cu")
		(at 23.34895 -30.631384 -90)
		(property "Reference" "PR541"
			(at 0 0 270)
			(layer "F.SilkS")
			(hide yes)
			(effects
				(font
					(size 1.27 1.27)
				)
			)
		)
		(property "Value" ""
			(at 0 0 270)
			(layer "F.Fab")
			(effects
				(font
					(size 1.27 1.27)
				)
			)
		)
		(duplicate_pad_numbers_are_jumpers no)
		(fp_line
			(start -0.7874 0.4064)
			(end -0.7874 -0.4064)
			(stroke
				(width 0.1524)
				(type default)
			)
			(layer "F.SilkS")
		)
		(fp_line
			(start 0.7874 0.4064)
			(end -0.7874 0.4064)
			(stroke
				(width 0.1524)
				(type default)
			)
			(layer "F.SilkS")
		)
		(fp_line
			(start -0.7874 -0.4064)
			(end 0.7874 -0.4064)
			(stroke
				(width 0.1524)
				(type default)
			)
			(layer "F.SilkS")
		)
		(fp_line
			(start 0.7874 -0.4064)
			(end 0.7874 0.4064)
			(stroke
				(width 0.1524)
				(type default)
			)
			(layer "F.SilkS")
		)
		(fp_line
			(start -0.67945 0.3048)
			(end -0.67945 -0.305054)
			(stroke
				(width 0.1)
				(type default)
			)
			(layer "F.Fab")
		)
		(fp_line
			(start -0.12065 0.3048)
			(end -0.67945 0.3048)
			(stroke
				(width 0.1)
				(type default)
			)
			(layer "F.Fab")
		)
		(fp_line
			(start 0.120396 0.3048)
			(end 0.120396 0.2794)
			(stroke
				(width 0.1)
				(type default)
			)
			(layer "F.Fab")
		)
		(fp_line
			(start 0.67945 0.3048)
			(end 0.120396 0.3048)
			(stroke
				(width 0.1)
				(type default)
			)
			(layer "F.Fab")
		)
		(fp_line
			(start -0.12065 0.2794)
			(end -0.12065 0.3048)
			(stroke
				(width 0.1)
				(type default)
			)
			(layer "F.Fab")
		)
		(fp_line
			(start 0.120396 0.2794)
			(end -0.12065 0.2794)
			(stroke
				(width 0.1)
				(type default)
			)
			(layer "F.Fab")
		)
		(fp_line
			(start -0.12065 -0.2794)
			(end 0.12065 -0.2794)
			(stroke
				(width 0.1)
				(type default)
			)
			(layer "F.Fab")
		)
		(fp_line
			(start 0.12065 -0.2794)
			(end 0.12065 -0.3048)
			(stroke
				(width 0.1)
				(type default)
			)
			(layer "F.Fab")
		)
		(fp_line
			(start 0.12065 -0.3048)
			(end 0.67945 -0.3048)
			(stroke
				(width 0.1)
				(type default)
			)
			(layer "F.Fab")
		)
		(fp_line
			(start 0.67945 -0.3048)
			(end 0.67945 0.3048)
			(stroke
				(width 0.1)
				(type default)
			)
			(layer "F.Fab")
		)
		(fp_line
			(start -0.67945 -0.305054)
			(end -0.12065 -0.305054)
			(stroke
				(width 0.1)
				(type default)
			)
			(layer "F.Fab")
		)
		(fp_line
			(start -0.12065 -0.305054)
			(end -0.12065 -0.2794)
			(stroke
				(width 0.1)
				(type default)
			)
			(layer "F.Fab")
		)
		(pad "1" smd circle
			(at -0.40005 0 270)
			(size 0 0)
			(layers "F.Cu" "F.Mask" "F.Paste")
			(net "PVCC2_AUX")
		)
		(pad "2" smd circle
			(at 0.40005 0 270)
			(size 0 0)
			(layers "F.Cu" "F.Mask" "F.Paste")
			(net "P1V0_AUX_VCC")
		)
	)
	(footprint ""
		(layer "F.Cu")
		(at 79.739744 -35.527488 90)
		(property "Reference" "R348"
			(at 0 0 90)
			(layer "F.SilkS")
			(hide yes)
			(effects
				(font
					(size 1.27 1.27)
				)
			)
		)
		(property "Value" ""
			(at 0 0 90)
			(layer "F.Fab")
			(effects
				(font
					(size 1.27 1.27)
				)
			)
		)
		(duplicate_pad_numbers_are_jumpers no)
		(fp_line
			(start 0.7874 -0.4064)
			(end 0.7874 0.4064)
			(stroke
				(width 0.1524)
				(type default)
			)
			(layer "F.SilkS")
		)
		(fp_line
			(start -0.7874 -0.4064)
			(end 0.7874 -0.4064)
			(stroke
				(width 0.1524)
				(type default)
			)
			(layer "F.SilkS")
		)
		(fp_line
			(start 0.7874 0.4064)
			(end -0.7874 0.4064)
			(stroke
				(width 0.1524)
				(type default)
			)
			(layer "F.SilkS")
		)
		(fp_line
			(start -0.7874 0.4064)
			(end -0.7874 -0.4064)
			(stroke
				(width 0.1524)
				(type default)
			)
			(layer "F.SilkS")
		)
		(fp_line
			(start -0.12065 -0.305054)
			(end -0.12065 -0.2794)
			(stroke
				(width 0.1)
				(type default)
			)
			(layer "F.Fab")
		)
		(fp_line
			(start -0.67945 -0.305054)
			(end -0.12065 -0.305054)
			(stroke
				(width 0.1)
				(type default)
			)
			(layer "F.Fab")
		)
		(fp_line
			(start 0.67945 -0.3048)
			(end 0.67945 0.3048)
			(stroke
				(width 0.1)
				(type default)
			)
			(layer "F.Fab")
		)
		(fp_line
			(start 0.12065 -0.3048)
			(end 0.67945 -0.3048)
			(stroke
				(width 0.1)
				(type default)
			)
			(layer "F.Fab")
		)
		(fp_line
			(start 0.12065 -0.2794)
			(end 0.12065 -0.3048)
			(stroke
				(width 0.1)
				(type default)
			)
			(layer "F.Fab")
		)
		(fp_line
			(start -0.12065 -0.2794)
			(end 0.12065 -0.2794)
			(stroke
				(width 0.1)
				(type default)
			)
			(layer "F.Fab")
		)
		(fp_line
			(start 0.120396 0.2794)
			(end -0.12065 0.2794)
			(stroke
				(width 0.1)
				(type default)
			)
			(layer "F.Fab")
		)
		(fp_line
			(start -0.12065 0.2794)
			(end -0.12065 0.3048)
			(stroke
				(width 0.1)
				(type default)
			)
			(layer "F.Fab")
		)
		(fp_line
			(start 0.67945 0.3048)
			(end 0.120396 0.3048)
			(stroke
				(width 0.1)
				(type default)
			)
			(layer "F.Fab")
		)
		(fp_line
			(start 0.120396 0.3048)
			(end 0.120396 0.2794)
			(stroke
				(width 0.1)
				(type default)
			)
			(layer "F.Fab")
		)
		(fp_line
			(start -0.12065 0.3048)
			(end -0.67945 0.3048)
			(stroke
				(width 0.1)
				(type default)
			)
			(layer "F.Fab")
		)
		(fp_line
			(start -0.67945 0.3048)
			(end -0.67945 -0.305054)
			(stroke
				(width 0.1)
				(type default)
			)
			(layer "F.Fab")
		)
		(pad "1" smd circle
			(at -0.40005 0 90)
			(size 0 0)
			(layers "F.Cu" "F.Mask" "F.Paste")
			(net "GND")
		)
		(pad "2" smd circle
			(at 0.40005 0 90)
			(size 0 0)
			(layers "F.Cu" "F.Mask" "F.Paste")
			(net "M_BMC_DDR4_MODT")
		)
	)
	(footprint ""
		(layer "F.Cu")
		(at 51.19116 -23.450804 180)
		(property "Reference" "U10"
			(at 1.97866 2.138426 0)
			(unlocked yes)
			(layer "F.SilkS")
			(effects
				(font
					(size 0.7874 0.5842)
					(thickness 0.1524)
				)
				(justify left)
			)
		)
		(property "Value" ""
			(at 0 0 180)
			(layer "F.Fab")
			(effects
				(font
					(size 1.27 1.27)
				)
			)
		)
		(duplicate_pad_numbers_are_jumpers no)
		(fp_line
			(start 1.738884 1.549908)
			(end 1.738884 -1.549908)
			(stroke
				(width 0.1524)
				(type default)
			)
			(layer "F.SilkS")
		)
		(fp_line
			(start 1.738884 -1.549908)
			(end 0.635508 -1.549908)
			(stroke
				(width 0.1524)
				(type default)
			)
			(layer "F.SilkS")
		)
		(fp_line
			(start 0.635508 -1.549908)
			(end 0 -0.9144)
			(stroke
				(width 0.1524)
				(type default)
			)
			(layer "F.SilkS")
		)
		(fp_line
			(start 0 -0.9144)
			(end -0.635508 -1.549908)
			(stroke
				(width 0.1524)
				(type default)
			)
			(layer "F.SilkS")
		)
		(fp_line
			(start -0.635508 -1.549908)
			(end -1.738884 -1.549908)
			(stroke
				(width 0.1524)
				(type default)
			)
			(layer "F.SilkS")
		)
		(fp_line
			(start -1.738884 1.549908)
			(end 1.738884 1.549908)
			(stroke
				(width 0.1524)
				(type default)
			)
			(layer "F.SilkS")
		)
		(fp_line
			(start -1.738884 -1.549908)
			(end -1.738884 1.549908)
			(stroke
				(width 0.1524)
				(type default)
			)
			(layer "F.SilkS")
		)
		(fp_poly
			(pts
				(xy -2.445766 -1.211326) (xy -1.923034 -0.94996) (xy -2.445766 -0.688594)
			)
			(stroke
				(width 0)
				(type default)
			)
			(fill yes)
			(layer "F.SilkS")
		)
		(fp_line
			(start 0.849884 1.549908)
			(end 0.849884 -1.549908)
			(stroke
				(width 0.1)
				(type default)
			)
			(layer "F.Fab")
		)
		(fp_line
			(start 0.849884 -1.549908)
			(end -0.849884 -1.549908)
			(stroke
				(width 0.1)
				(type default)
			)
			(layer "F.Fab")
		)
		(fp_line
			(start -0.849884 1.549908)
			(end 0.849884 1.549908)
			(stroke
				(width 0.1)
				(type default)
			)
			(layer "F.Fab")
		)
		(fp_line
			(start -0.849884 -1.549908)
			(end -0.849884 1.549908)
			(stroke
				(width 0.1)
				(type default)
			)
			(layer "F.Fab")
		)
		(fp_poly
			(pts
				(xy -2.445766 -1.211326) (xy -1.923034 -0.94996) (xy -2.445766 -0.688594)
			)
			(stroke
				(width 0)
				(type default)
			)
			(fill yes)
			(layer "F.Fab")
		)
		(pad "1" smd rect
			(at -1.124966 -0.94996 270)
			(size 0.6096 0.9652)
			(layers "F.Cu" "F.Mask" "F.Paste")
			(net "P5V_AUX")
		)
		(pad "2" smd rect
			(at -1.124966 0 270)
			(size 0.6096 0.9652)
			(layers "F.Cu" "F.Mask" "F.Paste")
			(net "GND")
		)
		(pad "3" smd rect
			(at -1.124966 0.94996 270)
			(size 0.6096 0.9652)
			(layers "F.Cu" "F.Mask" "F.Paste")
			(net "USB_OC0_EN")
		)
		(pad "4" smd rect
			(at 1.124966 0.94996 270)
			(size 0.6096 0.9652)
			(layers "F.Cu" "F.Mask" "F.Paste")
			(net "USB_OC0_REAR_N")
		)
		(pad "5" smd rect
			(at 1.124966 0 270)
			(size 0.6096 0.9652)
			(layers "F.Cu" "F.Mask" "F.Paste")
			(net "USB_OC0_ILIM")
		)
		(pad "6" smd rect
			(at 1.124966 -0.94996 270)
			(size 0.6096 0.9652)
			(layers "F.Cu" "F.Mask" "F.Paste")
			(net "P5V_USB_REAR")
		)
	)
	(footprint ""
		(layer "F.Cu")
		(at 55.9054 -21.4884 -90)
		(property "Reference" "C171"
			(at 0 0 270)
			(layer "F.SilkS")
			(hide yes)
			(effects
				(font
					(size 1.27 1.27)
				)
			)
		)
		(property "Value" ""
			(at 0 0 270)
			(layer "F.Fab")
			(effects
				(font
					(size 1.27 1.27)
				)
			)
		)
		(duplicate_pad_numbers_are_jumpers no)
		(fp_line
			(start -1.651 0.8382)
			(end -1.651 -0.8382)
			(stroke
				(width 0.1524)
				(type default)
			)
			(layer "F.SilkS")
		)
		(fp_line
			(start 0 0.8382)
			(end 0 -0.8382)
			(stroke
				(width 0.1524)
				(type default)
			)
			(layer "F.SilkS")
		)
		(fp_line
			(start 1.651 0.8382)
			(end -1.651 0.8382)
			(stroke
				(width 0.1524)
				(type default)
			)
			(layer "F.SilkS")
		)
		(fp_line
			(start -1.651 -0.8382)
			(end 1.651 -0.8382)
			(stroke
				(width 0.1524)
				(type default)
			)
			(layer "F.SilkS")
		)
		(fp_line
			(start 1.651 -0.8382)
			(end 1.651 0.8382)
			(stroke
				(width 0.1524)
				(type default)
			)
			(layer "F.SilkS")
		)
		(fp_line
			(start -1.55956 0.7366)
			(end -1.524 0.7366)
			(stroke
				(width 0.1)
				(type default)
			)
			(layer "F.Fab")
		)
		(fp_line
			(start -1.524 0.7366)
			(end 1.524 0.7366)
			(stroke
				(width 0.1)
				(type default)
			)
			(layer "F.Fab")
		)
		(fp_line
			(start 1.524 0.7366)
			(end 1.55956 0.7366)
			(stroke
				(width 0.1)
				(type default)
			)
			(layer "F.Fab")
		)
		(fp_line
			(start 1.55956 0.7366)
			(end 1.55956 -0.7366)
			(stroke
				(width 0.1)
				(type default)
			)
			(layer "F.Fab")
		)
		(fp_line
			(start -1.55956 -0.7366)
			(end -1.55956 0.7366)
			(stroke
				(width 0.1)
				(type default)
			)
			(layer "F.Fab")
		)
		(fp_line
			(start -1.524 -0.7366)
			(end -1.55956 -0.7366)
			(stroke
				(width 0.1)
				(type default)
			)
			(layer "F.Fab")
		)
		(fp_line
			(start 1.524 -0.7366)
			(end -1.524 -0.7366)
			(stroke
				(width 0.1)
				(type default)
			)
			(layer "F.Fab")
		)
		(fp_line
			(start 1.55956 -0.7366)
			(end 1.524 -0.7366)
			(stroke
				(width 0.1)
				(type default)
			)
			(layer "F.Fab")
		)
		(pad "1" smd rect
			(at -0.94996 0 90)
			(size 1.1176 1.3716)
			(layers "F.Cu" "F.Mask" "F.Paste")
			(net "P5V_AUX")
		)
		(pad "2" smd rect
			(at 0.94996 0 90)
			(size 1.1176 1.3716)
			(layers "F.Cu" "F.Mask" "F.Paste")
			(net "GND")
		)
	)
	(footprint ""
		(layer "F.Cu")
		(at 62.701932 -94.856046 180)
		(property "Reference" "J5"
			(at -3.414268 -4.217416 0)
			(unlocked yes)
			(layer "F.SilkS")
			(effects
				(font
					(size 0.7874 0.5842)
					(thickness 0.1524)
				)
				(justify left)
			)
		)
		(property "Value" ""
			(at 0 0 180)
			(layer "F.Fab")
			(effects
				(font
					(size 1.27 1.27)
				)
			)
		)
		(duplicate_pad_numbers_are_jumpers no)
		(fp_line
			(start 2.500122 5.150104)
			(end -2.500122 5.150104)
			(stroke
				(width 0.1524)
				(type default)
			)
			(layer "F.SilkS")
		)
		(fp_line
			(start 2.500122 5.08)
			(end 2.500122 5.150104)
			(stroke
				(width 0.1524)
				(type default)
			)
			(layer "F.SilkS")
		)
		(fp_line
			(start 2.500122 2.4384)
			(end 2.500122 3.3782)
			(stroke
				(width 0.1524)
				(type default)
			)
			(layer "F.SilkS")
		)
		(fp_line
			(start 2.500122 -3.3782)
			(end 2.500122 -2.4384)
			(stroke
				(width 0.1524)
				(type default)
			)
			(layer "F.SilkS")
		)
		(fp_line
			(start 2.500122 -5.150104)
			(end 2.500122 -5.08)
			(stroke
				(width 0.1524)
				(type default)
			)
			(layer "F.SilkS")
		)
		(fp_line
			(start -2.500122 5.150104)
			(end -2.500122 5.08)
			(stroke
				(width 0.1524)
				(type default)
			)
			(layer "F.SilkS")
		)
		(fp_line
			(start -2.500122 3.3782)
			(end -2.500122 2.9464)
			(stroke
				(width 0.1524)
				(type default)
			)
			(layer "F.SilkS")
		)
		(fp_line
			(start -2.500122 -2.9464)
			(end -2.500122 -3.3782)
			(stroke
				(width 0.1524)
				(type default)
			)
			(layer "F.SilkS")
		)
		(fp_line
			(start -2.500122 -5.08)
			(end -2.500122 -5.150104)
			(stroke
				(width 0.1524)
				(type default)
			)
			(layer "F.SilkS")
		)
		(fp_line
			(start -2.500122 -5.150104)
			(end 2.500122 -5.150104)
			(stroke
				(width 0.1524)
				(type default)
			)
			(layer "F.SilkS")
		)
		(fp_poly
			(pts
				(xy -4.0894 -1.992122) (xy -4.0894 -3.008122) (xy -3.0734 -2.500122)
			)
			(stroke
				(width 0)
				(type default)
			)
			(fill yes)
			(layer "F.SilkS")
		)
		(fp_line
			(start 2.500122 5.150104)
			(end 2.500122 -5.150104)
			(stroke
				(width 0.1)
				(type default)
			)
			(layer "F.Fab")
		)
		(fp_line
			(start 2.500122 -5.150104)
			(end -2.500122 -5.150104)
			(stroke
				(width 0.1)
				(type default)
			)
			(layer "F.Fab")
		)
		(fp_line
			(start -2.500122 5.150104)
			(end 2.500122 5.150104)
			(stroke
				(width 0.1)
				(type default)
			)
			(layer "F.Fab")
		)
		(fp_line
			(start -2.500122 -5.150104)
			(end -2.500122 5.150104)
			(stroke
				(width 0.1)
				(type default)
			)
			(layer "F.Fab")
		)
		(fp_poly
			(pts
				(xy -4.0894 -1.992122) (xy -4.0894 -3.008122) (xy -3.0734 -2.500122)
			)
			(stroke
				(width 0)
				(type default)
			)
			(fill yes)
			(layer "F.Fab")
		)
		(fp_text user "11"
			(at 4.002532 3.224784 0)
			(unlocked yes)
			(layer "F.SilkS")
			(effects
				(font
					(size 0.7874 0.5842)
					(thickness 0.1524)
				)
			)
		)
		(fp_text user "7"
			(at 3.646932 -2.134616 0)
			(unlocked yes)
			(layer "F.SilkS")
			(effects
				(font
					(size 0.7874 0.5842)
					(thickness 0.1524)
				)
			)
		)
		(fp_text user "6"
			(at -3.592068 2.668524 180)
			(unlocked yes)
			(layer "F.SilkS")
			(effects
				(font
					(size 0.7874 0.5842)
					(thickness 0.1524)
				)
			)
		)
		(fp_text user "7"
			(at 3.520948 -2.048002 90)
			(unlocked yes)
			(layer "F.Fab")
			(effects
				(font
					(size 0.7874 0.5842)
					(thickness 0.1524)
				)
			)
		)
		(fp_text user "11"
			(at 3.495548 2.028444 90)
			(unlocked yes)
			(layer "F.Fab")
			(effects
				(font
					(size 0.7874 0.5842)
					(thickness 0.1524)
				)
			)
		)
		(fp_text user "6"
			(at -3.591052 2.574798 90)
			(unlocked yes)
			(layer "F.Fab")
			(effects
				(font
					(size 0.7874 0.5842)
					(thickness 0.1524)
				)
			)
		)
		(pad "1" smd rect
			(at -2.109978 -2.500122 270)
			(size 0.6096 1.651)
			(layers "F.Cu" "F.Mask" "F.Paste")
			(net "SPI_SYS_R1_CLK")
		)
		(pad "2" smd rect
			(at -2.109978 -1.500124 270)
			(size 0.6096 1.651)
			(layers "F.Cu" "F.Mask" "F.Paste")
			(net "RST_PLTRST_TPM_N")
		)
		(pad "3" smd rect
			(at -2.109978 -0.499872 270)
			(size 0.6096 1.651)
			(layers "F.Cu" "F.Mask" "F.Paste")
			(net "SPI_SYS_R1_MOSI")
		)
		(pad "4" smd rect
			(at -2.109978 0.499872 270)
			(size 0.6096 1.651)
			(layers "F.Cu" "F.Mask" "F.Paste")
			(net "SPI_SYS_R1_MISO")
		)
		(pad "5" smd rect
			(at -2.109978 1.500124 270)
			(size 0.6096 1.651)
			(layers "F.Cu" "F.Mask" "F.Paste")
			(net "SPI_TPM_CS_N_R")
		)
		(pad "6" smd rect
			(at -2.109978 2.500122 270)
			(size 0.6096 1.651)
			(layers "F.Cu" "F.Mask" "F.Paste")
			(net "SMB_PCH_TPM_SDA")
		)
		(pad "7" smd rect
			(at 2.109978 -1.999996 90)
			(size 0.6096 1.651)
			(layers "F.Cu" "F.Mask" "F.Paste")
			(net "P3V3_AUX")
		)
		(pad "8" smd rect
			(at 2.109978 -0.999998 90)
			(size 0.6096 1.651)
			(layers "F.Cu" "F.Mask" "F.Paste")
			(net "FM_TPM_PRSNT_0_N")
		)
		(pad "9" smd rect
			(at 2.109978 0 90)
			(size 0.6096 1.651)
			(layers "F.Cu" "F.Mask" "F.Paste")
			(net "IRQ_PCH_TPM_SPI_R_N")
		)
		(pad "10" smd rect
			(at 2.109978 0.999998 90)
			(size 0.6096 1.651)
			(layers "F.Cu" "F.Mask" "F.Paste")
			(net "SMB_PCH_TPM_SCL")
		)
		(pad "11" smd rect
			(at 2.109978 1.999996 90)
			(size 0.6096 1.651)
			(layers "F.Cu" "F.Mask" "F.Paste")
			(net "GND")
		)
		(pad "G1" smd rect
			(at 0 -4.219956 270)
			(size 1.4224 5.8674)
			(layers "F.Cu" "F.Mask" "F.Paste")
			(net "GND")
		)
		(pad "G2" smd rect
			(at 0 4.219956 90)
			(size 1.4224 5.8674)
			(layers "F.Cu" "F.Mask" "F.Paste")
			(net "GND")
		)
	)
	(footprint ""
		(layer "F.Cu")
		(at 9.2202 -67.183 180)
		(property "Reference" "R415"
			(at 0 0 180)
			(layer "F.SilkS")
			(hide yes)
			(effects
				(font
					(size 1.27 1.27)
				)
			)
		)
		(property "Value" ""
			(at 0 0 180)
			(layer "F.Fab")
			(effects
				(font
					(size 1.27 1.27)
				)
			)
		)
		(duplicate_pad_numbers_are_jumpers no)
		(fp_line
			(start 0.7874 0.4064)
			(end -0.7874 0.4064)
			(stroke
				(width 0.1524)
				(type default)
			)
			(layer "F.SilkS")
		)
		(fp_line
			(start 0.7874 -0.4064)
			(end 0.7874 0.4064)
			(stroke
				(width 0.1524)
				(type default)
			)
			(layer "F.SilkS")
		)
		(fp_line
			(start -0.7874 0.4064)
			(end -0.7874 -0.4064)
			(stroke
				(width 0.1524)
				(type default)
			)
			(layer "F.SilkS")
		)
		(fp_line
			(start -0.7874 -0.4064)
			(end 0.7874 -0.4064)
			(stroke
				(width 0.1524)
				(type default)
			)
			(layer "F.SilkS")
		)
		(fp_line
			(start 0.67945 0.3048)
			(end 0.120396 0.3048)
			(stroke
				(width 0.1)
				(type default)
			)
			(layer "F.Fab")
		)
		(fp_line
			(start 0.67945 -0.3048)
			(end 0.67945 0.3048)
			(stroke
				(width 0.1)
				(type default)
			)
			(layer "F.Fab")
		)
		(fp_line
			(start 0.12065 -0.2794)
			(end 0.12065 -0.3048)
			(stroke
				(width 0.1)
				(type default)
			)
			(layer "F.Fab")
		)
		(fp_line
			(start 0.12065 -0.3048)
			(end 0.67945 -0.3048)
			(stroke
				(width 0.1)
				(type default)
			)
			(layer "F.Fab")
		)
		(fp_line
			(start 0.120396 0.3048)
			(end 0.120396 0.2794)
			(stroke
				(width 0.1)
				(type default)
			)
			(layer "F.Fab")
		)
		(fp_line
			(start 0.120396 0.2794)
			(end -0.12065 0.2794)
			(stroke
				(width 0.1)
				(type default)
			)
			(layer "F.Fab")
		)
		(fp_line
			(start -0.12065 0.3048)
			(end -0.67945 0.3048)
			(stroke
				(width 0.1)
				(type default)
			)
			(layer "F.Fab")
		)
		(fp_line
			(start -0.12065 0.2794)
			(end -0.12065 0.3048)
			(stroke
				(width 0.1)
				(type default)
			)
			(layer "F.Fab")
		)
		(fp_line
			(start -0.12065 -0.2794)
			(end 0.12065 -0.2794)
			(stroke
				(width 0.1)
				(type default)
			)
			(layer "F.Fab")
		)
		(fp_line
			(start -0.12065 -0.305054)
			(end -0.12065 -0.2794)
			(stroke
				(width 0.1)
				(type default)
			)
			(layer "F.Fab")
		)
		(fp_line
			(start -0.67945 0.3048)
			(end -0.67945 -0.305054)
			(stroke
				(width 0.1)
				(type default)
			)
			(layer "F.Fab")
		)
		(fp_line
			(start -0.67945 -0.305054)
			(end -0.12065 -0.305054)
			(stroke
				(width 0.1)
				(type default)
			)
			(layer "F.Fab")
		)
		(pad "1" smd circle
			(at -0.40005 0 180)
			(size 0 0)
			(layers "F.Cu" "F.Mask" "F.Paste")
			(net "SW_P3V3_AUX_BST_R")
		)
		(pad "2" smd circle
			(at 0.40005 0 180)
			(size 0 0)
			(layers "F.Cu" "F.Mask" "F.Paste")
			(net "SW_P3V3_AUX_BST")
		)
	)
	(footprint ""
		(layer "F.Cu")
		(at 70.370446 -33.033716 90)
		(property "Reference" "C251"
			(at 0 0 90)
			(layer "F.SilkS")
			(hide yes)
			(effects
				(font
					(size 1.27 1.27)
				)
			)
		)
		(property "Value" ""
			(at 0 0 90)
			(layer "F.Fab")
			(effects
				(font
					(size 1.27 1.27)
				)
			)
		)
		(duplicate_pad_numbers_are_jumpers no)
		(fp_line
			(start 0.7874 -0.4064)
			(end 0.7874 0.4064)
			(stroke
				(width 0.1524)
				(type default)
			)
			(layer "F.SilkS")
		)
		(fp_line
			(start -0.7874 -0.4064)
			(end 0.7874 -0.4064)
			(stroke
				(width 0.1524)
				(type default)
			)
			(layer "F.SilkS")
		)
		(fp_line
			(start 0.7874 0.4064)
			(end -0.7874 0.4064)
			(stroke
				(width 0.1524)
				(type default)
			)
			(layer "F.SilkS")
		)
		(fp_line
			(start -0.7874 0.4064)
			(end -0.7874 -0.4064)
			(stroke
				(width 0.1524)
				(type default)
			)
			(layer "F.SilkS")
		)
		(fp_line
			(start -0.12065 -0.305054)
			(end -0.12065 -0.2794)
			(stroke
				(width 0.1)
				(type default)
			)
			(layer "F.Fab")
		)
		(fp_line
			(start -0.67945 -0.305054)
			(end -0.12065 -0.305054)
			(stroke
				(width 0.1)
				(type default)
			)
			(layer "F.Fab")
		)
		(fp_line
			(start 0.67945 -0.3048)
			(end 0.67945 0.3048)
			(stroke
				(width 0.1)
				(type default)
			)
			(layer "F.Fab")
		)
		(fp_line
			(start 0.12065 -0.3048)
			(end 0.67945 -0.3048)
			(stroke
				(width 0.1)
				(type default)
			)
			(layer "F.Fab")
		)
		(fp_line
			(start 0.12065 -0.2794)
			(end 0.12065 -0.3048)
			(stroke
				(width 0.1)
				(type default)
			)
			(layer "F.Fab")
		)
		(fp_line
			(start -0.12065 -0.2794)
			(end 0.12065 -0.2794)
			(stroke
				(width 0.1)
				(type default)
			)
			(layer "F.Fab")
		)
		(fp_line
			(start 0.120396 0.2794)
			(end -0.12065 0.2794)
			(stroke
				(width 0.1)
				(type default)
			)
			(layer "F.Fab")
		)
		(fp_line
			(start -0.12065 0.2794)
			(end -0.12065 0.3048)
			(stroke
				(width 0.1)
				(type default)
			)
			(layer "F.Fab")
		)
		(fp_line
			(start 0.67945 0.3048)
			(end 0.120396 0.3048)
			(stroke
				(width 0.1)
				(type default)
			)
			(layer "F.Fab")
		)
		(fp_line
			(start 0.120396 0.3048)
			(end 0.120396 0.2794)
			(stroke
				(width 0.1)
				(type default)
			)
			(layer "F.Fab")
		)
		(fp_line
			(start -0.12065 0.3048)
			(end -0.67945 0.3048)
			(stroke
				(width 0.1)
				(type default)
			)
			(layer "F.Fab")
		)
		(fp_line
			(start -0.67945 0.3048)
			(end -0.67945 -0.305054)
			(stroke
				(width 0.1)
				(type default)
			)
			(layer "F.Fab")
		)
		(pad "1" smd circle
			(at -0.40005 0 90)
			(size 0 0)
			(layers "F.Cu" "F.Mask" "F.Paste")
			(net "P3V3_RGM")
		)
		(pad "2" smd circle
			(at 0.40005 0 90)
			(size 0 0)
			(layers "F.Cu" "F.Mask" "F.Paste")
			(net "GND")
		)
	)
	(footprint ""
		(layer "F.Cu")
		(at 29.2608 -28.5242)
		(property "Reference" "L28"
			(at 0 0 0)
			(layer "F.SilkS")
			(hide yes)
			(effects
				(font
					(size 1.27 1.27)
				)
			)
		)
		(property "Value" ""
			(at 0 0 0)
			(layer "F.Fab")
			(effects
				(font
					(size 1.27 1.27)
				)
			)
		)
		(duplicate_pad_numbers_are_jumpers no)
		(fp_line
			(start -1.27 -0.5842)
			(end 1.27 -0.5842)
			(stroke
				(width 0.1524)
				(type default)
			)
			(layer "F.SilkS")
		)
		(fp_line
			(start -1.27 -0.5588)
			(end -1.27 -0.5842)
			(stroke
				(width 0.1524)
				(type default)
			)
			(layer "F.SilkS")
		)
		(fp_line
			(start -1.27 0.5842)
			(end -1.27 -0.5842)
			(stroke
				(width 0.1524)
				(type default)
			)
			(layer "F.SilkS")
		)
		(fp_line
			(start -0.127 0.5842)
			(end -0.127 -0.5842)
			(stroke
				(width 0.1524)
				(type default)
			)
			(layer "F.SilkS")
		)
		(fp_line
			(start 0.127 0.5842)
			(end 0.127 -0.5842)
			(stroke
				(width 0.1524)
				(type default)
			)
			(layer "F.SilkS")
		)
		(fp_line
			(start 1.27 0.5842)
			(end -1.27 0.5842)
			(stroke
				(width 0.1524)
				(type default)
			)
			(layer "F.SilkS")
		)
		(fp_line
			(start 1.27 0.5842)
			(end 1.27 -0.5842)
			(stroke
				(width 0.1524)
				(type default)
			)
			(layer "F.SilkS")
		)
		(fp_line
			(start -1.194308 -0.406654)
			(end -0.9144 -0.406654)
			(stroke
				(width 0.1)
				(type default)
			)
			(layer "F.Fab")
		)
		(fp_line
			(start -1.194308 0.406654)
			(end -1.194308 -0.406654)
			(stroke
				(width 0.1)
				(type default)
			)
			(layer "F.Fab")
		)
		(fp_line
			(start -0.9144 -0.508)
			(end 0.9144 -0.508)
			(stroke
				(width 0.1)
				(type default)
			)
			(layer "F.Fab")
		)
		(fp_line
			(start -0.9144 -0.406654)
			(end -0.9144 -0.508)
			(stroke
				(width 0.1)
				(type default)
			)
			(layer "F.Fab")
		)
		(fp_line
			(start -0.9144 0.406654)
			(end -1.194308 0.406654)
			(stroke
				(width 0.1)
				(type default)
			)
			(layer "F.Fab")
		)
		(fp_line
			(start -0.9144 0.508)
			(end -0.9144 0.406654)
			(stroke
				(width 0.1)
				(type default)
			)
			(layer "F.Fab")
		)
		(fp_line
			(start 0.9144 -0.508)
			(end 0.9144 -0.406654)
			(stroke
				(width 0.1)
				(type default)
			)
			(layer "F.Fab")
		)
		(fp_line
			(start 0.9144 -0.406654)
			(end 1.1938 -0.406654)
			(stroke
				(width 0.1)
				(type default)
			)
			(layer "F.Fab")
		)
		(fp_line
			(start 0.9144 0.4064)
			(end 0.9144 0.508)
			(stroke
				(width 0.1)
				(type default)
			)
			(layer "F.Fab")
		)
		(fp_line
			(start 0.9144 0.508)
			(end -0.9144 0.508)
			(stroke
				(width 0.1)
				(type default)
			)
			(layer "F.Fab")
		)
		(fp_line
			(start 1.1938 -0.406654)
			(end 1.1938 0.4064)
			(stroke
				(width 0.1)
				(type default)
			)
			(layer "F.Fab")
		)
		(fp_line
			(start 1.1938 0.4064)
			(end 0.9144 0.4064)
			(stroke
				(width 0.1)
				(type default)
			)
			(layer "F.Fab")
		)
		(pad "1" smd rect
			(at -0.7366 0 270)
			(size 0.7112 0.8128)
			(layers "F.Cu" "F.Mask" "F.Paste")
			(net "V_DACB")
		)
		(pad "2" smd rect
			(at 0.7366 0 270)
			(size 0.7112 0.8128)
			(layers "F.Cu" "F.Mask" "F.Paste")
			(net "V_DACB_IO")
		)
	)
	(footprint ""
		(layer "F.Cu")
		(at 35.052 -53.213 -90)
		(property "Reference" "C292"
			(at 0 0 270)
			(layer "F.SilkS")
			(hide yes)
			(effects
				(font
					(size 1.27 1.27)
				)
			)
		)
		(property "Value" ""
			(at 0 0 270)
			(layer "F.Fab")
			(effects
				(font
					(size 1.27 1.27)
				)
			)
		)
		(duplicate_pad_numbers_are_jumpers no)
		(fp_line
			(start -0.7874 0.4064)
			(end -0.7874 -0.4064)
			(stroke
				(width 0.1524)
				(type default)
			)
			(layer "F.SilkS")
		)
		(fp_line
			(start 0.7874 0.4064)
			(end -0.7874 0.4064)
			(stroke
				(width 0.1524)
				(type default)
			)
			(layer "F.SilkS")
		)
		(fp_line
			(start -0.7874 -0.4064)
			(end 0.7874 -0.4064)
			(stroke
				(width 0.1524)
				(type default)
			)
			(layer "F.SilkS")
		)
		(fp_line
			(start 0.7874 -0.4064)
			(end 0.7874 0.4064)
			(stroke
				(width 0.1524)
				(type default)
			)
			(layer "F.SilkS")
		)
		(fp_line
			(start -0.67945 0.3048)
			(end -0.67945 -0.305054)
			(stroke
				(width 0.1)
				(type default)
			)
			(layer "F.Fab")
		)
		(fp_line
			(start -0.12065 0.3048)
			(end -0.67945 0.3048)
			(stroke
				(width 0.1)
				(type default)
			)
			(layer "F.Fab")
		)
		(fp_line
			(start 0.120396 0.3048)
			(end 0.120396 0.2794)
			(stroke
				(width 0.1)
				(type default)
			)
			(layer "F.Fab")
		)
		(fp_line
			(start 0.67945 0.3048)
			(end 0.120396 0.3048)
			(stroke
				(width 0.1)
				(type default)
			)
			(layer "F.Fab")
		)
		(fp_line
			(start -0.12065 0.2794)
			(end -0.12065 0.3048)
			(stroke
				(width 0.1)
				(type default)
			)
			(layer "F.Fab")
		)
		(fp_line
			(start 0.120396 0.2794)
			(end -0.12065 0.2794)
			(stroke
				(width 0.1)
				(type default)
			)
			(layer "F.Fab")
		)
		(fp_line
			(start -0.12065 -0.2794)
			(end 0.12065 -0.2794)
			(stroke
				(width 0.1)
				(type default)
			)
			(layer "F.Fab")
		)
		(fp_line
			(start 0.12065 -0.2794)
			(end 0.12065 -0.3048)
			(stroke
				(width 0.1)
				(type default)
			)
			(layer "F.Fab")
		)
		(fp_line
			(start 0.12065 -0.3048)
			(end 0.67945 -0.3048)
			(stroke
				(width 0.1)
				(type default)
			)
			(layer "F.Fab")
		)
		(fp_line
			(start 0.67945 -0.3048)
			(end 0.67945 0.3048)
			(stroke
				(width 0.1)
				(type default)
			)
			(layer "F.Fab")
		)
		(fp_line
			(start -0.67945 -0.305054)
			(end -0.12065 -0.305054)
			(stroke
				(width 0.1)
				(type default)
			)
			(layer "F.Fab")
		)
		(fp_line
			(start -0.12065 -0.305054)
			(end -0.12065 -0.2794)
			(stroke
				(width 0.1)
				(type default)
			)
			(layer "F.Fab")
		)
		(pad "1" smd circle
			(at -0.40005 0 270)
			(size 0 0)
			(layers "F.Cu" "F.Mask" "F.Paste")
			(net "P5V_AUX")
		)
		(pad "2" smd circle
			(at 0.40005 0 270)
			(size 0 0)
			(layers "F.Cu" "F.Mask" "F.Paste")
			(net "GND")
		)
	)
	(footprint ""
		(layer "F.Cu")
		(at 54.7878 -109.3978 -90)
		(property "Reference" "R860"
			(at 0 0 270)
			(layer "F.SilkS")
			(hide yes)
			(effects
				(font
					(size 1.27 1.27)
				)
			)
		)
		(property "Value" ""
			(at 0 0 270)
			(layer "F.Fab")
			(effects
				(font
					(size 1.27 1.27)
				)
			)
		)
		(duplicate_pad_numbers_are_jumpers no)
		(fp_line
			(start -0.7874 0.4064)
			(end -0.7874 -0.4064)
			(stroke
				(width 0.1524)
				(type default)
			)
			(layer "F.SilkS")
		)
		(fp_line
			(start 0.7874 0.4064)
			(end -0.7874 0.4064)
			(stroke
				(width 0.1524)
				(type default)
			)
			(layer "F.SilkS")
		)
		(fp_line
			(start -0.7874 -0.4064)
			(end 0.7874 -0.4064)
			(stroke
				(width 0.1524)
				(type default)
			)
			(layer "F.SilkS")
		)
		(fp_line
			(start 0.7874 -0.4064)
			(end 0.7874 0.4064)
			(stroke
				(width 0.1524)
				(type default)
			)
			(layer "F.SilkS")
		)
		(fp_line
			(start -0.67945 0.3048)
			(end -0.67945 -0.305054)
			(stroke
				(width 0.1)
				(type default)
			)
			(layer "F.Fab")
		)
		(fp_line
			(start -0.12065 0.3048)
			(end -0.67945 0.3048)
			(stroke
				(width 0.1)
				(type default)
			)
			(layer "F.Fab")
		)
		(fp_line
			(start 0.120396 0.3048)
			(end 0.120396 0.2794)
			(stroke
				(width 0.1)
				(type default)
			)
			(layer "F.Fab")
		)
		(fp_line
			(start 0.67945 0.3048)
			(end 0.120396 0.3048)
			(stroke
				(width 0.1)
				(type default)
			)
			(layer "F.Fab")
		)
		(fp_line
			(start -0.12065 0.2794)
			(end -0.12065 0.3048)
			(stroke
				(width 0.1)
				(type default)
			)
			(layer "F.Fab")
		)
		(fp_line
			(start 0.120396 0.2794)
			(end -0.12065 0.2794)
			(stroke
				(width 0.1)
				(type default)
			)
			(layer "F.Fab")
		)
		(fp_line
			(start -0.12065 -0.2794)
			(end 0.12065 -0.2794)
			(stroke
				(width 0.1)
				(type default)
			)
			(layer "F.Fab")
		)
		(fp_line
			(start 0.12065 -0.2794)
			(end 0.12065 -0.3048)
			(stroke
				(width 0.1)
				(type default)
			)
			(layer "F.Fab")
		)
		(fp_line
			(start 0.12065 -0.3048)
			(end 0.67945 -0.3048)
			(stroke
				(width 0.1)
				(type default)
			)
			(layer "F.Fab")
		)
		(fp_line
			(start 0.67945 -0.3048)
			(end 0.67945 0.3048)
			(stroke
				(width 0.1)
				(type default)
			)
			(layer "F.Fab")
		)
		(fp_line
			(start -0.67945 -0.305054)
			(end -0.12065 -0.305054)
			(stroke
				(width 0.1)
				(type default)
			)
			(layer "F.Fab")
		)
		(fp_line
			(start -0.12065 -0.305054)
			(end -0.12065 -0.2794)
			(stroke
				(width 0.1)
				(type default)
			)
			(layer "F.Fab")
		)
		(pad "1" smd circle
			(at -0.40005 0 270)
			(size 0 0)
			(layers "F.Cu" "F.Mask" "F.Paste")
			(net "SPI_SYS_R_MOSI")
		)
		(pad "2" smd circle
			(at 0.40005 0 270)
			(size 0 0)
			(layers "F.Cu" "F.Mask" "F.Paste")
			(net "SPI_SYS_MUX_MOSI")
		)
	)
	(footprint ""
		(layer "F.Cu")
		(at -7.62 -10.922)
		(property "Reference" "DB6"
			(at -3.5052 -5.552948 0)
			(unlocked yes)
			(layer "F.SilkS")
			(effects
				(font
					(size 0.7874 0.5842)
					(thickness 0.1524)
				)
				(justify left)
			)
		)
		(property "Value" ""
			(at 0 0 0)
			(layer "F.Fab")
			(effects
				(font
					(size 1.27 1.27)
				)
			)
		)
		(duplicate_pad_numbers_are_jumpers no)
		(fp_line
			(start -3.330702 -4.771136)
			(end 3.330702 -4.771136)
			(stroke
				(width 0.1524)
				(type default)
			)
			(layer "F.SilkS")
		)
		(fp_line
			(start 0 4.011168)
			(end -3.330702 -4.771136)
			(stroke
				(width 0.1524)
				(type default)
			)
			(layer "F.SilkS")
		)
		(fp_line
			(start 3.330702 -4.771136)
			(end 0 4.011168)
			(stroke
				(width 0.1524)
				(type default)
			)
			(layer "F.SilkS")
		)
		(fp_line
			(start -3.330702 -4.771136)
			(end 3.330702 -4.771136)
			(stroke
				(width 0.1)
				(type default)
			)
			(layer "F.Fab")
		)
		(fp_line
			(start 0 4.011168)
			(end -3.330702 -4.771136)
			(stroke
				(width 0.1)
				(type default)
			)
			(layer "F.Fab")
		)
		(fp_line
			(start 3.330702 -4.771136)
			(end 0 4.011168)
			(stroke
				(width 0.1)
				(type default)
			)
			(layer "F.Fab")
		)
		(pad "1" thru_hole circle
			(at 0 0)
			(size 2.159 2.159)
			(drill 1.7018)
			(layers "*.Cu" "*.Mask")
			(remove_unused_layers no)
			(net "T_GND")
			(clearance 0.0254)
			(thermal_gap 0.0254)
		)
		(pad "2" thru_hole circle
			(at -1.27 -3.348736)
			(size 2.159 2.159)
			(drill 1.7018)
			(layers "*.Cu" "*.Mask")
			(remove_unused_layers no)
			(net "TDR_SE_50_OHM_BOT")
			(clearance 0.0254)
			(thermal_gap 0.0254)
		)
		(pad "3" thru_hole circle
			(at 1.27 -3.348736)
			(size 2.159 2.159)
			(drill 1.7018)
			(layers "*.Cu" "*.Mask")
			(remove_unused_layers no)
			(net "TDR_SE_50_OHM_BOT")
			(clearance 0.0254)
			(thermal_gap 0.0254)
		)
	)
	(footprint ""
		(layer "F.Cu")
		(at 28.6512 -62.4332 90)
		(property "Reference" "U47"
			(at -3.65887 -1.7272 0)
			(unlocked yes)
			(layer "F.SilkS")
			(effects
				(font
					(size 0.7874 0.5842)
					(thickness 0.1524)
				)
				(justify left)
			)
		)
		(property "Value" ""
			(at 0 0 90)
			(layer "F.Fab")
			(effects
				(font
					(size 1.27 1.27)
				)
			)
		)
		(duplicate_pad_numbers_are_jumpers no)
		(fp_line
			(start 1.38176 -1.100074)
			(end 0.592074 -1.100074)
			(stroke
				(width 0.1524)
				(type default)
			)
			(layer "F.SilkS")
		)
		(fp_line
			(start 0.592074 -1.100074)
			(end 0 -0.508)
			(stroke
				(width 0.1524)
				(type default)
			)
			(layer "F.SilkS")
		)
		(fp_line
			(start -0.592074 -1.100074)
			(end -1.38176 -1.100074)
			(stroke
				(width 0.1524)
				(type default)
			)
			(layer "F.SilkS")
		)
		(fp_line
			(start -1.38176 -1.100074)
			(end -1.38176 1.100074)
			(stroke
				(width 0.1524)
				(type default)
			)
			(layer "F.SilkS")
		)
		(fp_line
			(start 0 -0.508)
			(end -0.592074 -1.100074)
			(stroke
				(width 0.1524)
				(type default)
			)
			(layer "F.SilkS")
		)
		(fp_line
			(start 1.38176 1.100074)
			(end 1.38176 -1.100074)
			(stroke
				(width 0.1524)
				(type default)
			)
			(layer "F.SilkS")
		)
		(fp_line
			(start -1.38176 1.100074)
			(end 1.38176 1.100074)
			(stroke
				(width 0.1524)
				(type default)
			)
			(layer "F.SilkS")
		)
		(fp_poly
			(pts
				(xy -1.9431 -0.870204) (xy -1.50241 -0.649986) (xy -1.9431 -0.429768)
			)
			(stroke
				(width 0)
				(type default)
			)
			(fill yes)
			(layer "F.SilkS")
		)
		(fp_line
			(start 0.674878 -1.100074)
			(end -0.674878 -1.100074)
			(stroke
				(width 0.1)
				(type default)
			)
			(layer "F.Fab")
		)
		(fp_line
			(start -0.674878 -1.100074)
			(end -0.674878 1.100074)
			(stroke
				(width 0.1)
				(type default)
			)
			(layer "F.Fab")
		)
		(fp_line
			(start 0.674878 1.100074)
			(end 0.674878 -1.100074)
			(stroke
				(width 0.1)
				(type default)
			)
			(layer "F.Fab")
		)
		(fp_line
			(start -0.674878 1.100074)
			(end 0.674878 1.100074)
			(stroke
				(width 0.1)
				(type default)
			)
			(layer "F.Fab")
		)
		(fp_poly
			(pts
				(xy -1.9431 -0.870204) (xy -1.50241 -0.649986) (xy -1.9431 -0.429768)
			)
			(stroke
				(width 0)
				(type default)
			)
			(fill yes)
			(layer "F.Fab")
		)
		(pad "1" smd rect
			(at -0.94996 -0.649986)
			(size 0.4318 0.6096)
			(layers "F.Cu" "F.Mask" "F.Paste")
			(net "UART_BMC_5_TXD_R")
		)
		(pad "2" smd rect
			(at -0.94996 0)
			(size 0.4318 0.6096)
			(layers "F.Cu" "F.Mask" "F.Paste")
			(net "GND")
		)
		(pad "3" smd rect
			(at -0.94996 0.649986)
			(size 0.4318 0.6096)
			(layers "F.Cu" "F.Mask" "F.Paste")
			(net "UART_BMC_5_RXD_BUF1")
		)
		(pad "4" smd rect
			(at 0.94996 0.649986)
			(size 0.4318 0.6096)
			(layers "F.Cu" "F.Mask" "F.Paste")
			(net "UART_BMC_5_RXD_BUF1_R")
		)
		(pad "5" smd rect
			(at 0.94996 0)
			(size 0.4318 0.6096)
			(layers "F.Cu" "F.Mask" "F.Paste")
			(net "P3V3_AUX")
		)
		(pad "6" smd rect
			(at 0.94996 -0.649986)
			(size 0.4318 0.6096)
			(layers "F.Cu" "F.Mask" "F.Paste")
			(net "UART_BMC_5_TXD_BUF1")
		)
	)
	(footprint ""
		(layer "F.Cu")
		(at 70.358 -19.685 90)
		(property "Reference" "R858"
			(at 0 0 90)
			(layer "F.SilkS")
			(hide yes)
			(effects
				(font
					(size 1.27 1.27)
				)
			)
		)
		(property "Value" ""
			(at 0 0 90)
			(layer "F.Fab")
			(effects
				(font
					(size 1.27 1.27)
				)
			)
		)
		(duplicate_pad_numbers_are_jumpers no)
		(fp_line
			(start 0.7874 -0.4064)
			(end 0.7874 0.4064)
			(stroke
				(width 0.1524)
				(type default)
			)
			(layer "F.SilkS")
		)
		(fp_line
			(start -0.7874 -0.4064)
			(end 0.7874 -0.4064)
			(stroke
				(width 0.1524)
				(type default)
			)
			(layer "F.SilkS")
		)
		(fp_line
			(start 0.7874 0.4064)
			(end -0.7874 0.4064)
			(stroke
				(width 0.1524)
				(type default)
			)
			(layer "F.SilkS")
		)
		(fp_line
			(start -0.7874 0.4064)
			(end -0.7874 -0.4064)
			(stroke
				(width 0.1524)
				(type default)
			)
			(layer "F.SilkS")
		)
		(fp_line
			(start -0.12065 -0.305054)
			(end -0.12065 -0.2794)
			(stroke
				(width 0.1)
				(type default)
			)
			(layer "F.Fab")
		)
		(fp_line
			(start -0.67945 -0.305054)
			(end -0.12065 -0.305054)
			(stroke
				(width 0.1)
				(type default)
			)
			(layer "F.Fab")
		)
		(fp_line
			(start 0.67945 -0.3048)
			(end 0.67945 0.3048)
			(stroke
				(width 0.1)
				(type default)
			)
			(layer "F.Fab")
		)
		(fp_line
			(start 0.12065 -0.3048)
			(end 0.67945 -0.3048)
			(stroke
				(width 0.1)
				(type default)
			)
			(layer "F.Fab")
		)
		(fp_line
			(start 0.12065 -0.2794)
			(end 0.12065 -0.3048)
			(stroke
				(width 0.1)
				(type default)
			)
			(layer "F.Fab")
		)
		(fp_line
			(start -0.12065 -0.2794)
			(end 0.12065 -0.2794)
			(stroke
				(width 0.1)
				(type default)
			)
			(layer "F.Fab")
		)
		(fp_line
			(start 0.120396 0.2794)
			(end -0.12065 0.2794)
			(stroke
				(width 0.1)
				(type default)
			)
			(layer "F.Fab")
		)
		(fp_line
			(start -0.12065 0.2794)
			(end -0.12065 0.3048)
			(stroke
				(width 0.1)
				(type default)
			)
			(layer "F.Fab")
		)
		(fp_line
			(start 0.67945 0.3048)
			(end 0.120396 0.3048)
			(stroke
				(width 0.1)
				(type default)
			)
			(layer "F.Fab")
		)
		(fp_line
			(start 0.120396 0.3048)
			(end 0.120396 0.2794)
			(stroke
				(width 0.1)
				(type default)
			)
			(layer "F.Fab")
		)
		(fp_line
			(start -0.12065 0.3048)
			(end -0.67945 0.3048)
			(stroke
				(width 0.1)
				(type default)
			)
			(layer "F.Fab")
		)
		(fp_line
			(start -0.67945 0.3048)
			(end -0.67945 -0.305054)
			(stroke
				(width 0.1)
				(type default)
			)
			(layer "F.Fab")
		)
		(pad "1" smd circle
			(at -0.40005 0 90)
			(size 0 0)
			(layers "F.Cu" "F.Mask" "F.Paste")
			(net "P1V8_AUX")
		)
		(pad "2" smd circle
			(at 0.40005 0 90)
			(size 0 0)
			(layers "F.Cu" "F.Mask" "F.Paste")
			(net "FM_BOARD_BMC_REV_ID0")
		)
	)
	(footprint ""
		(layer "F.Cu")
		(at 54.84368 -24.887936)
		(property "Reference" "R377"
			(at 0 0 0)
			(layer "F.SilkS")
			(hide yes)
			(effects
				(font
					(size 1.27 1.27)
				)
			)
		)
		(property "Value" ""
			(at 0 0 0)
			(layer "F.Fab")
			(effects
				(font
					(size 1.27 1.27)
				)
			)
		)
		(duplicate_pad_numbers_are_jumpers no)
		(fp_line
			(start -0.7874 -0.4064)
			(end 0.7874 -0.4064)
			(stroke
				(width 0.1524)
				(type default)
			)
			(layer "F.SilkS")
		)
		(fp_line
			(start -0.7874 0.4064)
			(end -0.7874 -0.4064)
			(stroke
				(width 0.1524)
				(type default)
			)
			(layer "F.SilkS")
		)
		(fp_line
			(start 0.7874 -0.4064)
			(end 0.7874 0.4064)
			(stroke
				(width 0.1524)
				(type default)
			)
			(layer "F.SilkS")
		)
		(fp_line
			(start 0.7874 0.4064)
			(end -0.7874 0.4064)
			(stroke
				(width 0.1524)
				(type default)
			)
			(layer "F.SilkS")
		)
		(fp_line
			(start -0.67945 -0.305054)
			(end -0.12065 -0.305054)
			(stroke
				(width 0.1)
				(type default)
			)
			(layer "F.Fab")
		)
		(fp_line
			(start -0.67945 0.3048)
			(end -0.67945 -0.305054)
			(stroke
				(width 0.1)
				(type default)
			)
			(layer "F.Fab")
		)
		(fp_line
			(start -0.12065 -0.305054)
			(end -0.12065 -0.2794)
			(stroke
				(width 0.1)
				(type default)
			)
			(layer "F.Fab")
		)
		(fp_line
			(start -0.12065 -0.2794)
			(end 0.12065 -0.2794)
			(stroke
				(width 0.1)
				(type default)
			)
			(layer "F.Fab")
		)
		(fp_line
			(start -0.12065 0.2794)
			(end -0.12065 0.3048)
			(stroke
				(width 0.1)
				(type default)
			)
			(layer "F.Fab")
		)
		(fp_line
			(start -0.12065 0.3048)
			(end -0.67945 0.3048)
			(stroke
				(width 0.1)
				(type default)
			)
			(layer "F.Fab")
		)
		(fp_line
			(start 0.120396 0.2794)
			(end -0.12065 0.2794)
			(stroke
				(width 0.1)
				(type default)
			)
			(layer "F.Fab")
		)
		(fp_line
			(start 0.120396 0.3048)
			(end 0.120396 0.2794)
			(stroke
				(width 0.1)
				(type default)
			)
			(layer "F.Fab")
		)
		(fp_line
			(start 0.12065 -0.3048)
			(end 0.67945 -0.3048)
			(stroke
				(width 0.1)
				(type default)
			)
			(layer "F.Fab")
		)
		(fp_line
			(start 0.12065 -0.2794)
			(end 0.12065 -0.3048)
			(stroke
				(width 0.1)
				(type default)
			)
			(layer "F.Fab")
		)
		(fp_line
			(start 0.67945 -0.3048)
			(end 0.67945 0.3048)
			(stroke
				(width 0.1)
				(type default)
			)
			(layer "F.Fab")
		)
		(fp_line
			(start 0.67945 0.3048)
			(end 0.120396 0.3048)
			(stroke
				(width 0.1)
				(type default)
			)
			(layer "F.Fab")
		)
		(pad "1" smd circle
			(at -0.40005 0)
			(size 0 0)
			(layers "F.Cu" "F.Mask" "F.Paste")
			(net "USB_OC0_EN")
		)
		(pad "2" smd circle
			(at 0.40005 0)
			(size 0 0)
			(layers "F.Cu" "F.Mask" "F.Paste")
			(net "GND")
		)
	)
	(footprint ""
		(layer "F.Cu")
		(at 80.280764 -26.496772 -90)
		(property "Reference" "R603"
			(at 0 0 270)
			(layer "F.SilkS")
			(hide yes)
			(effects
				(font
					(size 1.27 1.27)
				)
			)
		)
		(property "Value" ""
			(at 0 0 270)
			(layer "F.Fab")
			(effects
				(font
					(size 1.27 1.27)
				)
			)
		)
		(duplicate_pad_numbers_are_jumpers no)
		(fp_line
			(start -0.7874 0.4064)
			(end -0.7874 -0.4064)
			(stroke
				(width 0.1524)
				(type default)
			)
			(layer "F.SilkS")
		)
		(fp_line
			(start 0.7874 0.4064)
			(end -0.7874 0.4064)
			(stroke
				(width 0.1524)
				(type default)
			)
			(layer "F.SilkS")
		)
		(fp_line
			(start -0.7874 -0.4064)
			(end 0.7874 -0.4064)
			(stroke
				(width 0.1524)
				(type default)
			)
			(layer "F.SilkS")
		)
		(fp_line
			(start 0.7874 -0.4064)
			(end 0.7874 0.4064)
			(stroke
				(width 0.1524)
				(type default)
			)
			(layer "F.SilkS")
		)
		(fp_line
			(start -0.67945 0.3048)
			(end -0.67945 -0.305054)
			(stroke
				(width 0.1)
				(type default)
			)
			(layer "F.Fab")
		)
		(fp_line
			(start -0.12065 0.3048)
			(end -0.67945 0.3048)
			(stroke
				(width 0.1)
				(type default)
			)
			(layer "F.Fab")
		)
		(fp_line
			(start 0.120396 0.3048)
			(end 0.120396 0.2794)
			(stroke
				(width 0.1)
				(type default)
			)
			(layer "F.Fab")
		)
		(fp_line
			(start 0.67945 0.3048)
			(end 0.120396 0.3048)
			(stroke
				(width 0.1)
				(type default)
			)
			(layer "F.Fab")
		)
		(fp_line
			(start -0.12065 0.2794)
			(end -0.12065 0.3048)
			(stroke
				(width 0.1)
				(type default)
			)
			(layer "F.Fab")
		)
		(fp_line
			(start 0.120396 0.2794)
			(end -0.12065 0.2794)
			(stroke
				(width 0.1)
				(type default)
			)
			(layer "F.Fab")
		)
		(fp_line
			(start -0.12065 -0.2794)
			(end 0.12065 -0.2794)
			(stroke
				(width 0.1)
				(type default)
			)
			(layer "F.Fab")
		)
		(fp_line
			(start 0.12065 -0.2794)
			(end 0.12065 -0.3048)
			(stroke
				(width 0.1)
				(type default)
			)
			(layer "F.Fab")
		)
		(fp_line
			(start 0.12065 -0.3048)
			(end 0.67945 -0.3048)
			(stroke
				(width 0.1)
				(type default)
			)
			(layer "F.Fab")
		)
		(fp_line
			(start 0.67945 -0.3048)
			(end 0.67945 0.3048)
			(stroke
				(width 0.1)
				(type default)
			)
			(layer "F.Fab")
		)
		(fp_line
			(start -0.67945 -0.305054)
			(end -0.12065 -0.305054)
			(stroke
				(width 0.1)
				(type default)
			)
			(layer "F.Fab")
		)
		(fp_line
			(start -0.12065 -0.305054)
			(end -0.12065 -0.2794)
			(stroke
				(width 0.1)
				(type default)
			)
			(layer "F.Fab")
		)
		(pad "1" smd circle
			(at -0.40005 0 270)
			(size 0 0)
			(layers "F.Cu" "F.Mask" "F.Paste")
			(net "LED_POSTCODE_1")
		)
		(pad "2" smd circle
			(at 0.40005 0 270)
			(size 0 0)
			(layers "F.Cu" "F.Mask" "F.Paste")
			(net "LED_POSTCODE_1_R")
		)
	)
	(footprint ""
		(layer "F.Cu")
		(at 51.71313 -97.168716 90)
		(property "Reference" "Q1"
			(at 3.237484 -1.483614 0)
			(unlocked yes)
			(layer "F.SilkS")
			(effects
				(font
					(size 0.7874 0.5842)
					(thickness 0.1524)
				)
				(justify left)
			)
		)
		(property "Value" ""
			(at 0 0 90)
			(layer "F.Fab")
			(effects
				(font
					(size 1.27 1.27)
				)
			)
		)
		(duplicate_pad_numbers_are_jumpers no)
		(fp_line
			(start 1.905 -1.651)
			(end 1.905 1.651)
			(stroke
				(width 0.1524)
				(type default)
			)
			(layer "F.SilkS")
		)
		(fp_line
			(start -1.905 -1.651)
			(end 1.905 -1.651)
			(stroke
				(width 0.1524)
				(type default)
			)
			(layer "F.SilkS")
		)
		(fp_line
			(start 1.905 1.651)
			(end -1.905 1.651)
			(stroke
				(width 0.1524)
				(type default)
			)
			(layer "F.SilkS")
		)
		(fp_line
			(start -1.905 1.651)
			(end -1.905 -1.651)
			(stroke
				(width 0.1524)
				(type default)
			)
			(layer "F.SilkS")
		)
		(fp_line
			(start 0.6985 -1.524)
			(end 0.6985 -0.219964)
			(stroke
				(width 0.1)
				(type default)
			)
			(layer "F.Fab")
		)
		(fp_line
			(start -0.649986 -1.524)
			(end 0.6985 -1.524)
			(stroke
				(width 0.1)
				(type default)
			)
			(layer "F.Fab")
		)
		(fp_line
			(start -0.649986 -1.169924)
			(end -0.649986 -1.524)
			(stroke
				(width 0.1)
				(type default)
			)
			(layer "F.Fab")
		)
		(fp_line
			(start -1.249934 -1.169924)
			(end -0.649986 -1.169924)
			(stroke
				(width 0.1)
				(type default)
			)
			(layer "F.Fab")
		)
		(fp_line
			(start -0.6985 -0.729996)
			(end -1.249934 -0.729996)
			(stroke
				(width 0.1)
				(type default)
			)
			(layer "F.Fab")
		)
		(fp_line
			(start -1.249934 -0.729996)
			(end -1.249934 -1.169924)
			(stroke
				(width 0.1)
				(type default)
			)
			(layer "F.Fab")
		)
		(fp_line
			(start 1.249934 -0.219964)
			(end 1.249934 0.219964)
			(stroke
				(width 0.1)
				(type default)
			)
			(layer "F.Fab")
		)
		(fp_line
			(start 0.6985 -0.219964)
			(end 1.249934 -0.219964)
			(stroke
				(width 0.1)
				(type default)
			)
			(layer "F.Fab")
		)
		(fp_line
			(start 1.249934 0.219964)
			(end 0.6985 0.219964)
			(stroke
				(width 0.1)
				(type default)
			)
			(layer "F.Fab")
		)
		(fp_line
			(start 0.6985 0.219964)
			(end 0.6985 1.524)
			(stroke
				(width 0.1)
				(type default)
			)
			(layer "F.Fab")
		)
		(fp_line
			(start -0.6985 0.729996)
			(end -0.6985 -0.729996)
			(stroke
				(width 0.1)
				(type default)
			)
			(layer "F.Fab")
		)
		(fp_line
			(start -1.249934 0.729996)
			(end -0.6985 0.729996)
			(stroke
				(width 0.1)
				(type default)
			)
			(layer "F.Fab")
		)
		(fp_line
			(start -0.649986 1.169924)
			(end -1.249934 1.169924)
			(stroke
				(width 0.1)
				(type default)
			)
			(layer "F.Fab")
		)
		(fp_line
			(start -1.249934 1.169924)
			(end -1.249934 0.729996)
			(stroke
				(width 0.1)
				(type default)
			)
			(layer "F.Fab")
		)
		(fp_line
			(start 0.6985 1.524)
			(end -0.649986 1.524)
			(stroke
				(width 0.1)
				(type default)
			)
			(layer "F.Fab")
		)
		(fp_line
			(start -0.649986 1.524)
			(end -0.649986 1.169924)
			(stroke
				(width 0.1)
				(type default)
			)
			(layer "F.Fab")
		)
		(pad "B" smd rect
			(at -1.1176 -1.016)
			(size 1.016 1.27)
			(layers "F.Cu" "F.Mask" "F.Paste")
			(net "BJT_Q3_C")
		)
		(pad "C" smd rect
			(at 1.1176 0)
			(size 1.016 1.27)
			(layers "F.Cu" "F.Mask" "F.Paste")
			(net "RST_BMC_EXTRST_R2_N")
		)
		(pad "E" smd rect
			(at -1.1176 1.016)
			(size 1.016 1.27)
			(layers "F.Cu" "F.Mask" "F.Paste")
			(net "GND")
		)
	)
	(footprint ""
		(layer "F.Cu")
		(at 37.973 -58.674 -90)
		(property "Reference" "R874"
			(at 0 0 270)
			(layer "F.SilkS")
			(hide yes)
			(effects
				(font
					(size 1.27 1.27)
				)
			)
		)
		(property "Value" ""
			(at 0 0 270)
			(layer "F.Fab")
			(effects
				(font
					(size 1.27 1.27)
				)
			)
		)
		(duplicate_pad_numbers_are_jumpers no)
		(fp_line
			(start -0.7874 0.4064)
			(end -0.7874 -0.4064)
			(stroke
				(width 0.1524)
				(type default)
			)
			(layer "F.SilkS")
		)
		(fp_line
			(start 0.7874 0.4064)
			(end -0.7874 0.4064)
			(stroke
				(width 0.1524)
				(type default)
			)
			(layer "F.SilkS")
		)
		(fp_line
			(start -0.7874 -0.4064)
			(end 0.7874 -0.4064)
			(stroke
				(width 0.1524)
				(type default)
			)
			(layer "F.SilkS")
		)
		(fp_line
			(start 0.7874 -0.4064)
			(end 0.7874 0.4064)
			(stroke
				(width 0.1524)
				(type default)
			)
			(layer "F.SilkS")
		)
		(fp_line
			(start -0.67945 0.3048)
			(end -0.67945 -0.305054)
			(stroke
				(width 0.1)
				(type default)
			)
			(layer "F.Fab")
		)
		(fp_line
			(start -0.12065 0.3048)
			(end -0.67945 0.3048)
			(stroke
				(width 0.1)
				(type default)
			)
			(layer "F.Fab")
		)
		(fp_line
			(start 0.120396 0.3048)
			(end 0.120396 0.2794)
			(stroke
				(width 0.1)
				(type default)
			)
			(layer "F.Fab")
		)
		(fp_line
			(start 0.67945 0.3048)
			(end 0.120396 0.3048)
			(stroke
				(width 0.1)
				(type default)
			)
			(layer "F.Fab")
		)
		(fp_line
			(start -0.12065 0.2794)
			(end -0.12065 0.3048)
			(stroke
				(width 0.1)
				(type default)
			)
			(layer "F.Fab")
		)
		(fp_line
			(start 0.120396 0.2794)
			(end -0.12065 0.2794)
			(stroke
				(width 0.1)
				(type default)
			)
			(layer "F.Fab")
		)
		(fp_line
			(start -0.12065 -0.2794)
			(end 0.12065 -0.2794)
			(stroke
				(width 0.1)
				(type default)
			)
			(layer "F.Fab")
		)
		(fp_line
			(start 0.12065 -0.2794)
			(end 0.12065 -0.3048)
			(stroke
				(width 0.1)
				(type default)
			)
			(layer "F.Fab")
		)
		(fp_line
			(start 0.12065 -0.3048)
			(end 0.67945 -0.3048)
			(stroke
				(width 0.1)
				(type default)
			)
			(layer "F.Fab")
		)
		(fp_line
			(start 0.67945 -0.3048)
			(end 0.67945 0.3048)
			(stroke
				(width 0.1)
				(type default)
			)
			(layer "F.Fab")
		)
		(fp_line
			(start -0.67945 -0.305054)
			(end -0.12065 -0.305054)
			(stroke
				(width 0.1)
				(type default)
			)
			(layer "F.Fab")
		)
		(fp_line
			(start -0.12065 -0.305054)
			(end -0.12065 -0.2794)
			(stroke
				(width 0.1)
				(type default)
			)
			(layer "F.Fab")
		)
		(pad "1" smd circle
			(at -0.40005 0 270)
			(size 0 0)
			(layers "F.Cu" "F.Mask" "F.Paste")
			(net "PWRGD_P1V8_AUX_R3")
		)
		(pad "2" smd circle
			(at 0.40005 0 270)
			(size 0 0)
			(layers "F.Cu" "F.Mask" "F.Paste")
			(net "PWRGD_P1V8_AUX_R")
		)
	)
	(footprint ""
		(layer "F.Cu")
		(at 32.766 -44.45 90)
		(property "Reference" "C253"
			(at 0 0 90)
			(layer "F.SilkS")
			(hide yes)
			(effects
				(font
					(size 1.27 1.27)
				)
			)
		)
		(property "Value" ""
			(at 0 0 90)
			(layer "F.Fab")
			(effects
				(font
					(size 1.27 1.27)
				)
			)
		)
		(duplicate_pad_numbers_are_jumpers no)
		(fp_line
			(start 0.7874 -0.4064)
			(end 0.7874 0.4064)
			(stroke
				(width 0.1524)
				(type default)
			)
			(layer "F.SilkS")
		)
		(fp_line
			(start -0.7874 -0.4064)
			(end 0.7874 -0.4064)
			(stroke
				(width 0.1524)
				(type default)
			)
			(layer "F.SilkS")
		)
		(fp_line
			(start 0.7874 0.4064)
			(end -0.7874 0.4064)
			(stroke
				(width 0.1524)
				(type default)
			)
			(layer "F.SilkS")
		)
		(fp_line
			(start -0.7874 0.4064)
			(end -0.7874 -0.4064)
			(stroke
				(width 0.1524)
				(type default)
			)
			(layer "F.SilkS")
		)
		(fp_line
			(start -0.12065 -0.305054)
			(end -0.12065 -0.2794)
			(stroke
				(width 0.1)
				(type default)
			)
			(layer "F.Fab")
		)
		(fp_line
			(start -0.67945 -0.305054)
			(end -0.12065 -0.305054)
			(stroke
				(width 0.1)
				(type default)
			)
			(layer "F.Fab")
		)
		(fp_line
			(start 0.67945 -0.3048)
			(end 0.67945 0.3048)
			(stroke
				(width 0.1)
				(type default)
			)
			(layer "F.Fab")
		)
		(fp_line
			(start 0.12065 -0.3048)
			(end 0.67945 -0.3048)
			(stroke
				(width 0.1)
				(type default)
			)
			(layer "F.Fab")
		)
		(fp_line
			(start 0.12065 -0.2794)
			(end 0.12065 -0.3048)
			(stroke
				(width 0.1)
				(type default)
			)
			(layer "F.Fab")
		)
		(fp_line
			(start -0.12065 -0.2794)
			(end 0.12065 -0.2794)
			(stroke
				(width 0.1)
				(type default)
			)
			(layer "F.Fab")
		)
		(fp_line
			(start 0.120396 0.2794)
			(end -0.12065 0.2794)
			(stroke
				(width 0.1)
				(type default)
			)
			(layer "F.Fab")
		)
		(fp_line
			(start -0.12065 0.2794)
			(end -0.12065 0.3048)
			(stroke
				(width 0.1)
				(type default)
			)
			(layer "F.Fab")
		)
		(fp_line
			(start 0.67945 0.3048)
			(end 0.120396 0.3048)
			(stroke
				(width 0.1)
				(type default)
			)
			(layer "F.Fab")
		)
		(fp_line
			(start 0.120396 0.3048)
			(end 0.120396 0.2794)
			(stroke
				(width 0.1)
				(type default)
			)
			(layer "F.Fab")
		)
		(fp_line
			(start -0.12065 0.3048)
			(end -0.67945 0.3048)
			(stroke
				(width 0.1)
				(type default)
			)
			(layer "F.Fab")
		)
		(fp_line
			(start -0.67945 0.3048)
			(end -0.67945 -0.305054)
			(stroke
				(width 0.1)
				(type default)
			)
			(layer "F.Fab")
		)
		(pad "1" smd circle
			(at -0.40005 0 90)
			(size 0 0)
			(layers "F.Cu" "F.Mask" "F.Paste")
			(net "P3V3_AUX")
		)
		(pad "2" smd circle
			(at 0.40005 0 90)
			(size 0 0)
			(layers "F.Cu" "F.Mask" "F.Paste")
			(net "GND")
		)
	)
	(footprint ""
		(layer "F.Cu")
		(at 43.504104 -107.999784 -90)
		(property "Reference" "R488"
			(at 0 0 270)
			(layer "F.SilkS")
			(hide yes)
			(effects
				(font
					(size 1.27 1.27)
				)
			)
		)
		(property "Value" ""
			(at 0 0 270)
			(layer "F.Fab")
			(effects
				(font
					(size 1.27 1.27)
				)
			)
		)
		(duplicate_pad_numbers_are_jumpers no)
		(fp_line
			(start -0.7874 0.4064)
			(end -0.7874 -0.4064)
			(stroke
				(width 0.1524)
				(type default)
			)
			(layer "F.SilkS")
		)
		(fp_line
			(start 0.7874 0.4064)
			(end -0.7874 0.4064)
			(stroke
				(width 0.1524)
				(type default)
			)
			(layer "F.SilkS")
		)
		(fp_line
			(start -0.7874 -0.4064)
			(end 0.7874 -0.4064)
			(stroke
				(width 0.1524)
				(type default)
			)
			(layer "F.SilkS")
		)
		(fp_line
			(start 0.7874 -0.4064)
			(end 0.7874 0.4064)
			(stroke
				(width 0.1524)
				(type default)
			)
			(layer "F.SilkS")
		)
		(fp_line
			(start -0.67945 0.3048)
			(end -0.67945 -0.305054)
			(stroke
				(width 0.1)
				(type default)
			)
			(layer "F.Fab")
		)
		(fp_line
			(start -0.12065 0.3048)
			(end -0.67945 0.3048)
			(stroke
				(width 0.1)
				(type default)
			)
			(layer "F.Fab")
		)
		(fp_line
			(start 0.120396 0.3048)
			(end 0.120396 0.2794)
			(stroke
				(width 0.1)
				(type default)
			)
			(layer "F.Fab")
		)
		(fp_line
			(start 0.67945 0.3048)
			(end 0.120396 0.3048)
			(stroke
				(width 0.1)
				(type default)
			)
			(layer "F.Fab")
		)
		(fp_line
			(start -0.12065 0.2794)
			(end -0.12065 0.3048)
			(stroke
				(width 0.1)
				(type default)
			)
			(layer "F.Fab")
		)
		(fp_line
			(start 0.120396 0.2794)
			(end -0.12065 0.2794)
			(stroke
				(width 0.1)
				(type default)
			)
			(layer "F.Fab")
		)
		(fp_line
			(start -0.12065 -0.2794)
			(end 0.12065 -0.2794)
			(stroke
				(width 0.1)
				(type default)
			)
			(layer "F.Fab")
		)
		(fp_line
			(start 0.12065 -0.2794)
			(end 0.12065 -0.3048)
			(stroke
				(width 0.1)
				(type default)
			)
			(layer "F.Fab")
		)
		(fp_line
			(start 0.12065 -0.3048)
			(end 0.67945 -0.3048)
			(stroke
				(width 0.1)
				(type default)
			)
			(layer "F.Fab")
		)
		(fp_line
			(start 0.67945 -0.3048)
			(end 0.67945 0.3048)
			(stroke
				(width 0.1)
				(type default)
			)
			(layer "F.Fab")
		)
		(fp_line
			(start -0.67945 -0.305054)
			(end -0.12065 -0.305054)
			(stroke
				(width 0.1)
				(type default)
			)
			(layer "F.Fab")
		)
		(fp_line
			(start -0.12065 -0.305054)
			(end -0.12065 -0.2794)
			(stroke
				(width 0.1)
				(type default)
			)
			(layer "F.Fab")
		)
		(pad "1" smd circle
			(at -0.40005 0 270)
			(size 0 0)
			(layers "F.Cu" "F.Mask" "F.Paste")
			(net "P3V3_AUX")
		)
		(pad "2" smd circle
			(at 0.40005 0 270)
			(size 0 0)
			(layers "F.Cu" "F.Mask" "F.Paste")
			(net "SPI_PCH_IO2_FLASH_R1")
		)
	)
	(footprint ""
		(layer "F.Cu")
		(at 33.274 -54.356 -90)
		(property "Reference" "C293"
			(at 0 0 270)
			(layer "F.SilkS")
			(hide yes)
			(effects
				(font
					(size 1.27 1.27)
				)
			)
		)
		(property "Value" ""
			(at 0 0 270)
			(layer "F.Fab")
			(effects
				(font
					(size 1.27 1.27)
				)
			)
		)
		(duplicate_pad_numbers_are_jumpers no)
		(fp_line
			(start -1.651 0.8382)
			(end -1.651 -0.8382)
			(stroke
				(width 0.1524)
				(type default)
			)
			(layer "F.SilkS")
		)
		(fp_line
			(start 0 0.8382)
			(end 0 -0.8382)
			(stroke
				(width 0.1524)
				(type default)
			)
			(layer "F.SilkS")
		)
		(fp_line
			(start 1.651 0.8382)
			(end -1.651 0.8382)
			(stroke
				(width 0.1524)
				(type default)
			)
			(layer "F.SilkS")
		)
		(fp_line
			(start -1.651 -0.8382)
			(end 1.651 -0.8382)
			(stroke
				(width 0.1524)
				(type default)
			)
			(layer "F.SilkS")
		)
		(fp_line
			(start 1.651 -0.8382)
			(end 1.651 0.8382)
			(stroke
				(width 0.1524)
				(type default)
			)
			(layer "F.SilkS")
		)
		(fp_line
			(start -1.55956 0.7366)
			(end -1.524 0.7366)
			(stroke
				(width 0.1)
				(type default)
			)
			(layer "F.Fab")
		)
		(fp_line
			(start -1.524 0.7366)
			(end 1.524 0.7366)
			(stroke
				(width 0.1)
				(type default)
			)
			(layer "F.Fab")
		)
		(fp_line
			(start 1.524 0.7366)
			(end 1.55956 0.7366)
			(stroke
				(width 0.1)
				(type default)
			)
			(layer "F.Fab")
		)
		(fp_line
			(start 1.55956 0.7366)
			(end 1.55956 -0.7366)
			(stroke
				(width 0.1)
				(type default)
			)
			(layer "F.Fab")
		)
		(fp_line
			(start -1.55956 -0.7366)
			(end -1.55956 0.7366)
			(stroke
				(width 0.1)
				(type default)
			)
			(layer "F.Fab")
		)
		(fp_line
			(start -1.524 -0.7366)
			(end -1.55956 -0.7366)
			(stroke
				(width 0.1)
				(type default)
			)
			(layer "F.Fab")
		)
		(fp_line
			(start 1.524 -0.7366)
			(end -1.524 -0.7366)
			(stroke
				(width 0.1)
				(type default)
			)
			(layer "F.Fab")
		)
		(fp_line
			(start 1.55956 -0.7366)
			(end 1.524 -0.7366)
			(stroke
				(width 0.1)
				(type default)
			)
			(layer "F.Fab")
		)
		(pad "1" smd rect
			(at -0.94996 0 90)
			(size 1.1176 1.3716)
			(layers "F.Cu" "F.Mask" "F.Paste")
			(net "P3V3_AUX")
		)
		(pad "2" smd rect
			(at 0.94996 0 90)
			(size 1.1176 1.3716)
			(layers "F.Cu" "F.Mask" "F.Paste")
			(net "GND")
		)
	)
	(footprint ""
		(layer "F.Cu")
		(at 65.5066 -108.0008 -90)
		(property "Reference" "R311"
			(at 0 0 270)
			(layer "F.SilkS")
			(hide yes)
			(effects
				(font
					(size 1.27 1.27)
				)
			)
		)
		(property "Value" ""
			(at 0 0 270)
			(layer "F.Fab")
			(effects
				(font
					(size 1.27 1.27)
				)
			)
		)
		(duplicate_pad_numbers_are_jumpers no)
		(fp_line
			(start -0.7874 0.4064)
			(end -0.7874 -0.4064)
			(stroke
				(width 0.1524)
				(type default)
			)
			(layer "F.SilkS")
		)
		(fp_line
			(start 0.7874 0.4064)
			(end -0.7874 0.4064)
			(stroke
				(width 0.1524)
				(type default)
			)
			(layer "F.SilkS")
		)
		(fp_line
			(start -0.7874 -0.4064)
			(end 0.7874 -0.4064)
			(stroke
				(width 0.1524)
				(type default)
			)
			(layer "F.SilkS")
		)
		(fp_line
			(start 0.7874 -0.4064)
			(end 0.7874 0.4064)
			(stroke
				(width 0.1524)
				(type default)
			)
			(layer "F.SilkS")
		)
		(fp_line
			(start -0.67945 0.3048)
			(end -0.67945 -0.305054)
			(stroke
				(width 0.1)
				(type default)
			)
			(layer "F.Fab")
		)
		(fp_line
			(start -0.12065 0.3048)
			(end -0.67945 0.3048)
			(stroke
				(width 0.1)
				(type default)
			)
			(layer "F.Fab")
		)
		(fp_line
			(start 0.120396 0.3048)
			(end 0.120396 0.2794)
			(stroke
				(width 0.1)
				(type default)
			)
			(layer "F.Fab")
		)
		(fp_line
			(start 0.67945 0.3048)
			(end 0.120396 0.3048)
			(stroke
				(width 0.1)
				(type default)
			)
			(layer "F.Fab")
		)
		(fp_line
			(start -0.12065 0.2794)
			(end -0.12065 0.3048)
			(stroke
				(width 0.1)
				(type default)
			)
			(layer "F.Fab")
		)
		(fp_line
			(start 0.120396 0.2794)
			(end -0.12065 0.2794)
			(stroke
				(width 0.1)
				(type default)
			)
			(layer "F.Fab")
		)
		(fp_line
			(start -0.12065 -0.2794)
			(end 0.12065 -0.2794)
			(stroke
				(width 0.1)
				(type default)
			)
			(layer "F.Fab")
		)
		(fp_line
			(start 0.12065 -0.2794)
			(end 0.12065 -0.3048)
			(stroke
				(width 0.1)
				(type default)
			)
			(layer "F.Fab")
		)
		(fp_line
			(start 0.12065 -0.3048)
			(end 0.67945 -0.3048)
			(stroke
				(width 0.1)
				(type default)
			)
			(layer "F.Fab")
		)
		(fp_line
			(start 0.67945 -0.3048)
			(end 0.67945 0.3048)
			(stroke
				(width 0.1)
				(type default)
			)
			(layer "F.Fab")
		)
		(fp_line
			(start -0.67945 -0.305054)
			(end -0.12065 -0.305054)
			(stroke
				(width 0.1)
				(type default)
			)
			(layer "F.Fab")
		)
		(fp_line
			(start -0.12065 -0.305054)
			(end -0.12065 -0.2794)
			(stroke
				(width 0.1)
				(type default)
			)
			(layer "F.Fab")
		)
		(pad "1" smd circle
			(at -0.40005 0 270)
			(size 0 0)
			(layers "F.Cu" "F.Mask" "F.Paste")
			(net "ESPI_HOST_LPC_BMC_LFRAME_N")
		)
		(pad "2" smd circle
			(at 0.40005 0 270)
			(size 0 0)
			(layers "F.Cu" "F.Mask" "F.Paste")
			(net "ESPI_HOST_LPC_BMC_LFRAME_N_R")
		)
	)
	(footprint ""
		(layer "F.Cu")
		(at 39.5732 -49.7078)
		(property "Reference" "R400"
			(at 0 0 0)
			(layer "F.SilkS")
			(hide yes)
			(effects
				(font
					(size 1.27 1.27)
				)
			)
		)
		(property "Value" ""
			(at 0 0 0)
			(layer "F.Fab")
			(effects
				(font
					(size 1.27 1.27)
				)
			)
		)
		(duplicate_pad_numbers_are_jumpers no)
		(fp_line
			(start -0.7874 -0.4064)
			(end 0.7874 -0.4064)
			(stroke
				(width 0.1524)
				(type default)
			)
			(layer "F.SilkS")
		)
		(fp_line
			(start -0.7874 0.4064)
			(end -0.7874 -0.4064)
			(stroke
				(width 0.1524)
				(type default)
			)
			(layer "F.SilkS")
		)
		(fp_line
			(start 0.7874 -0.4064)
			(end 0.7874 0.4064)
			(stroke
				(width 0.1524)
				(type default)
			)
			(layer "F.SilkS")
		)
		(fp_line
			(start 0.7874 0.4064)
			(end -0.7874 0.4064)
			(stroke
				(width 0.1524)
				(type default)
			)
			(layer "F.SilkS")
		)
		(fp_line
			(start -0.67945 -0.305054)
			(end -0.12065 -0.305054)
			(stroke
				(width 0.1)
				(type default)
			)
			(layer "F.Fab")
		)
		(fp_line
			(start -0.67945 0.3048)
			(end -0.67945 -0.305054)
			(stroke
				(width 0.1)
				(type default)
			)
			(layer "F.Fab")
		)
		(fp_line
			(start -0.12065 -0.305054)
			(end -0.12065 -0.2794)
			(stroke
				(width 0.1)
				(type default)
			)
			(layer "F.Fab")
		)
		(fp_line
			(start -0.12065 -0.2794)
			(end 0.12065 -0.2794)
			(stroke
				(width 0.1)
				(type default)
			)
			(layer "F.Fab")
		)
		(fp_line
			(start -0.12065 0.2794)
			(end -0.12065 0.3048)
			(stroke
				(width 0.1)
				(type default)
			)
			(layer "F.Fab")
		)
		(fp_line
			(start -0.12065 0.3048)
			(end -0.67945 0.3048)
			(stroke
				(width 0.1)
				(type default)
			)
			(layer "F.Fab")
		)
		(fp_line
			(start 0.120396 0.2794)
			(end -0.12065 0.2794)
			(stroke
				(width 0.1)
				(type default)
			)
			(layer "F.Fab")
		)
		(fp_line
			(start 0.120396 0.3048)
			(end 0.120396 0.2794)
			(stroke
				(width 0.1)
				(type default)
			)
			(layer "F.Fab")
		)
		(fp_line
			(start 0.12065 -0.3048)
			(end 0.67945 -0.3048)
			(stroke
				(width 0.1)
				(type default)
			)
			(layer "F.Fab")
		)
		(fp_line
			(start 0.12065 -0.2794)
			(end 0.12065 -0.3048)
			(stroke
				(width 0.1)
				(type default)
			)
			(layer "F.Fab")
		)
		(fp_line
			(start 0.67945 -0.3048)
			(end 0.67945 0.3048)
			(stroke
				(width 0.1)
				(type default)
			)
			(layer "F.Fab")
		)
		(fp_line
			(start 0.67945 0.3048)
			(end 0.120396 0.3048)
			(stroke
				(width 0.1)
				(type default)
			)
			(layer "F.Fab")
		)
		(pad "1" smd circle
			(at -0.40005 0)
			(size 0 0)
			(layers "F.Cu" "F.Mask" "F.Paste")
			(net "P3V3_AUX")
		)
		(pad "2" smd circle
			(at 0.40005 0)
			(size 0 0)
			(layers "F.Cu" "F.Mask" "F.Paste")
			(net "FM_THERMTRIP_DLY_LVC1_R_N")
		)
	)
	(footprint ""
		(layer "F.Cu")
		(at 33.7566 -46.4058 -90)
		(property "Reference" "R70"
			(at 0 0 270)
			(layer "F.SilkS")
			(hide yes)
			(effects
				(font
					(size 1.27 1.27)
				)
			)
		)
		(property "Value" ""
			(at 0 0 270)
			(layer "F.Fab")
			(effects
				(font
					(size 1.27 1.27)
				)
			)
		)
		(duplicate_pad_numbers_are_jumpers no)
		(fp_line
			(start -0.7874 0.4064)
			(end -0.7874 -0.4064)
			(stroke
				(width 0.1524)
				(type default)
			)
			(layer "F.SilkS")
		)
		(fp_line
			(start 0.7874 0.4064)
			(end -0.7874 0.4064)
			(stroke
				(width 0.1524)
				(type default)
			)
			(layer "F.SilkS")
		)
		(fp_line
			(start -0.7874 -0.4064)
			(end 0.7874 -0.4064)
			(stroke
				(width 0.1524)
				(type default)
			)
			(layer "F.SilkS")
		)
		(fp_line
			(start 0.7874 -0.4064)
			(end 0.7874 0.4064)
			(stroke
				(width 0.1524)
				(type default)
			)
			(layer "F.SilkS")
		)
		(fp_line
			(start -0.67945 0.3048)
			(end -0.67945 -0.305054)
			(stroke
				(width 0.1)
				(type default)
			)
			(layer "F.Fab")
		)
		(fp_line
			(start -0.12065 0.3048)
			(end -0.67945 0.3048)
			(stroke
				(width 0.1)
				(type default)
			)
			(layer "F.Fab")
		)
		(fp_line
			(start 0.120396 0.3048)
			(end 0.120396 0.2794)
			(stroke
				(width 0.1)
				(type default)
			)
			(layer "F.Fab")
		)
		(fp_line
			(start 0.67945 0.3048)
			(end 0.120396 0.3048)
			(stroke
				(width 0.1)
				(type default)
			)
			(layer "F.Fab")
		)
		(fp_line
			(start -0.12065 0.2794)
			(end -0.12065 0.3048)
			(stroke
				(width 0.1)
				(type default)
			)
			(layer "F.Fab")
		)
		(fp_line
			(start 0.120396 0.2794)
			(end -0.12065 0.2794)
			(stroke
				(width 0.1)
				(type default)
			)
			(layer "F.Fab")
		)
		(fp_line
			(start -0.12065 -0.2794)
			(end 0.12065 -0.2794)
			(stroke
				(width 0.1)
				(type default)
			)
			(layer "F.Fab")
		)
		(fp_line
			(start 0.12065 -0.2794)
			(end 0.12065 -0.3048)
			(stroke
				(width 0.1)
				(type default)
			)
			(layer "F.Fab")
		)
		(fp_line
			(start 0.12065 -0.3048)
			(end 0.67945 -0.3048)
			(stroke
				(width 0.1)
				(type default)
			)
			(layer "F.Fab")
		)
		(fp_line
			(start 0.67945 -0.3048)
			(end 0.67945 0.3048)
			(stroke
				(width 0.1)
				(type default)
			)
			(layer "F.Fab")
		)
		(fp_line
			(start -0.67945 -0.305054)
			(end -0.12065 -0.305054)
			(stroke
				(width 0.1)
				(type default)
			)
			(layer "F.Fab")
		)
		(fp_line
			(start -0.12065 -0.305054)
			(end -0.12065 -0.2794)
			(stroke
				(width 0.1)
				(type default)
			)
			(layer "F.Fab")
		)
		(pad "1" smd circle
			(at -0.40005 0 270)
			(size 0 0)
			(layers "F.Cu" "F.Mask" "F.Paste")
			(net "RST_PCA9548_SENSOR_R_N")
		)
		(pad "2" smd circle
			(at 0.40005 0 270)
			(size 0 0)
			(layers "F.Cu" "F.Mask" "F.Paste")
			(net "RST_PCA9548_SENSOR_N")
		)
	)
	(footprint ""
		(layer "F.Cu")
		(at 23.61946 -108.71708 180)
		(property "Reference" "C161"
			(at 0 0 180)
			(layer "F.SilkS")
			(hide yes)
			(effects
				(font
					(size 1.27 1.27)
				)
			)
		)
		(property "Value" ""
			(at 0 0 180)
			(layer "F.Fab")
			(effects
				(font
					(size 1.27 1.27)
				)
			)
		)
		(duplicate_pad_numbers_are_jumpers no)
		(fp_line
			(start 0.7874 0.4064)
			(end -0.7874 0.4064)
			(stroke
				(width 0.1524)
				(type default)
			)
			(layer "F.SilkS")
		)
		(fp_line
			(start 0.7874 -0.4064)
			(end 0.7874 0.4064)
			(stroke
				(width 0.1524)
				(type default)
			)
			(layer "F.SilkS")
		)
		(fp_line
			(start -0.7874 0.4064)
			(end -0.7874 -0.4064)
			(stroke
				(width 0.1524)
				(type default)
			)
			(layer "F.SilkS")
		)
		(fp_line
			(start -0.7874 -0.4064)
			(end 0.7874 -0.4064)
			(stroke
				(width 0.1524)
				(type default)
			)
			(layer "F.SilkS")
		)
		(fp_line
			(start 0.67945 0.3048)
			(end 0.120396 0.3048)
			(stroke
				(width 0.1)
				(type default)
			)
			(layer "F.Fab")
		)
		(fp_line
			(start 0.67945 -0.3048)
			(end 0.67945 0.3048)
			(stroke
				(width 0.1)
				(type default)
			)
			(layer "F.Fab")
		)
		(fp_line
			(start 0.12065 -0.2794)
			(end 0.12065 -0.3048)
			(stroke
				(width 0.1)
				(type default)
			)
			(layer "F.Fab")
		)
		(fp_line
			(start 0.12065 -0.3048)
			(end 0.67945 -0.3048)
			(stroke
				(width 0.1)
				(type default)
			)
			(layer "F.Fab")
		)
		(fp_line
			(start 0.120396 0.3048)
			(end 0.120396 0.2794)
			(stroke
				(width 0.1)
				(type default)
			)
			(layer "F.Fab")
		)
		(fp_line
			(start 0.120396 0.2794)
			(end -0.12065 0.2794)
			(stroke
				(width 0.1)
				(type default)
			)
			(layer "F.Fab")
		)
		(fp_line
			(start -0.12065 0.3048)
			(end -0.67945 0.3048)
			(stroke
				(width 0.1)
				(type default)
			)
			(layer "F.Fab")
		)
		(fp_line
			(start -0.12065 0.2794)
			(end -0.12065 0.3048)
			(stroke
				(width 0.1)
				(type default)
			)
			(layer "F.Fab")
		)
		(fp_line
			(start -0.12065 -0.2794)
			(end 0.12065 -0.2794)
			(stroke
				(width 0.1)
				(type default)
			)
			(layer "F.Fab")
		)
		(fp_line
			(start -0.12065 -0.305054)
			(end -0.12065 -0.2794)
			(stroke
				(width 0.1)
				(type default)
			)
			(layer "F.Fab")
		)
		(fp_line
			(start -0.67945 0.3048)
			(end -0.67945 -0.305054)
			(stroke
				(width 0.1)
				(type default)
			)
			(layer "F.Fab")
		)
		(fp_line
			(start -0.67945 -0.305054)
			(end -0.12065 -0.305054)
			(stroke
				(width 0.1)
				(type default)
			)
			(layer "F.Fab")
		)
		(pad "1" smd circle
			(at -0.40005 0 180)
			(size 0 0)
			(layers "F.Cu" "F.Mask" "F.Paste")
			(net "RST_BMC_SELF_HW_D")
		)
		(pad "2" smd circle
			(at 0.40005 0 180)
			(size 0 0)
			(layers "F.Cu" "F.Mask" "F.Paste")
			(net "RST_BMC_SELF_HW_D_C")
		)
	)
	(footprint ""
		(layer "F.Cu")
		(at 30.2514 -101.0412 -90)
		(property "Reference" "R769"
			(at 0 0 270)
			(layer "F.SilkS")
			(hide yes)
			(effects
				(font
					(size 1.27 1.27)
				)
			)
		)
		(property "Value" ""
			(at 0 0 270)
			(layer "F.Fab")
			(effects
				(font
					(size 1.27 1.27)
				)
			)
		)
		(duplicate_pad_numbers_are_jumpers no)
		(fp_line
			(start -0.7874 0.4064)
			(end -0.7874 -0.4064)
			(stroke
				(width 0.1524)
				(type default)
			)
			(layer "F.SilkS")
		)
		(fp_line
			(start 0.7874 0.4064)
			(end -0.7874 0.4064)
			(stroke
				(width 0.1524)
				(type default)
			)
			(layer "F.SilkS")
		)
		(fp_line
			(start -0.7874 -0.4064)
			(end 0.7874 -0.4064)
			(stroke
				(width 0.1524)
				(type default)
			)
			(layer "F.SilkS")
		)
		(fp_line
			(start 0.7874 -0.4064)
			(end 0.7874 0.4064)
			(stroke
				(width 0.1524)
				(type default)
			)
			(layer "F.SilkS")
		)
		(fp_line
			(start -0.67945 0.3048)
			(end -0.67945 -0.305054)
			(stroke
				(width 0.1)
				(type default)
			)
			(layer "F.Fab")
		)
		(fp_line
			(start -0.12065 0.3048)
			(end -0.67945 0.3048)
			(stroke
				(width 0.1)
				(type default)
			)
			(layer "F.Fab")
		)
		(fp_line
			(start 0.120396 0.3048)
			(end 0.120396 0.2794)
			(stroke
				(width 0.1)
				(type default)
			)
			(layer "F.Fab")
		)
		(fp_line
			(start 0.67945 0.3048)
			(end 0.120396 0.3048)
			(stroke
				(width 0.1)
				(type default)
			)
			(layer "F.Fab")
		)
		(fp_line
			(start -0.12065 0.2794)
			(end -0.12065 0.3048)
			(stroke
				(width 0.1)
				(type default)
			)
			(layer "F.Fab")
		)
		(fp_line
			(start 0.120396 0.2794)
			(end -0.12065 0.2794)
			(stroke
				(width 0.1)
				(type default)
			)
			(layer "F.Fab")
		)
		(fp_line
			(start -0.12065 -0.2794)
			(end 0.12065 -0.2794)
			(stroke
				(width 0.1)
				(type default)
			)
			(layer "F.Fab")
		)
		(fp_line
			(start 0.12065 -0.2794)
			(end 0.12065 -0.3048)
			(stroke
				(width 0.1)
				(type default)
			)
			(layer "F.Fab")
		)
		(fp_line
			(start 0.12065 -0.3048)
			(end 0.67945 -0.3048)
			(stroke
				(width 0.1)
				(type default)
			)
			(layer "F.Fab")
		)
		(fp_line
			(start 0.67945 -0.3048)
			(end 0.67945 0.3048)
			(stroke
				(width 0.1)
				(type default)
			)
			(layer "F.Fab")
		)
		(fp_line
			(start -0.67945 -0.305054)
			(end -0.12065 -0.305054)
			(stroke
				(width 0.1)
				(type default)
			)
			(layer "F.Fab")
		)
		(fp_line
			(start -0.12065 -0.305054)
			(end -0.12065 -0.2794)
			(stroke
				(width 0.1)
				(type default)
			)
			(layer "F.Fab")
		)
		(pad "1" smd circle
			(at -0.40005 0 270)
			(size 0 0)
			(layers "F.Cu" "F.Mask" "F.Paste")
			(net "FM_THROTTLE_N")
		)
		(pad "2" smd circle
			(at 0.40005 0 270)
			(size 0 0)
			(layers "F.Cu" "F.Mask" "F.Paste")
			(net "FM_THROTTLE_R_N")
		)
	)
	(footprint ""
		(layer "F.Cu")
		(at 7.28091 -62.512702 180)
		(property "Reference" "PC223"
			(at 0 0 180)
			(layer "F.SilkS")
			(hide yes)
			(effects
				(font
					(size 1.27 1.27)
				)
			)
		)
		(property "Value" ""
			(at 0 0 180)
			(layer "F.Fab")
			(effects
				(font
					(size 1.27 1.27)
				)
			)
		)
		(duplicate_pad_numbers_are_jumpers no)
		(fp_line
			(start 0.7874 0.4064)
			(end -0.7874 0.4064)
			(stroke
				(width 0.1524)
				(type default)
			)
			(layer "F.SilkS")
		)
		(fp_line
			(start 0.7874 -0.4064)
			(end 0.7874 0.4064)
			(stroke
				(width 0.1524)
				(type default)
			)
			(layer "F.SilkS")
		)
		(fp_line
			(start -0.7874 0.4064)
			(end -0.7874 -0.4064)
			(stroke
				(width 0.1524)
				(type default)
			)
			(layer "F.SilkS")
		)
		(fp_line
			(start -0.7874 -0.4064)
			(end 0.7874 -0.4064)
			(stroke
				(width 0.1524)
				(type default)
			)
			(layer "F.SilkS")
		)
		(fp_line
			(start 0.67945 0.3048)
			(end 0.120396 0.3048)
			(stroke
				(width 0.1)
				(type default)
			)
			(layer "F.Fab")
		)
		(fp_line
			(start 0.67945 -0.3048)
			(end 0.67945 0.3048)
			(stroke
				(width 0.1)
				(type default)
			)
			(layer "F.Fab")
		)
		(fp_line
			(start 0.12065 -0.2794)
			(end 0.12065 -0.3048)
			(stroke
				(width 0.1)
				(type default)
			)
			(layer "F.Fab")
		)
		(fp_line
			(start 0.12065 -0.3048)
			(end 0.67945 -0.3048)
			(stroke
				(width 0.1)
				(type default)
			)
			(layer "F.Fab")
		)
		(fp_line
			(start 0.120396 0.3048)
			(end 0.120396 0.2794)
			(stroke
				(width 0.1)
				(type default)
			)
			(layer "F.Fab")
		)
		(fp_line
			(start 0.120396 0.2794)
			(end -0.12065 0.2794)
			(stroke
				(width 0.1)
				(type default)
			)
			(layer "F.Fab")
		)
		(fp_line
			(start -0.12065 0.3048)
			(end -0.67945 0.3048)
			(stroke
				(width 0.1)
				(type default)
			)
			(layer "F.Fab")
		)
		(fp_line
			(start -0.12065 0.2794)
			(end -0.12065 0.3048)
			(stroke
				(width 0.1)
				(type default)
			)
			(layer "F.Fab")
		)
		(fp_line
			(start -0.12065 -0.2794)
			(end 0.12065 -0.2794)
			(stroke
				(width 0.1)
				(type default)
			)
			(layer "F.Fab")
		)
		(fp_line
			(start -0.12065 -0.305054)
			(end -0.12065 -0.2794)
			(stroke
				(width 0.1)
				(type default)
			)
			(layer "F.Fab")
		)
		(fp_line
			(start -0.67945 0.3048)
			(end -0.67945 -0.305054)
			(stroke
				(width 0.1)
				(type default)
			)
			(layer "F.Fab")
		)
		(fp_line
			(start -0.67945 -0.305054)
			(end -0.12065 -0.305054)
			(stroke
				(width 0.1)
				(type default)
			)
			(layer "F.Fab")
		)
		(pad "1" smd circle
			(at -0.40005 0 180)
			(size 0 0)
			(layers "F.Cu" "F.Mask" "F.Paste")
			(net "SW_P3V3_AUX_FLT")
		)
		(pad "2" smd circle
			(at 0.40005 0 180)
			(size 0 0)
			(layers "F.Cu" "F.Mask" "F.Paste")
			(net "GND")
		)
	)
	(footprint ""
		(layer "F.Cu")
		(at 85.29955 -43.157394 180)
		(property "Reference" "R335"
			(at 0 0 180)
			(layer "F.SilkS")
			(hide yes)
			(effects
				(font
					(size 1.27 1.27)
				)
			)
		)
		(property "Value" ""
			(at 0 0 180)
			(layer "F.Fab")
			(effects
				(font
					(size 1.27 1.27)
				)
			)
		)
		(duplicate_pad_numbers_are_jumpers no)
		(fp_line
			(start 0.7874 0.4064)
			(end -0.7874 0.4064)
			(stroke
				(width 0.1524)
				(type default)
			)
			(layer "F.SilkS")
		)
		(fp_line
			(start 0.7874 -0.4064)
			(end 0.7874 0.4064)
			(stroke
				(width 0.1524)
				(type default)
			)
			(layer "F.SilkS")
		)
		(fp_line
			(start -0.7874 0.4064)
			(end -0.7874 -0.4064)
			(stroke
				(width 0.1524)
				(type default)
			)
			(layer "F.SilkS")
		)
		(fp_line
			(start -0.7874 -0.4064)
			(end 0.7874 -0.4064)
			(stroke
				(width 0.1524)
				(type default)
			)
			(layer "F.SilkS")
		)
		(fp_line
			(start 0.67945 0.3048)
			(end 0.120396 0.3048)
			(stroke
				(width 0.1)
				(type default)
			)
			(layer "F.Fab")
		)
		(fp_line
			(start 0.67945 -0.3048)
			(end 0.67945 0.3048)
			(stroke
				(width 0.1)
				(type default)
			)
			(layer "F.Fab")
		)
		(fp_line
			(start 0.12065 -0.2794)
			(end 0.12065 -0.3048)
			(stroke
				(width 0.1)
				(type default)
			)
			(layer "F.Fab")
		)
		(fp_line
			(start 0.12065 -0.3048)
			(end 0.67945 -0.3048)
			(stroke
				(width 0.1)
				(type default)
			)
			(layer "F.Fab")
		)
		(fp_line
			(start 0.120396 0.3048)
			(end 0.120396 0.2794)
			(stroke
				(width 0.1)
				(type default)
			)
			(layer "F.Fab")
		)
		(fp_line
			(start 0.120396 0.2794)
			(end -0.12065 0.2794)
			(stroke
				(width 0.1)
				(type default)
			)
			(layer "F.Fab")
		)
		(fp_line
			(start -0.12065 0.3048)
			(end -0.67945 0.3048)
			(stroke
				(width 0.1)
				(type default)
			)
			(layer "F.Fab")
		)
		(fp_line
			(start -0.12065 0.2794)
			(end -0.12065 0.3048)
			(stroke
				(width 0.1)
				(type default)
			)
			(layer "F.Fab")
		)
		(fp_line
			(start -0.12065 -0.2794)
			(end 0.12065 -0.2794)
			(stroke
				(width 0.1)
				(type default)
			)
			(layer "F.Fab")
		)
		(fp_line
			(start -0.12065 -0.305054)
			(end -0.12065 -0.2794)
			(stroke
				(width 0.1)
				(type default)
			)
			(layer "F.Fab")
		)
		(fp_line
			(start -0.67945 0.3048)
			(end -0.67945 -0.305054)
			(stroke
				(width 0.1)
				(type default)
			)
			(layer "F.Fab")
		)
		(fp_line
			(start -0.67945 -0.305054)
			(end -0.12065 -0.305054)
			(stroke
				(width 0.1)
				(type default)
			)
			(layer "F.Fab")
		)
		(pad "1" smd circle
			(at -0.40005 0 180)
			(size 0 0)
			(layers "F.Cu" "F.Mask" "F.Paste")
			(net "GND")
		)
		(pad "2" smd circle
			(at 0.40005 0 180)
			(size 0 0)
			(layers "F.Cu" "F.Mask" "F.Paste")
			(net "M_BMC_DDR4_MA<9>")
		)
	)
	(footprint ""
		(layer "F.Cu")
		(at 64.9732 -24.1554 180)
		(property "Reference" "R511"
			(at 0 0 180)
			(layer "F.SilkS")
			(hide yes)
			(effects
				(font
					(size 1.27 1.27)
				)
			)
		)
		(property "Value" ""
			(at 0 0 180)
			(layer "F.Fab")
			(effects
				(font
					(size 1.27 1.27)
				)
			)
		)
		(duplicate_pad_numbers_are_jumpers no)
		(fp_line
			(start 0.7874 0.4064)
			(end -0.7874 0.4064)
			(stroke
				(width 0.1524)
				(type default)
			)
			(layer "F.SilkS")
		)
		(fp_line
			(start 0.7874 -0.4064)
			(end 0.7874 0.4064)
			(stroke
				(width 0.1524)
				(type default)
			)
			(layer "F.SilkS")
		)
		(fp_line
			(start -0.7874 0.4064)
			(end -0.7874 -0.4064)
			(stroke
				(width 0.1524)
				(type default)
			)
			(layer "F.SilkS")
		)
		(fp_line
			(start -0.7874 -0.4064)
			(end 0.7874 -0.4064)
			(stroke
				(width 0.1524)
				(type default)
			)
			(layer "F.SilkS")
		)
		(fp_line
			(start 0.67945 0.3048)
			(end 0.120396 0.3048)
			(stroke
				(width 0.1)
				(type default)
			)
			(layer "F.Fab")
		)
		(fp_line
			(start 0.67945 -0.3048)
			(end 0.67945 0.3048)
			(stroke
				(width 0.1)
				(type default)
			)
			(layer "F.Fab")
		)
		(fp_line
			(start 0.12065 -0.2794)
			(end 0.12065 -0.3048)
			(stroke
				(width 0.1)
				(type default)
			)
			(layer "F.Fab")
		)
		(fp_line
			(start 0.12065 -0.3048)
			(end 0.67945 -0.3048)
			(stroke
				(width 0.1)
				(type default)
			)
			(layer "F.Fab")
		)
		(fp_line
			(start 0.120396 0.3048)
			(end 0.120396 0.2794)
			(stroke
				(width 0.1)
				(type default)
			)
			(layer "F.Fab")
		)
		(fp_line
			(start 0.120396 0.2794)
			(end -0.12065 0.2794)
			(stroke
				(width 0.1)
				(type default)
			)
			(layer "F.Fab")
		)
		(fp_line
			(start -0.12065 0.3048)
			(end -0.67945 0.3048)
			(stroke
				(width 0.1)
				(type default)
			)
			(layer "F.Fab")
		)
		(fp_line
			(start -0.12065 0.2794)
			(end -0.12065 0.3048)
			(stroke
				(width 0.1)
				(type default)
			)
			(layer "F.Fab")
		)
		(fp_line
			(start -0.12065 -0.2794)
			(end 0.12065 -0.2794)
			(stroke
				(width 0.1)
				(type default)
			)
			(layer "F.Fab")
		)
		(fp_line
			(start -0.12065 -0.305054)
			(end -0.12065 -0.2794)
			(stroke
				(width 0.1)
				(type default)
			)
			(layer "F.Fab")
		)
		(fp_line
			(start -0.67945 0.3048)
			(end -0.67945 -0.305054)
			(stroke
				(width 0.1)
				(type default)
			)
			(layer "F.Fab")
		)
		(fp_line
			(start -0.67945 -0.305054)
			(end -0.12065 -0.305054)
			(stroke
				(width 0.1)
				(type default)
			)
			(layer "F.Fab")
		)
		(pad "1" smd circle
			(at -0.40005 0 180)
			(size 0 0)
			(layers "F.Cu" "F.Mask" "F.Paste")
			(net "JTAG_SCM_TMS")
		)
		(pad "2" smd circle
			(at 0.40005 0 180)
			(size 0 0)
			(layers "F.Cu" "F.Mask" "F.Paste")
			(net "JTAG_SCM_PLD_TMS")
		)
	)
	(footprint ""
		(layer "F.Cu")
		(at 17.4752 -83.7692 -90)
		(property "Reference" "R447"
			(at 0 0 270)
			(layer "F.SilkS")
			(hide yes)
			(effects
				(font
					(size 1.27 1.27)
				)
			)
		)
		(property "Value" ""
			(at 0 0 270)
			(layer "F.Fab")
			(effects
				(font
					(size 1.27 1.27)
				)
			)
		)
		(duplicate_pad_numbers_are_jumpers no)
		(fp_line
			(start -0.7874 0.4064)
			(end -0.7874 -0.4064)
			(stroke
				(width 0.1524)
				(type default)
			)
			(layer "F.SilkS")
		)
		(fp_line
			(start 0.7874 0.4064)
			(end -0.7874 0.4064)
			(stroke
				(width 0.1524)
				(type default)
			)
			(layer "F.SilkS")
		)
		(fp_line
			(start -0.7874 -0.4064)
			(end 0.7874 -0.4064)
			(stroke
				(width 0.1524)
				(type default)
			)
			(layer "F.SilkS")
		)
		(fp_line
			(start 0.7874 -0.4064)
			(end 0.7874 0.4064)
			(stroke
				(width 0.1524)
				(type default)
			)
			(layer "F.SilkS")
		)
		(fp_line
			(start -0.67945 0.3048)
			(end -0.67945 -0.305054)
			(stroke
				(width 0.1)
				(type default)
			)
			(layer "F.Fab")
		)
		(fp_line
			(start -0.12065 0.3048)
			(end -0.67945 0.3048)
			(stroke
				(width 0.1)
				(type default)
			)
			(layer "F.Fab")
		)
		(fp_line
			(start 0.120396 0.3048)
			(end 0.120396 0.2794)
			(stroke
				(width 0.1)
				(type default)
			)
			(layer "F.Fab")
		)
		(fp_line
			(start 0.67945 0.3048)
			(end 0.120396 0.3048)
			(stroke
				(width 0.1)
				(type default)
			)
			(layer "F.Fab")
		)
		(fp_line
			(start -0.12065 0.2794)
			(end -0.12065 0.3048)
			(stroke
				(width 0.1)
				(type default)
			)
			(layer "F.Fab")
		)
		(fp_line
			(start 0.120396 0.2794)
			(end -0.12065 0.2794)
			(stroke
				(width 0.1)
				(type default)
			)
			(layer "F.Fab")
		)
		(fp_line
			(start -0.12065 -0.2794)
			(end 0.12065 -0.2794)
			(stroke
				(width 0.1)
				(type default)
			)
			(layer "F.Fab")
		)
		(fp_line
			(start 0.12065 -0.2794)
			(end 0.12065 -0.3048)
			(stroke
				(width 0.1)
				(type default)
			)
			(layer "F.Fab")
		)
		(fp_line
			(start 0.12065 -0.3048)
			(end 0.67945 -0.3048)
			(stroke
				(width 0.1)
				(type default)
			)
			(layer "F.Fab")
		)
		(fp_line
			(start 0.67945 -0.3048)
			(end 0.67945 0.3048)
			(stroke
				(width 0.1)
				(type default)
			)
			(layer "F.Fab")
		)
		(fp_line
			(start -0.67945 -0.305054)
			(end -0.12065 -0.305054)
			(stroke
				(width 0.1)
				(type default)
			)
			(layer "F.Fab")
		)
		(fp_line
			(start -0.12065 -0.305054)
			(end -0.12065 -0.2794)
			(stroke
				(width 0.1)
				(type default)
			)
			(layer "F.Fab")
		)
		(pad "1" smd circle
			(at -0.40005 0 270)
			(size 0 0)
			(layers "F.Cu" "F.Mask" "F.Paste")
			(net "RST_EXTRST_R_N")
		)
		(pad "2" smd circle
			(at 0.40005 0 270)
			(size 0 0)
			(layers "F.Cu" "F.Mask" "F.Paste")
			(net "RST_EXTRST_N")
		)
	)
	(footprint ""
		(layer "F.Cu")
		(at 31.56204 -68.504054 90)
		(property "Reference" "R652"
			(at 0 0 90)
			(layer "F.SilkS")
			(hide yes)
			(effects
				(font
					(size 1.27 1.27)
				)
			)
		)
		(property "Value" ""
			(at 0 0 90)
			(layer "F.Fab")
			(effects
				(font
					(size 1.27 1.27)
				)
			)
		)
		(duplicate_pad_numbers_are_jumpers no)
		(fp_line
			(start 0.7874 -0.4064)
			(end 0.7874 0.4064)
			(stroke
				(width 0.1524)
				(type default)
			)
			(layer "F.SilkS")
		)
		(fp_line
			(start -0.7874 -0.4064)
			(end 0.7874 -0.4064)
			(stroke
				(width 0.1524)
				(type default)
			)
			(layer "F.SilkS")
		)
		(fp_line
			(start 0.7874 0.4064)
			(end -0.7874 0.4064)
			(stroke
				(width 0.1524)
				(type default)
			)
			(layer "F.SilkS")
		)
		(fp_line
			(start -0.7874 0.4064)
			(end -0.7874 -0.4064)
			(stroke
				(width 0.1524)
				(type default)
			)
			(layer "F.SilkS")
		)
		(fp_line
			(start -0.12065 -0.305054)
			(end -0.12065 -0.2794)
			(stroke
				(width 0.1)
				(type default)
			)
			(layer "F.Fab")
		)
		(fp_line
			(start -0.67945 -0.305054)
			(end -0.12065 -0.305054)
			(stroke
				(width 0.1)
				(type default)
			)
			(layer "F.Fab")
		)
		(fp_line
			(start 0.67945 -0.3048)
			(end 0.67945 0.3048)
			(stroke
				(width 0.1)
				(type default)
			)
			(layer "F.Fab")
		)
		(fp_line
			(start 0.12065 -0.3048)
			(end 0.67945 -0.3048)
			(stroke
				(width 0.1)
				(type default)
			)
			(layer "F.Fab")
		)
		(fp_line
			(start 0.12065 -0.2794)
			(end 0.12065 -0.3048)
			(stroke
				(width 0.1)
				(type default)
			)
			(layer "F.Fab")
		)
		(fp_line
			(start -0.12065 -0.2794)
			(end 0.12065 -0.2794)
			(stroke
				(width 0.1)
				(type default)
			)
			(layer "F.Fab")
		)
		(fp_line
			(start 0.120396 0.2794)
			(end -0.12065 0.2794)
			(stroke
				(width 0.1)
				(type default)
			)
			(layer "F.Fab")
		)
		(fp_line
			(start -0.12065 0.2794)
			(end -0.12065 0.3048)
			(stroke
				(width 0.1)
				(type default)
			)
			(layer "F.Fab")
		)
		(fp_line
			(start 0.67945 0.3048)
			(end 0.120396 0.3048)
			(stroke
				(width 0.1)
				(type default)
			)
			(layer "F.Fab")
		)
		(fp_line
			(start 0.120396 0.3048)
			(end 0.120396 0.2794)
			(stroke
				(width 0.1)
				(type default)
			)
			(layer "F.Fab")
		)
		(fp_line
			(start -0.12065 0.3048)
			(end -0.67945 0.3048)
			(stroke
				(width 0.1)
				(type default)
			)
			(layer "F.Fab")
		)
		(fp_line
			(start -0.67945 0.3048)
			(end -0.67945 -0.305054)
			(stroke
				(width 0.1)
				(type default)
			)
			(layer "F.Fab")
		)
		(pad "1" smd circle
			(at -0.40005 0 90)
			(size 0 0)
			(layers "F.Cu" "F.Mask" "F.Paste")
			(net "BMC_EMMC_DT5")
		)
		(pad "2" smd circle
			(at 0.40005 0 90)
			(size 0 0)
			(layers "F.Cu" "F.Mask" "F.Paste")
			(net "EMMC_DT5_R")
		)
	)
	(footprint ""
		(layer "F.Cu")
		(at 28.270454 -17.008602)
		(property "Reference" "R385"
			(at 0 0 0)
			(layer "F.SilkS")
			(hide yes)
			(effects
				(font
					(size 1.27 1.27)
				)
			)
		)
		(property "Value" ""
			(at 0 0 0)
			(layer "F.Fab")
			(effects
				(font
					(size 1.27 1.27)
				)
			)
		)
		(duplicate_pad_numbers_are_jumpers no)
		(fp_line
			(start -0.7874 -0.4064)
			(end 0.7874 -0.4064)
			(stroke
				(width 0.1524)
				(type default)
			)
			(layer "F.SilkS")
		)
		(fp_line
			(start 0.7874 0.4064)
			(end -0.7874 0.4064)
			(stroke
				(width 0.1524)
				(type default)
			)
			(layer "F.SilkS")
		)
		(fp_line
			(start -0.67945 -0.305054)
			(end -0.12065 -0.305054)
			(stroke
				(width 0.1)
				(type default)
			)
			(layer "F.Fab")
		)
		(fp_line
			(start -0.67945 0.3048)
			(end -0.67945 -0.305054)
			(stroke
				(width 0.1)
				(type default)
			)
			(layer "F.Fab")
		)
		(fp_line
			(start -0.12065 -0.305054)
			(end -0.12065 -0.2794)
			(stroke
				(width 0.1)
				(type default)
			)
			(layer "F.Fab")
		)
		(fp_line
			(start -0.12065 -0.2794)
			(end 0.12065 -0.2794)
			(stroke
				(width 0.1)
				(type default)
			)
			(layer "F.Fab")
		)
		(fp_line
			(start -0.12065 0.2794)
			(end -0.12065 0.3048)
			(stroke
				(width 0.1)
				(type default)
			)
			(layer "F.Fab")
		)
		(fp_line
			(start -0.12065 0.3048)
			(end -0.67945 0.3048)
			(stroke
				(width 0.1)
				(type default)
			)
			(layer "F.Fab")
		)
		(fp_line
			(start 0.120396 0.2794)
			(end -0.12065 0.2794)
			(stroke
				(width 0.1)
				(type default)
			)
			(layer "F.Fab")
		)
		(fp_line
			(start 0.120396 0.3048)
			(end 0.120396 0.2794)
			(stroke
				(width 0.1)
				(type default)
			)
			(layer "F.Fab")
		)
		(fp_line
			(start 0.12065 -0.3048)
			(end 0.67945 -0.3048)
			(stroke
				(width 0.1)
				(type default)
			)
			(layer "F.Fab")
		)
		(fp_line
			(start 0.12065 -0.2794)
			(end 0.12065 -0.3048)
			(stroke
				(width 0.1)
				(type default)
			)
			(layer "F.Fab")
		)
		(fp_line
			(start 0.67945 -0.3048)
			(end 0.67945 0.3048)
			(stroke
				(width 0.1)
				(type default)
			)
			(layer "F.Fab")
		)
		(fp_line
			(start 0.67945 0.3048)
			(end 0.120396 0.3048)
			(stroke
				(width 0.1)
				(type default)
			)
			(layer "F.Fab")
		)
		(pad "1" smd circle
			(at -0.40005 0)
			(size 0 0)
			(layers "F.Cu" "F.Mask" "F.Paste")
			(net "USB_FPNL_DN")
		)
		(pad "2" smd circle
			(at 0.40005 0)
			(size 0 0)
			(layers "F.Cu" "F.Mask" "F.Paste")
			(net "USB2_01_F_DN")
		)
	)
	(footprint ""
		(layer "F.Cu")
		(at 79.739744 -37.559488 -90)
		(property "Reference" "R373"
			(at 0 0 270)
			(layer "F.SilkS")
			(hide yes)
			(effects
				(font
					(size 1.27 1.27)
				)
			)
		)
		(property "Value" ""
			(at 0 0 270)
			(layer "F.Fab")
			(effects
				(font
					(size 1.27 1.27)
				)
			)
		)
		(duplicate_pad_numbers_are_jumpers no)
		(fp_line
			(start -0.7874 0.4064)
			(end -0.7874 -0.4064)
			(stroke
				(width 0.1524)
				(type default)
			)
			(layer "F.SilkS")
		)
		(fp_line
			(start 0.7874 0.4064)
			(end -0.7874 0.4064)
			(stroke
				(width 0.1524)
				(type default)
			)
			(layer "F.SilkS")
		)
		(fp_line
			(start -0.7874 -0.4064)
			(end 0.7874 -0.4064)
			(stroke
				(width 0.1524)
				(type default)
			)
			(layer "F.SilkS")
		)
		(fp_line
			(start 0.7874 -0.4064)
			(end 0.7874 0.4064)
			(stroke
				(width 0.1524)
				(type default)
			)
			(layer "F.SilkS")
		)
		(fp_line
			(start -0.67945 0.3048)
			(end -0.67945 -0.305054)
			(stroke
				(width 0.1)
				(type default)
			)
			(layer "F.Fab")
		)
		(fp_line
			(start -0.12065 0.3048)
			(end -0.67945 0.3048)
			(stroke
				(width 0.1)
				(type default)
			)
			(layer "F.Fab")
		)
		(fp_line
			(start 0.120396 0.3048)
			(end 0.120396 0.2794)
			(stroke
				(width 0.1)
				(type default)
			)
			(layer "F.Fab")
		)
		(fp_line
			(start 0.67945 0.3048)
			(end 0.120396 0.3048)
			(stroke
				(width 0.1)
				(type default)
			)
			(layer "F.Fab")
		)
		(fp_line
			(start -0.12065 0.2794)
			(end -0.12065 0.3048)
			(stroke
				(width 0.1)
				(type default)
			)
			(layer "F.Fab")
		)
		(fp_line
			(start 0.120396 0.2794)
			(end -0.12065 0.2794)
			(stroke
				(width 0.1)
				(type default)
			)
			(layer "F.Fab")
		)
		(fp_line
			(start -0.12065 -0.2794)
			(end 0.12065 -0.2794)
			(stroke
				(width 0.1)
				(type default)
			)
			(layer "F.Fab")
		)
		(fp_line
			(start 0.12065 -0.2794)
			(end 0.12065 -0.3048)
			(stroke
				(width 0.1)
				(type default)
			)
			(layer "F.Fab")
		)
		(fp_line
			(start 0.12065 -0.3048)
			(end 0.67945 -0.3048)
			(stroke
				(width 0.1)
				(type default)
			)
			(layer "F.Fab")
		)
		(fp_line
			(start 0.67945 -0.3048)
			(end 0.67945 0.3048)
			(stroke
				(width 0.1)
				(type default)
			)
			(layer "F.Fab")
		)
		(fp_line
			(start -0.67945 -0.305054)
			(end -0.12065 -0.305054)
			(stroke
				(width 0.1)
				(type default)
			)
			(layer "F.Fab")
		)
		(fp_line
			(start -0.12065 -0.305054)
			(end -0.12065 -0.2794)
			(stroke
				(width 0.1)
				(type default)
			)
			(layer "F.Fab")
		)
		(pad "1" smd circle
			(at -0.40005 0 270)
			(size 0 0)
			(layers "F.Cu" "F.Mask" "F.Paste")
			(net "M_BMC_DDR4_MODT")
		)
		(pad "2" smd circle
			(at 0.40005 0 270)
			(size 0 0)
			(layers "F.Cu" "F.Mask" "F.Paste")
			(net "P1V2_AUX")
		)
	)
	(footprint ""
		(layer "F.Cu")
		(at 40.222678 -53.992272)
		(property "Reference" "C294"
			(at 0 0 0)
			(layer "F.SilkS")
			(hide yes)
			(effects
				(font
					(size 1.27 1.27)
				)
			)
		)
		(property "Value" ""
			(at 0 0 0)
			(layer "F.Fab")
			(effects
				(font
					(size 1.27 1.27)
				)
			)
		)
		(duplicate_pad_numbers_are_jumpers no)
		(fp_line
			(start -0.7874 -0.4064)
			(end 0.7874 -0.4064)
			(stroke
				(width 0.1524)
				(type default)
			)
			(layer "F.SilkS")
		)
		(fp_line
			(start -0.7874 0.4064)
			(end -0.7874 -0.4064)
			(stroke
				(width 0.1524)
				(type default)
			)
			(layer "F.SilkS")
		)
		(fp_line
			(start 0.7874 -0.4064)
			(end 0.7874 0.4064)
			(stroke
				(width 0.1524)
				(type default)
			)
			(layer "F.SilkS")
		)
		(fp_line
			(start 0.7874 0.4064)
			(end -0.7874 0.4064)
			(stroke
				(width 0.1524)
				(type default)
			)
			(layer "F.SilkS")
		)
		(fp_line
			(start -0.67945 -0.305054)
			(end -0.12065 -0.305054)
			(stroke
				(width 0.1)
				(type default)
			)
			(layer "F.Fab")
		)
		(fp_line
			(start -0.67945 0.3048)
			(end -0.67945 -0.305054)
			(stroke
				(width 0.1)
				(type default)
			)
			(layer "F.Fab")
		)
		(fp_line
			(start -0.12065 -0.305054)
			(end -0.12065 -0.2794)
			(stroke
				(width 0.1)
				(type default)
			)
			(layer "F.Fab")
		)
		(fp_line
			(start -0.12065 -0.2794)
			(end 0.12065 -0.2794)
			(stroke
				(width 0.1)
				(type default)
			)
			(layer "F.Fab")
		)
		(fp_line
			(start -0.12065 0.2794)
			(end -0.12065 0.3048)
			(stroke
				(width 0.1)
				(type default)
			)
			(layer "F.Fab")
		)
		(fp_line
			(start -0.12065 0.3048)
			(end -0.67945 0.3048)
			(stroke
				(width 0.1)
				(type default)
			)
			(layer "F.Fab")
		)
		(fp_line
			(start 0.120396 0.2794)
			(end -0.12065 0.2794)
			(stroke
				(width 0.1)
				(type default)
			)
			(layer "F.Fab")
		)
		(fp_line
			(start 0.120396 0.3048)
			(end 0.120396 0.2794)
			(stroke
				(width 0.1)
				(type default)
			)
			(layer "F.Fab")
		)
		(fp_line
			(start 0.12065 -0.3048)
			(end 0.67945 -0.3048)
			(stroke
				(width 0.1)
				(type default)
			)
			(layer "F.Fab")
		)
		(fp_line
			(start 0.12065 -0.2794)
			(end 0.12065 -0.3048)
			(stroke
				(width 0.1)
				(type default)
			)
			(layer "F.Fab")
		)
		(fp_line
			(start 0.67945 -0.3048)
			(end 0.67945 0.3048)
			(stroke
				(width 0.1)
				(type default)
			)
			(layer "F.Fab")
		)
		(fp_line
			(start 0.67945 0.3048)
			(end 0.120396 0.3048)
			(stroke
				(width 0.1)
				(type default)
			)
			(layer "F.Fab")
		)
		(pad "1" smd circle
			(at -0.40005 0)
			(size 0 0)
			(layers "F.Cu" "F.Mask" "F.Paste")
			(net "P1V8_AUX")
		)
		(pad "2" smd circle
			(at 0.40005 0)
			(size 0 0)
			(layers "F.Cu" "F.Mask" "F.Paste")
			(net "GND")
		)
	)
	(footprint ""
		(layer "F.Cu")
		(at 33.782 -68.453 90)
		(property "Reference" "R11"
			(at 0 0 90)
			(layer "F.SilkS")
			(hide yes)
			(effects
				(font
					(size 1.27 1.27)
				)
			)
		)
		(property "Value" ""
			(at 0 0 90)
			(layer "F.Fab")
			(effects
				(font
					(size 1.27 1.27)
				)
			)
		)
		(duplicate_pad_numbers_are_jumpers no)
		(fp_line
			(start 0.7874 -0.4064)
			(end 0.7874 0.4064)
			(stroke
				(width 0.1524)
				(type default)
			)
			(layer "F.SilkS")
		)
		(fp_line
			(start -0.7874 -0.4064)
			(end 0.7874 -0.4064)
			(stroke
				(width 0.1524)
				(type default)
			)
			(layer "F.SilkS")
		)
		(fp_line
			(start 0.7874 0.4064)
			(end -0.7874 0.4064)
			(stroke
				(width 0.1524)
				(type default)
			)
			(layer "F.SilkS")
		)
		(fp_line
			(start -0.7874 0.4064)
			(end -0.7874 -0.4064)
			(stroke
				(width 0.1524)
				(type default)
			)
			(layer "F.SilkS")
		)
		(fp_line
			(start -0.12065 -0.305054)
			(end -0.12065 -0.2794)
			(stroke
				(width 0.1)
				(type default)
			)
			(layer "F.Fab")
		)
		(fp_line
			(start -0.67945 -0.305054)
			(end -0.12065 -0.305054)
			(stroke
				(width 0.1)
				(type default)
			)
			(layer "F.Fab")
		)
		(fp_line
			(start 0.67945 -0.3048)
			(end 0.67945 0.3048)
			(stroke
				(width 0.1)
				(type default)
			)
			(layer "F.Fab")
		)
		(fp_line
			(start 0.12065 -0.3048)
			(end 0.67945 -0.3048)
			(stroke
				(width 0.1)
				(type default)
			)
			(layer "F.Fab")
		)
		(fp_line
			(start 0.12065 -0.2794)
			(end 0.12065 -0.3048)
			(stroke
				(width 0.1)
				(type default)
			)
			(layer "F.Fab")
		)
		(fp_line
			(start -0.12065 -0.2794)
			(end 0.12065 -0.2794)
			(stroke
				(width 0.1)
				(type default)
			)
			(layer "F.Fab")
		)
		(fp_line
			(start 0.120396 0.2794)
			(end -0.12065 0.2794)
			(stroke
				(width 0.1)
				(type default)
			)
			(layer "F.Fab")
		)
		(fp_line
			(start -0.12065 0.2794)
			(end -0.12065 0.3048)
			(stroke
				(width 0.1)
				(type default)
			)
			(layer "F.Fab")
		)
		(fp_line
			(start 0.67945 0.3048)
			(end 0.120396 0.3048)
			(stroke
				(width 0.1)
				(type default)
			)
			(layer "F.Fab")
		)
		(fp_line
			(start 0.120396 0.3048)
			(end 0.120396 0.2794)
			(stroke
				(width 0.1)
				(type default)
			)
			(layer "F.Fab")
		)
		(fp_line
			(start -0.12065 0.3048)
			(end -0.67945 0.3048)
			(stroke
				(width 0.1)
				(type default)
			)
			(layer "F.Fab")
		)
		(fp_line
			(start -0.67945 0.3048)
			(end -0.67945 -0.305054)
			(stroke
				(width 0.1)
				(type default)
			)
			(layer "F.Fab")
		)
		(pad "1" smd circle
			(at -0.40005 0 90)
			(size 0 0)
			(layers "F.Cu" "F.Mask" "F.Paste")
			(net "P3V3_AUX")
		)
		(pad "2" smd circle
			(at 0.40005 0 90)
			(size 0 0)
			(layers "F.Cu" "F.Mask" "F.Paste")
			(net "BMC_EMMC_RST_N")
		)
	)
	(footprint ""
		(layer "F.Cu")
		(at 12.875006 -25.146 180)
		(property "Reference" "J6"
			(at 4.6228 3.38963 0)
			(unlocked yes)
			(layer "F.SilkS")
			(effects
				(font
					(size 0.7874 0.5842)
					(thickness 0.1524)
				)
				(justify left)
			)
		)
		(property "Value" ""
			(at 0 0 180)
			(layer "F.Fab")
			(effects
				(font
					(size 1.27 1.27)
				)
			)
		)
		(duplicate_pad_numbers_are_jumpers no)
		(fp_line
			(start 1.249934 3.860038)
			(end 1.249934 3.1877)
			(stroke
				(width 0.1524)
				(type default)
			)
			(layer "F.SilkS")
		)
		(fp_line
			(start 1.249934 1.8923)
			(end 1.249934 -1.8923)
			(stroke
				(width 0.1524)
				(type default)
			)
			(layer "F.SilkS")
		)
		(fp_line
			(start 1.249934 -3.1877)
			(end 1.249934 -3.860038)
			(stroke
				(width 0.1524)
				(type default)
			)
			(layer "F.SilkS")
		)
		(fp_line
			(start 1.249934 -3.860038)
			(end -1.249934 -3.860038)
			(stroke
				(width 0.1524)
				(type default)
			)
			(layer "F.SilkS")
		)
		(fp_line
			(start -1.249934 3.860038)
			(end 1.249934 3.860038)
			(stroke
				(width 0.1524)
				(type default)
			)
			(layer "F.SilkS")
		)
		(fp_line
			(start -1.249934 0.6477)
			(end -1.249934 3.860038)
			(stroke
				(width 0.1524)
				(type default)
			)
			(layer "F.SilkS")
		)
		(fp_line
			(start -1.249934 -3.860038)
			(end -1.249934 -0.6477)
			(stroke
				(width 0.1524)
				(type default)
			)
			(layer "F.SilkS")
		)
		(fp_poly
			(pts
				(xy 2.413 -5.334) (xy 1.397 -5.334) (xy 1.905 -4.318)
			)
			(stroke
				(width 0)
				(type default)
			)
			(fill yes)
			(layer "F.SilkS")
		)
		(fp_line
			(start 1.249934 3.860038)
			(end 1.249934 -3.860038)
			(stroke
				(width 0.1)
				(type default)
			)
			(layer "F.Fab")
		)
		(fp_line
			(start 1.249934 -3.860038)
			(end -1.249934 -3.860038)
			(stroke
				(width 0.1)
				(type default)
			)
			(layer "F.Fab")
		)
		(fp_line
			(start -1.249934 3.860038)
			(end 1.249934 3.860038)
			(stroke
				(width 0.1)
				(type default)
			)
			(layer "F.Fab")
		)
		(fp_line
			(start -1.249934 -3.860038)
			(end -1.249934 3.860038)
			(stroke
				(width 0.1)
				(type default)
			)
			(layer "F.Fab")
		)
		(fp_poly
			(pts
				(xy 4.281678 -2.032) (xy 4.281678 -3.048) (xy 3.265678 -2.54)
			)
			(stroke
				(width 0)
				(type default)
			)
			(fill yes)
			(layer "F.Fab")
		)
		(pad "1" smd rect
			(at 1.374902 -2.54 90)
			(size 1.016 2.7686)
			(layers "F.Cu" "F.Mask" "F.Paste")
			(net "UART_BMC_5_TXD_BUF_R")
		)
		(pad "2" smd rect
			(at -1.374902 0 90)
			(size 1.016 2.7686)
			(layers "F.Cu" "F.Mask" "F.Paste")
			(net "GND")
		)
		(pad "3" smd rect
			(at 1.374902 2.54 90)
			(size 1.016 2.7686)
			(layers "F.Cu" "F.Mask" "F.Paste")
			(net "UART_BMC_5_RXD_BUF")
		)
	)
	(footprint ""
		(layer "F.Cu")
		(at 19.431 -83.72602 -90)
		(property "Reference" "R297"
			(at 0 0 270)
			(layer "F.SilkS")
			(hide yes)
			(effects
				(font
					(size 1.27 1.27)
				)
			)
		)
		(property "Value" ""
			(at 0 0 270)
			(layer "F.Fab")
			(effects
				(font
					(size 1.27 1.27)
				)
			)
		)
		(duplicate_pad_numbers_are_jumpers no)
		(fp_line
			(start -0.7874 0.4064)
			(end -0.7874 -0.4064)
			(stroke
				(width 0.1524)
				(type default)
			)
			(layer "F.SilkS")
		)
		(fp_line
			(start 0.7874 0.4064)
			(end -0.7874 0.4064)
			(stroke
				(width 0.1524)
				(type default)
			)
			(layer "F.SilkS")
		)
		(fp_line
			(start -0.7874 -0.4064)
			(end 0.7874 -0.4064)
			(stroke
				(width 0.1524)
				(type default)
			)
			(layer "F.SilkS")
		)
		(fp_line
			(start 0.7874 -0.4064)
			(end 0.7874 0.4064)
			(stroke
				(width 0.1524)
				(type default)
			)
			(layer "F.SilkS")
		)
		(fp_line
			(start -0.67945 0.3048)
			(end -0.67945 -0.305054)
			(stroke
				(width 0.1)
				(type default)
			)
			(layer "F.Fab")
		)
		(fp_line
			(start -0.12065 0.3048)
			(end -0.67945 0.3048)
			(stroke
				(width 0.1)
				(type default)
			)
			(layer "F.Fab")
		)
		(fp_line
			(start 0.120396 0.3048)
			(end 0.120396 0.2794)
			(stroke
				(width 0.1)
				(type default)
			)
			(layer "F.Fab")
		)
		(fp_line
			(start 0.67945 0.3048)
			(end 0.120396 0.3048)
			(stroke
				(width 0.1)
				(type default)
			)
			(layer "F.Fab")
		)
		(fp_line
			(start -0.12065 0.2794)
			(end -0.12065 0.3048)
			(stroke
				(width 0.1)
				(type default)
			)
			(layer "F.Fab")
		)
		(fp_line
			(start 0.120396 0.2794)
			(end -0.12065 0.2794)
			(stroke
				(width 0.1)
				(type default)
			)
			(layer "F.Fab")
		)
		(fp_line
			(start -0.12065 -0.2794)
			(end 0.12065 -0.2794)
			(stroke
				(width 0.1)
				(type default)
			)
			(layer "F.Fab")
		)
		(fp_line
			(start 0.12065 -0.2794)
			(end 0.12065 -0.3048)
			(stroke
				(width 0.1)
				(type default)
			)
			(layer "F.Fab")
		)
		(fp_line
			(start 0.12065 -0.3048)
			(end 0.67945 -0.3048)
			(stroke
				(width 0.1)
				(type default)
			)
			(layer "F.Fab")
		)
		(fp_line
			(start 0.67945 -0.3048)
			(end 0.67945 0.3048)
			(stroke
				(width 0.1)
				(type default)
			)
			(layer "F.Fab")
		)
		(fp_line
			(start -0.67945 -0.305054)
			(end -0.12065 -0.305054)
			(stroke
				(width 0.1)
				(type default)
			)
			(layer "F.Fab")
		)
		(fp_line
			(start -0.12065 -0.305054)
			(end -0.12065 -0.2794)
			(stroke
				(width 0.1)
				(type default)
			)
			(layer "F.Fab")
		)
		(pad "1" smd circle
			(at -0.40005 0 270)
			(size 0 0)
			(layers "F.Cu" "F.Mask" "F.Paste")
			(net "PU_PT20D")
		)
		(pad "2" smd circle
			(at 0.40005 0 270)
			(size 0 0)
			(layers "F.Cu" "F.Mask" "F.Paste")
			(net "VCCIO2")
		)
	)
	(footprint ""
		(layer "F.Cu")
		(at 84.201 -97.917)
		(property "Reference" "R100"
			(at 0 0 0)
			(layer "F.SilkS")
			(hide yes)
			(effects
				(font
					(size 1.27 1.27)
				)
			)
		)
		(property "Value" ""
			(at 0 0 0)
			(layer "F.Fab")
			(effects
				(font
					(size 1.27 1.27)
				)
			)
		)
		(duplicate_pad_numbers_are_jumpers no)
		(fp_line
			(start -0.7874 -0.4064)
			(end 0.7874 -0.4064)
			(stroke
				(width 0.1524)
				(type default)
			)
			(layer "F.SilkS")
		)
		(fp_line
			(start -0.7874 0.4064)
			(end -0.7874 -0.4064)
			(stroke
				(width 0.1524)
				(type default)
			)
			(layer "F.SilkS")
		)
		(fp_line
			(start 0.7874 -0.4064)
			(end 0.7874 0.4064)
			(stroke
				(width 0.1524)
				(type default)
			)
			(layer "F.SilkS")
		)
		(fp_line
			(start 0.7874 0.4064)
			(end -0.7874 0.4064)
			(stroke
				(width 0.1524)
				(type default)
			)
			(layer "F.SilkS")
		)
		(fp_line
			(start -0.67945 -0.305054)
			(end -0.12065 -0.305054)
			(stroke
				(width 0.1)
				(type default)
			)
			(layer "F.Fab")
		)
		(fp_line
			(start -0.67945 0.3048)
			(end -0.67945 -0.305054)
			(stroke
				(width 0.1)
				(type default)
			)
			(layer "F.Fab")
		)
		(fp_line
			(start -0.12065 -0.305054)
			(end -0.12065 -0.2794)
			(stroke
				(width 0.1)
				(type default)
			)
			(layer "F.Fab")
		)
		(fp_line
			(start -0.12065 -0.2794)
			(end 0.12065 -0.2794)
			(stroke
				(width 0.1)
				(type default)
			)
			(layer "F.Fab")
		)
		(fp_line
			(start -0.12065 0.2794)
			(end -0.12065 0.3048)
			(stroke
				(width 0.1)
				(type default)
			)
			(layer "F.Fab")
		)
		(fp_line
			(start -0.12065 0.3048)
			(end -0.67945 0.3048)
			(stroke
				(width 0.1)
				(type default)
			)
			(layer "F.Fab")
		)
		(fp_line
			(start 0.120396 0.2794)
			(end -0.12065 0.2794)
			(stroke
				(width 0.1)
				(type default)
			)
			(layer "F.Fab")
		)
		(fp_line
			(start 0.120396 0.3048)
			(end 0.120396 0.2794)
			(stroke
				(width 0.1)
				(type default)
			)
			(layer "F.Fab")
		)
		(fp_line
			(start 0.12065 -0.3048)
			(end 0.67945 -0.3048)
			(stroke
				(width 0.1)
				(type default)
			)
			(layer "F.Fab")
		)
		(fp_line
			(start 0.12065 -0.2794)
			(end 0.12065 -0.3048)
			(stroke
				(width 0.1)
				(type default)
			)
			(layer "F.Fab")
		)
		(fp_line
			(start 0.67945 -0.3048)
			(end 0.67945 0.3048)
			(stroke
				(width 0.1)
				(type default)
			)
			(layer "F.Fab")
		)
		(fp_line
			(start 0.67945 0.3048)
			(end 0.120396 0.3048)
			(stroke
				(width 0.1)
				(type default)
			)
			(layer "F.Fab")
		)
		(pad "1" smd circle
			(at -0.40005 0)
			(size 0 0)
			(layers "F.Cu" "F.Mask" "F.Paste")
			(net "SPI_BMC_TPM_CS2_N_R")
		)
		(pad "2" smd circle
			(at 0.40005 0)
			(size 0 0)
			(layers "F.Cu" "F.Mask" "F.Paste")
			(net "SPI_BMC_TPM_CS2_R_N")
		)
	)
	(footprint ""
		(layer "F.Cu")
		(at 10.287 -59.055 90)
		(property "Reference" "C262"
			(at 0 0 90)
			(layer "F.SilkS")
			(hide yes)
			(effects
				(font
					(size 1.27 1.27)
				)
			)
		)
		(property "Value" ""
			(at 0 0 90)
			(layer "F.Fab")
			(effects
				(font
					(size 1.27 1.27)
				)
			)
		)
		(duplicate_pad_numbers_are_jumpers no)
		(fp_line
			(start 0.7874 -0.4064)
			(end 0.7874 0.4064)
			(stroke
				(width 0.1524)
				(type default)
			)
			(layer "F.SilkS")
		)
		(fp_line
			(start -0.7874 -0.4064)
			(end 0.7874 -0.4064)
			(stroke
				(width 0.1524)
				(type default)
			)
			(layer "F.SilkS")
		)
		(fp_line
			(start 0.7874 0.4064)
			(end -0.7874 0.4064)
			(stroke
				(width 0.1524)
				(type default)
			)
			(layer "F.SilkS")
		)
		(fp_line
			(start -0.7874 0.4064)
			(end -0.7874 -0.4064)
			(stroke
				(width 0.1524)
				(type default)
			)
			(layer "F.SilkS")
		)
		(fp_line
			(start -0.12065 -0.305054)
			(end -0.12065 -0.2794)
			(stroke
				(width 0.1)
				(type default)
			)
			(layer "F.Fab")
		)
		(fp_line
			(start -0.67945 -0.305054)
			(end -0.12065 -0.305054)
			(stroke
				(width 0.1)
				(type default)
			)
			(layer "F.Fab")
		)
		(fp_line
			(start 0.67945 -0.3048)
			(end 0.67945 0.3048)
			(stroke
				(width 0.1)
				(type default)
			)
			(layer "F.Fab")
		)
		(fp_line
			(start 0.12065 -0.3048)
			(end 0.67945 -0.3048)
			(stroke
				(width 0.1)
				(type default)
			)
			(layer "F.Fab")
		)
		(fp_line
			(start 0.12065 -0.2794)
			(end 0.12065 -0.3048)
			(stroke
				(width 0.1)
				(type default)
			)
			(layer "F.Fab")
		)
		(fp_line
			(start -0.12065 -0.2794)
			(end 0.12065 -0.2794)
			(stroke
				(width 0.1)
				(type default)
			)
			(layer "F.Fab")
		)
		(fp_line
			(start 0.120396 0.2794)
			(end -0.12065 0.2794)
			(stroke
				(width 0.1)
				(type default)
			)
			(layer "F.Fab")
		)
		(fp_line
			(start -0.12065 0.2794)
			(end -0.12065 0.3048)
			(stroke
				(width 0.1)
				(type default)
			)
			(layer "F.Fab")
		)
		(fp_line
			(start 0.67945 0.3048)
			(end 0.120396 0.3048)
			(stroke
				(width 0.1)
				(type default)
			)
			(layer "F.Fab")
		)
		(fp_line
			(start 0.120396 0.3048)
			(end 0.120396 0.2794)
			(stroke
				(width 0.1)
				(type default)
			)
			(layer "F.Fab")
		)
		(fp_line
			(start -0.12065 0.3048)
			(end -0.67945 0.3048)
			(stroke
				(width 0.1)
				(type default)
			)
			(layer "F.Fab")
		)
		(fp_line
			(start -0.67945 0.3048)
			(end -0.67945 -0.305054)
			(stroke
				(width 0.1)
				(type default)
			)
			(layer "F.Fab")
		)
		(pad "1" smd circle
			(at -0.40005 0 90)
			(size 0 0)
			(layers "F.Cu" "F.Mask" "F.Paste")
			(net "P12V_AUX")
		)
		(pad "2" smd circle
			(at 0.40005 0 90)
			(size 0 0)
			(layers "F.Cu" "F.Mask" "F.Paste")
			(net "GND")
		)
	)
	(footprint ""
		(layer "F.Cu")
		(at 84.201 -92.202)
		(property "Reference" "R109"
			(at 0 0 0)
			(layer "F.SilkS")
			(hide yes)
			(effects
				(font
					(size 1.27 1.27)
				)
			)
		)
		(property "Value" ""
			(at 0 0 0)
			(layer "F.Fab")
			(effects
				(font
					(size 1.27 1.27)
				)
			)
		)
		(duplicate_pad_numbers_are_jumpers no)
		(fp_line
			(start -0.7874 -0.4064)
			(end 0.7874 -0.4064)
			(stroke
				(width 0.1524)
				(type default)
			)
			(layer "F.SilkS")
		)
		(fp_line
			(start -0.7874 0.4064)
			(end -0.7874 -0.4064)
			(stroke
				(width 0.1524)
				(type default)
			)
			(layer "F.SilkS")
		)
		(fp_line
			(start 0.7874 -0.4064)
			(end 0.7874 0.4064)
			(stroke
				(width 0.1524)
				(type default)
			)
			(layer "F.SilkS")
		)
		(fp_line
			(start 0.7874 0.4064)
			(end -0.7874 0.4064)
			(stroke
				(width 0.1524)
				(type default)
			)
			(layer "F.SilkS")
		)
		(fp_line
			(start -0.67945 -0.305054)
			(end -0.12065 -0.305054)
			(stroke
				(width 0.1)
				(type default)
			)
			(layer "F.Fab")
		)
		(fp_line
			(start -0.67945 0.3048)
			(end -0.67945 -0.305054)
			(stroke
				(width 0.1)
				(type default)
			)
			(layer "F.Fab")
		)
		(fp_line
			(start -0.12065 -0.305054)
			(end -0.12065 -0.2794)
			(stroke
				(width 0.1)
				(type default)
			)
			(layer "F.Fab")
		)
		(fp_line
			(start -0.12065 -0.2794)
			(end 0.12065 -0.2794)
			(stroke
				(width 0.1)
				(type default)
			)
			(layer "F.Fab")
		)
		(fp_line
			(start -0.12065 0.2794)
			(end -0.12065 0.3048)
			(stroke
				(width 0.1)
				(type default)
			)
			(layer "F.Fab")
		)
		(fp_line
			(start -0.12065 0.3048)
			(end -0.67945 0.3048)
			(stroke
				(width 0.1)
				(type default)
			)
			(layer "F.Fab")
		)
		(fp_line
			(start 0.120396 0.2794)
			(end -0.12065 0.2794)
			(stroke
				(width 0.1)
				(type default)
			)
			(layer "F.Fab")
		)
		(fp_line
			(start 0.120396 0.3048)
			(end 0.120396 0.2794)
			(stroke
				(width 0.1)
				(type default)
			)
			(layer "F.Fab")
		)
		(fp_line
			(start 0.12065 -0.3048)
			(end 0.67945 -0.3048)
			(stroke
				(width 0.1)
				(type default)
			)
			(layer "F.Fab")
		)
		(fp_line
			(start 0.12065 -0.2794)
			(end 0.12065 -0.3048)
			(stroke
				(width 0.1)
				(type default)
			)
			(layer "F.Fab")
		)
		(fp_line
			(start 0.67945 -0.3048)
			(end 0.67945 0.3048)
			(stroke
				(width 0.1)
				(type default)
			)
			(layer "F.Fab")
		)
		(fp_line
			(start 0.67945 0.3048)
			(end 0.120396 0.3048)
			(stroke
				(width 0.1)
				(type default)
			)
			(layer "F.Fab")
		)
		(pad "1" smd circle
			(at -0.40005 0)
			(size 0 0)
			(layers "F.Cu" "F.Mask" "F.Paste")
			(net "SPI_BMC_TPM_CLK_R")
		)
		(pad "2" smd circle
			(at 0.40005 0)
			(size 0 0)
			(layers "F.Cu" "F.Mask" "F.Paste")
			(net "SPI_BMC_TPM_CLK")
		)
	)
	(footprint ""
		(layer "F.Cu")
		(at 36.957 -36.068 -90)
		(property "Reference" "R231"
			(at 0 0 270)
			(layer "F.SilkS")
			(hide yes)
			(effects
				(font
					(size 1.27 1.27)
				)
			)
		)
		(property "Value" ""
			(at 0 0 270)
			(layer "F.Fab")
			(effects
				(font
					(size 1.27 1.27)
				)
			)
		)
		(duplicate_pad_numbers_are_jumpers no)
		(fp_line
			(start -0.7874 0.4064)
			(end -0.7874 -0.4064)
			(stroke
				(width 0.1524)
				(type default)
			)
			(layer "F.SilkS")
		)
		(fp_line
			(start 0.7874 0.4064)
			(end -0.7874 0.4064)
			(stroke
				(width 0.1524)
				(type default)
			)
			(layer "F.SilkS")
		)
		(fp_line
			(start -0.7874 -0.4064)
			(end 0.7874 -0.4064)
			(stroke
				(width 0.1524)
				(type default)
			)
			(layer "F.SilkS")
		)
		(fp_line
			(start 0.7874 -0.4064)
			(end 0.7874 0.4064)
			(stroke
				(width 0.1524)
				(type default)
			)
			(layer "F.SilkS")
		)
		(fp_line
			(start -0.67945 0.3048)
			(end -0.67945 -0.305054)
			(stroke
				(width 0.1)
				(type default)
			)
			(layer "F.Fab")
		)
		(fp_line
			(start -0.12065 0.3048)
			(end -0.67945 0.3048)
			(stroke
				(width 0.1)
				(type default)
			)
			(layer "F.Fab")
		)
		(fp_line
			(start 0.120396 0.3048)
			(end 0.120396 0.2794)
			(stroke
				(width 0.1)
				(type default)
			)
			(layer "F.Fab")
		)
		(fp_line
			(start 0.67945 0.3048)
			(end 0.120396 0.3048)
			(stroke
				(width 0.1)
				(type default)
			)
			(layer "F.Fab")
		)
		(fp_line
			(start -0.12065 0.2794)
			(end -0.12065 0.3048)
			(stroke
				(width 0.1)
				(type default)
			)
			(layer "F.Fab")
		)
		(fp_line
			(start 0.120396 0.2794)
			(end -0.12065 0.2794)
			(stroke
				(width 0.1)
				(type default)
			)
			(layer "F.Fab")
		)
		(fp_line
			(start -0.12065 -0.2794)
			(end 0.12065 -0.2794)
			(stroke
				(width 0.1)
				(type default)
			)
			(layer "F.Fab")
		)
		(fp_line
			(start 0.12065 -0.2794)
			(end 0.12065 -0.3048)
			(stroke
				(width 0.1)
				(type default)
			)
			(layer "F.Fab")
		)
		(fp_line
			(start 0.12065 -0.3048)
			(end 0.67945 -0.3048)
			(stroke
				(width 0.1)
				(type default)
			)
			(layer "F.Fab")
		)
		(fp_line
			(start 0.67945 -0.3048)
			(end 0.67945 0.3048)
			(stroke
				(width 0.1)
				(type default)
			)
			(layer "F.Fab")
		)
		(fp_line
			(start -0.67945 -0.305054)
			(end -0.12065 -0.305054)
			(stroke
				(width 0.1)
				(type default)
			)
			(layer "F.Fab")
		)
		(fp_line
			(start -0.12065 -0.305054)
			(end -0.12065 -0.2794)
			(stroke
				(width 0.1)
				(type default)
			)
			(layer "F.Fab")
		)
		(pad "1" smd circle
			(at -0.40005 0 270)
			(size 0 0)
			(layers "F.Cu" "F.Mask" "F.Paste")
			(net "P3V3_AUX")
		)
		(pad "2" smd circle
			(at 0.40005 0 270)
			(size 0 0)
			(layers "F.Cu" "F.Mask" "F.Paste")
			(net "P3V3_P1V8_I2C_I3C")
		)
	)
	(footprint ""
		(layer "F.Cu")
		(at 85.29955 -45.697394 180)
		(property "Reference" "R331"
			(at 0 0 180)
			(layer "F.SilkS")
			(hide yes)
			(effects
				(font
					(size 1.27 1.27)
				)
			)
		)
		(property "Value" ""
			(at 0 0 180)
			(layer "F.Fab")
			(effects
				(font
					(size 1.27 1.27)
				)
			)
		)
		(duplicate_pad_numbers_are_jumpers no)
		(fp_line
			(start 0.7874 0.4064)
			(end -0.7874 0.4064)
			(stroke
				(width 0.1524)
				(type default)
			)
			(layer "F.SilkS")
		)
		(fp_line
			(start 0.7874 -0.4064)
			(end 0.7874 0.4064)
			(stroke
				(width 0.1524)
				(type default)
			)
			(layer "F.SilkS")
		)
		(fp_line
			(start -0.7874 0.4064)
			(end -0.7874 -0.4064)
			(stroke
				(width 0.1524)
				(type default)
			)
			(layer "F.SilkS")
		)
		(fp_line
			(start -0.7874 -0.4064)
			(end 0.7874 -0.4064)
			(stroke
				(width 0.1524)
				(type default)
			)
			(layer "F.SilkS")
		)
		(fp_line
			(start 0.67945 0.3048)
			(end 0.120396 0.3048)
			(stroke
				(width 0.1)
				(type default)
			)
			(layer "F.Fab")
		)
		(fp_line
			(start 0.67945 -0.3048)
			(end 0.67945 0.3048)
			(stroke
				(width 0.1)
				(type default)
			)
			(layer "F.Fab")
		)
		(fp_line
			(start 0.12065 -0.2794)
			(end 0.12065 -0.3048)
			(stroke
				(width 0.1)
				(type default)
			)
			(layer "F.Fab")
		)
		(fp_line
			(start 0.12065 -0.3048)
			(end 0.67945 -0.3048)
			(stroke
				(width 0.1)
				(type default)
			)
			(layer "F.Fab")
		)
		(fp_line
			(start 0.120396 0.3048)
			(end 0.120396 0.2794)
			(stroke
				(width 0.1)
				(type default)
			)
			(layer "F.Fab")
		)
		(fp_line
			(start 0.120396 0.2794)
			(end -0.12065 0.2794)
			(stroke
				(width 0.1)
				(type default)
			)
			(layer "F.Fab")
		)
		(fp_line
			(start -0.12065 0.3048)
			(end -0.67945 0.3048)
			(stroke
				(width 0.1)
				(type default)
			)
			(layer "F.Fab")
		)
		(fp_line
			(start -0.12065 0.2794)
			(end -0.12065 0.3048)
			(stroke
				(width 0.1)
				(type default)
			)
			(layer "F.Fab")
		)
		(fp_line
			(start -0.12065 -0.2794)
			(end 0.12065 -0.2794)
			(stroke
				(width 0.1)
				(type default)
			)
			(layer "F.Fab")
		)
		(fp_line
			(start -0.12065 -0.305054)
			(end -0.12065 -0.2794)
			(stroke
				(width 0.1)
				(type default)
			)
			(layer "F.Fab")
		)
		(fp_line
			(start -0.67945 0.3048)
			(end -0.67945 -0.305054)
			(stroke
				(width 0.1)
				(type default)
			)
			(layer "F.Fab")
		)
		(fp_line
			(start -0.67945 -0.305054)
			(end -0.12065 -0.305054)
			(stroke
				(width 0.1)
				(type default)
			)
			(layer "F.Fab")
		)
		(pad "1" smd circle
			(at -0.40005 0 180)
			(size 0 0)
			(layers "F.Cu" "F.Mask" "F.Paste")
			(net "GND")
		)
		(pad "2" smd circle
			(at 0.40005 0 180)
			(size 0 0)
			(layers "F.Cu" "F.Mask" "F.Paste")
			(net "M_BMC_DDR4_MA<5>")
		)
	)
	(footprint ""
		(layer "F.Cu")
		(at 77.947774 -70.3834)
		(property "Reference" "R876"
			(at 0 0 0)
			(layer "F.SilkS")
			(hide yes)
			(effects
				(font
					(size 1.27 1.27)
				)
			)
		)
		(property "Value" ""
			(at 0 0 0)
			(layer "F.Fab")
			(effects
				(font
					(size 1.27 1.27)
				)
			)
		)
		(duplicate_pad_numbers_are_jumpers no)
		(fp_line
			(start -0.7874 -0.4064)
			(end 0.7874 -0.4064)
			(stroke
				(width 0.1524)
				(type default)
			)
			(layer "F.SilkS")
		)
		(fp_line
			(start -0.7874 0.4064)
			(end -0.7874 -0.4064)
			(stroke
				(width 0.1524)
				(type default)
			)
			(layer "F.SilkS")
		)
		(fp_line
			(start 0.7874 -0.4064)
			(end 0.7874 0.4064)
			(stroke
				(width 0.1524)
				(type default)
			)
			(layer "F.SilkS")
		)
		(fp_line
			(start 0.7874 0.4064)
			(end -0.7874 0.4064)
			(stroke
				(width 0.1524)
				(type default)
			)
			(layer "F.SilkS")
		)
		(fp_line
			(start -0.67945 -0.305054)
			(end -0.12065 -0.305054)
			(stroke
				(width 0.1)
				(type default)
			)
			(layer "F.Fab")
		)
		(fp_line
			(start -0.67945 0.3048)
			(end -0.67945 -0.305054)
			(stroke
				(width 0.1)
				(type default)
			)
			(layer "F.Fab")
		)
		(fp_line
			(start -0.12065 -0.305054)
			(end -0.12065 -0.2794)
			(stroke
				(width 0.1)
				(type default)
			)
			(layer "F.Fab")
		)
		(fp_line
			(start -0.12065 -0.2794)
			(end 0.12065 -0.2794)
			(stroke
				(width 0.1)
				(type default)
			)
			(layer "F.Fab")
		)
		(fp_line
			(start -0.12065 0.2794)
			(end -0.12065 0.3048)
			(stroke
				(width 0.1)
				(type default)
			)
			(layer "F.Fab")
		)
		(fp_line
			(start -0.12065 0.3048)
			(end -0.67945 0.3048)
			(stroke
				(width 0.1)
				(type default)
			)
			(layer "F.Fab")
		)
		(fp_line
			(start 0.120396 0.2794)
			(end -0.12065 0.2794)
			(stroke
				(width 0.1)
				(type default)
			)
			(layer "F.Fab")
		)
		(fp_line
			(start 0.120396 0.3048)
			(end 0.120396 0.2794)
			(stroke
				(width 0.1)
				(type default)
			)
			(layer "F.Fab")
		)
		(fp_line
			(start 0.12065 -0.3048)
			(end 0.67945 -0.3048)
			(stroke
				(width 0.1)
				(type default)
			)
			(layer "F.Fab")
		)
		(fp_line
			(start 0.12065 -0.2794)
			(end 0.12065 -0.3048)
			(stroke
				(width 0.1)
				(type default)
			)
			(layer "F.Fab")
		)
		(fp_line
			(start 0.67945 -0.3048)
			(end 0.67945 0.3048)
			(stroke
				(width 0.1)
				(type default)
			)
			(layer "F.Fab")
		)
		(fp_line
			(start 0.67945 0.3048)
			(end 0.120396 0.3048)
			(stroke
				(width 0.1)
				(type default)
			)
			(layer "F.Fab")
		)
		(pad "1" smd circle
			(at -0.40005 0)
			(size 0 0)
			(layers "F.Cu" "F.Mask" "F.Paste")
			(net "PWRGD_P3V3_RGM_R3")
		)
		(pad "2" smd circle
			(at 0.40005 0)
			(size 0 0)
			(layers "F.Cu" "F.Mask" "F.Paste")
			(net "EN_P1V2_AUX_R")
		)
	)
	(footprint ""
		(layer "F.Cu")
		(at 27.1272 -65.5574 90)
		(property "Reference" "R715"
			(at 0 0 90)
			(layer "F.SilkS")
			(hide yes)
			(effects
				(font
					(size 1.27 1.27)
				)
			)
		)
		(property "Value" ""
			(at 0 0 90)
			(layer "F.Fab")
			(effects
				(font
					(size 1.27 1.27)
				)
			)
		)
		(duplicate_pad_numbers_are_jumpers no)
		(fp_line
			(start 0.7874 -0.4064)
			(end 0.7874 0.4064)
			(stroke
				(width 0.1524)
				(type default)
			)
			(layer "F.SilkS")
		)
		(fp_line
			(start -0.7874 -0.4064)
			(end 0.7874 -0.4064)
			(stroke
				(width 0.1524)
				(type default)
			)
			(layer "F.SilkS")
		)
		(fp_line
			(start 0.7874 0.4064)
			(end -0.7874 0.4064)
			(stroke
				(width 0.1524)
				(type default)
			)
			(layer "F.SilkS")
		)
		(fp_line
			(start -0.7874 0.4064)
			(end -0.7874 -0.4064)
			(stroke
				(width 0.1524)
				(type default)
			)
			(layer "F.SilkS")
		)
		(fp_line
			(start -0.12065 -0.305054)
			(end -0.12065 -0.2794)
			(stroke
				(width 0.1)
				(type default)
			)
			(layer "F.Fab")
		)
		(fp_line
			(start -0.67945 -0.305054)
			(end -0.12065 -0.305054)
			(stroke
				(width 0.1)
				(type default)
			)
			(layer "F.Fab")
		)
		(fp_line
			(start 0.67945 -0.3048)
			(end 0.67945 0.3048)
			(stroke
				(width 0.1)
				(type default)
			)
			(layer "F.Fab")
		)
		(fp_line
			(start 0.12065 -0.3048)
			(end 0.67945 -0.3048)
			(stroke
				(width 0.1)
				(type default)
			)
			(layer "F.Fab")
		)
		(fp_line
			(start 0.12065 -0.2794)
			(end 0.12065 -0.3048)
			(stroke
				(width 0.1)
				(type default)
			)
			(layer "F.Fab")
		)
		(fp_line
			(start -0.12065 -0.2794)
			(end 0.12065 -0.2794)
			(stroke
				(width 0.1)
				(type default)
			)
			(layer "F.Fab")
		)
		(fp_line
			(start 0.120396 0.2794)
			(end -0.12065 0.2794)
			(stroke
				(width 0.1)
				(type default)
			)
			(layer "F.Fab")
		)
		(fp_line
			(start -0.12065 0.2794)
			(end -0.12065 0.3048)
			(stroke
				(width 0.1)
				(type default)
			)
			(layer "F.Fab")
		)
		(fp_line
			(start 0.67945 0.3048)
			(end 0.120396 0.3048)
			(stroke
				(width 0.1)
				(type default)
			)
			(layer "F.Fab")
		)
		(fp_line
			(start 0.120396 0.3048)
			(end 0.120396 0.2794)
			(stroke
				(width 0.1)
				(type default)
			)
			(layer "F.Fab")
		)
		(fp_line
			(start -0.12065 0.3048)
			(end -0.67945 0.3048)
			(stroke
				(width 0.1)
				(type default)
			)
			(layer "F.Fab")
		)
		(fp_line
			(start -0.67945 0.3048)
			(end -0.67945 -0.305054)
			(stroke
				(width 0.1)
				(type default)
			)
			(layer "F.Fab")
		)
		(pad "1" smd circle
			(at -0.40005 0 90)
			(size 0 0)
			(layers "F.Cu" "F.Mask" "F.Paste")
			(net "UART_BMC_5_TXD_BUF1")
		)
		(pad "2" smd circle
			(at 0.40005 0 90)
			(size 0 0)
			(layers "F.Cu" "F.Mask" "F.Paste")
			(net "UART_BMC_5_TXD_BUF1_R")
		)
	)
	(footprint ""
		(layer "F.Cu")
		(at 71.501 -10.922 90)
		(property "Reference" "R470"
			(at 0 0 90)
			(layer "F.SilkS")
			(hide yes)
			(effects
				(font
					(size 1.27 1.27)
				)
			)
		)
		(property "Value" ""
			(at 0 0 90)
			(layer "F.Fab")
			(effects
				(font
					(size 1.27 1.27)
				)
			)
		)
		(duplicate_pad_numbers_are_jumpers no)
		(fp_line
			(start 0.7874 -0.4064)
			(end 0.7874 0.4064)
			(stroke
				(width 0.1524)
				(type default)
			)
			(layer "F.SilkS")
		)
		(fp_line
			(start -0.7874 -0.4064)
			(end 0.7874 -0.4064)
			(stroke
				(width 0.1524)
				(type default)
			)
			(layer "F.SilkS")
		)
		(fp_line
			(start 0.7874 0.4064)
			(end -0.7874 0.4064)
			(stroke
				(width 0.1524)
				(type default)
			)
			(layer "F.SilkS")
		)
		(fp_line
			(start -0.7874 0.4064)
			(end -0.7874 -0.4064)
			(stroke
				(width 0.1524)
				(type default)
			)
			(layer "F.SilkS")
		)
		(fp_line
			(start -0.12065 -0.305054)
			(end -0.12065 -0.2794)
			(stroke
				(width 0.1)
				(type default)
			)
			(layer "F.Fab")
		)
		(fp_line
			(start -0.67945 -0.305054)
			(end -0.12065 -0.305054)
			(stroke
				(width 0.1)
				(type default)
			)
			(layer "F.Fab")
		)
		(fp_line
			(start 0.67945 -0.3048)
			(end 0.67945 0.3048)
			(stroke
				(width 0.1)
				(type default)
			)
			(layer "F.Fab")
		)
		(fp_line
			(start 0.12065 -0.3048)
			(end 0.67945 -0.3048)
			(stroke
				(width 0.1)
				(type default)
			)
			(layer "F.Fab")
		)
		(fp_line
			(start 0.12065 -0.2794)
			(end 0.12065 -0.3048)
			(stroke
				(width 0.1)
				(type default)
			)
			(layer "F.Fab")
		)
		(fp_line
			(start -0.12065 -0.2794)
			(end 0.12065 -0.2794)
			(stroke
				(width 0.1)
				(type default)
			)
			(layer "F.Fab")
		)
		(fp_line
			(start 0.120396 0.2794)
			(end -0.12065 0.2794)
			(stroke
				(width 0.1)
				(type default)
			)
			(layer "F.Fab")
		)
		(fp_line
			(start -0.12065 0.2794)
			(end -0.12065 0.3048)
			(stroke
				(width 0.1)
				(type default)
			)
			(layer "F.Fab")
		)
		(fp_line
			(start 0.67945 0.3048)
			(end 0.120396 0.3048)
			(stroke
				(width 0.1)
				(type default)
			)
			(layer "F.Fab")
		)
		(fp_line
			(start 0.120396 0.3048)
			(end 0.120396 0.2794)
			(stroke
				(width 0.1)
				(type default)
			)
			(layer "F.Fab")
		)
		(fp_line
			(start -0.12065 0.3048)
			(end -0.67945 0.3048)
			(stroke
				(width 0.1)
				(type default)
			)
			(layer "F.Fab")
		)
		(fp_line
			(start -0.67945 0.3048)
			(end -0.67945 -0.305054)
			(stroke
				(width 0.1)
				(type default)
			)
			(layer "F.Fab")
		)
		(pad "1" smd circle
			(at -0.40005 0 90)
			(size 0 0)
			(layers "F.Cu" "F.Mask" "F.Paste")
			(net "REAR_AC_PWR_BTN")
		)
		(pad "2" smd circle
			(at 0.40005 0 90)
			(size 0 0)
			(layers "F.Cu" "F.Mask" "F.Paste")
			(net "REAR_AC_PWR_BTN_N")
		)
	)
	(footprint ""
		(layer "F.Cu")
		(at 85.172296 -74.18959 180)
		(property "Reference" "PR498"
			(at 0 0 180)
			(layer "F.SilkS")
			(hide yes)
			(effects
				(font
					(size 1.27 1.27)
				)
			)
		)
		(property "Value" ""
			(at 0 0 180)
			(layer "F.Fab")
			(effects
				(font
					(size 1.27 1.27)
				)
			)
		)
		(duplicate_pad_numbers_are_jumpers no)
		(fp_line
			(start 0.7874 0.4064)
			(end -0.7874 0.4064)
			(stroke
				(width 0.1524)
				(type default)
			)
			(layer "F.SilkS")
		)
		(fp_line
			(start 0.7874 -0.4064)
			(end 0.7874 0.4064)
			(stroke
				(width 0.1524)
				(type default)
			)
			(layer "F.SilkS")
		)
		(fp_line
			(start -0.7874 0.4064)
			(end -0.7874 -0.4064)
			(stroke
				(width 0.1524)
				(type default)
			)
			(layer "F.SilkS")
		)
		(fp_line
			(start -0.7874 -0.4064)
			(end 0.7874 -0.4064)
			(stroke
				(width 0.1524)
				(type default)
			)
			(layer "F.SilkS")
		)
		(fp_line
			(start 0.67945 0.3048)
			(end 0.120396 0.3048)
			(stroke
				(width 0.1)
				(type default)
			)
			(layer "F.Fab")
		)
		(fp_line
			(start 0.67945 -0.3048)
			(end 0.67945 0.3048)
			(stroke
				(width 0.1)
				(type default)
			)
			(layer "F.Fab")
		)
		(fp_line
			(start 0.12065 -0.2794)
			(end 0.12065 -0.3048)
			(stroke
				(width 0.1)
				(type default)
			)
			(layer "F.Fab")
		)
		(fp_line
			(start 0.12065 -0.3048)
			(end 0.67945 -0.3048)
			(stroke
				(width 0.1)
				(type default)
			)
			(layer "F.Fab")
		)
		(fp_line
			(start 0.120396 0.3048)
			(end 0.120396 0.2794)
			(stroke
				(width 0.1)
				(type default)
			)
			(layer "F.Fab")
		)
		(fp_line
			(start 0.120396 0.2794)
			(end -0.12065 0.2794)
			(stroke
				(width 0.1)
				(type default)
			)
			(layer "F.Fab")
		)
		(fp_line
			(start -0.12065 0.3048)
			(end -0.67945 0.3048)
			(stroke
				(width 0.1)
				(type default)
			)
			(layer "F.Fab")
		)
		(fp_line
			(start -0.12065 0.2794)
			(end -0.12065 0.3048)
			(stroke
				(width 0.1)
				(type default)
			)
			(layer "F.Fab")
		)
		(fp_line
			(start -0.12065 -0.2794)
			(end 0.12065 -0.2794)
			(stroke
				(width 0.1)
				(type default)
			)
			(layer "F.Fab")
		)
		(fp_line
			(start -0.12065 -0.305054)
			(end -0.12065 -0.2794)
			(stroke
				(width 0.1)
				(type default)
			)
			(layer "F.Fab")
		)
		(fp_line
			(start -0.67945 0.3048)
			(end -0.67945 -0.305054)
			(stroke
				(width 0.1)
				(type default)
			)
			(layer "F.Fab")
		)
		(fp_line
			(start -0.67945 -0.305054)
			(end -0.12065 -0.305054)
			(stroke
				(width 0.1)
				(type default)
			)
			(layer "F.Fab")
		)
		(pad "1" smd circle
			(at -0.40005 0 180)
			(size 0 0)
			(layers "F.Cu" "F.Mask" "F.Paste")
			(net "P3V3_AUX")
		)
		(pad "2" smd circle
			(at 0.40005 0 180)
			(size 0 0)
			(layers "F.Cu" "F.Mask" "F.Paste")
			(net "PWRGD_P1V2_AUX_R")
		)
	)
	(footprint ""
		(layer "F.Cu")
		(at 28.270454 -15.992602)
		(property "Reference" "R386"
			(at 0 0 0)
			(layer "F.SilkS")
			(hide yes)
			(effects
				(font
					(size 1.27 1.27)
				)
			)
		)
		(property "Value" ""
			(at 0 0 0)
			(layer "F.Fab")
			(effects
				(font
					(size 1.27 1.27)
				)
			)
		)
		(duplicate_pad_numbers_are_jumpers no)
		(fp_line
			(start -0.7874 -0.4064)
			(end 0.7874 -0.4064)
			(stroke
				(width 0.1524)
				(type default)
			)
			(layer "F.SilkS")
		)
		(fp_line
			(start 0.7874 0.4064)
			(end -0.7874 0.4064)
			(stroke
				(width 0.1524)
				(type default)
			)
			(layer "F.SilkS")
		)
		(fp_line
			(start -0.67945 -0.305054)
			(end -0.12065 -0.305054)
			(stroke
				(width 0.1)
				(type default)
			)
			(layer "F.Fab")
		)
		(fp_line
			(start -0.67945 0.3048)
			(end -0.67945 -0.305054)
			(stroke
				(width 0.1)
				(type default)
			)
			(layer "F.Fab")
		)
		(fp_line
			(start -0.12065 -0.305054)
			(end -0.12065 -0.2794)
			(stroke
				(width 0.1)
				(type default)
			)
			(layer "F.Fab")
		)
		(fp_line
			(start -0.12065 -0.2794)
			(end 0.12065 -0.2794)
			(stroke
				(width 0.1)
				(type default)
			)
			(layer "F.Fab")
		)
		(fp_line
			(start -0.12065 0.2794)
			(end -0.12065 0.3048)
			(stroke
				(width 0.1)
				(type default)
			)
			(layer "F.Fab")
		)
		(fp_line
			(start -0.12065 0.3048)
			(end -0.67945 0.3048)
			(stroke
				(width 0.1)
				(type default)
			)
			(layer "F.Fab")
		)
		(fp_line
			(start 0.120396 0.2794)
			(end -0.12065 0.2794)
			(stroke
				(width 0.1)
				(type default)
			)
			(layer "F.Fab")
		)
		(fp_line
			(start 0.120396 0.3048)
			(end 0.120396 0.2794)
			(stroke
				(width 0.1)
				(type default)
			)
			(layer "F.Fab")
		)
		(fp_line
			(start 0.12065 -0.3048)
			(end 0.67945 -0.3048)
			(stroke
				(width 0.1)
				(type default)
			)
			(layer "F.Fab")
		)
		(fp_line
			(start 0.12065 -0.2794)
			(end 0.12065 -0.3048)
			(stroke
				(width 0.1)
				(type default)
			)
			(layer "F.Fab")
		)
		(fp_line
			(start 0.67945 -0.3048)
			(end 0.67945 0.3048)
			(stroke
				(width 0.1)
				(type default)
			)
			(layer "F.Fab")
		)
		(fp_line
			(start 0.67945 0.3048)
			(end 0.120396 0.3048)
			(stroke
				(width 0.1)
				(type default)
			)
			(layer "F.Fab")
		)
		(pad "1" smd circle
			(at -0.40005 0)
			(size 0 0)
			(layers "F.Cu" "F.Mask" "F.Paste")
			(net "USB_FPNL_DP")
		)
		(pad "2" smd circle
			(at 0.40005 0)
			(size 0 0)
			(layers "F.Cu" "F.Mask" "F.Paste")
			(net "USB2_01_F_DP")
		)
	)
	(footprint ""
		(layer "F.Cu")
		(at 7.79907 -64.787018 90)
		(property "Reference" "PU1"
			(at 3.716782 3.4544 90)
			(unlocked yes)
			(layer "F.SilkS")
			(effects
				(font
					(size 0.7874 0.5842)
					(thickness 0.1524)
				)
				(justify left)
			)
		)
		(property "Value" ""
			(at 0 0 90)
			(layer "F.Fab")
			(effects
				(font
					(size 1.27 1.27)
				)
			)
		)
		(duplicate_pad_numbers_are_jumpers no)
		(fp_line
			(start 1.050036 -1.549908)
			(end 1.050036 -1.253998)
			(stroke
				(width 0.1524)
				(type default)
			)
			(layer "F.SilkS")
		)
		(fp_line
			(start 0.503936 -1.549908)
			(end 1.050036 -1.549908)
			(stroke
				(width 0.1524)
				(type default)
			)
			(layer "F.SilkS")
		)
		(fp_line
			(start -1.050036 -1.549908)
			(end -0.503936 -1.549908)
			(stroke
				(width 0.1524)
				(type default)
			)
			(layer "F.SilkS")
		)
		(fp_line
			(start -1.050036 -1.253998)
			(end -1.050036 -1.549908)
			(stroke
				(width 0.1524)
				(type default)
			)
			(layer "F.SilkS")
		)
		(fp_line
			(start 1.050036 1.253998)
			(end 1.050036 1.549908)
			(stroke
				(width 0.1524)
				(type default)
			)
			(layer "F.SilkS")
		)
		(fp_line
			(start 1.050036 1.549908)
			(end 0.503936 1.549908)
			(stroke
				(width 0.1524)
				(type default)
			)
			(layer "F.SilkS")
		)
		(fp_line
			(start -0.503936 1.549908)
			(end -1.050036 1.549908)
			(stroke
				(width 0.1524)
				(type default)
			)
			(layer "F.SilkS")
		)
		(fp_line
			(start -1.050036 1.549908)
			(end -1.050036 1.253998)
			(stroke
				(width 0.1524)
				(type default)
			)
			(layer "F.SilkS")
		)
		(fp_poly
			(pts
				(xy -2.019808 -1.80086) (xy -1.341374 -2.148078) (xy -1.3335 -1.296162)
			)
			(stroke
				(width 0)
				(type default)
			)
			(fill yes)
			(layer "F.SilkS")
		)
		(fp_line
			(start 1.050036 -1.549908)
			(end 1.050036 1.549908)
			(stroke
				(width 0.1)
				(type default)
			)
			(layer "F.Fab")
		)
		(fp_line
			(start -1.050036 -1.549908)
			(end 1.050036 -1.549908)
			(stroke
				(width 0.1)
				(type default)
			)
			(layer "F.Fab")
		)
		(fp_line
			(start 1.050036 1.549908)
			(end -1.050036 1.549908)
			(stroke
				(width 0.1)
				(type default)
			)
			(layer "F.Fab")
		)
		(fp_line
			(start -1.050036 1.549908)
			(end -1.050036 -1.549908)
			(stroke
				(width 0.1)
				(type default)
			)
			(layer "F.Fab")
		)
		(fp_poly
			(pts
				(xy -2.2352 -0.618998) (xy -2.2352 -1.380998) (xy -1.4732 -0.999998)
			)
			(stroke
				(width 0)
				(type default)
			)
			(fill yes)
			(layer "F.Fab")
		)
		(pad "1" smd circle
			(at -0.94996 -0.999998)
			(size 0 0)
			(layers "F.Cu" "F.Mask" "F.Paste")
			(net "GND")
		)
		(pad "2" smd rect
			(at -0.849884 -0.499872 180)
			(size 0.254 0.9144)
			(layers "F.Cu" "F.Mask" "F.Paste")
			(net "SW_P3V3_AUX_SW")
		)
		(pad "3" smd rect
			(at -0.649986 0 180)
			(size 0.254 1.3208)
			(layers "F.Cu" "F.Mask" "F.Paste")
			(net "SW_P3V3_AUX_FLT")
		)
		(pad "4" smd rect
			(at -0.849884 0.499872 180)
			(size 0.254 0.9144)
			(layers "F.Cu" "F.Mask" "F.Paste")
			(net "P3V3_AUX_CS")
		)
		(pad "5" smd circle
			(at -0.94996 0.999998)
			(size 0 0)
			(layers "F.Cu" "F.Mask" "F.Paste")
			(net "PWRGD_EN_P3V3_R")
		)
		(pad "6" smd circle
			(at -0.249936 1.450086 90)
			(size 0 0)
			(layers "F.Cu" "F.Mask" "F.Paste")
			(net "P3V3_AUX_FB_RC")
		)
		(pad "7" smd circle
			(at 0.249936 1.450086 90)
			(size 0 0)
			(layers "F.Cu" "F.Mask" "F.Paste")
			(net "GND")
		)
		(pad "8" smd circle
			(at 0.94996 0.999998 180)
			(size 0 0)
			(layers "F.Cu" "F.Mask" "F.Paste")
			(net "P3V3_AUX_REF")
		)
		(pad "9" smd rect
			(at 0.849884 0.499872 180)
			(size 0.254 0.9144)
			(layers "F.Cu" "F.Mask" "F.Paste")
			(net "PWRGD_P3V3_AUX_R")
		)
		(pad "10" smd rect
			(at 0.849884 0 180)
			(size 0.254 0.9144)
			(layers "F.Cu" "F.Mask" "F.Paste")
			(net "SW_P3V3_AUX_BST_R")
		)
		(pad "11" smd rect
			(at 0.849884 -0.499872 180)
			(size 0.254 0.9144)
			(layers "F.Cu" "F.Mask" "F.Paste")
			(net "SW_P3V3_AUX_SW")
		)
		(pad "12" smd circle
			(at 0.94996 -0.999998 180)
			(size 0 0)
			(layers "F.Cu" "F.Mask" "F.Paste")
			(net "P3V3_AUX_MODE")
		)
		(pad "13" smd circle
			(at 0.249936 -1.450086 270)
			(size 0 0)
			(layers "F.Cu" "F.Mask" "F.Paste")
			(net "P3V3_AUX_VCC")
		)
		(pad "14" smd circle
			(at -0.249936 -1.450086 270)
			(size 0 0)
			(layers "F.Cu" "F.Mask" "F.Paste")
			(net "GND")
		)
	)
	(footprint ""
		(layer "F.Cu")
		(at 51.562 -85.9028 180)
		(property "Reference" "J1"
			(at 3.6322 -1.44907 0)
			(unlocked yes)
			(layer "F.SilkS")
			(effects
				(font
					(size 0.7874 0.5842)
					(thickness 0.1524)
				)
				(justify left)
			)
		)
		(property "Value" ""
			(at 0 0 180)
			(layer "F.Fab")
			(effects
				(font
					(size 1.27 1.27)
				)
			)
		)
		(duplicate_pad_numbers_are_jumpers no)
		(fp_line
			(start 1.249934 3.860038)
			(end 1.249934 0.6477)
			(stroke
				(width 0.1524)
				(type default)
			)
			(layer "F.SilkS")
		)
		(fp_line
			(start 1.249934 -0.6477)
			(end 1.249934 -3.860038)
			(stroke
				(width 0.1524)
				(type default)
			)
			(layer "F.SilkS")
		)
		(fp_line
			(start 1.249934 -3.860038)
			(end -1.249934 -3.860038)
			(stroke
				(width 0.1524)
				(type default)
			)
			(layer "F.SilkS")
		)
		(fp_line
			(start -1.249934 3.860038)
			(end 1.249934 3.860038)
			(stroke
				(width 0.1524)
				(type default)
			)
			(layer "F.SilkS")
		)
		(fp_line
			(start -1.249934 3.1877)
			(end -1.249934 3.860038)
			(stroke
				(width 0.1524)
				(type default)
			)
			(layer "F.SilkS")
		)
		(fp_line
			(start -1.249934 -1.8923)
			(end -1.249934 1.8923)
			(stroke
				(width 0.1524)
				(type default)
			)
			(layer "F.SilkS")
		)
		(fp_line
			(start -1.249934 -3.860038)
			(end -1.249934 -3.1877)
			(stroke
				(width 0.1524)
				(type default)
			)
			(layer "F.SilkS")
		)
		(fp_poly
			(pts
				(xy -3.7084 -3.9116) (xy -2.6924 -3.4036) (xy -3.7084 -2.8956)
			)
			(stroke
				(width 0)
				(type default)
			)
			(fill yes)
			(layer "F.SilkS")
		)
		(fp_line
			(start 1.249934 3.860038)
			(end 1.249934 -3.860038)
			(stroke
				(width 0.1)
				(type default)
			)
			(layer "F.Fab")
		)
		(fp_line
			(start 1.249934 -3.860038)
			(end -1.249934 -3.860038)
			(stroke
				(width 0.1)
				(type default)
			)
			(layer "F.Fab")
		)
		(fp_line
			(start -1.249934 3.860038)
			(end 1.249934 3.860038)
			(stroke
				(width 0.1)
				(type default)
			)
			(layer "F.Fab")
		)
		(fp_line
			(start -1.249934 -3.860038)
			(end -1.249934 3.860038)
			(stroke
				(width 0.1)
				(type default)
			)
			(layer "F.Fab")
		)
		(fp_poly
			(pts
				(xy -4.2164 -3.048) (xy -3.2004 -2.54) (xy -4.2164 -2.032)
			)
			(stroke
				(width 0)
				(type default)
			)
			(fill yes)
			(layer "F.Fab")
		)
		(pad "1" smd rect
			(at -1.374902 -2.54 90)
			(size 1.016 2.7686)
			(layers "F.Cu" "F.Mask" "F.Paste")
			(net "PU_J1_P1")
		)
		(pad "2" smd rect
			(at 1.374902 0 90)
			(size 1.016 2.7686)
			(layers "F.Cu" "F.Mask" "F.Paste")
			(net "FLASH_LATCH_Q_N_R2")
		)
		(pad "3" smd rect
			(at -1.374902 2.54 90)
			(size 1.016 2.7686)
			(layers "F.Cu" "F.Mask" "F.Paste")
			(net "NC_J1_P3")
		)
	)
	(footprint ""
		(layer "F.Cu")
		(at 54.473856 -30.867604 90)
		(property "Reference" "R521"
			(at 0 0 90)
			(layer "F.SilkS")
			(hide yes)
			(effects
				(font
					(size 1.27 1.27)
				)
			)
		)
		(property "Value" ""
			(at 0 0 90)
			(layer "F.Fab")
			(effects
				(font
					(size 1.27 1.27)
				)
			)
		)
		(duplicate_pad_numbers_are_jumpers no)
		(fp_line
			(start 0.7874 -0.4064)
			(end 0.7874 0.4064)
			(stroke
				(width 0.1524)
				(type default)
			)
			(layer "F.SilkS")
		)
		(fp_line
			(start -0.7874 -0.4064)
			(end 0.7874 -0.4064)
			(stroke
				(width 0.1524)
				(type default)
			)
			(layer "F.SilkS")
		)
		(fp_line
			(start 0.7874 0.4064)
			(end -0.7874 0.4064)
			(stroke
				(width 0.1524)
				(type default)
			)
			(layer "F.SilkS")
		)
		(fp_line
			(start -0.7874 0.4064)
			(end -0.7874 -0.4064)
			(stroke
				(width 0.1524)
				(type default)
			)
			(layer "F.SilkS")
		)
		(fp_line
			(start -0.12065 -0.305054)
			(end -0.12065 -0.2794)
			(stroke
				(width 0.1)
				(type default)
			)
			(layer "F.Fab")
		)
		(fp_line
			(start -0.67945 -0.305054)
			(end -0.12065 -0.305054)
			(stroke
				(width 0.1)
				(type default)
			)
			(layer "F.Fab")
		)
		(fp_line
			(start 0.67945 -0.3048)
			(end 0.67945 0.3048)
			(stroke
				(width 0.1)
				(type default)
			)
			(layer "F.Fab")
		)
		(fp_line
			(start 0.12065 -0.3048)
			(end 0.67945 -0.3048)
			(stroke
				(width 0.1)
				(type default)
			)
			(layer "F.Fab")
		)
		(fp_line
			(start 0.12065 -0.2794)
			(end 0.12065 -0.3048)
			(stroke
				(width 0.1)
				(type default)
			)
			(layer "F.Fab")
		)
		(fp_line
			(start -0.12065 -0.2794)
			(end 0.12065 -0.2794)
			(stroke
				(width 0.1)
				(type default)
			)
			(layer "F.Fab")
		)
		(fp_line
			(start 0.120396 0.2794)
			(end -0.12065 0.2794)
			(stroke
				(width 0.1)
				(type default)
			)
			(layer "F.Fab")
		)
		(fp_line
			(start -0.12065 0.2794)
			(end -0.12065 0.3048)
			(stroke
				(width 0.1)
				(type default)
			)
			(layer "F.Fab")
		)
		(fp_line
			(start 0.67945 0.3048)
			(end 0.120396 0.3048)
			(stroke
				(width 0.1)
				(type default)
			)
			(layer "F.Fab")
		)
		(fp_line
			(start 0.120396 0.3048)
			(end 0.120396 0.2794)
			(stroke
				(width 0.1)
				(type default)
			)
			(layer "F.Fab")
		)
		(fp_line
			(start -0.12065 0.3048)
			(end -0.67945 0.3048)
			(stroke
				(width 0.1)
				(type default)
			)
			(layer "F.Fab")
		)
		(fp_line
			(start -0.67945 0.3048)
			(end -0.67945 -0.305054)
			(stroke
				(width 0.1)
				(type default)
			)
			(layer "F.Fab")
		)
		(pad "1" smd circle
			(at -0.40005 0 90)
			(size 0 0)
			(layers "F.Cu" "F.Mask" "F.Paste")
			(net "P3V3_AUX")
		)
		(pad "2" smd circle
			(at 0.40005 0 90)
			(size 0 0)
			(layers "F.Cu" "F.Mask" "F.Paste")
			(net "SMB_BMC_MM10_SDA")
		)
	)
	(footprint ""
		(layer "F.Cu")
		(at 39.905686 -46.391576 180)
		(property "Reference" "R817"
			(at 0 0 180)
			(layer "F.SilkS")
			(hide yes)
			(effects
				(font
					(size 1.27 1.27)
				)
			)
		)
		(property "Value" ""
			(at 0 0 180)
			(layer "F.Fab")
			(effects
				(font
					(size 1.27 1.27)
				)
			)
		)
		(duplicate_pad_numbers_are_jumpers no)
		(fp_line
			(start 0.7874 0.4064)
			(end -0.7874 0.4064)
			(stroke
				(width 0.1524)
				(type default)
			)
			(layer "F.SilkS")
		)
		(fp_line
			(start 0.7874 -0.4064)
			(end 0.7874 0.4064)
			(stroke
				(width 0.1524)
				(type default)
			)
			(layer "F.SilkS")
		)
		(fp_line
			(start -0.7874 0.4064)
			(end -0.7874 -0.4064)
			(stroke
				(width 0.1524)
				(type default)
			)
			(layer "F.SilkS")
		)
		(fp_line
			(start -0.7874 -0.4064)
			(end 0.7874 -0.4064)
			(stroke
				(width 0.1524)
				(type default)
			)
			(layer "F.SilkS")
		)
		(fp_line
			(start 0.67945 0.3048)
			(end 0.120396 0.3048)
			(stroke
				(width 0.1)
				(type default)
			)
			(layer "F.Fab")
		)
		(fp_line
			(start 0.67945 -0.3048)
			(end 0.67945 0.3048)
			(stroke
				(width 0.1)
				(type default)
			)
			(layer "F.Fab")
		)
		(fp_line
			(start 0.12065 -0.2794)
			(end 0.12065 -0.3048)
			(stroke
				(width 0.1)
				(type default)
			)
			(layer "F.Fab")
		)
		(fp_line
			(start 0.12065 -0.3048)
			(end 0.67945 -0.3048)
			(stroke
				(width 0.1)
				(type default)
			)
			(layer "F.Fab")
		)
		(fp_line
			(start 0.120396 0.3048)
			(end 0.120396 0.2794)
			(stroke
				(width 0.1)
				(type default)
			)
			(layer "F.Fab")
		)
		(fp_line
			(start 0.120396 0.2794)
			(end -0.12065 0.2794)
			(stroke
				(width 0.1)
				(type default)
			)
			(layer "F.Fab")
		)
		(fp_line
			(start -0.12065 0.3048)
			(end -0.67945 0.3048)
			(stroke
				(width 0.1)
				(type default)
			)
			(layer "F.Fab")
		)
		(fp_line
			(start -0.12065 0.2794)
			(end -0.12065 0.3048)
			(stroke
				(width 0.1)
				(type default)
			)
			(layer "F.Fab")
		)
		(fp_line
			(start -0.12065 -0.2794)
			(end 0.12065 -0.2794)
			(stroke
				(width 0.1)
				(type default)
			)
			(layer "F.Fab")
		)
		(fp_line
			(start -0.12065 -0.305054)
			(end -0.12065 -0.2794)
			(stroke
				(width 0.1)
				(type default)
			)
			(layer "F.Fab")
		)
		(fp_line
			(start -0.67945 0.3048)
			(end -0.67945 -0.305054)
			(stroke
				(width 0.1)
				(type default)
			)
			(layer "F.Fab")
		)
		(fp_line
			(start -0.67945 -0.305054)
			(end -0.12065 -0.305054)
			(stroke
				(width 0.1)
				(type default)
			)
			(layer "F.Fab")
		)
		(pad "1" smd circle
			(at -0.40005 0 180)
			(size 0 0)
			(layers "F.Cu" "F.Mask" "F.Paste")
			(net "SMB_BMC_MM13_R_SCL")
		)
		(pad "2" smd circle
			(at 0.40005 0 180)
			(size 0 0)
			(layers "F.Cu" "F.Mask" "F.Paste")
			(net "GND")
		)
	)
	(footprint ""
		(layer "F.Cu")
		(at 64.4144 -28.0162 180)
		(property "Reference" "R440"
			(at 0 0 180)
			(layer "F.SilkS")
			(hide yes)
			(effects
				(font
					(size 1.27 1.27)
				)
			)
		)
		(property "Value" ""
			(at 0 0 180)
			(layer "F.Fab")
			(effects
				(font
					(size 1.27 1.27)
				)
			)
		)
		(duplicate_pad_numbers_are_jumpers no)
		(fp_line
			(start 0.7874 0.4064)
			(end -0.3048 0.4064)
			(stroke
				(width 0.1524)
				(type default)
			)
			(layer "F.SilkS")
		)
		(fp_line
			(start 0.7874 -0.4064)
			(end 0.7874 0.4064)
			(stroke
				(width 0.1524)
				(type default)
			)
			(layer "F.SilkS")
		)
		(fp_line
			(start -0.381 -0.4064)
			(end 0.7874 -0.4064)
			(stroke
				(width 0.1524)
				(type default)
			)
			(layer "F.SilkS")
		)
		(fp_line
			(start 0.67945 0.3048)
			(end 0.120396 0.3048)
			(stroke
				(width 0.1)
				(type default)
			)
			(layer "F.Fab")
		)
		(fp_line
			(start 0.67945 -0.3048)
			(end 0.67945 0.3048)
			(stroke
				(width 0.1)
				(type default)
			)
			(layer "F.Fab")
		)
		(fp_line
			(start 0.12065 -0.2794)
			(end 0.12065 -0.3048)
			(stroke
				(width 0.1)
				(type default)
			)
			(layer "F.Fab")
		)
		(fp_line
			(start 0.12065 -0.3048)
			(end 0.67945 -0.3048)
			(stroke
				(width 0.1)
				(type default)
			)
			(layer "F.Fab")
		)
		(fp_line
			(start 0.120396 0.3048)
			(end 0.120396 0.2794)
			(stroke
				(width 0.1)
				(type default)
			)
			(layer "F.Fab")
		)
		(fp_line
			(start 0.120396 0.2794)
			(end -0.12065 0.2794)
			(stroke
				(width 0.1)
				(type default)
			)
			(layer "F.Fab")
		)
		(fp_line
			(start -0.12065 0.3048)
			(end -0.67945 0.3048)
			(stroke
				(width 0.1)
				(type default)
			)
			(layer "F.Fab")
		)
		(fp_line
			(start -0.12065 0.2794)
			(end -0.12065 0.3048)
			(stroke
				(width 0.1)
				(type default)
			)
			(layer "F.Fab")
		)
		(fp_line
			(start -0.12065 -0.2794)
			(end 0.12065 -0.2794)
			(stroke
				(width 0.1)
				(type default)
			)
			(layer "F.Fab")
		)
		(fp_line
			(start -0.12065 -0.305054)
			(end -0.12065 -0.2794)
			(stroke
				(width 0.1)
				(type default)
			)
			(layer "F.Fab")
		)
		(fp_line
			(start -0.67945 0.3048)
			(end -0.67945 -0.305054)
			(stroke
				(width 0.1)
				(type default)
			)
			(layer "F.Fab")
		)
		(fp_line
			(start -0.67945 -0.305054)
			(end -0.12065 -0.305054)
			(stroke
				(width 0.1)
				(type default)
			)
			(layer "F.Fab")
		)
		(pad "1" smd circle
			(at -0.40005 0 180)
			(size 0 0)
			(layers "F.Cu" "F.Mask" "F.Paste")
			(net "USB_HOST_BMC_A_DP")
		)
		(pad "2" smd circle
			(at 0.40005 0 180)
			(size 0 0)
			(layers "F.Cu" "F.Mask" "F.Paste")
			(net "GND")
		)
	)
	(footprint ""
		(layer "F.Cu")
		(at 57.023 -77.3684)
		(property "Reference" "R555"
			(at 0 0 0)
			(layer "F.SilkS")
			(hide yes)
			(effects
				(font
					(size 1.27 1.27)
				)
			)
		)
		(property "Value" ""
			(at 0 0 0)
			(layer "F.Fab")
			(effects
				(font
					(size 1.27 1.27)
				)
			)
		)
		(duplicate_pad_numbers_are_jumpers no)
		(fp_line
			(start -0.7874 -0.4064)
			(end 0.7874 -0.4064)
			(stroke
				(width 0.1524)
				(type default)
			)
			(layer "F.SilkS")
		)
		(fp_line
			(start -0.7874 0.4064)
			(end -0.7874 -0.4064)
			(stroke
				(width 0.1524)
				(type default)
			)
			(layer "F.SilkS")
		)
		(fp_line
			(start 0.7874 -0.4064)
			(end 0.7874 0.4064)
			(stroke
				(width 0.1524)
				(type default)
			)
			(layer "F.SilkS")
		)
		(fp_line
			(start 0.7874 0.4064)
			(end -0.7874 0.4064)
			(stroke
				(width 0.1524)
				(type default)
			)
			(layer "F.SilkS")
		)
		(fp_line
			(start -0.67945 -0.305054)
			(end -0.12065 -0.305054)
			(stroke
				(width 0.1)
				(type default)
			)
			(layer "F.Fab")
		)
		(fp_line
			(start -0.67945 0.3048)
			(end -0.67945 -0.305054)
			(stroke
				(width 0.1)
				(type default)
			)
			(layer "F.Fab")
		)
		(fp_line
			(start -0.12065 -0.305054)
			(end -0.12065 -0.2794)
			(stroke
				(width 0.1)
				(type default)
			)
			(layer "F.Fab")
		)
		(fp_line
			(start -0.12065 -0.2794)
			(end 0.12065 -0.2794)
			(stroke
				(width 0.1)
				(type default)
			)
			(layer "F.Fab")
		)
		(fp_line
			(start -0.12065 0.2794)
			(end -0.12065 0.3048)
			(stroke
				(width 0.1)
				(type default)
			)
			(layer "F.Fab")
		)
		(fp_line
			(start -0.12065 0.3048)
			(end -0.67945 0.3048)
			(stroke
				(width 0.1)
				(type default)
			)
			(layer "F.Fab")
		)
		(fp_line
			(start 0.120396 0.2794)
			(end -0.12065 0.2794)
			(stroke
				(width 0.1)
				(type default)
			)
			(layer "F.Fab")
		)
		(fp_line
			(start 0.120396 0.3048)
			(end 0.120396 0.2794)
			(stroke
				(width 0.1)
				(type default)
			)
			(layer "F.Fab")
		)
		(fp_line
			(start 0.12065 -0.3048)
			(end 0.67945 -0.3048)
			(stroke
				(width 0.1)
				(type default)
			)
			(layer "F.Fab")
		)
		(fp_line
			(start 0.12065 -0.2794)
			(end 0.12065 -0.3048)
			(stroke
				(width 0.1)
				(type default)
			)
			(layer "F.Fab")
		)
		(fp_line
			(start 0.67945 -0.3048)
			(end 0.67945 0.3048)
			(stroke
				(width 0.1)
				(type default)
			)
			(layer "F.Fab")
		)
		(fp_line
			(start 0.67945 0.3048)
			(end 0.120396 0.3048)
			(stroke
				(width 0.1)
				(type default)
			)
			(layer "F.Fab")
		)
		(pad "1" smd circle
			(at -0.40005 0)
			(size 0 0)
			(layers "F.Cu" "F.Mask" "F.Paste")
			(net "FLASH_LATCH_Q_N_R")
		)
		(pad "2" smd circle
			(at 0.40005 0)
			(size 0 0)
			(layers "F.Cu" "F.Mask" "F.Paste")
			(net "FLASH_LATCH_Q_N_R1")
		)
	)
	(footprint ""
		(layer "F.Cu")
		(at 46.6852 -30.861 -90)
		(property "Reference" "R60"
			(at 0 0 270)
			(layer "F.SilkS")
			(hide yes)
			(effects
				(font
					(size 1.27 1.27)
				)
			)
		)
		(property "Value" ""
			(at 0 0 270)
			(layer "F.Fab")
			(effects
				(font
					(size 1.27 1.27)
				)
			)
		)
		(duplicate_pad_numbers_are_jumpers no)
		(fp_line
			(start -0.7874 0.4064)
			(end -0.7874 -0.4064)
			(stroke
				(width 0.1524)
				(type default)
			)
			(layer "F.SilkS")
		)
		(fp_line
			(start 0.7874 0.4064)
			(end -0.7874 0.4064)
			(stroke
				(width 0.1524)
				(type default)
			)
			(layer "F.SilkS")
		)
		(fp_line
			(start -0.7874 -0.4064)
			(end 0.7874 -0.4064)
			(stroke
				(width 0.1524)
				(type default)
			)
			(layer "F.SilkS")
		)
		(fp_line
			(start 0.7874 -0.4064)
			(end 0.7874 0.4064)
			(stroke
				(width 0.1524)
				(type default)
			)
			(layer "F.SilkS")
		)
		(fp_line
			(start -0.67945 0.3048)
			(end -0.67945 -0.305054)
			(stroke
				(width 0.1)
				(type default)
			)
			(layer "F.Fab")
		)
		(fp_line
			(start -0.12065 0.3048)
			(end -0.67945 0.3048)
			(stroke
				(width 0.1)
				(type default)
			)
			(layer "F.Fab")
		)
		(fp_line
			(start 0.120396 0.3048)
			(end 0.120396 0.2794)
			(stroke
				(width 0.1)
				(type default)
			)
			(layer "F.Fab")
		)
		(fp_line
			(start 0.67945 0.3048)
			(end 0.120396 0.3048)
			(stroke
				(width 0.1)
				(type default)
			)
			(layer "F.Fab")
		)
		(fp_line
			(start -0.12065 0.2794)
			(end -0.12065 0.3048)
			(stroke
				(width 0.1)
				(type default)
			)
			(layer "F.Fab")
		)
		(fp_line
			(start 0.120396 0.2794)
			(end -0.12065 0.2794)
			(stroke
				(width 0.1)
				(type default)
			)
			(layer "F.Fab")
		)
		(fp_line
			(start -0.12065 -0.2794)
			(end 0.12065 -0.2794)
			(stroke
				(width 0.1)
				(type default)
			)
			(layer "F.Fab")
		)
		(fp_line
			(start 0.12065 -0.2794)
			(end 0.12065 -0.3048)
			(stroke
				(width 0.1)
				(type default)
			)
			(layer "F.Fab")
		)
		(fp_line
			(start 0.12065 -0.3048)
			(end 0.67945 -0.3048)
			(stroke
				(width 0.1)
				(type default)
			)
			(layer "F.Fab")
		)
		(fp_line
			(start 0.67945 -0.3048)
			(end 0.67945 0.3048)
			(stroke
				(width 0.1)
				(type default)
			)
			(layer "F.Fab")
		)
		(fp_line
			(start -0.67945 -0.305054)
			(end -0.12065 -0.305054)
			(stroke
				(width 0.1)
				(type default)
			)
			(layer "F.Fab")
		)
		(fp_line
			(start -0.12065 -0.305054)
			(end -0.12065 -0.2794)
			(stroke
				(width 0.1)
				(type default)
			)
			(layer "F.Fab")
		)
		(pad "1" smd circle
			(at -0.40005 0 270)
			(size 0 0)
			(layers "F.Cu" "F.Mask" "F.Paste")
			(net "RST_ROT_CPU_R1_N")
		)
		(pad "2" smd circle
			(at 0.40005 0 270)
			(size 0 0)
			(layers "F.Cu" "F.Mask" "F.Paste")
			(net "RST_ROT_CPU_N")
		)
	)
	(footprint ""
		(layer "F.Cu")
		(at 58.7248 -65.5828)
		(property "Reference" "R683"
			(at 0 0 0)
			(layer "F.SilkS")
			(hide yes)
			(effects
				(font
					(size 1.27 1.27)
				)
			)
		)
		(property "Value" ""
			(at 0 0 0)
			(layer "F.Fab")
			(effects
				(font
					(size 1.27 1.27)
				)
			)
		)
		(duplicate_pad_numbers_are_jumpers no)
		(fp_line
			(start -0.7874 -0.4064)
			(end 0.7874 -0.4064)
			(stroke
				(width 0.1524)
				(type default)
			)
			(layer "F.SilkS")
		)
		(fp_line
			(start -0.7874 0.4064)
			(end -0.7874 -0.4064)
			(stroke
				(width 0.1524)
				(type default)
			)
			(layer "F.SilkS")
		)
		(fp_line
			(start 0.7874 -0.4064)
			(end 0.7874 0.4064)
			(stroke
				(width 0.1524)
				(type default)
			)
			(layer "F.SilkS")
		)
		(fp_line
			(start 0.7874 0.4064)
			(end -0.7874 0.4064)
			(stroke
				(width 0.1524)
				(type default)
			)
			(layer "F.SilkS")
		)
		(fp_line
			(start -0.67945 -0.305054)
			(end -0.12065 -0.305054)
			(stroke
				(width 0.1)
				(type default)
			)
			(layer "F.Fab")
		)
		(fp_line
			(start -0.67945 0.3048)
			(end -0.67945 -0.305054)
			(stroke
				(width 0.1)
				(type default)
			)
			(layer "F.Fab")
		)
		(fp_line
			(start -0.12065 -0.305054)
			(end -0.12065 -0.2794)
			(stroke
				(width 0.1)
				(type default)
			)
			(layer "F.Fab")
		)
		(fp_line
			(start -0.12065 -0.2794)
			(end 0.12065 -0.2794)
			(stroke
				(width 0.1)
				(type default)
			)
			(layer "F.Fab")
		)
		(fp_line
			(start -0.12065 0.2794)
			(end -0.12065 0.3048)
			(stroke
				(width 0.1)
				(type default)
			)
			(layer "F.Fab")
		)
		(fp_line
			(start -0.12065 0.3048)
			(end -0.67945 0.3048)
			(stroke
				(width 0.1)
				(type default)
			)
			(layer "F.Fab")
		)
		(fp_line
			(start 0.120396 0.2794)
			(end -0.12065 0.2794)
			(stroke
				(width 0.1)
				(type default)
			)
			(layer "F.Fab")
		)
		(fp_line
			(start 0.120396 0.3048)
			(end 0.120396 0.2794)
			(stroke
				(width 0.1)
				(type default)
			)
			(layer "F.Fab")
		)
		(fp_line
			(start 0.12065 -0.3048)
			(end 0.67945 -0.3048)
			(stroke
				(width 0.1)
				(type default)
			)
			(layer "F.Fab")
		)
		(fp_line
			(start 0.12065 -0.2794)
			(end 0.12065 -0.3048)
			(stroke
				(width 0.1)
				(type default)
			)
			(layer "F.Fab")
		)
		(fp_line
			(start 0.67945 -0.3048)
			(end 0.67945 0.3048)
			(stroke
				(width 0.1)
				(type default)
			)
			(layer "F.Fab")
		)
		(fp_line
			(start 0.67945 0.3048)
			(end 0.120396 0.3048)
			(stroke
				(width 0.1)
				(type default)
			)
			(layer "F.Fab")
		)
		(pad "1" smd circle
			(at -0.40005 0)
			(size 0 0)
			(layers "F.Cu" "F.Mask" "F.Paste")
			(net "P3V3_AUX")
		)
		(pad "2" smd circle
			(at 0.40005 0)
			(size 0 0)
			(layers "F.Cu" "F.Mask" "F.Paste")
			(net "PU_SPI1WP_N")
		)
	)
	(footprint ""
		(layer "F.Cu")
		(at 29.2608 -30.099)
		(property "Reference" "L29"
			(at 0 0 0)
			(layer "F.SilkS")
			(hide yes)
			(effects
				(font
					(size 1.27 1.27)
				)
			)
		)
		(property "Value" ""
			(at 0 0 0)
			(layer "F.Fab")
			(effects
				(font
					(size 1.27 1.27)
				)
			)
		)
		(duplicate_pad_numbers_are_jumpers no)
		(fp_line
			(start -1.27 -0.5842)
			(end 1.27 -0.5842)
			(stroke
				(width 0.1524)
				(type default)
			)
			(layer "F.SilkS")
		)
		(fp_line
			(start -1.27 -0.5588)
			(end -1.27 -0.5842)
			(stroke
				(width 0.1524)
				(type default)
			)
			(layer "F.SilkS")
		)
		(fp_line
			(start -1.27 0.5842)
			(end -1.27 -0.5842)
			(stroke
				(width 0.1524)
				(type default)
			)
			(layer "F.SilkS")
		)
		(fp_line
			(start -0.127 0.5842)
			(end -0.127 -0.5842)
			(stroke
				(width 0.1524)
				(type default)
			)
			(layer "F.SilkS")
		)
		(fp_line
			(start 0.127 0.5842)
			(end 0.127 -0.5842)
			(stroke
				(width 0.1524)
				(type default)
			)
			(layer "F.SilkS")
		)
		(fp_line
			(start 1.27 0.5842)
			(end -1.27 0.5842)
			(stroke
				(width 0.1524)
				(type default)
			)
			(layer "F.SilkS")
		)
		(fp_line
			(start 1.27 0.5842)
			(end 1.27 -0.5842)
			(stroke
				(width 0.1524)
				(type default)
			)
			(layer "F.SilkS")
		)
		(fp_line
			(start -1.194308 -0.406654)
			(end -0.9144 -0.406654)
			(stroke
				(width 0.1)
				(type default)
			)
			(layer "F.Fab")
		)
		(fp_line
			(start -1.194308 0.406654)
			(end -1.194308 -0.406654)
			(stroke
				(width 0.1)
				(type default)
			)
			(layer "F.Fab")
		)
		(fp_line
			(start -0.9144 -0.508)
			(end 0.9144 -0.508)
			(stroke
				(width 0.1)
				(type default)
			)
			(layer "F.Fab")
		)
		(fp_line
			(start -0.9144 -0.406654)
			(end -0.9144 -0.508)
			(stroke
				(width 0.1)
				(type default)
			)
			(layer "F.Fab")
		)
		(fp_line
			(start -0.9144 0.406654)
			(end -1.194308 0.406654)
			(stroke
				(width 0.1)
				(type default)
			)
			(layer "F.Fab")
		)
		(fp_line
			(start -0.9144 0.508)
			(end -0.9144 0.406654)
			(stroke
				(width 0.1)
				(type default)
			)
			(layer "F.Fab")
		)
		(fp_line
			(start 0.9144 -0.508)
			(end 0.9144 -0.406654)
			(stroke
				(width 0.1)
				(type default)
			)
			(layer "F.Fab")
		)
		(fp_line
			(start 0.9144 -0.406654)
			(end 1.1938 -0.406654)
			(stroke
				(width 0.1)
				(type default)
			)
			(layer "F.Fab")
		)
		(fp_line
			(start 0.9144 0.4064)
			(end 0.9144 0.508)
			(stroke
				(width 0.1)
				(type default)
			)
			(layer "F.Fab")
		)
		(fp_line
			(start 0.9144 0.508)
			(end -0.9144 0.508)
			(stroke
				(width 0.1)
				(type default)
			)
			(layer "F.Fab")
		)
		(fp_line
			(start 1.1938 -0.406654)
			(end 1.1938 0.4064)
			(stroke
				(width 0.1)
				(type default)
			)
			(layer "F.Fab")
		)
		(fp_line
			(start 1.1938 0.4064)
			(end 0.9144 0.4064)
			(stroke
				(width 0.1)
				(type default)
			)
			(layer "F.Fab")
		)
		(pad "1" smd rect
			(at -0.7366 0 270)
			(size 0.7112 0.8128)
			(layers "F.Cu" "F.Mask" "F.Paste")
			(net "V_DACG")
		)
		(pad "2" smd rect
			(at 0.7366 0 270)
			(size 0.7112 0.8128)
			(layers "F.Cu" "F.Mask" "F.Paste")
			(net "V_DACG_IO")
		)
	)
	(footprint ""
		(layer "F.Cu")
		(at 81.818988 -59.05373 -90)
		(property "Reference" "PC257"
			(at 0 0 270)
			(layer "F.SilkS")
			(hide yes)
			(effects
				(font
					(size 1.27 1.27)
				)
			)
		)
		(property "Value" ""
			(at 0 0 270)
			(layer "F.Fab")
			(effects
				(font
					(size 1.27 1.27)
				)
			)
		)
		(duplicate_pad_numbers_are_jumpers no)
		(fp_line
			(start -1.651 0.8382)
			(end -1.651 -0.8382)
			(stroke
				(width 0.1524)
				(type default)
			)
			(layer "F.SilkS")
		)
		(fp_line
			(start 0 0.8382)
			(end 0 -0.8382)
			(stroke
				(width 0.1524)
				(type default)
			)
			(layer "F.SilkS")
		)
		(fp_line
			(start 1.651 0.8382)
			(end -1.651 0.8382)
			(stroke
				(width 0.1524)
				(type default)
			)
			(layer "F.SilkS")
		)
		(fp_line
			(start -1.651 -0.8382)
			(end 1.651 -0.8382)
			(stroke
				(width 0.1524)
				(type default)
			)
			(layer "F.SilkS")
		)
		(fp_line
			(start 1.651 -0.8382)
			(end 1.651 0.8382)
			(stroke
				(width 0.1524)
				(type default)
			)
			(layer "F.SilkS")
		)
		(fp_line
			(start -1.55956 0.7366)
			(end -1.524 0.7366)
			(stroke
				(width 0.1)
				(type default)
			)
			(layer "F.Fab")
		)
		(fp_line
			(start -1.524 0.7366)
			(end 1.524 0.7366)
			(stroke
				(width 0.1)
				(type default)
			)
			(layer "F.Fab")
		)
		(fp_line
			(start 1.524 0.7366)
			(end 1.55956 0.7366)
			(stroke
				(width 0.1)
				(type default)
			)
			(layer "F.Fab")
		)
		(fp_line
			(start 1.55956 0.7366)
			(end 1.55956 -0.7366)
			(stroke
				(width 0.1)
				(type default)
			)
			(layer "F.Fab")
		)
		(fp_line
			(start -1.55956 -0.7366)
			(end -1.55956 0.7366)
			(stroke
				(width 0.1)
				(type default)
			)
			(layer "F.Fab")
		)
		(fp_line
			(start -1.524 -0.7366)
			(end -1.55956 -0.7366)
			(stroke
				(width 0.1)
				(type default)
			)
			(layer "F.Fab")
		)
		(fp_line
			(start 1.524 -0.7366)
			(end -1.524 -0.7366)
			(stroke
				(width 0.1)
				(type default)
			)
			(layer "F.Fab")
		)
		(fp_line
			(start 1.55956 -0.7366)
			(end 1.524 -0.7366)
			(stroke
				(width 0.1)
				(type default)
			)
			(layer "F.Fab")
		)
		(pad "1" smd rect
			(at -0.94996 0 90)
			(size 1.1176 1.3716)
			(layers "F.Cu" "F.Mask" "F.Paste")
			(net "P1V2_AUX")
		)
		(pad "2" smd rect
			(at 0.94996 0 90)
			(size 1.1176 1.3716)
			(layers "F.Cu" "F.Mask" "F.Paste")
			(net "GND")
		)
	)
	(footprint ""
		(layer "F.Cu")
		(at 20.701 -42.9006 -90)
		(property "Reference" "R752"
			(at 0 0 270)
			(layer "F.SilkS")
			(hide yes)
			(effects
				(font
					(size 1.27 1.27)
				)
			)
		)
		(property "Value" ""
			(at 0 0 270)
			(layer "F.Fab")
			(effects
				(font
					(size 1.27 1.27)
				)
			)
		)
		(duplicate_pad_numbers_are_jumpers no)
		(fp_line
			(start -0.7874 0.4064)
			(end -0.7874 -0.4064)
			(stroke
				(width 0.1524)
				(type default)
			)
			(layer "F.SilkS")
		)
		(fp_line
			(start 0.7874 0.4064)
			(end -0.7874 0.4064)
			(stroke
				(width 0.1524)
				(type default)
			)
			(layer "F.SilkS")
		)
		(fp_line
			(start -0.7874 -0.4064)
			(end 0.7874 -0.4064)
			(stroke
				(width 0.1524)
				(type default)
			)
			(layer "F.SilkS")
		)
		(fp_line
			(start 0.7874 -0.4064)
			(end 0.7874 0.4064)
			(stroke
				(width 0.1524)
				(type default)
			)
			(layer "F.SilkS")
		)
		(fp_line
			(start -0.67945 0.3048)
			(end -0.67945 -0.305054)
			(stroke
				(width 0.1)
				(type default)
			)
			(layer "F.Fab")
		)
		(fp_line
			(start -0.12065 0.3048)
			(end -0.67945 0.3048)
			(stroke
				(width 0.1)
				(type default)
			)
			(layer "F.Fab")
		)
		(fp_line
			(start 0.120396 0.3048)
			(end 0.120396 0.2794)
			(stroke
				(width 0.1)
				(type default)
			)
			(layer "F.Fab")
		)
		(fp_line
			(start 0.67945 0.3048)
			(end 0.120396 0.3048)
			(stroke
				(width 0.1)
				(type default)
			)
			(layer "F.Fab")
		)
		(fp_line
			(start -0.12065 0.2794)
			(end -0.12065 0.3048)
			(stroke
				(width 0.1)
				(type default)
			)
			(layer "F.Fab")
		)
		(fp_line
			(start 0.120396 0.2794)
			(end -0.12065 0.2794)
			(stroke
				(width 0.1)
				(type default)
			)
			(layer "F.Fab")
		)
		(fp_line
			(start -0.12065 -0.2794)
			(end 0.12065 -0.2794)
			(stroke
				(width 0.1)
				(type default)
			)
			(layer "F.Fab")
		)
		(fp_line
			(start 0.12065 -0.2794)
			(end 0.12065 -0.3048)
			(stroke
				(width 0.1)
				(type default)
			)
			(layer "F.Fab")
		)
		(fp_line
			(start 0.12065 -0.3048)
			(end 0.67945 -0.3048)
			(stroke
				(width 0.1)
				(type default)
			)
			(layer "F.Fab")
		)
		(fp_line
			(start 0.67945 -0.3048)
			(end 0.67945 0.3048)
			(stroke
				(width 0.1)
				(type default)
			)
			(layer "F.Fab")
		)
		(fp_line
			(start -0.67945 -0.305054)
			(end -0.12065 -0.305054)
			(stroke
				(width 0.1)
				(type default)
			)
			(layer "F.Fab")
		)
		(fp_line
			(start -0.12065 -0.305054)
			(end -0.12065 -0.2794)
			(stroke
				(width 0.1)
				(type default)
			)
			(layer "F.Fab")
		)
		(pad "1" smd circle
			(at -0.40005 0 270)
			(size 0 0)
			(layers "F.Cu" "F.Mask" "F.Paste")
			(net "RST_SPI_FLASH_N")
		)
		(pad "2" smd circle
			(at 0.40005 0 270)
			(size 0 0)
			(layers "F.Cu" "F.Mask" "F.Paste")
			(net "RST_SPI_FLASH_R_N")
		)
	)
	(footprint ""
		(layer "F.Cu")
		(at 11.4554 -62.2046 180)
		(property "Reference" "R871"
			(at 0 0 180)
			(layer "F.SilkS")
			(hide yes)
			(effects
				(font
					(size 1.27 1.27)
				)
			)
		)
		(property "Value" ""
			(at 0 0 180)
			(layer "F.Fab")
			(effects
				(font
					(size 1.27 1.27)
				)
			)
		)
		(duplicate_pad_numbers_are_jumpers no)
		(fp_line
			(start 0.7874 0.4064)
			(end -0.7874 0.4064)
			(stroke
				(width 0.1524)
				(type default)
			)
			(layer "F.SilkS")
		)
		(fp_line
			(start 0.7874 -0.4064)
			(end 0.7874 0.4064)
			(stroke
				(width 0.1524)
				(type default)
			)
			(layer "F.SilkS")
		)
		(fp_line
			(start -0.7874 0.4064)
			(end -0.7874 -0.4064)
			(stroke
				(width 0.1524)
				(type default)
			)
			(layer "F.SilkS")
		)
		(fp_line
			(start -0.7874 -0.4064)
			(end 0.7874 -0.4064)
			(stroke
				(width 0.1524)
				(type default)
			)
			(layer "F.SilkS")
		)
		(fp_line
			(start 0.67945 0.3048)
			(end 0.120396 0.3048)
			(stroke
				(width 0.1)
				(type default)
			)
			(layer "F.Fab")
		)
		(fp_line
			(start 0.67945 -0.3048)
			(end 0.67945 0.3048)
			(stroke
				(width 0.1)
				(type default)
			)
			(layer "F.Fab")
		)
		(fp_line
			(start 0.12065 -0.2794)
			(end 0.12065 -0.3048)
			(stroke
				(width 0.1)
				(type default)
			)
			(layer "F.Fab")
		)
		(fp_line
			(start 0.12065 -0.3048)
			(end 0.67945 -0.3048)
			(stroke
				(width 0.1)
				(type default)
			)
			(layer "F.Fab")
		)
		(fp_line
			(start 0.120396 0.3048)
			(end 0.120396 0.2794)
			(stroke
				(width 0.1)
				(type default)
			)
			(layer "F.Fab")
		)
		(fp_line
			(start 0.120396 0.2794)
			(end -0.12065 0.2794)
			(stroke
				(width 0.1)
				(type default)
			)
			(layer "F.Fab")
		)
		(fp_line
			(start -0.12065 0.3048)
			(end -0.67945 0.3048)
			(stroke
				(width 0.1)
				(type default)
			)
			(layer "F.Fab")
		)
		(fp_line
			(start -0.12065 0.2794)
			(end -0.12065 0.3048)
			(stroke
				(width 0.1)
				(type default)
			)
			(layer "F.Fab")
		)
		(fp_line
			(start -0.12065 -0.2794)
			(end 0.12065 -0.2794)
			(stroke
				(width 0.1)
				(type default)
			)
			(layer "F.Fab")
		)
		(fp_line
			(start -0.12065 -0.305054)
			(end -0.12065 -0.2794)
			(stroke
				(width 0.1)
				(type default)
			)
			(layer "F.Fab")
		)
		(fp_line
			(start -0.67945 0.3048)
			(end -0.67945 -0.305054)
			(stroke
				(width 0.1)
				(type default)
			)
			(layer "F.Fab")
		)
		(fp_line
			(start -0.67945 -0.305054)
			(end -0.12065 -0.305054)
			(stroke
				(width 0.1)
				(type default)
			)
			(layer "F.Fab")
		)
		(pad "1" smd circle
			(at -0.40005 0 180)
			(size 0 0)
			(layers "F.Cu" "F.Mask" "F.Paste")
			(net "EN_P3V3_R1")
		)
		(pad "2" smd circle
			(at 0.40005 0 180)
			(size 0 0)
			(layers "F.Cu" "F.Mask" "F.Paste")
			(net "PWRGD_EN_P3V3_R")
		)
	)
	(footprint ""
		(layer "F.Cu")
		(at 63.62827 -63.919862 -90)
		(property "Reference" "R119"
			(at 0 0 270)
			(layer "F.SilkS")
			(hide yes)
			(effects
				(font
					(size 1.27 1.27)
				)
			)
		)
		(property "Value" ""
			(at 0 0 270)
			(layer "F.Fab")
			(effects
				(font
					(size 1.27 1.27)
				)
			)
		)
		(duplicate_pad_numbers_are_jumpers no)
		(fp_line
			(start -0.7874 0.4064)
			(end -0.7874 -0.4064)
			(stroke
				(width 0.1524)
				(type default)
			)
			(layer "F.SilkS")
		)
		(fp_line
			(start 0.7874 0.4064)
			(end -0.7874 0.4064)
			(stroke
				(width 0.1524)
				(type default)
			)
			(layer "F.SilkS")
		)
		(fp_line
			(start -0.7874 -0.4064)
			(end 0.7874 -0.4064)
			(stroke
				(width 0.1524)
				(type default)
			)
			(layer "F.SilkS")
		)
		(fp_line
			(start 0.7874 -0.4064)
			(end 0.7874 0.4064)
			(stroke
				(width 0.1524)
				(type default)
			)
			(layer "F.SilkS")
		)
		(fp_line
			(start -0.67945 0.3048)
			(end -0.67945 -0.305054)
			(stroke
				(width 0.1)
				(type default)
			)
			(layer "F.Fab")
		)
		(fp_line
			(start -0.12065 0.3048)
			(end -0.67945 0.3048)
			(stroke
				(width 0.1)
				(type default)
			)
			(layer "F.Fab")
		)
		(fp_line
			(start 0.120396 0.3048)
			(end 0.120396 0.2794)
			(stroke
				(width 0.1)
				(type default)
			)
			(layer "F.Fab")
		)
		(fp_line
			(start 0.67945 0.3048)
			(end 0.120396 0.3048)
			(stroke
				(width 0.1)
				(type default)
			)
			(layer "F.Fab")
		)
		(fp_line
			(start -0.12065 0.2794)
			(end -0.12065 0.3048)
			(stroke
				(width 0.1)
				(type default)
			)
			(layer "F.Fab")
		)
		(fp_line
			(start 0.120396 0.2794)
			(end -0.12065 0.2794)
			(stroke
				(width 0.1)
				(type default)
			)
			(layer "F.Fab")
		)
		(fp_line
			(start -0.12065 -0.2794)
			(end 0.12065 -0.2794)
			(stroke
				(width 0.1)
				(type default)
			)
			(layer "F.Fab")
		)
		(fp_line
			(start 0.12065 -0.2794)
			(end 0.12065 -0.3048)
			(stroke
				(width 0.1)
				(type default)
			)
			(layer "F.Fab")
		)
		(fp_line
			(start 0.12065 -0.3048)
			(end 0.67945 -0.3048)
			(stroke
				(width 0.1)
				(type default)
			)
			(layer "F.Fab")
		)
		(fp_line
			(start 0.67945 -0.3048)
			(end 0.67945 0.3048)
			(stroke
				(width 0.1)
				(type default)
			)
			(layer "F.Fab")
		)
		(fp_line
			(start -0.67945 -0.305054)
			(end -0.12065 -0.305054)
			(stroke
				(width 0.1)
				(type default)
			)
			(layer "F.Fab")
		)
		(fp_line
			(start -0.12065 -0.305054)
			(end -0.12065 -0.2794)
			(stroke
				(width 0.1)
				(type default)
			)
			(layer "F.Fab")
		)
		(pad "1" smd circle
			(at -0.40005 0 270)
			(size 0 0)
			(layers "F.Cu" "F.Mask" "F.Paste")
			(net "IRQ_BMC_LPC_SERIRQ_ESPI_GF")
		)
		(pad "2" smd circle
			(at 0.40005 0 270)
			(size 0 0)
			(layers "F.Cu" "F.Mask" "F.Paste")
			(net "IRQ_ESPI_LPC_SERIRQ_ALERT0_N")
		)
	)
	(footprint ""
		(layer "F.Cu")
		(at 58.0644 -30.861 90)
		(property "Reference" "R836"
			(at 0 0 90)
			(layer "F.SilkS")
			(hide yes)
			(effects
				(font
					(size 1.27 1.27)
				)
			)
		)
		(property "Value" ""
			(at 0 0 90)
			(layer "F.Fab")
			(effects
				(font
					(size 1.27 1.27)
				)
			)
		)
		(duplicate_pad_numbers_are_jumpers no)
		(fp_line
			(start 0.7874 -0.4064)
			(end 0.7874 0.4064)
			(stroke
				(width 0.1524)
				(type default)
			)
			(layer "F.SilkS")
		)
		(fp_line
			(start -0.7874 -0.4064)
			(end 0.7874 -0.4064)
			(stroke
				(width 0.1524)
				(type default)
			)
			(layer "F.SilkS")
		)
		(fp_line
			(start 0.7874 0.4064)
			(end -0.7874 0.4064)
			(stroke
				(width 0.1524)
				(type default)
			)
			(layer "F.SilkS")
		)
		(fp_line
			(start -0.7874 0.4064)
			(end -0.7874 -0.4064)
			(stroke
				(width 0.1524)
				(type default)
			)
			(layer "F.SilkS")
		)
		(fp_line
			(start -0.12065 -0.305054)
			(end -0.12065 -0.2794)
			(stroke
				(width 0.1)
				(type default)
			)
			(layer "F.Fab")
		)
		(fp_line
			(start -0.67945 -0.305054)
			(end -0.12065 -0.305054)
			(stroke
				(width 0.1)
				(type default)
			)
			(layer "F.Fab")
		)
		(fp_line
			(start 0.67945 -0.3048)
			(end 0.67945 0.3048)
			(stroke
				(width 0.1)
				(type default)
			)
			(layer "F.Fab")
		)
		(fp_line
			(start 0.12065 -0.3048)
			(end 0.67945 -0.3048)
			(stroke
				(width 0.1)
				(type default)
			)
			(layer "F.Fab")
		)
		(fp_line
			(start 0.12065 -0.2794)
			(end 0.12065 -0.3048)
			(stroke
				(width 0.1)
				(type default)
			)
			(layer "F.Fab")
		)
		(fp_line
			(start -0.12065 -0.2794)
			(end 0.12065 -0.2794)
			(stroke
				(width 0.1)
				(type default)
			)
			(layer "F.Fab")
		)
		(fp_line
			(start 0.120396 0.2794)
			(end -0.12065 0.2794)
			(stroke
				(width 0.1)
				(type default)
			)
			(layer "F.Fab")
		)
		(fp_line
			(start -0.12065 0.2794)
			(end -0.12065 0.3048)
			(stroke
				(width 0.1)
				(type default)
			)
			(layer "F.Fab")
		)
		(fp_line
			(start 0.67945 0.3048)
			(end 0.120396 0.3048)
			(stroke
				(width 0.1)
				(type default)
			)
			(layer "F.Fab")
		)
		(fp_line
			(start 0.120396 0.3048)
			(end 0.120396 0.2794)
			(stroke
				(width 0.1)
				(type default)
			)
			(layer "F.Fab")
		)
		(fp_line
			(start -0.12065 0.3048)
			(end -0.67945 0.3048)
			(stroke
				(width 0.1)
				(type default)
			)
			(layer "F.Fab")
		)
		(fp_line
			(start -0.67945 0.3048)
			(end -0.67945 -0.305054)
			(stroke
				(width 0.1)
				(type default)
			)
			(layer "F.Fab")
		)
		(pad "1" smd circle
			(at -0.40005 0 90)
			(size 0 0)
			(layers "F.Cu" "F.Mask" "F.Paste")
			(net "PWRGD_PSU_AC_PWROK")
		)
		(pad "2" smd circle
			(at 0.40005 0 90)
			(size 0 0)
			(layers "F.Cu" "F.Mask" "F.Paste")
			(net "PWRGD_PSU_AC_PWROK_BMC")
		)
	)
	(footprint ""
		(layer "F.Cu")
		(at 54.483 -23.495 90)
		(property "Reference" "C172"
			(at 0 0 90)
			(layer "F.SilkS")
			(hide yes)
			(effects
				(font
					(size 1.27 1.27)
				)
			)
		)
		(property "Value" ""
			(at 0 0 90)
			(layer "F.Fab")
			(effects
				(font
					(size 1.27 1.27)
				)
			)
		)
		(duplicate_pad_numbers_are_jumpers no)
		(fp_line
			(start 0.7874 -0.4064)
			(end 0.7874 0.4064)
			(stroke
				(width 0.1524)
				(type default)
			)
			(layer "F.SilkS")
		)
		(fp_line
			(start -0.7874 -0.4064)
			(end 0.7874 -0.4064)
			(stroke
				(width 0.1524)
				(type default)
			)
			(layer "F.SilkS")
		)
		(fp_line
			(start 0.7874 0.4064)
			(end -0.7874 0.4064)
			(stroke
				(width 0.1524)
				(type default)
			)
			(layer "F.SilkS")
		)
		(fp_line
			(start -0.7874 0.4064)
			(end -0.7874 -0.4064)
			(stroke
				(width 0.1524)
				(type default)
			)
			(layer "F.SilkS")
		)
		(fp_line
			(start -0.12065 -0.305054)
			(end -0.12065 -0.2794)
			(stroke
				(width 0.1)
				(type default)
			)
			(layer "F.Fab")
		)
		(fp_line
			(start -0.67945 -0.305054)
			(end -0.12065 -0.305054)
			(stroke
				(width 0.1)
				(type default)
			)
			(layer "F.Fab")
		)
		(fp_line
			(start 0.67945 -0.3048)
			(end 0.67945 0.3048)
			(stroke
				(width 0.1)
				(type default)
			)
			(layer "F.Fab")
		)
		(fp_line
			(start 0.12065 -0.3048)
			(end 0.67945 -0.3048)
			(stroke
				(width 0.1)
				(type default)
			)
			(layer "F.Fab")
		)
		(fp_line
			(start 0.12065 -0.2794)
			(end 0.12065 -0.3048)
			(stroke
				(width 0.1)
				(type default)
			)
			(layer "F.Fab")
		)
		(fp_line
			(start -0.12065 -0.2794)
			(end 0.12065 -0.2794)
			(stroke
				(width 0.1)
				(type default)
			)
			(layer "F.Fab")
		)
		(fp_line
			(start 0.120396 0.2794)
			(end -0.12065 0.2794)
			(stroke
				(width 0.1)
				(type default)
			)
			(layer "F.Fab")
		)
		(fp_line
			(start -0.12065 0.2794)
			(end -0.12065 0.3048)
			(stroke
				(width 0.1)
				(type default)
			)
			(layer "F.Fab")
		)
		(fp_line
			(start 0.67945 0.3048)
			(end 0.120396 0.3048)
			(stroke
				(width 0.1)
				(type default)
			)
			(layer "F.Fab")
		)
		(fp_line
			(start 0.120396 0.3048)
			(end 0.120396 0.2794)
			(stroke
				(width 0.1)
				(type default)
			)
			(layer "F.Fab")
		)
		(fp_line
			(start -0.12065 0.3048)
			(end -0.67945 0.3048)
			(stroke
				(width 0.1)
				(type default)
			)
			(layer "F.Fab")
		)
		(fp_line
			(start -0.67945 0.3048)
			(end -0.67945 -0.305054)
			(stroke
				(width 0.1)
				(type default)
			)
			(layer "F.Fab")
		)
		(pad "1" smd circle
			(at -0.40005 0 90)
			(size 0 0)
			(layers "F.Cu" "F.Mask" "F.Paste")
			(net "P5V_AUX")
		)
		(pad "2" smd circle
			(at 0.40005 0 90)
			(size 0 0)
			(layers "F.Cu" "F.Mask" "F.Paste")
			(net "GND")
		)
	)
	(footprint ""
		(layer "F.Cu")
		(at 75.946 -74.422 -90)
		(property "Reference" "R881"
			(at 0 0 270)
			(layer "F.SilkS")
			(hide yes)
			(effects
				(font
					(size 1.27 1.27)
				)
			)
		)
		(property "Value" ""
			(at 0 0 270)
			(layer "F.Fab")
			(effects
				(font
					(size 1.27 1.27)
				)
			)
		)
		(duplicate_pad_numbers_are_jumpers no)
		(fp_line
			(start -0.7874 0.4064)
			(end -0.7874 -0.4064)
			(stroke
				(width 0.1524)
				(type default)
			)
			(layer "F.SilkS")
		)
		(fp_line
			(start 0.7874 0.4064)
			(end -0.7874 0.4064)
			(stroke
				(width 0.1524)
				(type default)
			)
			(layer "F.SilkS")
		)
		(fp_line
			(start -0.7874 -0.4064)
			(end 0.7874 -0.4064)
			(stroke
				(width 0.1524)
				(type default)
			)
			(layer "F.SilkS")
		)
		(fp_line
			(start 0.7874 -0.4064)
			(end 0.7874 0.4064)
			(stroke
				(width 0.1524)
				(type default)
			)
			(layer "F.SilkS")
		)
		(fp_line
			(start -0.67945 0.3048)
			(end -0.67945 -0.305054)
			(stroke
				(width 0.1)
				(type default)
			)
			(layer "F.Fab")
		)
		(fp_line
			(start -0.12065 0.3048)
			(end -0.67945 0.3048)
			(stroke
				(width 0.1)
				(type default)
			)
			(layer "F.Fab")
		)
		(fp_line
			(start 0.120396 0.3048)
			(end 0.120396 0.2794)
			(stroke
				(width 0.1)
				(type default)
			)
			(layer "F.Fab")
		)
		(fp_line
			(start 0.67945 0.3048)
			(end 0.120396 0.3048)
			(stroke
				(width 0.1)
				(type default)
			)
			(layer "F.Fab")
		)
		(fp_line
			(start -0.12065 0.2794)
			(end -0.12065 0.3048)
			(stroke
				(width 0.1)
				(type default)
			)
			(layer "F.Fab")
		)
		(fp_line
			(start 0.120396 0.2794)
			(end -0.12065 0.2794)
			(stroke
				(width 0.1)
				(type default)
			)
			(layer "F.Fab")
		)
		(fp_line
			(start -0.12065 -0.2794)
			(end 0.12065 -0.2794)
			(stroke
				(width 0.1)
				(type default)
			)
			(layer "F.Fab")
		)
		(fp_line
			(start 0.12065 -0.2794)
			(end 0.12065 -0.3048)
			(stroke
				(width 0.1)
				(type default)
			)
			(layer "F.Fab")
		)
		(fp_line
			(start 0.12065 -0.3048)
			(end 0.67945 -0.3048)
			(stroke
				(width 0.1)
				(type default)
			)
			(layer "F.Fab")
		)
		(fp_line
			(start 0.67945 -0.3048)
			(end 0.67945 0.3048)
			(stroke
				(width 0.1)
				(type default)
			)
			(layer "F.Fab")
		)
		(fp_line
			(start -0.67945 -0.305054)
			(end -0.12065 -0.305054)
			(stroke
				(width 0.1)
				(type default)
			)
			(layer "F.Fab")
		)
		(fp_line
			(start -0.12065 -0.305054)
			(end -0.12065 -0.2794)
			(stroke
				(width 0.1)
				(type default)
			)
			(layer "F.Fab")
		)
		(pad "1" smd circle
			(at -0.40005 0 270)
			(size 0 0)
			(layers "F.Cu" "F.Mask" "F.Paste")
			(net "P3V3_AUX")
		)
		(pad "2" smd circle
			(at 0.40005 0 270)
			(size 0 0)
			(layers "F.Cu" "F.Mask" "F.Paste")
			(net "FM_JTAG_TCK_MUX_BMC_SEL_R")
		)
	)
	(footprint ""
		(layer "F.Cu")
		(at 32.766 -10.6426)
		(property "Reference" "Q9"
			(at 1.397 1.65227 0)
			(unlocked yes)
			(layer "F.SilkS")
			(effects
				(font
					(size 0.7874 0.5842)
					(thickness 0.1524)
				)
				(justify left)
			)
		)
		(property "Value" ""
			(at 0 0 0)
			(layer "F.Fab")
			(effects
				(font
					(size 1.27 1.27)
				)
			)
		)
		(duplicate_pad_numbers_are_jumpers no)
		(fp_line
			(start -1.332738 -1.100074)
			(end -0.4826 -1.100074)
			(stroke
				(width 0.1524)
				(type default)
			)
			(layer "F.SilkS")
		)
		(fp_line
			(start -1.332738 1.100074)
			(end -1.332738 -1.100074)
			(stroke
				(width 0.1524)
				(type default)
			)
			(layer "F.SilkS")
		)
		(fp_line
			(start -0.4826 -1.100074)
			(end 0 -0.541274)
			(stroke
				(width 0.1524)
				(type default)
			)
			(layer "F.SilkS")
		)
		(fp_line
			(start 0 -0.541274)
			(end 0.4826 -1.100074)
			(stroke
				(width 0.1524)
				(type default)
			)
			(layer "F.SilkS")
		)
		(fp_line
			(start 0.4826 -1.100074)
			(end 1.332738 -1.100074)
			(stroke
				(width 0.1524)
				(type default)
			)
			(layer "F.SilkS")
		)
		(fp_line
			(start 1.332738 -1.100074)
			(end 1.332738 1.100074)
			(stroke
				(width 0.1524)
				(type default)
			)
			(layer "F.SilkS")
		)
		(fp_line
			(start 1.332738 1.100074)
			(end -1.332738 1.100074)
			(stroke
				(width 0.1524)
				(type default)
			)
			(layer "F.SilkS")
		)
		(fp_poly
			(pts
				(xy -2.169668 -1.389634) (xy -1.673352 -1.88595) (xy -1.425194 -1.141222)
			)
			(stroke
				(width 0)
				(type default)
			)
			(fill yes)
			(layer "F.SilkS")
		)
		(fp_line
			(start -0.674878 -1.100074)
			(end 0.674878 -1.100074)
			(stroke
				(width 0.1)
				(type default)
			)
			(layer "F.Fab")
		)
		(fp_line
			(start -0.674878 1.100074)
			(end -0.674878 -1.100074)
			(stroke
				(width 0.1)
				(type default)
			)
			(layer "F.Fab")
		)
		(fp_line
			(start 0.674878 -1.100074)
			(end 0.674878 1.100074)
			(stroke
				(width 0.1)
				(type default)
			)
			(layer "F.Fab")
		)
		(fp_line
			(start 0.674878 1.100074)
			(end -0.674878 1.100074)
			(stroke
				(width 0.1)
				(type default)
			)
			(layer "F.Fab")
		)
		(fp_poly
			(pts
				(xy -2.2352 -0.298958) (xy -2.2352 -1.001014) (xy -1.533144 -0.649986)
			)
			(stroke
				(width 0)
				(type default)
			)
			(fill yes)
			(layer "F.Fab")
		)
		(pad "1" smd rect
			(at -0.94996 -0.649986 90)
			(size 0.4318 0.508)
			(layers "F.Cu" "F.Mask" "F.Paste")
			(net "GND")
		)
		(pad "2" smd rect
			(at -0.94996 0 90)
			(size 0.4318 0.508)
			(layers "F.Cu" "F.Mask" "F.Paste")
			(net "ID_LED_BUF")
		)
		(pad "3" smd rect
			(at -0.94996 0.649986 90)
			(size 0.4318 0.508)
			(layers "F.Cu" "F.Mask" "F.Paste")
			(net "Net_318")
		)
		(pad "4" smd rect
			(at 0.94996 0.649986 90)
			(size 0.4318 0.508)
			(layers "F.Cu" "F.Mask" "F.Paste")
			(net "Net_320")
		)
		(pad "5" smd rect
			(at 0.94996 0 90)
			(size 0.4318 0.508)
			(layers "F.Cu" "F.Mask" "F.Paste")
			(net "Net_319")
		)
		(pad "6" smd rect
			(at 0.94996 -0.649986 90)
			(size 0.4318 0.508)
			(layers "F.Cu" "F.Mask" "F.Paste")
			(net "ID_LED_D_P3V3_AUX")
		)
	)
	(footprint ""
		(layer "F.Cu")
		(at 7.17677 -72.06107 90)
		(property "Reference" "PL35"
			(at -0.90297 4.18592 90)
			(unlocked yes)
			(layer "F.SilkS")
			(effects
				(font
					(size 0.7874 0.5842)
					(thickness 0.1524)
				)
				(justify left)
			)
		)
		(property "Value" ""
			(at 0 0 90)
			(layer "F.Fab")
			(effects
				(font
					(size 1.27 1.27)
				)
			)
		)
		(duplicate_pad_numbers_are_jumpers no)
		(fp_line
			(start 3.64998 -3.350006)
			(end 3.64998 -1.8034)
			(stroke
				(width 0.1524)
				(type default)
			)
			(layer "F.SilkS")
		)
		(fp_line
			(start -3.6576 -3.350006)
			(end 3.64998 -3.350006)
			(stroke
				(width 0.1524)
				(type default)
			)
			(layer "F.SilkS")
		)
		(fp_line
			(start -3.64998 -1.8034)
			(end -3.64998 -3.350006)
			(stroke
				(width 0.1524)
				(type default)
			)
			(layer "F.SilkS")
		)
		(fp_line
			(start 3.64998 1.8034)
			(end 3.64998 3.350006)
			(stroke
				(width 0.1524)
				(type default)
			)
			(layer "F.SilkS")
		)
		(fp_line
			(start 3.64998 3.350006)
			(end -3.64998 3.350006)
			(stroke
				(width 0.1524)
				(type default)
			)
			(layer "F.SilkS")
		)
		(fp_line
			(start -3.64998 3.350006)
			(end -3.64998 1.8288)
			(stroke
				(width 0.1524)
				(type default)
			)
			(layer "F.SilkS")
		)
		(fp_line
			(start 3.64998 -3.350006)
			(end 3.64998 3.350006)
			(stroke
				(width 0.1)
				(type default)
			)
			(layer "F.Fab")
		)
		(fp_line
			(start -3.64998 -3.350006)
			(end 3.64998 -3.350006)
			(stroke
				(width 0.1)
				(type default)
			)
			(layer "F.Fab")
		)
		(fp_line
			(start 3.64998 3.350006)
			(end -3.64998 3.350006)
			(stroke
				(width 0.1)
				(type default)
			)
			(layer "F.Fab")
		)
		(fp_line
			(start -3.64998 3.350006)
			(end -3.64998 -3.350006)
			(stroke
				(width 0.1)
				(type default)
			)
			(layer "F.Fab")
		)
		(pad "1" smd rect
			(at -2.92481 0 90)
			(size 2.15392 3.302)
			(layers "F.Cu" "F.Mask" "F.Paste")
			(net "SW_P3V3_AUX_SW")
		)
		(pad "2" smd rect
			(at 2.92481 0 90)
			(size 2.15392 3.302)
			(layers "F.Cu" "F.Mask" "F.Paste")
			(net "P3V3_AUX")
		)
	)
	(footprint ""
		(layer "F.Cu")
		(at 31.75 -33.274)
		(property "Reference" "R89"
			(at 0 0 0)
			(layer "F.SilkS")
			(hide yes)
			(effects
				(font
					(size 1.27 1.27)
				)
			)
		)
		(property "Value" ""
			(at 0 0 0)
			(layer "F.Fab")
			(effects
				(font
					(size 1.27 1.27)
				)
			)
		)
		(duplicate_pad_numbers_are_jumpers no)
		(fp_line
			(start -0.7874 -0.4064)
			(end 0.7874 -0.4064)
			(stroke
				(width 0.1524)
				(type default)
			)
			(layer "F.SilkS")
		)
		(fp_line
			(start -0.7874 0.4064)
			(end -0.7874 -0.4064)
			(stroke
				(width 0.1524)
				(type default)
			)
			(layer "F.SilkS")
		)
		(fp_line
			(start 0.7874 -0.4064)
			(end 0.7874 0.4064)
			(stroke
				(width 0.1524)
				(type default)
			)
			(layer "F.SilkS")
		)
		(fp_line
			(start 0.7874 0.4064)
			(end -0.7874 0.4064)
			(stroke
				(width 0.1524)
				(type default)
			)
			(layer "F.SilkS")
		)
		(fp_line
			(start -0.67945 -0.305054)
			(end -0.12065 -0.305054)
			(stroke
				(width 0.1)
				(type default)
			)
			(layer "F.Fab")
		)
		(fp_line
			(start -0.67945 0.3048)
			(end -0.67945 -0.305054)
			(stroke
				(width 0.1)
				(type default)
			)
			(layer "F.Fab")
		)
		(fp_line
			(start -0.12065 -0.305054)
			(end -0.12065 -0.2794)
			(stroke
				(width 0.1)
				(type default)
			)
			(layer "F.Fab")
		)
		(fp_line
			(start -0.12065 -0.2794)
			(end 0.12065 -0.2794)
			(stroke
				(width 0.1)
				(type default)
			)
			(layer "F.Fab")
		)
		(fp_line
			(start -0.12065 0.2794)
			(end -0.12065 0.3048)
			(stroke
				(width 0.1)
				(type default)
			)
			(layer "F.Fab")
		)
		(fp_line
			(start -0.12065 0.3048)
			(end -0.67945 0.3048)
			(stroke
				(width 0.1)
				(type default)
			)
			(layer "F.Fab")
		)
		(fp_line
			(start 0.120396 0.2794)
			(end -0.12065 0.2794)
			(stroke
				(width 0.1)
				(type default)
			)
			(layer "F.Fab")
		)
		(fp_line
			(start 0.120396 0.3048)
			(end 0.120396 0.2794)
			(stroke
				(width 0.1)
				(type default)
			)
			(layer "F.Fab")
		)
		(fp_line
			(start 0.12065 -0.3048)
			(end 0.67945 -0.3048)
			(stroke
				(width 0.1)
				(type default)
			)
			(layer "F.Fab")
		)
		(fp_line
			(start 0.12065 -0.2794)
			(end 0.12065 -0.3048)
			(stroke
				(width 0.1)
				(type default)
			)
			(layer "F.Fab")
		)
		(fp_line
			(start 0.67945 -0.3048)
			(end 0.67945 0.3048)
			(stroke
				(width 0.1)
				(type default)
			)
			(layer "F.Fab")
		)
		(fp_line
			(start 0.67945 0.3048)
			(end 0.120396 0.3048)
			(stroke
				(width 0.1)
				(type default)
			)
			(layer "F.Fab")
		)
		(pad "1" smd circle
			(at -0.40005 0)
			(size 0 0)
			(layers "F.Cu" "F.Mask" "F.Paste")
			(net "V_DACR_IO")
		)
		(pad "2" smd circle
			(at 0.40005 0)
			(size 0 0)
			(layers "F.Cu" "F.Mask" "F.Paste")
			(net "GND")
		)
	)
	(footprint ""
		(layer "F.Cu")
		(at 12.319 -86.36)
		(property "Reference" "R454"
			(at 0 0 0)
			(layer "F.SilkS")
			(hide yes)
			(effects
				(font
					(size 1.27 1.27)
				)
			)
		)
		(property "Value" ""
			(at 0 0 0)
			(layer "F.Fab")
			(effects
				(font
					(size 1.27 1.27)
				)
			)
		)
		(duplicate_pad_numbers_are_jumpers no)
		(fp_line
			(start -0.7874 -0.4064)
			(end 0.7874 -0.4064)
			(stroke
				(width 0.1524)
				(type default)
			)
			(layer "F.SilkS")
		)
		(fp_line
			(start -0.7874 0.4064)
			(end -0.7874 -0.4064)
			(stroke
				(width 0.1524)
				(type default)
			)
			(layer "F.SilkS")
		)
		(fp_line
			(start 0.7874 -0.4064)
			(end 0.7874 0.4064)
			(stroke
				(width 0.1524)
				(type default)
			)
			(layer "F.SilkS")
		)
		(fp_line
			(start 0.7874 0.4064)
			(end -0.7874 0.4064)
			(stroke
				(width 0.1524)
				(type default)
			)
			(layer "F.SilkS")
		)
		(fp_line
			(start -0.67945 -0.305054)
			(end -0.12065 -0.305054)
			(stroke
				(width 0.1)
				(type default)
			)
			(layer "F.Fab")
		)
		(fp_line
			(start -0.67945 0.3048)
			(end -0.67945 -0.305054)
			(stroke
				(width 0.1)
				(type default)
			)
			(layer "F.Fab")
		)
		(fp_line
			(start -0.12065 -0.305054)
			(end -0.12065 -0.2794)
			(stroke
				(width 0.1)
				(type default)
			)
			(layer "F.Fab")
		)
		(fp_line
			(start -0.12065 -0.2794)
			(end 0.12065 -0.2794)
			(stroke
				(width 0.1)
				(type default)
			)
			(layer "F.Fab")
		)
		(fp_line
			(start -0.12065 0.2794)
			(end -0.12065 0.3048)
			(stroke
				(width 0.1)
				(type default)
			)
			(layer "F.Fab")
		)
		(fp_line
			(start -0.12065 0.3048)
			(end -0.67945 0.3048)
			(stroke
				(width 0.1)
				(type default)
			)
			(layer "F.Fab")
		)
		(fp_line
			(start 0.120396 0.2794)
			(end -0.12065 0.2794)
			(stroke
				(width 0.1)
				(type default)
			)
			(layer "F.Fab")
		)
		(fp_line
			(start 0.120396 0.3048)
			(end 0.120396 0.2794)
			(stroke
				(width 0.1)
				(type default)
			)
			(layer "F.Fab")
		)
		(fp_line
			(start 0.12065 -0.3048)
			(end 0.67945 -0.3048)
			(stroke
				(width 0.1)
				(type default)
			)
			(layer "F.Fab")
		)
		(fp_line
			(start 0.12065 -0.2794)
			(end 0.12065 -0.3048)
			(stroke
				(width 0.1)
				(type default)
			)
			(layer "F.Fab")
		)
		(fp_line
			(start 0.67945 -0.3048)
			(end 0.67945 0.3048)
			(stroke
				(width 0.1)
				(type default)
			)
			(layer "F.Fab")
		)
		(fp_line
			(start 0.67945 0.3048)
			(end 0.120396 0.3048)
			(stroke
				(width 0.1)
				(type default)
			)
			(layer "F.Fab")
		)
		(pad "1" smd circle
			(at -0.40005 0)
			(size 0 0)
			(layers "F.Cu" "F.Mask" "F.Paste")
			(net "SMB_BMC_ALERT4_N")
		)
		(pad "2" smd circle
			(at 0.40005 0)
			(size 0 0)
			(layers "F.Cu" "F.Mask" "F.Paste")
			(net "SMB_BMC_ALERT4_R1_N")
		)
	)
	(footprint ""
		(layer "F.Cu")
		(at 52.809648 -63.912496 90)
		(property "Reference" "R178"
			(at 0 0 90)
			(layer "F.SilkS")
			(hide yes)
			(effects
				(font
					(size 1.27 1.27)
				)
			)
		)
		(property "Value" ""
			(at 0 0 90)
			(layer "F.Fab")
			(effects
				(font
					(size 1.27 1.27)
				)
			)
		)
		(duplicate_pad_numbers_are_jumpers no)
		(fp_line
			(start 0.7874 -0.4064)
			(end 0.7874 0.4064)
			(stroke
				(width 0.1524)
				(type default)
			)
			(layer "F.SilkS")
		)
		(fp_line
			(start -0.7874 -0.4064)
			(end 0.7874 -0.4064)
			(stroke
				(width 0.1524)
				(type default)
			)
			(layer "F.SilkS")
		)
		(fp_line
			(start 0.7874 0.4064)
			(end -0.7874 0.4064)
			(stroke
				(width 0.1524)
				(type default)
			)
			(layer "F.SilkS")
		)
		(fp_line
			(start -0.7874 0.4064)
			(end -0.7874 -0.4064)
			(stroke
				(width 0.1524)
				(type default)
			)
			(layer "F.SilkS")
		)
		(fp_line
			(start -0.12065 -0.305054)
			(end -0.12065 -0.2794)
			(stroke
				(width 0.1)
				(type default)
			)
			(layer "F.Fab")
		)
		(fp_line
			(start -0.67945 -0.305054)
			(end -0.12065 -0.305054)
			(stroke
				(width 0.1)
				(type default)
			)
			(layer "F.Fab")
		)
		(fp_line
			(start 0.67945 -0.3048)
			(end 0.67945 0.3048)
			(stroke
				(width 0.1)
				(type default)
			)
			(layer "F.Fab")
		)
		(fp_line
			(start 0.12065 -0.3048)
			(end 0.67945 -0.3048)
			(stroke
				(width 0.1)
				(type default)
			)
			(layer "F.Fab")
		)
		(fp_line
			(start 0.12065 -0.2794)
			(end 0.12065 -0.3048)
			(stroke
				(width 0.1)
				(type default)
			)
			(layer "F.Fab")
		)
		(fp_line
			(start -0.12065 -0.2794)
			(end 0.12065 -0.2794)
			(stroke
				(width 0.1)
				(type default)
			)
			(layer "F.Fab")
		)
		(fp_line
			(start 0.120396 0.2794)
			(end -0.12065 0.2794)
			(stroke
				(width 0.1)
				(type default)
			)
			(layer "F.Fab")
		)
		(fp_line
			(start -0.12065 0.2794)
			(end -0.12065 0.3048)
			(stroke
				(width 0.1)
				(type default)
			)
			(layer "F.Fab")
		)
		(fp_line
			(start 0.67945 0.3048)
			(end 0.120396 0.3048)
			(stroke
				(width 0.1)
				(type default)
			)
			(layer "F.Fab")
		)
		(fp_line
			(start 0.120396 0.3048)
			(end 0.120396 0.2794)
			(stroke
				(width 0.1)
				(type default)
			)
			(layer "F.Fab")
		)
		(fp_line
			(start -0.12065 0.3048)
			(end -0.67945 0.3048)
			(stroke
				(width 0.1)
				(type default)
			)
			(layer "F.Fab")
		)
		(fp_line
			(start -0.67945 0.3048)
			(end -0.67945 -0.305054)
			(stroke
				(width 0.1)
				(type default)
			)
			(layer "F.Fab")
		)
		(pad "1" smd circle
			(at -0.40005 0 90)
			(size 0 0)
			(layers "F.Cu" "F.Mask" "F.Paste")
			(net "SPI_BMC_CLK_R")
		)
		(pad "2" smd circle
			(at 0.40005 0 90)
			(size 0 0)
			(layers "F.Cu" "F.Mask" "F.Paste")
			(net "SPI_BMC_BOOT_CLK")
		)
	)
	(footprint ""
		(layer "F.Cu")
		(at 39.500048 -97.909888 90)
		(property "Reference" "J40"
			(at 4.896358 10.069068 90)
			(unlocked yes)
			(layer "F.SilkS")
			(effects
				(font
					(size 0.7874 0.5842)
					(thickness 0.1524)
				)
				(justify left)
			)
		)
		(property "Value" ""
			(at 0 0 90)
			(layer "F.Fab")
			(effects
				(font
					(size 1.27 1.27)
				)
			)
		)
		(duplicate_pad_numbers_are_jumpers no)
		(fp_line
			(start 6.945122 -7.649972)
			(end 0 -7.649972)
			(stroke
				(width 0.1524)
				(type default)
			)
			(layer "F.SilkS")
		)
		(fp_line
			(start 6.945122 -7.649972)
			(end 6.945122 7.649972)
			(stroke
				(width 0.1524)
				(type default)
			)
			(layer "F.SilkS")
		)
		(fp_line
			(start 0 -7.649972)
			(end 8.320278 -7.649972)
			(stroke
				(width 0.1524)
				(type default)
			)
			(layer "F.SilkS")
		)
		(fp_line
			(start -6.945122 -7.649972)
			(end 0 -7.649972)
			(stroke
				(width 0.1524)
				(type default)
			)
			(layer "F.SilkS")
		)
		(fp_line
			(start -6.945122 -7.649972)
			(end -6.945122 7.649972)
			(stroke
				(width 0.1524)
				(type default)
			)
			(layer "F.SilkS")
		)
		(fp_line
			(start -10.508742 -7.649972)
			(end 0 -7.649972)
			(stroke
				(width 0.1524)
				(type default)
			)
			(layer "F.SilkS")
		)
		(fp_line
			(start -11.554968 -7.649972)
			(end -11.296142 -7.649972)
			(stroke
				(width 0.1524)
				(type default)
			)
			(layer "F.SilkS")
		)
		(fp_line
			(start -11.554968 -1.171702)
			(end -11.554968 -7.649972)
			(stroke
				(width 0.1524)
				(type default)
			)
			(layer "F.SilkS")
		)
		(fp_line
			(start -11.554968 1.368298)
			(end -11.554968 0.047498)
			(stroke
				(width 0.1524)
				(type default)
			)
			(layer "F.SilkS")
		)
		(fp_line
			(start 11.554968 2.104898)
			(end 11.554968 3.095498)
			(stroke
				(width 0.1524)
				(type default)
			)
			(layer "F.SilkS")
		)
		(fp_line
			(start -11.554968 2.993898)
			(end -11.554968 2.485898)
			(stroke
				(width 0.1524)
				(type default)
			)
			(layer "F.SilkS")
		)
		(fp_line
			(start 11.554968 4.136898)
			(end 11.554968 5.584698)
			(stroke
				(width 0.1524)
				(type default)
			)
			(layer "F.SilkS")
		)
		(fp_line
			(start -11.554968 4.238498)
			(end -11.554968 3.730498)
			(stroke
				(width 0.1524)
				(type default)
			)
			(layer "F.SilkS")
		)
		(fp_line
			(start 11.106658 7.649972)
			(end -9.010142 7.649972)
			(stroke
				(width 0.1524)
				(type default)
			)
			(layer "F.SilkS")
		)
		(fp_line
			(start 6.945122 7.649972)
			(end -6.945122 7.649972)
			(stroke
				(width 0.1524)
				(type default)
			)
			(layer "F.SilkS")
		)
		(fp_line
			(start -11.554968 7.649972)
			(end -11.554968 5.381498)
			(stroke
				(width 0.1524)
				(type default)
			)
			(layer "F.SilkS")
		)
		(fp_poly
			(pts
				(xy -7.112 -4.445) (xy -8.128 -4.953) (xy -8.128 -3.937)
			)
			(stroke
				(width 0)
				(type default)
			)
			(fill yes)
			(layer "F.SilkS")
		)
		(fp_line
			(start 6.945122 -7.649972)
			(end 6.945122 7.649972)
			(stroke
				(width 0.1)
				(type default)
			)
			(layer "F.Fab")
		)
		(fp_line
			(start -6.945122 -7.649972)
			(end 6.945122 -7.649972)
			(stroke
				(width 0.1)
				(type default)
			)
			(layer "F.Fab")
		)
		(fp_line
			(start 6.945122 7.649972)
			(end -6.945122 7.649972)
			(stroke
				(width 0.1)
				(type default)
			)
			(layer "F.Fab")
		)
		(fp_line
			(start -6.945122 7.649972)
			(end -6.945122 -7.649972)
			(stroke
				(width 0.1)
				(type default)
			)
			(layer "F.Fab")
		)
		(fp_poly
			(pts
				(xy -7.112 -4.445) (xy -8.128 -4.953) (xy -8.128 -3.937)
			)
			(stroke
				(width 0)
				(type default)
			)
			(fill yes)
			(layer "F.Fab")
		)
		(fp_text user "16"
			(at 7.49173 -5.2324 0)
			(unlocked yes)
			(layer "F.SilkS")
			(effects
				(font
					(size 0.7874 0.5842)
					(thickness 0.1524)
				)
				(justify left)
			)
		)
		(fp_text user "9"
			(at 7.51713 4.1656 0)
			(unlocked yes)
			(layer "F.SilkS")
			(effects
				(font
					(size 0.7874 0.5842)
					(thickness 0.1524)
				)
				(justify left)
			)
		)
		(fp_text user "8"
			(at -7.77367 4.2164 0)
			(unlocked yes)
			(layer "F.SilkS")
			(effects
				(font
					(size 0.7874 0.5842)
					(thickness 0.1524)
				)
				(justify left)
			)
		)
		(fp_text user "16"
			(at 7.49173 -5.2324 0)
			(unlocked yes)
			(layer "F.Fab")
			(effects
				(font
					(size 0.7874 0.5842)
					(thickness 0.1524)
				)
				(justify left)
			)
		)
		(fp_text user "9"
			(at 7.51713 4.1656 0)
			(unlocked yes)
			(layer "F.Fab")
			(effects
				(font
					(size 0.7874 0.5842)
					(thickness 0.1524)
				)
				(justify left)
			)
		)
		(fp_text user "8"
			(at -7.77367 4.2164 0)
			(unlocked yes)
			(layer "F.Fab")
			(effects
				(font
					(size 0.7874 0.5842)
					(thickness 0.1524)
				)
				(justify left)
			)
		)
		(pad "1" smd rect
			(at -4.800092 -4.445)
			(size 0.508 1.4986)
			(layers "F.Cu" "F.Mask" "F.Paste")
			(net "SPI_PCH_IO3_FLASH_R1")
		)
		(pad "2" smd rect
			(at -4.800092 -3.175)
			(size 0.508 1.4986)
			(layers "F.Cu" "F.Mask" "F.Paste")
			(net "P3V3_AUX")
		)
		(pad "3" smd rect
			(at -4.800092 -1.905)
			(size 0.508 1.4986)
			(layers "F.Cu" "F.Mask" "F.Paste")
			(net "RST_SPI_PCH_FLASH_R1_N")
		)
		(pad "4" smd rect
			(at -4.800092 -0.635)
			(size 0.508 1.4986)
			(layers "F.Cu" "F.Mask" "F.Paste")
			(net "TP_J40_4")
		)
		(pad "5" smd rect
			(at -4.800092 0.635)
			(size 0.508 1.4986)
			(layers "F.Cu" "F.Mask" "F.Paste")
			(net "TP_J40_5")
		)
		(pad "6" smd rect
			(at -4.800092 1.905)
			(size 0.508 1.4986)
			(layers "F.Cu" "F.Mask" "F.Paste")
			(net "TP_J40_6")
		)
		(pad "7" smd rect
			(at -4.800092 3.175)
			(size 0.508 1.4986)
			(layers "F.Cu" "F.Mask" "F.Paste")
			(net "SPI_PCH_CS0_FLASH_R1_N")
		)
		(pad "8" smd rect
			(at -4.800092 4.445)
			(size 0.508 1.4986)
			(layers "F.Cu" "F.Mask" "F.Paste")
			(net "SPI_PCH_IO1_FLASH_R1")
		)
		(pad "9" smd rect
			(at 4.800092 4.445)
			(size 0.508 1.4986)
			(layers "F.Cu" "F.Mask" "F.Paste")
			(net "SPI_PCH_IO2_FLASH_R1")
		)
		(pad "10" smd rect
			(at 4.800092 3.175)
			(size 0.508 1.4986)
			(layers "F.Cu" "F.Mask" "F.Paste")
			(net "GND")
		)
		(pad "11" smd rect
			(at 4.800092 1.905)
			(size 0.508 1.4986)
			(layers "F.Cu" "F.Mask" "F.Paste")
			(net "TP_J40_11")
		)
		(pad "12" smd rect
			(at 4.800092 0.635)
			(size 0.508 1.4986)
			(layers "F.Cu" "F.Mask" "F.Paste")
			(net "TP_J40_12")
		)
		(pad "13" smd rect
			(at 4.800092 -0.635)
			(size 0.508 1.4986)
			(layers "F.Cu" "F.Mask" "F.Paste")
			(net "TP_J40_13")
		)
		(pad "14" smd rect
			(at 4.800092 -1.905)
			(size 0.508 1.4986)
			(layers "F.Cu" "F.Mask" "F.Paste")
			(net "TP_J40_14")
		)
		(pad "15" smd rect
			(at 4.800092 -3.175)
			(size 0.508 1.4986)
			(layers "F.Cu" "F.Mask" "F.Paste")
			(net "SPI_PCH_IO0_FLASH_R1")
		)
		(pad "16" smd rect
			(at 4.800092 -4.445)
			(size 0.508 1.4986)
			(layers "F.Cu" "F.Mask" "F.Paste")
			(net "SPI_PCH_CLK_FLASH_R1")
		)
	)
	(footprint ""
		(layer "F.Cu")
		(at 13.22197 -31.800292 -90)
		(property "Reference" "PC212"
			(at 0 0 270)
			(layer "F.SilkS")
			(hide yes)
			(effects
				(font
					(size 1.27 1.27)
				)
			)
		)
		(property "Value" ""
			(at 0 0 270)
			(layer "F.Fab")
			(effects
				(font
					(size 1.27 1.27)
				)
			)
		)
		(duplicate_pad_numbers_are_jumpers no)
		(fp_line
			(start -0.7874 0.4064)
			(end -0.7874 -0.4064)
			(stroke
				(width 0.1524)
				(type default)
			)
			(layer "F.SilkS")
		)
		(fp_line
			(start 0.7874 0.4064)
			(end -0.7874 0.4064)
			(stroke
				(width 0.1524)
				(type default)
			)
			(layer "F.SilkS")
		)
		(fp_line
			(start -0.7874 -0.4064)
			(end 0.7874 -0.4064)
			(stroke
				(width 0.1524)
				(type default)
			)
			(layer "F.SilkS")
		)
		(fp_line
			(start 0.7874 -0.4064)
			(end 0.7874 0.4064)
			(stroke
				(width 0.1524)
				(type default)
			)
			(layer "F.SilkS")
		)
		(fp_line
			(start -0.67945 0.3048)
			(end -0.67945 -0.305054)
			(stroke
				(width 0.1)
				(type default)
			)
			(layer "F.Fab")
		)
		(fp_line
			(start -0.12065 0.3048)
			(end -0.67945 0.3048)
			(stroke
				(width 0.1)
				(type default)
			)
			(layer "F.Fab")
		)
		(fp_line
			(start 0.120396 0.3048)
			(end 0.120396 0.2794)
			(stroke
				(width 0.1)
				(type default)
			)
			(layer "F.Fab")
		)
		(fp_line
			(start 0.67945 0.3048)
			(end 0.120396 0.3048)
			(stroke
				(width 0.1)
				(type default)
			)
			(layer "F.Fab")
		)
		(fp_line
			(start -0.12065 0.2794)
			(end -0.12065 0.3048)
			(stroke
				(width 0.1)
				(type default)
			)
			(layer "F.Fab")
		)
		(fp_line
			(start 0.120396 0.2794)
			(end -0.12065 0.2794)
			(stroke
				(width 0.1)
				(type default)
			)
			(layer "F.Fab")
		)
		(fp_line
			(start -0.12065 -0.2794)
			(end 0.12065 -0.2794)
			(stroke
				(width 0.1)
				(type default)
			)
			(layer "F.Fab")
		)
		(fp_line
			(start 0.12065 -0.2794)
			(end 0.12065 -0.3048)
			(stroke
				(width 0.1)
				(type default)
			)
			(layer "F.Fab")
		)
		(fp_line
			(start 0.12065 -0.3048)
			(end 0.67945 -0.3048)
			(stroke
				(width 0.1)
				(type default)
			)
			(layer "F.Fab")
		)
		(fp_line
			(start 0.67945 -0.3048)
			(end 0.67945 0.3048)
			(stroke
				(width 0.1)
				(type default)
			)
			(layer "F.Fab")
		)
		(fp_line
			(start -0.67945 -0.305054)
			(end -0.12065 -0.305054)
			(stroke
				(width 0.1)
				(type default)
			)
			(layer "F.Fab")
		)
		(fp_line
			(start -0.12065 -0.305054)
			(end -0.12065 -0.2794)
			(stroke
				(width 0.1)
				(type default)
			)
			(layer "F.Fab")
		)
		(pad "1" smd circle
			(at -0.40005 0 270)
			(size 0 0)
			(layers "F.Cu" "F.Mask" "F.Paste")
			(net "P5V_AUX")
		)
		(pad "2" smd circle
			(at 0.40005 0 270)
			(size 0 0)
			(layers "F.Cu" "F.Mask" "F.Paste")
			(net "GND")
		)
	)
	(footprint ""
		(layer "F.Cu")
		(at 65.056512 -63.926466 -90)
		(property "Reference" "R643"
			(at 0 0 270)
			(layer "F.SilkS")
			(hide yes)
			(effects
				(font
					(size 1.27 1.27)
				)
			)
		)
		(property "Value" ""
			(at 0 0 270)
			(layer "F.Fab")
			(effects
				(font
					(size 1.27 1.27)
				)
			)
		)
		(duplicate_pad_numbers_are_jumpers no)
		(fp_line
			(start -0.7874 0.4064)
			(end -0.7874 -0.4064)
			(stroke
				(width 0.1524)
				(type default)
			)
			(layer "F.SilkS")
		)
		(fp_line
			(start 0.7874 0.4064)
			(end -0.7874 0.4064)
			(stroke
				(width 0.1524)
				(type default)
			)
			(layer "F.SilkS")
		)
		(fp_line
			(start -0.7874 -0.4064)
			(end 0.7874 -0.4064)
			(stroke
				(width 0.1524)
				(type default)
			)
			(layer "F.SilkS")
		)
		(fp_line
			(start 0.7874 -0.4064)
			(end 0.7874 0.4064)
			(stroke
				(width 0.1524)
				(type default)
			)
			(layer "F.SilkS")
		)
		(fp_line
			(start -0.67945 0.3048)
			(end -0.67945 -0.305054)
			(stroke
				(width 0.1)
				(type default)
			)
			(layer "F.Fab")
		)
		(fp_line
			(start -0.12065 0.3048)
			(end -0.67945 0.3048)
			(stroke
				(width 0.1)
				(type default)
			)
			(layer "F.Fab")
		)
		(fp_line
			(start 0.120396 0.3048)
			(end 0.120396 0.2794)
			(stroke
				(width 0.1)
				(type default)
			)
			(layer "F.Fab")
		)
		(fp_line
			(start 0.67945 0.3048)
			(end 0.120396 0.3048)
			(stroke
				(width 0.1)
				(type default)
			)
			(layer "F.Fab")
		)
		(fp_line
			(start -0.12065 0.2794)
			(end -0.12065 0.3048)
			(stroke
				(width 0.1)
				(type default)
			)
			(layer "F.Fab")
		)
		(fp_line
			(start 0.120396 0.2794)
			(end -0.12065 0.2794)
			(stroke
				(width 0.1)
				(type default)
			)
			(layer "F.Fab")
		)
		(fp_line
			(start -0.12065 -0.2794)
			(end 0.12065 -0.2794)
			(stroke
				(width 0.1)
				(type default)
			)
			(layer "F.Fab")
		)
		(fp_line
			(start 0.12065 -0.2794)
			(end 0.12065 -0.3048)
			(stroke
				(width 0.1)
				(type default)
			)
			(layer "F.Fab")
		)
		(fp_line
			(start 0.12065 -0.3048)
			(end 0.67945 -0.3048)
			(stroke
				(width 0.1)
				(type default)
			)
			(layer "F.Fab")
		)
		(fp_line
			(start 0.67945 -0.3048)
			(end 0.67945 0.3048)
			(stroke
				(width 0.1)
				(type default)
			)
			(layer "F.Fab")
		)
		(fp_line
			(start -0.67945 -0.305054)
			(end -0.12065 -0.305054)
			(stroke
				(width 0.1)
				(type default)
			)
			(layer "F.Fab")
		)
		(fp_line
			(start -0.12065 -0.305054)
			(end -0.12065 -0.2794)
			(stroke
				(width 0.1)
				(type default)
			)
			(layer "F.Fab")
		)
		(pad "1" smd circle
			(at -0.40005 0 270)
			(size 0 0)
			(layers "F.Cu" "F.Mask" "F.Paste")
			(net "PWRGD_DSW_PWROK")
		)
		(pad "2" smd circle
			(at 0.40005 0 270)
			(size 0 0)
			(layers "F.Cu" "F.Mask" "F.Paste")
			(net "PWRGD_DSW_PWROK_R1")
		)
	)
	(footprint ""
		(layer "F.Cu")
		(at 40.821102 -65.793366 90)
		(property "Reference" "R198"
			(at 0 0 90)
			(layer "F.SilkS")
			(hide yes)
			(effects
				(font
					(size 1.27 1.27)
				)
			)
		)
		(property "Value" ""
			(at 0 0 90)
			(layer "F.Fab")
			(effects
				(font
					(size 1.27 1.27)
				)
			)
		)
		(duplicate_pad_numbers_are_jumpers no)
		(fp_line
			(start 0.7874 -0.4064)
			(end 0.7874 0.4064)
			(stroke
				(width 0.1524)
				(type default)
			)
			(layer "F.SilkS")
		)
		(fp_line
			(start -0.7874 -0.4064)
			(end 0.7874 -0.4064)
			(stroke
				(width 0.1524)
				(type default)
			)
			(layer "F.SilkS")
		)
		(fp_line
			(start 0.7874 0.4064)
			(end -0.7874 0.4064)
			(stroke
				(width 0.1524)
				(type default)
			)
			(layer "F.SilkS")
		)
		(fp_line
			(start -0.7874 0.4064)
			(end -0.7874 -0.4064)
			(stroke
				(width 0.1524)
				(type default)
			)
			(layer "F.SilkS")
		)
		(fp_line
			(start -0.12065 -0.305054)
			(end -0.12065 -0.2794)
			(stroke
				(width 0.1)
				(type default)
			)
			(layer "F.Fab")
		)
		(fp_line
			(start -0.67945 -0.305054)
			(end -0.12065 -0.305054)
			(stroke
				(width 0.1)
				(type default)
			)
			(layer "F.Fab")
		)
		(fp_line
			(start 0.67945 -0.3048)
			(end 0.67945 0.3048)
			(stroke
				(width 0.1)
				(type default)
			)
			(layer "F.Fab")
		)
		(fp_line
			(start 0.12065 -0.3048)
			(end 0.67945 -0.3048)
			(stroke
				(width 0.1)
				(type default)
			)
			(layer "F.Fab")
		)
		(fp_line
			(start 0.12065 -0.2794)
			(end 0.12065 -0.3048)
			(stroke
				(width 0.1)
				(type default)
			)
			(layer "F.Fab")
		)
		(fp_line
			(start -0.12065 -0.2794)
			(end 0.12065 -0.2794)
			(stroke
				(width 0.1)
				(type default)
			)
			(layer "F.Fab")
		)
		(fp_line
			(start 0.120396 0.2794)
			(end -0.12065 0.2794)
			(stroke
				(width 0.1)
				(type default)
			)
			(layer "F.Fab")
		)
		(fp_line
			(start -0.12065 0.2794)
			(end -0.12065 0.3048)
			(stroke
				(width 0.1)
				(type default)
			)
			(layer "F.Fab")
		)
		(fp_line
			(start 0.67945 0.3048)
			(end 0.120396 0.3048)
			(stroke
				(width 0.1)
				(type default)
			)
			(layer "F.Fab")
		)
		(fp_line
			(start 0.120396 0.3048)
			(end 0.120396 0.2794)
			(stroke
				(width 0.1)
				(type default)
			)
			(layer "F.Fab")
		)
		(fp_line
			(start -0.12065 0.3048)
			(end -0.67945 0.3048)
			(stroke
				(width 0.1)
				(type default)
			)
			(layer "F.Fab")
		)
		(fp_line
			(start -0.67945 0.3048)
			(end -0.67945 -0.305054)
			(stroke
				(width 0.1)
				(type default)
			)
			(layer "F.Fab")
		)
		(pad "1" smd circle
			(at -0.40005 0 90)
			(size 0 0)
			(layers "F.Cu" "F.Mask" "F.Paste")
			(net "I3C3_SCL_R")
		)
		(pad "2" smd circle
			(at 0.40005 0 90)
			(size 0 0)
			(layers "F.Cu" "F.Mask" "F.Paste")
			(net "I3C3_SPD_SCL")
		)
	)
	(footprint ""
		(layer "F.Cu")
		(at 36.322 -106.934 -90)
		(property "Reference" "R481"
			(at 0 0 270)
			(layer "F.SilkS")
			(hide yes)
			(effects
				(font
					(size 1.27 1.27)
				)
			)
		)
		(property "Value" ""
			(at 0 0 270)
			(layer "F.Fab")
			(effects
				(font
					(size 1.27 1.27)
				)
			)
		)
		(duplicate_pad_numbers_are_jumpers no)
		(fp_line
			(start -0.7874 0.4064)
			(end -0.7874 -0.4064)
			(stroke
				(width 0.1524)
				(type default)
			)
			(layer "F.SilkS")
		)
		(fp_line
			(start 0.7874 0.4064)
			(end -0.7874 0.4064)
			(stroke
				(width 0.1524)
				(type default)
			)
			(layer "F.SilkS")
		)
		(fp_line
			(start -0.7874 -0.4064)
			(end 0.7874 -0.4064)
			(stroke
				(width 0.1524)
				(type default)
			)
			(layer "F.SilkS")
		)
		(fp_line
			(start 0.7874 -0.4064)
			(end 0.7874 0.4064)
			(stroke
				(width 0.1524)
				(type default)
			)
			(layer "F.SilkS")
		)
		(fp_line
			(start -0.67945 0.3048)
			(end -0.67945 -0.305054)
			(stroke
				(width 0.1)
				(type default)
			)
			(layer "F.Fab")
		)
		(fp_line
			(start -0.12065 0.3048)
			(end -0.67945 0.3048)
			(stroke
				(width 0.1)
				(type default)
			)
			(layer "F.Fab")
		)
		(fp_line
			(start 0.120396 0.3048)
			(end 0.120396 0.2794)
			(stroke
				(width 0.1)
				(type default)
			)
			(layer "F.Fab")
		)
		(fp_line
			(start 0.67945 0.3048)
			(end 0.120396 0.3048)
			(stroke
				(width 0.1)
				(type default)
			)
			(layer "F.Fab")
		)
		(fp_line
			(start -0.12065 0.2794)
			(end -0.12065 0.3048)
			(stroke
				(width 0.1)
				(type default)
			)
			(layer "F.Fab")
		)
		(fp_line
			(start 0.120396 0.2794)
			(end -0.12065 0.2794)
			(stroke
				(width 0.1)
				(type default)
			)
			(layer "F.Fab")
		)
		(fp_line
			(start -0.12065 -0.2794)
			(end 0.12065 -0.2794)
			(stroke
				(width 0.1)
				(type default)
			)
			(layer "F.Fab")
		)
		(fp_line
			(start 0.12065 -0.2794)
			(end 0.12065 -0.3048)
			(stroke
				(width 0.1)
				(type default)
			)
			(layer "F.Fab")
		)
		(fp_line
			(start 0.12065 -0.3048)
			(end 0.67945 -0.3048)
			(stroke
				(width 0.1)
				(type default)
			)
			(layer "F.Fab")
		)
		(fp_line
			(start 0.67945 -0.3048)
			(end 0.67945 0.3048)
			(stroke
				(width 0.1)
				(type default)
			)
			(layer "F.Fab")
		)
		(fp_line
			(start -0.67945 -0.305054)
			(end -0.12065 -0.305054)
			(stroke
				(width 0.1)
				(type default)
			)
			(layer "F.Fab")
		)
		(fp_line
			(start -0.12065 -0.305054)
			(end -0.12065 -0.2794)
			(stroke
				(width 0.1)
				(type default)
			)
			(layer "F.Fab")
		)
		(pad "1" smd circle
			(at -0.40005 0 270)
			(size 0 0)
			(layers "F.Cu" "F.Mask" "F.Paste")
			(net "SPI_PCH_MUXED_CLK")
		)
		(pad "2" smd circle
			(at 0.40005 0 270)
			(size 0 0)
			(layers "F.Cu" "F.Mask" "F.Paste")
			(net "SPI_PCH_CLK_FLASH_R1")
		)
	)
	(footprint ""
		(layer "F.Cu")
		(at 82.44967 -65.20815 -90)
		(property "Reference" "PL31"
			(at 0 0 270)
			(layer "F.SilkS")
			(hide yes)
			(effects
				(font
					(size 1.27 1.27)
				)
			)
		)
		(property "Value" ""
			(at 0 0 270)
			(layer "F.Fab")
			(effects
				(font
					(size 1.27 1.27)
				)
			)
		)
		(duplicate_pad_numbers_are_jumpers no)
		(fp_line
			(start -3.64998 3.350006)
			(end -3.64998 1.8288)
			(stroke
				(width 0.1524)
				(type default)
			)
			(layer "F.SilkS")
		)
		(fp_line
			(start 3.64998 3.350006)
			(end -3.64998 3.350006)
			(stroke
				(width 0.1524)
				(type default)
			)
			(layer "F.SilkS")
		)
		(fp_line
			(start 3.64998 1.8034)
			(end 3.64998 3.350006)
			(stroke
				(width 0.1524)
				(type default)
			)
			(layer "F.SilkS")
		)
		(fp_line
			(start -3.64998 -1.8034)
			(end -3.64998 -3.350006)
			(stroke
				(width 0.1524)
				(type default)
			)
			(layer "F.SilkS")
		)
		(fp_line
			(start -3.6576 -3.350006)
			(end 3.64998 -3.350006)
			(stroke
				(width 0.1524)
				(type default)
			)
			(layer "F.SilkS")
		)
		(fp_line
			(start 3.64998 -3.350006)
			(end 3.64998 -1.8034)
			(stroke
				(width 0.1524)
				(type default)
			)
			(layer "F.SilkS")
		)
		(fp_line
			(start -3.64998 3.350006)
			(end -3.64998 -3.350006)
			(stroke
				(width 0.1)
				(type default)
			)
			(layer "F.Fab")
		)
		(fp_line
			(start 3.64998 3.350006)
			(end -3.64998 3.350006)
			(stroke
				(width 0.1)
				(type default)
			)
			(layer "F.Fab")
		)
		(fp_line
			(start -3.64998 -3.350006)
			(end 3.64998 -3.350006)
			(stroke
				(width 0.1)
				(type default)
			)
			(layer "F.Fab")
		)
		(fp_line
			(start 3.64998 -3.350006)
			(end 3.64998 3.350006)
			(stroke
				(width 0.1)
				(type default)
			)
			(layer "F.Fab")
		)
		(pad "1" smd rect
			(at -2.92481 0 270)
			(size 2.15392 3.302)
			(layers "F.Cu" "F.Mask" "F.Paste")
			(net "SW_P1V2_AUX_SW")
		)
		(pad "2" smd rect
			(at 2.92481 0 270)
			(size 2.15392 3.302)
			(layers "F.Cu" "F.Mask" "F.Paste")
			(net "P1V2_AUX")
		)
	)
	(footprint ""
		(layer "F.Cu")
		(at -4.191 -138.303)
		(property "Reference" "DM3"
			(at -0.3937 -0.588518 0)
			(unlocked yes)
			(layer "F.SilkS")
			(effects
				(font
					(size 0.254 0.127)
					(thickness 0.000001)
				)
				(justify left)
			)
		)
		(property "Value" ""
			(at 0 0 0)
			(layer "F.Fab")
			(effects
				(font
					(size 1.27 1.27)
				)
			)
		)
		(duplicate_pad_numbers_are_jumpers no)
		(pad "1" smd circle
			(at 0 0)
			(size 0.762 0.762)
			(layers "F.Cu" "F.Mask" "F.Paste")
			(net "Net_1198")
		)
	)
	(footprint ""
		(layer "F.Cu")
		(at 28.575 -102.743 -90)
		(property "Reference" "R577"
			(at 0 0 270)
			(layer "F.SilkS")
			(hide yes)
			(effects
				(font
					(size 1.27 1.27)
				)
			)
		)
		(property "Value" ""
			(at 0 0 270)
			(layer "F.Fab")
			(effects
				(font
					(size 1.27 1.27)
				)
			)
		)
		(duplicate_pad_numbers_are_jumpers no)
		(fp_line
			(start -0.7874 0.4064)
			(end -0.7874 -0.4064)
			(stroke
				(width 0.1524)
				(type default)
			)
			(layer "F.SilkS")
		)
		(fp_line
			(start 0.7874 0.4064)
			(end -0.7874 0.4064)
			(stroke
				(width 0.1524)
				(type default)
			)
			(layer "F.SilkS")
		)
		(fp_line
			(start -0.7874 -0.4064)
			(end 0.7874 -0.4064)
			(stroke
				(width 0.1524)
				(type default)
			)
			(layer "F.SilkS")
		)
		(fp_line
			(start 0.7874 -0.4064)
			(end 0.7874 0.4064)
			(stroke
				(width 0.1524)
				(type default)
			)
			(layer "F.SilkS")
		)
		(fp_line
			(start -0.67945 0.3048)
			(end -0.67945 -0.305054)
			(stroke
				(width 0.1)
				(type default)
			)
			(layer "F.Fab")
		)
		(fp_line
			(start -0.12065 0.3048)
			(end -0.67945 0.3048)
			(stroke
				(width 0.1)
				(type default)
			)
			(layer "F.Fab")
		)
		(fp_line
			(start 0.120396 0.3048)
			(end 0.120396 0.2794)
			(stroke
				(width 0.1)
				(type default)
			)
			(layer "F.Fab")
		)
		(fp_line
			(start 0.67945 0.3048)
			(end 0.120396 0.3048)
			(stroke
				(width 0.1)
				(type default)
			)
			(layer "F.Fab")
		)
		(fp_line
			(start -0.12065 0.2794)
			(end -0.12065 0.3048)
			(stroke
				(width 0.1)
				(type default)
			)
			(layer "F.Fab")
		)
		(fp_line
			(start 0.120396 0.2794)
			(end -0.12065 0.2794)
			(stroke
				(width 0.1)
				(type default)
			)
			(layer "F.Fab")
		)
		(fp_line
			(start -0.12065 -0.2794)
			(end 0.12065 -0.2794)
			(stroke
				(width 0.1)
				(type default)
			)
			(layer "F.Fab")
		)
		(fp_line
			(start 0.12065 -0.2794)
			(end 0.12065 -0.3048)
			(stroke
				(width 0.1)
				(type default)
			)
			(layer "F.Fab")
		)
		(fp_line
			(start 0.12065 -0.3048)
			(end 0.67945 -0.3048)
			(stroke
				(width 0.1)
				(type default)
			)
			(layer "F.Fab")
		)
		(fp_line
			(start 0.67945 -0.3048)
			(end 0.67945 0.3048)
			(stroke
				(width 0.1)
				(type default)
			)
			(layer "F.Fab")
		)
		(fp_line
			(start -0.67945 -0.305054)
			(end -0.12065 -0.305054)
			(stroke
				(width 0.1)
				(type default)
			)
			(layer "F.Fab")
		)
		(fp_line
			(start -0.12065 -0.305054)
			(end -0.12065 -0.2794)
			(stroke
				(width 0.1)
				(type default)
			)
			(layer "F.Fab")
		)
		(pad "1" smd circle
			(at -0.40005 0 270)
			(size 0 0)
			(layers "F.Cu" "F.Mask" "F.Paste")
			(net "FM_SOL_UART_CH_SEL")
		)
		(pad "2" smd circle
			(at 0.40005 0 270)
			(size 0 0)
			(layers "F.Cu" "F.Mask" "F.Paste")
			(net "FM_SOL_UART_CH_SEL_R2")
		)
	)
	(footprint ""
		(layer "F.Cu")
		(at 16.4846 -83.693 -90)
		(property "Reference" "R436"
			(at 0 0 270)
			(layer "F.SilkS")
			(hide yes)
			(effects
				(font
					(size 1.27 1.27)
				)
			)
		)
		(property "Value" ""
			(at 0 0 270)
			(layer "F.Fab")
			(effects
				(font
					(size 1.27 1.27)
				)
			)
		)
		(duplicate_pad_numbers_are_jumpers no)
		(fp_line
			(start -0.7874 0.4064)
			(end -0.7874 -0.4064)
			(stroke
				(width 0.1524)
				(type default)
			)
			(layer "F.SilkS")
		)
		(fp_line
			(start 0.7874 0.4064)
			(end -0.7874 0.4064)
			(stroke
				(width 0.1524)
				(type default)
			)
			(layer "F.SilkS")
		)
		(fp_line
			(start -0.7874 -0.4064)
			(end 0.7874 -0.4064)
			(stroke
				(width 0.1524)
				(type default)
			)
			(layer "F.SilkS")
		)
		(fp_line
			(start 0.7874 -0.4064)
			(end 0.7874 0.4064)
			(stroke
				(width 0.1524)
				(type default)
			)
			(layer "F.SilkS")
		)
		(fp_line
			(start -0.67945 0.3048)
			(end -0.67945 -0.305054)
			(stroke
				(width 0.1)
				(type default)
			)
			(layer "F.Fab")
		)
		(fp_line
			(start -0.12065 0.3048)
			(end -0.67945 0.3048)
			(stroke
				(width 0.1)
				(type default)
			)
			(layer "F.Fab")
		)
		(fp_line
			(start 0.120396 0.3048)
			(end 0.120396 0.2794)
			(stroke
				(width 0.1)
				(type default)
			)
			(layer "F.Fab")
		)
		(fp_line
			(start 0.67945 0.3048)
			(end 0.120396 0.3048)
			(stroke
				(width 0.1)
				(type default)
			)
			(layer "F.Fab")
		)
		(fp_line
			(start -0.12065 0.2794)
			(end -0.12065 0.3048)
			(stroke
				(width 0.1)
				(type default)
			)
			(layer "F.Fab")
		)
		(fp_line
			(start 0.120396 0.2794)
			(end -0.12065 0.2794)
			(stroke
				(width 0.1)
				(type default)
			)
			(layer "F.Fab")
		)
		(fp_line
			(start -0.12065 -0.2794)
			(end 0.12065 -0.2794)
			(stroke
				(width 0.1)
				(type default)
			)
			(layer "F.Fab")
		)
		(fp_line
			(start 0.12065 -0.2794)
			(end 0.12065 -0.3048)
			(stroke
				(width 0.1)
				(type default)
			)
			(layer "F.Fab")
		)
		(fp_line
			(start 0.12065 -0.3048)
			(end 0.67945 -0.3048)
			(stroke
				(width 0.1)
				(type default)
			)
			(layer "F.Fab")
		)
		(fp_line
			(start 0.67945 -0.3048)
			(end 0.67945 0.3048)
			(stroke
				(width 0.1)
				(type default)
			)
			(layer "F.Fab")
		)
		(fp_line
			(start -0.67945 -0.305054)
			(end -0.12065 -0.305054)
			(stroke
				(width 0.1)
				(type default)
			)
			(layer "F.Fab")
		)
		(fp_line
			(start -0.12065 -0.305054)
			(end -0.12065 -0.2794)
			(stroke
				(width 0.1)
				(type default)
			)
			(layer "F.Fab")
		)
		(pad "1" smd circle
			(at -0.40005 0 270)
			(size 0 0)
			(layers "F.Cu" "F.Mask" "F.Paste")
			(net "SGPIO_PLD_LD_0")
		)
		(pad "2" smd circle
			(at 0.40005 0 270)
			(size 0 0)
			(layers "F.Cu" "F.Mask" "F.Paste")
			(net "SGPIO_LD_0")
		)
	)
	(footprint ""
		(layer "F.Cu")
		(at 23.1775 -104.775)
		(property "Reference" "C173"
			(at 0 0 0)
			(layer "F.SilkS")
			(hide yes)
			(effects
				(font
					(size 1.27 1.27)
				)
			)
		)
		(property "Value" ""
			(at 0 0 0)
			(layer "F.Fab")
			(effects
				(font
					(size 1.27 1.27)
				)
			)
		)
		(duplicate_pad_numbers_are_jumpers no)
		(fp_line
			(start -0.7874 -0.4064)
			(end 0.7874 -0.4064)
			(stroke
				(width 0.1524)
				(type default)
			)
			(layer "F.SilkS")
		)
		(fp_line
			(start -0.7874 0.4064)
			(end -0.7874 -0.4064)
			(stroke
				(width 0.1524)
				(type default)
			)
			(layer "F.SilkS")
		)
		(fp_line
			(start 0.7874 -0.4064)
			(end 0.7874 0.4064)
			(stroke
				(width 0.1524)
				(type default)
			)
			(layer "F.SilkS")
		)
		(fp_line
			(start 0.7874 0.4064)
			(end -0.7874 0.4064)
			(stroke
				(width 0.1524)
				(type default)
			)
			(layer "F.SilkS")
		)
		(fp_line
			(start -0.67945 -0.305054)
			(end -0.12065 -0.305054)
			(stroke
				(width 0.1)
				(type default)
			)
			(layer "F.Fab")
		)
		(fp_line
			(start -0.67945 0.3048)
			(end -0.67945 -0.305054)
			(stroke
				(width 0.1)
				(type default)
			)
			(layer "F.Fab")
		)
		(fp_line
			(start -0.12065 -0.305054)
			(end -0.12065 -0.2794)
			(stroke
				(width 0.1)
				(type default)
			)
			(layer "F.Fab")
		)
		(fp_line
			(start -0.12065 -0.2794)
			(end 0.12065 -0.2794)
			(stroke
				(width 0.1)
				(type default)
			)
			(layer "F.Fab")
		)
		(fp_line
			(start -0.12065 0.2794)
			(end -0.12065 0.3048)
			(stroke
				(width 0.1)
				(type default)
			)
			(layer "F.Fab")
		)
		(fp_line
			(start -0.12065 0.3048)
			(end -0.67945 0.3048)
			(stroke
				(width 0.1)
				(type default)
			)
			(layer "F.Fab")
		)
		(fp_line
			(start 0.120396 0.2794)
			(end -0.12065 0.2794)
			(stroke
				(width 0.1)
				(type default)
			)
			(layer "F.Fab")
		)
		(fp_line
			(start 0.120396 0.3048)
			(end 0.120396 0.2794)
			(stroke
				(width 0.1)
				(type default)
			)
			(layer "F.Fab")
		)
		(fp_line
			(start 0.12065 -0.3048)
			(end 0.67945 -0.3048)
			(stroke
				(width 0.1)
				(type default)
			)
			(layer "F.Fab")
		)
		(fp_line
			(start 0.12065 -0.2794)
			(end 0.12065 -0.3048)
			(stroke
				(width 0.1)
				(type default)
			)
			(layer "F.Fab")
		)
		(fp_line
			(start 0.67945 -0.3048)
			(end 0.67945 0.3048)
			(stroke
				(width 0.1)
				(type default)
			)
			(layer "F.Fab")
		)
		(fp_line
			(start 0.67945 0.3048)
			(end 0.120396 0.3048)
			(stroke
				(width 0.1)
				(type default)
			)
			(layer "F.Fab")
		)
		(pad "1" smd circle
			(at -0.40005 0)
			(size 0 0)
			(layers "F.Cu" "F.Mask" "F.Paste")
			(net "RST_BMC_SELF_HW_D_C")
		)
		(pad "2" smd circle
			(at 0.40005 0)
			(size 0 0)
			(layers "F.Cu" "F.Mask" "F.Paste")
			(net "GND")
		)
	)
	(footprint ""
		(layer "F.Cu")
		(at 11.612626 -47.63135)
		(property "Reference" "PR525"
			(at 0 0 0)
			(layer "F.SilkS")
			(hide yes)
			(effects
				(font
					(size 1.27 1.27)
				)
			)
		)
		(property "Value" ""
			(at 0 0 0)
			(layer "F.Fab")
			(effects
				(font
					(size 1.27 1.27)
				)
			)
		)
		(duplicate_pad_numbers_are_jumpers no)
		(fp_line
			(start -0.7874 -0.4064)
			(end 0.7874 -0.4064)
			(stroke
				(width 0.1524)
				(type default)
			)
			(layer "F.SilkS")
		)
		(fp_line
			(start -0.7874 0.4064)
			(end -0.7874 -0.4064)
			(stroke
				(width 0.1524)
				(type default)
			)
			(layer "F.SilkS")
		)
		(fp_line
			(start 0.7874 -0.4064)
			(end 0.7874 0.4064)
			(stroke
				(width 0.1524)
				(type default)
			)
			(layer "F.SilkS")
		)
		(fp_line
			(start 0.7874 0.4064)
			(end -0.7874 0.4064)
			(stroke
				(width 0.1524)
				(type default)
			)
			(layer "F.SilkS")
		)
		(fp_line
			(start -0.67945 -0.305054)
			(end -0.12065 -0.305054)
			(stroke
				(width 0.1)
				(type default)
			)
			(layer "F.Fab")
		)
		(fp_line
			(start -0.67945 0.3048)
			(end -0.67945 -0.305054)
			(stroke
				(width 0.1)
				(type default)
			)
			(layer "F.Fab")
		)
		(fp_line
			(start -0.12065 -0.305054)
			(end -0.12065 -0.2794)
			(stroke
				(width 0.1)
				(type default)
			)
			(layer "F.Fab")
		)
		(fp_line
			(start -0.12065 -0.2794)
			(end 0.12065 -0.2794)
			(stroke
				(width 0.1)
				(type default)
			)
			(layer "F.Fab")
		)
		(fp_line
			(start -0.12065 0.2794)
			(end -0.12065 0.3048)
			(stroke
				(width 0.1)
				(type default)
			)
			(layer "F.Fab")
		)
		(fp_line
			(start -0.12065 0.3048)
			(end -0.67945 0.3048)
			(stroke
				(width 0.1)
				(type default)
			)
			(layer "F.Fab")
		)
		(fp_line
			(start 0.120396 0.2794)
			(end -0.12065 0.2794)
			(stroke
				(width 0.1)
				(type default)
			)
			(layer "F.Fab")
		)
		(fp_line
			(start 0.120396 0.3048)
			(end 0.120396 0.2794)
			(stroke
				(width 0.1)
				(type default)
			)
			(layer "F.Fab")
		)
		(fp_line
			(start 0.12065 -0.3048)
			(end 0.67945 -0.3048)
			(stroke
				(width 0.1)
				(type default)
			)
			(layer "F.Fab")
		)
		(fp_line
			(start 0.12065 -0.2794)
			(end 0.12065 -0.3048)
			(stroke
				(width 0.1)
				(type default)
			)
			(layer "F.Fab")
		)
		(fp_line
			(start 0.67945 -0.3048)
			(end 0.67945 0.3048)
			(stroke
				(width 0.1)
				(type default)
			)
			(layer "F.Fab")
		)
		(fp_line
			(start 0.67945 0.3048)
			(end 0.120396 0.3048)
			(stroke
				(width 0.1)
				(type default)
			)
			(layer "F.Fab")
		)
		(pad "1" smd circle
			(at -0.40005 0)
			(size 0 0)
			(layers "F.Cu" "F.Mask" "F.Paste")
			(net "P5V_AUX_CS")
		)
		(pad "2" smd circle
			(at 0.40005 0)
			(size 0 0)
			(layers "F.Cu" "F.Mask" "F.Paste")
			(net "GND")
		)
	)
	(footprint ""
		(layer "F.Cu")
		(at 77.707744 -35.527488 90)
		(property "Reference" "R330"
			(at 0 0 90)
			(layer "F.SilkS")
			(hide yes)
			(effects
				(font
					(size 1.27 1.27)
				)
			)
		)
		(property "Value" ""
			(at 0 0 90)
			(layer "F.Fab")
			(effects
				(font
					(size 1.27 1.27)
				)
			)
		)
		(duplicate_pad_numbers_are_jumpers no)
		(fp_line
			(start 0.7874 -0.4064)
			(end 0.7874 0.4064)
			(stroke
				(width 0.1524)
				(type default)
			)
			(layer "F.SilkS")
		)
		(fp_line
			(start -0.7874 -0.4064)
			(end 0.7874 -0.4064)
			(stroke
				(width 0.1524)
				(type default)
			)
			(layer "F.SilkS")
		)
		(fp_line
			(start 0.7874 0.4064)
			(end -0.7874 0.4064)
			(stroke
				(width 0.1524)
				(type default)
			)
			(layer "F.SilkS")
		)
		(fp_line
			(start -0.7874 0.4064)
			(end -0.7874 -0.4064)
			(stroke
				(width 0.1524)
				(type default)
			)
			(layer "F.SilkS")
		)
		(fp_line
			(start -0.12065 -0.305054)
			(end -0.12065 -0.2794)
			(stroke
				(width 0.1)
				(type default)
			)
			(layer "F.Fab")
		)
		(fp_line
			(start -0.67945 -0.305054)
			(end -0.12065 -0.305054)
			(stroke
				(width 0.1)
				(type default)
			)
			(layer "F.Fab")
		)
		(fp_line
			(start 0.67945 -0.3048)
			(end 0.67945 0.3048)
			(stroke
				(width 0.1)
				(type default)
			)
			(layer "F.Fab")
		)
		(fp_line
			(start 0.12065 -0.3048)
			(end 0.67945 -0.3048)
			(stroke
				(width 0.1)
				(type default)
			)
			(layer "F.Fab")
		)
		(fp_line
			(start 0.12065 -0.2794)
			(end 0.12065 -0.3048)
			(stroke
				(width 0.1)
				(type default)
			)
			(layer "F.Fab")
		)
		(fp_line
			(start -0.12065 -0.2794)
			(end 0.12065 -0.2794)
			(stroke
				(width 0.1)
				(type default)
			)
			(layer "F.Fab")
		)
		(fp_line
			(start 0.120396 0.2794)
			(end -0.12065 0.2794)
			(stroke
				(width 0.1)
				(type default)
			)
			(layer "F.Fab")
		)
		(fp_line
			(start -0.12065 0.2794)
			(end -0.12065 0.3048)
			(stroke
				(width 0.1)
				(type default)
			)
			(layer "F.Fab")
		)
		(fp_line
			(start 0.67945 0.3048)
			(end 0.120396 0.3048)
			(stroke
				(width 0.1)
				(type default)
			)
			(layer "F.Fab")
		)
		(fp_line
			(start 0.120396 0.3048)
			(end 0.120396 0.2794)
			(stroke
				(width 0.1)
				(type default)
			)
			(layer "F.Fab")
		)
		(fp_line
			(start -0.12065 0.3048)
			(end -0.67945 0.3048)
			(stroke
				(width 0.1)
				(type default)
			)
			(layer "F.Fab")
		)
		(fp_line
			(start -0.67945 0.3048)
			(end -0.67945 -0.305054)
			(stroke
				(width 0.1)
				(type default)
			)
			(layer "F.Fab")
		)
		(pad "1" smd circle
			(at -0.40005 0 90)
			(size 0 0)
			(layers "F.Cu" "F.Mask" "F.Paste")
			(net "GND")
		)
		(pad "2" smd circle
			(at 0.40005 0 90)
			(size 0 0)
			(layers "F.Cu" "F.Mask" "F.Paste")
			(net "M_BMC_DDR4_MA<4>")
		)
	)
	(footprint ""
		(layer "F.Cu")
		(at 24.7142 -65.8622 -90)
		(property "Reference" "R742"
			(at 0 0 270)
			(layer "F.SilkS")
			(hide yes)
			(effects
				(font
					(size 1.27 1.27)
				)
			)
		)
		(property "Value" ""
			(at 0 0 270)
			(layer "F.Fab")
			(effects
				(font
					(size 1.27 1.27)
				)
			)
		)
		(duplicate_pad_numbers_are_jumpers no)
		(fp_line
			(start -0.7874 0.4064)
			(end -0.7874 -0.4064)
			(stroke
				(width 0.1524)
				(type default)
			)
			(layer "F.SilkS")
		)
		(fp_line
			(start 0.7874 0.4064)
			(end -0.7874 0.4064)
			(stroke
				(width 0.1524)
				(type default)
			)
			(layer "F.SilkS")
		)
		(fp_line
			(start -0.7874 -0.4064)
			(end 0.7874 -0.4064)
			(stroke
				(width 0.1524)
				(type default)
			)
			(layer "F.SilkS")
		)
		(fp_line
			(start 0.7874 -0.4064)
			(end 0.7874 0.4064)
			(stroke
				(width 0.1524)
				(type default)
			)
			(layer "F.SilkS")
		)
		(fp_line
			(start -0.67945 0.3048)
			(end -0.67945 -0.305054)
			(stroke
				(width 0.1)
				(type default)
			)
			(layer "F.Fab")
		)
		(fp_line
			(start -0.12065 0.3048)
			(end -0.67945 0.3048)
			(stroke
				(width 0.1)
				(type default)
			)
			(layer "F.Fab")
		)
		(fp_line
			(start 0.120396 0.3048)
			(end 0.120396 0.2794)
			(stroke
				(width 0.1)
				(type default)
			)
			(layer "F.Fab")
		)
		(fp_line
			(start 0.67945 0.3048)
			(end 0.120396 0.3048)
			(stroke
				(width 0.1)
				(type default)
			)
			(layer "F.Fab")
		)
		(fp_line
			(start -0.12065 0.2794)
			(end -0.12065 0.3048)
			(stroke
				(width 0.1)
				(type default)
			)
			(layer "F.Fab")
		)
		(fp_line
			(start 0.120396 0.2794)
			(end -0.12065 0.2794)
			(stroke
				(width 0.1)
				(type default)
			)
			(layer "F.Fab")
		)
		(fp_line
			(start -0.12065 -0.2794)
			(end 0.12065 -0.2794)
			(stroke
				(width 0.1)
				(type default)
			)
			(layer "F.Fab")
		)
		(fp_line
			(start 0.12065 -0.2794)
			(end 0.12065 -0.3048)
			(stroke
				(width 0.1)
				(type default)
			)
			(layer "F.Fab")
		)
		(fp_line
			(start 0.12065 -0.3048)
			(end 0.67945 -0.3048)
			(stroke
				(width 0.1)
				(type default)
			)
			(layer "F.Fab")
		)
		(fp_line
			(start 0.67945 -0.3048)
			(end 0.67945 0.3048)
			(stroke
				(width 0.1)
				(type default)
			)
			(layer "F.Fab")
		)
		(fp_line
			(start -0.67945 -0.305054)
			(end -0.12065 -0.305054)
			(stroke
				(width 0.1)
				(type default)
			)
			(layer "F.Fab")
		)
		(fp_line
			(start -0.12065 -0.305054)
			(end -0.12065 -0.2794)
			(stroke
				(width 0.1)
				(type default)
			)
			(layer "F.Fab")
		)
		(pad "1" smd circle
			(at -0.40005 0 270)
			(size 0 0)
			(layers "F.Cu" "F.Mask" "F.Paste")
			(net "P3V3_AUX")
		)
		(pad "2" smd circle
			(at 0.40005 0 270)
			(size 0 0)
			(layers "F.Cu" "F.Mask" "F.Paste")
			(net "SPA_SOUT_SW_BUF")
		)
	)
	(footprint ""
		(layer "F.Cu")
		(at 40.0304 -109.474 -90)
		(property "Reference" "R75"
			(at 0 0 270)
			(layer "F.SilkS")
			(hide yes)
			(effects
				(font
					(size 1.27 1.27)
				)
			)
		)
		(property "Value" ""
			(at 0 0 270)
			(layer "F.Fab")
			(effects
				(font
					(size 1.27 1.27)
				)
			)
		)
		(duplicate_pad_numbers_are_jumpers no)
		(fp_line
			(start -0.7874 0.4064)
			(end -0.7874 -0.4064)
			(stroke
				(width 0.1524)
				(type default)
			)
			(layer "F.SilkS")
		)
		(fp_line
			(start 0.7874 0.4064)
			(end -0.7874 0.4064)
			(stroke
				(width 0.1524)
				(type default)
			)
			(layer "F.SilkS")
		)
		(fp_line
			(start -0.7874 -0.4064)
			(end 0.7874 -0.4064)
			(stroke
				(width 0.1524)
				(type default)
			)
			(layer "F.SilkS")
		)
		(fp_line
			(start 0.7874 -0.4064)
			(end 0.7874 0.4064)
			(stroke
				(width 0.1524)
				(type default)
			)
			(layer "F.SilkS")
		)
		(fp_line
			(start -0.67945 0.3048)
			(end -0.67945 -0.305054)
			(stroke
				(width 0.1)
				(type default)
			)
			(layer "F.Fab")
		)
		(fp_line
			(start -0.12065 0.3048)
			(end -0.67945 0.3048)
			(stroke
				(width 0.1)
				(type default)
			)
			(layer "F.Fab")
		)
		(fp_line
			(start 0.120396 0.3048)
			(end 0.120396 0.2794)
			(stroke
				(width 0.1)
				(type default)
			)
			(layer "F.Fab")
		)
		(fp_line
			(start 0.67945 0.3048)
			(end 0.120396 0.3048)
			(stroke
				(width 0.1)
				(type default)
			)
			(layer "F.Fab")
		)
		(fp_line
			(start -0.12065 0.2794)
			(end -0.12065 0.3048)
			(stroke
				(width 0.1)
				(type default)
			)
			(layer "F.Fab")
		)
		(fp_line
			(start 0.120396 0.2794)
			(end -0.12065 0.2794)
			(stroke
				(width 0.1)
				(type default)
			)
			(layer "F.Fab")
		)
		(fp_line
			(start -0.12065 -0.2794)
			(end 0.12065 -0.2794)
			(stroke
				(width 0.1)
				(type default)
			)
			(layer "F.Fab")
		)
		(fp_line
			(start 0.12065 -0.2794)
			(end 0.12065 -0.3048)
			(stroke
				(width 0.1)
				(type default)
			)
			(layer "F.Fab")
		)
		(fp_line
			(start 0.12065 -0.3048)
			(end 0.67945 -0.3048)
			(stroke
				(width 0.1)
				(type default)
			)
			(layer "F.Fab")
		)
		(fp_line
			(start 0.67945 -0.3048)
			(end 0.67945 0.3048)
			(stroke
				(width 0.1)
				(type default)
			)
			(layer "F.Fab")
		)
		(fp_line
			(start -0.67945 -0.305054)
			(end -0.12065 -0.305054)
			(stroke
				(width 0.1)
				(type default)
			)
			(layer "F.Fab")
		)
		(fp_line
			(start -0.12065 -0.305054)
			(end -0.12065 -0.2794)
			(stroke
				(width 0.1)
				(type default)
			)
			(layer "F.Fab")
		)
		(pad "1" smd circle
			(at -0.40005 0 270)
			(size 0 0)
			(layers "F.Cu" "F.Mask" "F.Paste")
			(net "P3V3_AUX")
		)
		(pad "2" smd circle
			(at 0.40005 0 270)
			(size 0 0)
			(layers "F.Cu" "F.Mask" "F.Paste")
			(net "SGPIO_DO_1")
		)
	)
	(footprint ""
		(layer "F.Cu")
		(at 57.023 -75.3364 180)
		(property "Reference" "R545"
			(at 0 0 180)
			(layer "F.SilkS")
			(hide yes)
			(effects
				(font
					(size 1.27 1.27)
				)
			)
		)
		(property "Value" ""
			(at 0 0 180)
			(layer "F.Fab")
			(effects
				(font
					(size 1.27 1.27)
				)
			)
		)
		(duplicate_pad_numbers_are_jumpers no)
		(fp_line
			(start 0.7874 0.4064)
			(end -0.7874 0.4064)
			(stroke
				(width 0.1524)
				(type default)
			)
			(layer "F.SilkS")
		)
		(fp_line
			(start 0.7874 -0.4064)
			(end 0.7874 0.4064)
			(stroke
				(width 0.1524)
				(type default)
			)
			(layer "F.SilkS")
		)
		(fp_line
			(start -0.7874 0.4064)
			(end -0.7874 -0.4064)
			(stroke
				(width 0.1524)
				(type default)
			)
			(layer "F.SilkS")
		)
		(fp_line
			(start -0.7874 -0.4064)
			(end 0.7874 -0.4064)
			(stroke
				(width 0.1524)
				(type default)
			)
			(layer "F.SilkS")
		)
		(fp_line
			(start 0.67945 0.3048)
			(end 0.120396 0.3048)
			(stroke
				(width 0.1)
				(type default)
			)
			(layer "F.Fab")
		)
		(fp_line
			(start 0.67945 -0.3048)
			(end 0.67945 0.3048)
			(stroke
				(width 0.1)
				(type default)
			)
			(layer "F.Fab")
		)
		(fp_line
			(start 0.12065 -0.2794)
			(end 0.12065 -0.3048)
			(stroke
				(width 0.1)
				(type default)
			)
			(layer "F.Fab")
		)
		(fp_line
			(start 0.12065 -0.3048)
			(end 0.67945 -0.3048)
			(stroke
				(width 0.1)
				(type default)
			)
			(layer "F.Fab")
		)
		(fp_line
			(start 0.120396 0.3048)
			(end 0.120396 0.2794)
			(stroke
				(width 0.1)
				(type default)
			)
			(layer "F.Fab")
		)
		(fp_line
			(start 0.120396 0.2794)
			(end -0.12065 0.2794)
			(stroke
				(width 0.1)
				(type default)
			)
			(layer "F.Fab")
		)
		(fp_line
			(start -0.12065 0.3048)
			(end -0.67945 0.3048)
			(stroke
				(width 0.1)
				(type default)
			)
			(layer "F.Fab")
		)
		(fp_line
			(start -0.12065 0.2794)
			(end -0.12065 0.3048)
			(stroke
				(width 0.1)
				(type default)
			)
			(layer "F.Fab")
		)
		(fp_line
			(start -0.12065 -0.2794)
			(end 0.12065 -0.2794)
			(stroke
				(width 0.1)
				(type default)
			)
			(layer "F.Fab")
		)
		(fp_line
			(start -0.12065 -0.305054)
			(end -0.12065 -0.2794)
			(stroke
				(width 0.1)
				(type default)
			)
			(layer "F.Fab")
		)
		(fp_line
			(start -0.67945 0.3048)
			(end -0.67945 -0.305054)
			(stroke
				(width 0.1)
				(type default)
			)
			(layer "F.Fab")
		)
		(fp_line
			(start -0.67945 -0.305054)
			(end -0.12065 -0.305054)
			(stroke
				(width 0.1)
				(type default)
			)
			(layer "F.Fab")
		)
		(pad "1" smd circle
			(at -0.40005 0 180)
			(size 0 0)
			(layers "F.Cu" "F.Mask" "F.Paste")
			(net "GND")
		)
		(pad "2" smd circle
			(at 0.40005 0 180)
			(size 0 0)
			(layers "F.Cu" "F.Mask" "F.Paste")
			(net "FLASH_LATCH_CP")
		)
	)
	(footprint ""
		(layer "F.Cu")
		(at 60.198 -10.922 90)
		(property "Reference" "R80"
			(at 0 0 90)
			(layer "F.SilkS")
			(hide yes)
			(effects
				(font
					(size 1.27 1.27)
				)
			)
		)
		(property "Value" ""
			(at 0 0 90)
			(layer "F.Fab")
			(effects
				(font
					(size 1.27 1.27)
				)
			)
		)
		(duplicate_pad_numbers_are_jumpers no)
		(fp_line
			(start 0.7874 -0.4064)
			(end 0.7874 0.4064)
			(stroke
				(width 0.1524)
				(type default)
			)
			(layer "F.SilkS")
		)
		(fp_line
			(start -0.7874 -0.4064)
			(end 0.7874 -0.4064)
			(stroke
				(width 0.1524)
				(type default)
			)
			(layer "F.SilkS")
		)
		(fp_line
			(start 0.7874 0.4064)
			(end -0.7874 0.4064)
			(stroke
				(width 0.1524)
				(type default)
			)
			(layer "F.SilkS")
		)
		(fp_line
			(start -0.7874 0.4064)
			(end -0.7874 -0.4064)
			(stroke
				(width 0.1524)
				(type default)
			)
			(layer "F.SilkS")
		)
		(fp_line
			(start -0.12065 -0.305054)
			(end -0.12065 -0.2794)
			(stroke
				(width 0.1)
				(type default)
			)
			(layer "F.Fab")
		)
		(fp_line
			(start -0.67945 -0.305054)
			(end -0.12065 -0.305054)
			(stroke
				(width 0.1)
				(type default)
			)
			(layer "F.Fab")
		)
		(fp_line
			(start 0.67945 -0.3048)
			(end 0.67945 0.3048)
			(stroke
				(width 0.1)
				(type default)
			)
			(layer "F.Fab")
		)
		(fp_line
			(start 0.12065 -0.3048)
			(end 0.67945 -0.3048)
			(stroke
				(width 0.1)
				(type default)
			)
			(layer "F.Fab")
		)
		(fp_line
			(start 0.12065 -0.2794)
			(end 0.12065 -0.3048)
			(stroke
				(width 0.1)
				(type default)
			)
			(layer "F.Fab")
		)
		(fp_line
			(start -0.12065 -0.2794)
			(end 0.12065 -0.2794)
			(stroke
				(width 0.1)
				(type default)
			)
			(layer "F.Fab")
		)
		(fp_line
			(start 0.120396 0.2794)
			(end -0.12065 0.2794)
			(stroke
				(width 0.1)
				(type default)
			)
			(layer "F.Fab")
		)
		(fp_line
			(start -0.12065 0.2794)
			(end -0.12065 0.3048)
			(stroke
				(width 0.1)
				(type default)
			)
			(layer "F.Fab")
		)
		(fp_line
			(start 0.67945 0.3048)
			(end 0.120396 0.3048)
			(stroke
				(width 0.1)
				(type default)
			)
			(layer "F.Fab")
		)
		(fp_line
			(start 0.120396 0.3048)
			(end 0.120396 0.2794)
			(stroke
				(width 0.1)
				(type default)
			)
			(layer "F.Fab")
		)
		(fp_line
			(start -0.12065 0.3048)
			(end -0.67945 0.3048)
			(stroke
				(width 0.1)
				(type default)
			)
			(layer "F.Fab")
		)
		(fp_line
			(start -0.67945 0.3048)
			(end -0.67945 -0.305054)
			(stroke
				(width 0.1)
				(type default)
			)
			(layer "F.Fab")
		)
		(pad "1" smd circle
			(at -0.40005 0 90)
			(size 0 0)
			(layers "F.Cu" "F.Mask" "F.Paste")
			(net "LED_D22_R")
		)
		(pad "2" smd circle
			(at 0.40005 0 90)
			(size 0 0)
			(layers "F.Cu" "F.Mask" "F.Paste")
			(net "P5V_AUX")
		)
	)
	(footprint ""
		(layer "F.Cu")
		(at 72.644 -10.922 90)
		(property "Reference" "R471"
			(at 0 0 90)
			(layer "F.SilkS")
			(hide yes)
			(effects
				(font
					(size 1.27 1.27)
				)
			)
		)
		(property "Value" ""
			(at 0 0 90)
			(layer "F.Fab")
			(effects
				(font
					(size 1.27 1.27)
				)
			)
		)
		(duplicate_pad_numbers_are_jumpers no)
		(fp_line
			(start 0.7874 -0.4064)
			(end 0.7874 0.4064)
			(stroke
				(width 0.1524)
				(type default)
			)
			(layer "F.SilkS")
		)
		(fp_line
			(start -0.7874 -0.4064)
			(end 0.7874 -0.4064)
			(stroke
				(width 0.1524)
				(type default)
			)
			(layer "F.SilkS")
		)
		(fp_line
			(start 0.7874 0.4064)
			(end -0.7874 0.4064)
			(stroke
				(width 0.1524)
				(type default)
			)
			(layer "F.SilkS")
		)
		(fp_line
			(start -0.7874 0.4064)
			(end -0.7874 -0.4064)
			(stroke
				(width 0.1524)
				(type default)
			)
			(layer "F.SilkS")
		)
		(fp_line
			(start -0.12065 -0.305054)
			(end -0.12065 -0.2794)
			(stroke
				(width 0.1)
				(type default)
			)
			(layer "F.Fab")
		)
		(fp_line
			(start -0.67945 -0.305054)
			(end -0.12065 -0.305054)
			(stroke
				(width 0.1)
				(type default)
			)
			(layer "F.Fab")
		)
		(fp_line
			(start 0.67945 -0.3048)
			(end 0.67945 0.3048)
			(stroke
				(width 0.1)
				(type default)
			)
			(layer "F.Fab")
		)
		(fp_line
			(start 0.12065 -0.3048)
			(end 0.67945 -0.3048)
			(stroke
				(width 0.1)
				(type default)
			)
			(layer "F.Fab")
		)
		(fp_line
			(start 0.12065 -0.2794)
			(end 0.12065 -0.3048)
			(stroke
				(width 0.1)
				(type default)
			)
			(layer "F.Fab")
		)
		(fp_line
			(start -0.12065 -0.2794)
			(end 0.12065 -0.2794)
			(stroke
				(width 0.1)
				(type default)
			)
			(layer "F.Fab")
		)
		(fp_line
			(start 0.120396 0.2794)
			(end -0.12065 0.2794)
			(stroke
				(width 0.1)
				(type default)
			)
			(layer "F.Fab")
		)
		(fp_line
			(start -0.12065 0.2794)
			(end -0.12065 0.3048)
			(stroke
				(width 0.1)
				(type default)
			)
			(layer "F.Fab")
		)
		(fp_line
			(start 0.67945 0.3048)
			(end 0.120396 0.3048)
			(stroke
				(width 0.1)
				(type default)
			)
			(layer "F.Fab")
		)
		(fp_line
			(start 0.120396 0.3048)
			(end 0.120396 0.2794)
			(stroke
				(width 0.1)
				(type default)
			)
			(layer "F.Fab")
		)
		(fp_line
			(start -0.12065 0.3048)
			(end -0.67945 0.3048)
			(stroke
				(width 0.1)
				(type default)
			)
			(layer "F.Fab")
		)
		(fp_line
			(start -0.67945 0.3048)
			(end -0.67945 -0.305054)
			(stroke
				(width 0.1)
				(type default)
			)
			(layer "F.Fab")
		)
		(pad "1" smd circle
			(at -0.40005 0 90)
			(size 0 0)
			(layers "F.Cu" "F.Mask" "F.Paste")
			(net "REAR_AC_PWR_BTN")
		)
		(pad "2" smd circle
			(at 0.40005 0 90)
			(size 0 0)
			(layers "F.Cu" "F.Mask" "F.Paste")
			(net "AC_PWR_BTN_N")
		)
	)
	(footprint ""
		(layer "F.Cu")
		(at 73.152 -74.295 90)
		(property "Reference" "R431"
			(at 0 0 90)
			(layer "F.SilkS")
			(hide yes)
			(effects
				(font
					(size 1.27 1.27)
				)
			)
		)
		(property "Value" ""
			(at 0 0 90)
			(layer "F.Fab")
			(effects
				(font
					(size 1.27 1.27)
				)
			)
		)
		(duplicate_pad_numbers_are_jumpers no)
		(fp_line
			(start 0.7874 -0.4064)
			(end 0.7874 0.4064)
			(stroke
				(width 0.1524)
				(type default)
			)
			(layer "F.SilkS")
		)
		(fp_line
			(start -0.7874 -0.4064)
			(end 0.7874 -0.4064)
			(stroke
				(width 0.1524)
				(type default)
			)
			(layer "F.SilkS")
		)
		(fp_line
			(start 0.7874 0.4064)
			(end -0.7874 0.4064)
			(stroke
				(width 0.1524)
				(type default)
			)
			(layer "F.SilkS")
		)
		(fp_line
			(start -0.7874 0.4064)
			(end -0.7874 -0.4064)
			(stroke
				(width 0.1524)
				(type default)
			)
			(layer "F.SilkS")
		)
		(fp_line
			(start -0.12065 -0.305054)
			(end -0.12065 -0.2794)
			(stroke
				(width 0.1)
				(type default)
			)
			(layer "F.Fab")
		)
		(fp_line
			(start -0.67945 -0.305054)
			(end -0.12065 -0.305054)
			(stroke
				(width 0.1)
				(type default)
			)
			(layer "F.Fab")
		)
		(fp_line
			(start 0.67945 -0.3048)
			(end 0.67945 0.3048)
			(stroke
				(width 0.1)
				(type default)
			)
			(layer "F.Fab")
		)
		(fp_line
			(start 0.12065 -0.3048)
			(end 0.67945 -0.3048)
			(stroke
				(width 0.1)
				(type default)
			)
			(layer "F.Fab")
		)
		(fp_line
			(start 0.12065 -0.2794)
			(end 0.12065 -0.3048)
			(stroke
				(width 0.1)
				(type default)
			)
			(layer "F.Fab")
		)
		(fp_line
			(start -0.12065 -0.2794)
			(end 0.12065 -0.2794)
			(stroke
				(width 0.1)
				(type default)
			)
			(layer "F.Fab")
		)
		(fp_line
			(start 0.120396 0.2794)
			(end -0.12065 0.2794)
			(stroke
				(width 0.1)
				(type default)
			)
			(layer "F.Fab")
		)
		(fp_line
			(start -0.12065 0.2794)
			(end -0.12065 0.3048)
			(stroke
				(width 0.1)
				(type default)
			)
			(layer "F.Fab")
		)
		(fp_line
			(start 0.67945 0.3048)
			(end 0.120396 0.3048)
			(stroke
				(width 0.1)
				(type default)
			)
			(layer "F.Fab")
		)
		(fp_line
			(start 0.120396 0.3048)
			(end 0.120396 0.2794)
			(stroke
				(width 0.1)
				(type default)
			)
			(layer "F.Fab")
		)
		(fp_line
			(start -0.12065 0.3048)
			(end -0.67945 0.3048)
			(stroke
				(width 0.1)
				(type default)
			)
			(layer "F.Fab")
		)
		(fp_line
			(start -0.67945 0.3048)
			(end -0.67945 -0.305054)
			(stroke
				(width 0.1)
				(type default)
			)
			(layer "F.Fab")
		)
		(pad "1" smd circle
			(at -0.40005 0 90)
			(size 0 0)
			(layers "F.Cu" "F.Mask" "F.Paste")
			(net "FM_BMC_DISABLE")
		)
		(pad "2" smd circle
			(at 0.40005 0 90)
			(size 0 0)
			(layers "F.Cu" "F.Mask" "F.Paste")
			(net "GND")
		)
	)
	(footprint ""
		(layer "F.Cu")
		(at 31.115 -64.8208 -90)
		(property "Reference" "R530"
			(at 0 0 270)
			(layer "F.SilkS")
			(hide yes)
			(effects
				(font
					(size 1.27 1.27)
				)
			)
		)
		(property "Value" ""
			(at 0 0 270)
			(layer "F.Fab")
			(effects
				(font
					(size 1.27 1.27)
				)
			)
		)
		(duplicate_pad_numbers_are_jumpers no)
		(fp_line
			(start -0.7874 0.4064)
			(end -0.7874 -0.4064)
			(stroke
				(width 0.1524)
				(type default)
			)
			(layer "F.SilkS")
		)
		(fp_line
			(start 0.7874 0.4064)
			(end -0.7874 0.4064)
			(stroke
				(width 0.1524)
				(type default)
			)
			(layer "F.SilkS")
		)
		(fp_line
			(start -0.7874 -0.4064)
			(end 0.7874 -0.4064)
			(stroke
				(width 0.1524)
				(type default)
			)
			(layer "F.SilkS")
		)
		(fp_line
			(start 0.7874 -0.4064)
			(end 0.7874 0.4064)
			(stroke
				(width 0.1524)
				(type default)
			)
			(layer "F.SilkS")
		)
		(fp_line
			(start -0.67945 0.3048)
			(end -0.67945 -0.305054)
			(stroke
				(width 0.1)
				(type default)
			)
			(layer "F.Fab")
		)
		(fp_line
			(start -0.12065 0.3048)
			(end -0.67945 0.3048)
			(stroke
				(width 0.1)
				(type default)
			)
			(layer "F.Fab")
		)
		(fp_line
			(start 0.120396 0.3048)
			(end 0.120396 0.2794)
			(stroke
				(width 0.1)
				(type default)
			)
			(layer "F.Fab")
		)
		(fp_line
			(start 0.67945 0.3048)
			(end 0.120396 0.3048)
			(stroke
				(width 0.1)
				(type default)
			)
			(layer "F.Fab")
		)
		(fp_line
			(start -0.12065 0.2794)
			(end -0.12065 0.3048)
			(stroke
				(width 0.1)
				(type default)
			)
			(layer "F.Fab")
		)
		(fp_line
			(start 0.120396 0.2794)
			(end -0.12065 0.2794)
			(stroke
				(width 0.1)
				(type default)
			)
			(layer "F.Fab")
		)
		(fp_line
			(start -0.12065 -0.2794)
			(end 0.12065 -0.2794)
			(stroke
				(width 0.1)
				(type default)
			)
			(layer "F.Fab")
		)
		(fp_line
			(start 0.12065 -0.2794)
			(end 0.12065 -0.3048)
			(stroke
				(width 0.1)
				(type default)
			)
			(layer "F.Fab")
		)
		(fp_line
			(start 0.12065 -0.3048)
			(end 0.67945 -0.3048)
			(stroke
				(width 0.1)
				(type default)
			)
			(layer "F.Fab")
		)
		(fp_line
			(start 0.67945 -0.3048)
			(end 0.67945 0.3048)
			(stroke
				(width 0.1)
				(type default)
			)
			(layer "F.Fab")
		)
		(fp_line
			(start -0.67945 -0.305054)
			(end -0.12065 -0.305054)
			(stroke
				(width 0.1)
				(type default)
			)
			(layer "F.Fab")
		)
		(fp_line
			(start -0.12065 -0.305054)
			(end -0.12065 -0.2794)
			(stroke
				(width 0.1)
				(type default)
			)
			(layer "F.Fab")
		)
		(pad "1" smd circle
			(at -0.40005 0 270)
			(size 0 0)
			(layers "F.Cu" "F.Mask" "F.Paste")
			(net "PWRGD_P3V3_RGM")
		)
		(pad "2" smd circle
			(at 0.40005 0 270)
			(size 0 0)
			(layers "F.Cu" "F.Mask" "F.Paste")
			(net "PWRGD_P3V3_RGM_R2")
		)
	)
	(footprint ""
		(layer "F.Cu")
		(at 20.0025 -105.9942 180)
		(property "Reference" "U12"
			(at -1.1303 2.28473 0)
			(unlocked yes)
			(layer "F.SilkS")
			(effects
				(font
					(size 0.7874 0.5842)
					(thickness 0.1524)
				)
			)
		)
		(property "Value" ""
			(at 0 0 180)
			(layer "F.Fab")
			(effects
				(font
					(size 1.27 1.27)
				)
			)
		)
		(duplicate_pad_numbers_are_jumpers no)
		(fp_line
			(start 1.949958 1.610106)
			(end -1.949958 1.610106)
			(stroke
				(width 0.1524)
				(type default)
			)
			(layer "F.SilkS")
		)
		(fp_line
			(start 1.949958 -1.560068)
			(end 1.949958 1.610106)
			(stroke
				(width 0.1524)
				(type default)
			)
			(layer "F.SilkS")
		)
		(fp_line
			(start -1.949958 1.610106)
			(end -1.949958 -1.610106)
			(stroke
				(width 0.1524)
				(type default)
			)
			(layer "F.SilkS")
		)
		(fp_line
			(start -1.949958 -1.610106)
			(end 1.949958 -1.610106)
			(stroke
				(width 0.1524)
				(type default)
			)
			(layer "F.SilkS")
		)
		(fp_line
			(start 0.750062 1.560068)
			(end -0.750062 1.560068)
			(stroke
				(width 0.1)
				(type default)
			)
			(layer "F.Fab")
		)
		(fp_line
			(start 0.750062 -1.560068)
			(end 0.750062 1.560068)
			(stroke
				(width 0.1)
				(type default)
			)
			(layer "F.Fab")
		)
		(fp_line
			(start -0.750062 1.560068)
			(end -0.750062 -1.560068)
			(stroke
				(width 0.1)
				(type default)
			)
			(layer "F.Fab")
		)
		(fp_line
			(start -0.750062 -1.560068)
			(end 0.750062 -1.560068)
			(stroke
				(width 0.1)
				(type default)
			)
			(layer "F.Fab")
		)
		(pad "D" smd rect
			(at 1.100074 0 90)
			(size 1.016 1.4224)
			(layers "F.Cu" "F.Mask" "F.Paste")
			(net "RST_BMC_EXTRST_R1_N")
		)
		(pad "G" smd rect
			(at -1.100074 -0.94996 90)
			(size 1.016 1.4224)
			(layers "F.Cu" "F.Mask" "F.Paste")
			(net "RST_BMC_SELF_HW_D_C")
		)
		(pad "S" smd rect
			(at -1.100074 0.94996 90)
			(size 1.016 1.4224)
			(layers "F.Cu" "F.Mask" "F.Paste")
			(net "GND")
		)
	)
	(footprint ""
		(layer "F.Cu")
		(at 13.262864 -8.857742)
		(property "Reference" "R734"
			(at 0 0 0)
			(layer "F.SilkS")
			(hide yes)
			(effects
				(font
					(size 1.27 1.27)
				)
			)
		)
		(property "Value" ""
			(at 0 0 0)
			(layer "F.Fab")
			(effects
				(font
					(size 1.27 1.27)
				)
			)
		)
		(duplicate_pad_numbers_are_jumpers no)
		(fp_line
			(start -0.7874 -0.4064)
			(end 0.7874 -0.4064)
			(stroke
				(width 0.1524)
				(type default)
			)
			(layer "F.SilkS")
		)
		(fp_line
			(start -0.7874 0.4064)
			(end -0.7874 -0.4064)
			(stroke
				(width 0.1524)
				(type default)
			)
			(layer "F.SilkS")
		)
		(fp_line
			(start 0.7874 -0.4064)
			(end 0.7874 0.4064)
			(stroke
				(width 0.1524)
				(type default)
			)
			(layer "F.SilkS")
		)
		(fp_line
			(start 0.7874 0.4064)
			(end -0.7874 0.4064)
			(stroke
				(width 0.1524)
				(type default)
			)
			(layer "F.SilkS")
		)
		(fp_line
			(start -0.67945 -0.305054)
			(end -0.12065 -0.305054)
			(stroke
				(width 0.1)
				(type default)
			)
			(layer "F.Fab")
		)
		(fp_line
			(start -0.67945 0.3048)
			(end -0.67945 -0.305054)
			(stroke
				(width 0.1)
				(type default)
			)
			(layer "F.Fab")
		)
		(fp_line
			(start -0.12065 -0.305054)
			(end -0.12065 -0.2794)
			(stroke
				(width 0.1)
				(type default)
			)
			(layer "F.Fab")
		)
		(fp_line
			(start -0.12065 -0.2794)
			(end 0.12065 -0.2794)
			(stroke
				(width 0.1)
				(type default)
			)
			(layer "F.Fab")
		)
		(fp_line
			(start -0.12065 0.2794)
			(end -0.12065 0.3048)
			(stroke
				(width 0.1)
				(type default)
			)
			(layer "F.Fab")
		)
		(fp_line
			(start -0.12065 0.3048)
			(end -0.67945 0.3048)
			(stroke
				(width 0.1)
				(type default)
			)
			(layer "F.Fab")
		)
		(fp_line
			(start 0.120396 0.2794)
			(end -0.12065 0.2794)
			(stroke
				(width 0.1)
				(type default)
			)
			(layer "F.Fab")
		)
		(fp_line
			(start 0.120396 0.3048)
			(end 0.120396 0.2794)
			(stroke
				(width 0.1)
				(type default)
			)
			(layer "F.Fab")
		)
		(fp_line
			(start 0.12065 -0.3048)
			(end 0.67945 -0.3048)
			(stroke
				(width 0.1)
				(type default)
			)
			(layer "F.Fab")
		)
		(fp_line
			(start 0.12065 -0.2794)
			(end 0.12065 -0.3048)
			(stroke
				(width 0.1)
				(type default)
			)
			(layer "F.Fab")
		)
		(fp_line
			(start 0.67945 -0.3048)
			(end 0.67945 0.3048)
			(stroke
				(width 0.1)
				(type default)
			)
			(layer "F.Fab")
		)
		(fp_line
			(start 0.67945 0.3048)
			(end 0.120396 0.3048)
			(stroke
				(width 0.1)
				(type default)
			)
			(layer "F.Fab")
		)
		(pad "1" smd circle
			(at -0.40005 0)
			(size 0 0)
			(layers "F.Cu" "F.Mask" "F.Paste")
			(net "REAR_PWR_BTN_N")
		)
		(pad "2" smd circle
			(at 0.40005 0)
			(size 0 0)
			(layers "F.Cu" "F.Mask" "F.Paste")
			(net "FM_DEBUG_PWR_BTN_N")
		)
	)
	(footprint ""
		(layer "F.Cu")
		(at 22.225 -68.834 -90)
		(property "Reference" "R562"
			(at 0 0 270)
			(layer "F.SilkS")
			(hide yes)
			(effects
				(font
					(size 1.27 1.27)
				)
			)
		)
		(property "Value" ""
			(at 0 0 270)
			(layer "F.Fab")
			(effects
				(font
					(size 1.27 1.27)
				)
			)
		)
		(duplicate_pad_numbers_are_jumpers no)
		(fp_line
			(start -0.7874 0.4064)
			(end -0.7874 -0.4064)
			(stroke
				(width 0.1524)
				(type default)
			)
			(layer "F.SilkS")
		)
		(fp_line
			(start 0.7874 0.4064)
			(end -0.7874 0.4064)
			(stroke
				(width 0.1524)
				(type default)
			)
			(layer "F.SilkS")
		)
		(fp_line
			(start -0.7874 -0.4064)
			(end 0.7874 -0.4064)
			(stroke
				(width 0.1524)
				(type default)
			)
			(layer "F.SilkS")
		)
		(fp_line
			(start 0.7874 -0.4064)
			(end 0.7874 0.4064)
			(stroke
				(width 0.1524)
				(type default)
			)
			(layer "F.SilkS")
		)
		(fp_line
			(start -0.67945 0.3048)
			(end -0.67945 -0.305054)
			(stroke
				(width 0.1)
				(type default)
			)
			(layer "F.Fab")
		)
		(fp_line
			(start -0.12065 0.3048)
			(end -0.67945 0.3048)
			(stroke
				(width 0.1)
				(type default)
			)
			(layer "F.Fab")
		)
		(fp_line
			(start 0.120396 0.3048)
			(end 0.120396 0.2794)
			(stroke
				(width 0.1)
				(type default)
			)
			(layer "F.Fab")
		)
		(fp_line
			(start 0.67945 0.3048)
			(end 0.120396 0.3048)
			(stroke
				(width 0.1)
				(type default)
			)
			(layer "F.Fab")
		)
		(fp_line
			(start -0.12065 0.2794)
			(end -0.12065 0.3048)
			(stroke
				(width 0.1)
				(type default)
			)
			(layer "F.Fab")
		)
		(fp_line
			(start 0.120396 0.2794)
			(end -0.12065 0.2794)
			(stroke
				(width 0.1)
				(type default)
			)
			(layer "F.Fab")
		)
		(fp_line
			(start -0.12065 -0.2794)
			(end 0.12065 -0.2794)
			(stroke
				(width 0.1)
				(type default)
			)
			(layer "F.Fab")
		)
		(fp_line
			(start 0.12065 -0.2794)
			(end 0.12065 -0.3048)
			(stroke
				(width 0.1)
				(type default)
			)
			(layer "F.Fab")
		)
		(fp_line
			(start 0.12065 -0.3048)
			(end 0.67945 -0.3048)
			(stroke
				(width 0.1)
				(type default)
			)
			(layer "F.Fab")
		)
		(fp_line
			(start 0.67945 -0.3048)
			(end 0.67945 0.3048)
			(stroke
				(width 0.1)
				(type default)
			)
			(layer "F.Fab")
		)
		(fp_line
			(start -0.67945 -0.305054)
			(end -0.12065 -0.305054)
			(stroke
				(width 0.1)
				(type default)
			)
			(layer "F.Fab")
		)
		(fp_line
			(start -0.12065 -0.305054)
			(end -0.12065 -0.2794)
			(stroke
				(width 0.1)
				(type default)
			)
			(layer "F.Fab")
		)
		(pad "1" smd circle
			(at -0.40005 0 270)
			(size 0 0)
			(layers "F.Cu" "F.Mask" "F.Paste")
			(net "RST_SPI_BMC_FLASH_R1_N")
		)
		(pad "2" smd circle
			(at 0.40005 0 270)
			(size 0 0)
			(layers "F.Cu" "F.Mask" "F.Paste")
			(net "RST_SPI_FLASH_BUF_N")
		)
	)
	(footprint ""
		(layer "F.Cu")
		(at 114.554 82.1436 -90)
		(property "Reference" "X23"
			(at -1.96723 3.1115 0)
			(unlocked yes)
			(layer "F.SilkS")
			(effects
				(font
					(size 0.7874 0.5842)
					(thickness 0.1524)
				)
				(justify left)
			)
		)
		(property "Value" ""
			(at 0 0 270)
			(layer "F.Fab")
			(effects
				(font
					(size 1.27 1.27)
				)
			)
		)
		(property "Device Type" "TP_TDR_4P_FTS_TH-TP_TDR_4P_DIPA"
			(at 1.30175 1.27 0)
			(unlocked yes)
			(layer "F.Fab")
			(hide yes)
			(effects
				(font
					(size 0.635 0.4064)
					(thickness 0.1524)
				)
			)
		)
		(property "User Part Number" "N_A"
			(at 1.30175 1.27 0)
			(unlocked yes)
			(layer "Cmts.User")
			(hide yes)
			(effects
				(font
					(size 0.635 0.4064)
					(thickness 0.1524)
				)
			)
		)
		(duplicate_pad_numbers_are_jumpers no)
		(fp_line
			(start 0 3.81)
			(end 2.54 3.81)
			(stroke
				(width 0.1524)
				(type default)
			)
			(layer "F.SilkS")
		)
		(fp_line
			(start 2.54 3.81)
			(end 2.54 3.6703)
			(stroke
				(width 0.1524)
				(type default)
			)
			(layer "F.SilkS")
		)
		(fp_line
			(start 0 3.175)
			(end 0 3.81)
			(stroke
				(width 0.1524)
				(type default)
			)
			(layer "F.SilkS")
		)
		(fp_line
			(start 2.54 1.4097)
			(end 2.54 1.1303)
			(stroke
				(width 0.1524)
				(type default)
			)
			(layer "F.SilkS")
		)
		(fp_line
			(start 0 0.635)
			(end 0 1.905)
			(stroke
				(width 0.1524)
				(type default)
			)
			(layer "F.SilkS")
		)
		(fp_line
			(start 2.54 -1.1303)
			(end 2.54 -1.27)
			(stroke
				(width 0.1524)
				(type default)
			)
			(layer "F.SilkS")
		)
		(fp_line
			(start 0 -1.27)
			(end 0 -0.635)
			(stroke
				(width 0.1524)
				(type default)
			)
			(layer "F.SilkS")
		)
		(fp_line
			(start 2.54 -1.27)
			(end 0 -1.27)
			(stroke
				(width 0.1524)
				(type default)
			)
			(layer "F.SilkS")
		)
		(fp_poly
			(pts
				(xy -0.761746 0) (xy -2.285746 -0.762) (xy -2.285746 0.762)
			)
			(stroke
				(width 0)
				(type default)
			)
			(fill yes)
			(layer "F.SilkS")
		)
		(fp_line
			(start 0 3.81)
			(end 2.54 3.81)
			(stroke
				(width 0.1)
				(type default)
			)
			(layer "F.Fab")
		)
		(fp_line
			(start 2.54 3.81)
			(end 2.54 -1.27)
			(stroke
				(width 0.1)
				(type default)
			)
			(layer "F.Fab")
		)
		(fp_line
			(start 0 -1.27)
			(end 0 3.81)
			(stroke
				(width 0.1)
				(type default)
			)
			(layer "F.Fab")
		)
		(fp_line
			(start 2.54 -1.27)
			(end 0 -1.27)
			(stroke
				(width 0.1)
				(type default)
			)
			(layer "F.Fab")
		)
		(fp_poly
			(pts
				(xy -0.761746 0) (xy -2.285746 -0.762) (xy -2.285746 0.762)
			)
			(stroke
				(width 0)
				(type default)
			)
			(fill yes)
			(layer "F.Fab")
		)
		(pad "1" thru_hole circle
			(at 0 0 270)
			(size 1.0033 1.0033)
			(drill 0.249936)
			(layers "*.Cu" "*.Mask")
			(remove_unused_layers no)
			(net "TDR_DIFF_100_IN4_DN")
			(clearance 0.10795)
			(thermal_gap 0.10795)
			(padstack
				(mode front_inner_back)
				(layer "Inner"
					(shape circle)
					(size 0.8001 0.8001)
					(clearance 0.1524)
				)
				(layer "B.Cu"
					(shape circle)
					(size 1.0033 1.0033)
					(clearance 0.10795)
				)
			)
		)
		(pad "2" thru_hole circle
			(at 2.54 0 270)
			(size 1.9939 1.9939)
			(drill 0.249936)
			(layers "*.Cu" "*.Mask")
			(remove_unused_layers no)
			(net "GND_P1")
			(clearance 0.10795)
			(thermal_gap 0.10795)
			(padstack
				(mode front_inner_back)
				(layer "Inner"
					(shape circle)
					(size 0.8001 0.8001)
					(clearance 0.1524)
				)
				(layer "B.Cu"
					(shape circle)
					(size 1.9939 1.9939)
					(clearance 0.10795)
				)
			)
		)
		(pad "3" thru_hole circle
			(at 2.54 2.54 270)
			(size 1.9939 1.9939)
			(drill 0.249936)
			(layers "*.Cu" "*.Mask")
			(remove_unused_layers no)
			(net "GND_P1")
			(clearance 0.10795)
			(thermal_gap 0.10795)
			(padstack
				(mode front_inner_back)
				(layer "Inner"
					(shape circle)
					(size 0.8001 0.8001)
					(clearance 0.1524)
				)
				(layer "B.Cu"
					(shape circle)
					(size 1.9939 1.9939)
					(clearance 0.10795)
				)
			)
		)
		(pad "4" thru_hole circle
			(at 0 2.54 270)
			(size 1.0033 1.0033)
			(drill 0.249936)
			(layers "*.Cu" "*.Mask")
			(remove_unused_layers no)
			(net "TDR_DIFF_100_IN4_DP")
			(clearance 0.10795)
			(thermal_gap 0.10795)
			(padstack
				(mode front_inner_back)
				(layer "Inner"
					(shape circle)
					(size 0.8001 0.8001)
					(clearance 0.1524)
				)
				(layer "B.Cu"
					(shape circle)
					(size 1.0033 1.0033)
					(clearance 0.10795)
				)
			)
		)
	)
	(footprint ""
		(layer "F.Cu")
		(at 12.319 -82.296 180)
		(property "Reference" "R437"
			(at 0 0 180)
			(layer "F.SilkS")
			(hide yes)
			(effects
				(font
					(size 1.27 1.27)
				)
			)
		)
		(property "Value" ""
			(at 0 0 180)
			(layer "F.Fab")
			(effects
				(font
					(size 1.27 1.27)
				)
			)
		)
		(duplicate_pad_numbers_are_jumpers no)
		(fp_line
			(start 0.7874 0.4064)
			(end -0.7874 0.4064)
			(stroke
				(width 0.1524)
				(type default)
			)
			(layer "F.SilkS")
		)
		(fp_line
			(start 0.7874 -0.4064)
			(end 0.7874 0.4064)
			(stroke
				(width 0.1524)
				(type default)
			)
			(layer "F.SilkS")
		)
		(fp_line
			(start -0.7874 0.4064)
			(end -0.7874 -0.4064)
			(stroke
				(width 0.1524)
				(type default)
			)
			(layer "F.SilkS")
		)
		(fp_line
			(start -0.7874 -0.4064)
			(end 0.7874 -0.4064)
			(stroke
				(width 0.1524)
				(type default)
			)
			(layer "F.SilkS")
		)
		(fp_line
			(start 0.67945 0.3048)
			(end 0.120396 0.3048)
			(stroke
				(width 0.1)
				(type default)
			)
			(layer "F.Fab")
		)
		(fp_line
			(start 0.67945 -0.3048)
			(end 0.67945 0.3048)
			(stroke
				(width 0.1)
				(type default)
			)
			(layer "F.Fab")
		)
		(fp_line
			(start 0.12065 -0.2794)
			(end 0.12065 -0.3048)
			(stroke
				(width 0.1)
				(type default)
			)
			(layer "F.Fab")
		)
		(fp_line
			(start 0.12065 -0.3048)
			(end 0.67945 -0.3048)
			(stroke
				(width 0.1)
				(type default)
			)
			(layer "F.Fab")
		)
		(fp_line
			(start 0.120396 0.3048)
			(end 0.120396 0.2794)
			(stroke
				(width 0.1)
				(type default)
			)
			(layer "F.Fab")
		)
		(fp_line
			(start 0.120396 0.2794)
			(end -0.12065 0.2794)
			(stroke
				(width 0.1)
				(type default)
			)
			(layer "F.Fab")
		)
		(fp_line
			(start -0.12065 0.3048)
			(end -0.67945 0.3048)
			(stroke
				(width 0.1)
				(type default)
			)
			(layer "F.Fab")
		)
		(fp_line
			(start -0.12065 0.2794)
			(end -0.12065 0.3048)
			(stroke
				(width 0.1)
				(type default)
			)
			(layer "F.Fab")
		)
		(fp_line
			(start -0.12065 -0.2794)
			(end 0.12065 -0.2794)
			(stroke
				(width 0.1)
				(type default)
			)
			(layer "F.Fab")
		)
		(fp_line
			(start -0.12065 -0.305054)
			(end -0.12065 -0.2794)
			(stroke
				(width 0.1)
				(type default)
			)
			(layer "F.Fab")
		)
		(fp_line
			(start -0.67945 0.3048)
			(end -0.67945 -0.305054)
			(stroke
				(width 0.1)
				(type default)
			)
			(layer "F.Fab")
		)
		(fp_line
			(start -0.67945 -0.305054)
			(end -0.12065 -0.305054)
			(stroke
				(width 0.1)
				(type default)
			)
			(layer "F.Fab")
		)
		(pad "1" smd circle
			(at -0.40005 0 180)
			(size 0 0)
			(layers "F.Cu" "F.Mask" "F.Paste")
			(net "SGPIO_PLD_DI_0")
		)
		(pad "2" smd circle
			(at 0.40005 0 180)
			(size 0 0)
			(layers "F.Cu" "F.Mask" "F.Paste")
			(net "SGPIO_DI_0")
		)
	)
	(footprint ""
		(layer "F.Cu")
		(at 13.5636 -56.0324)
		(property "Reference" "R529"
			(at 0 0 0)
			(layer "F.SilkS")
			(hide yes)
			(effects
				(font
					(size 1.27 1.27)
				)
			)
		)
		(property "Value" ""
			(at 0 0 0)
			(layer "F.Fab")
			(effects
				(font
					(size 1.27 1.27)
				)
			)
		)
		(duplicate_pad_numbers_are_jumpers no)
		(fp_line
			(start -0.7874 -0.4064)
			(end 0.7874 -0.4064)
			(stroke
				(width 0.1524)
				(type default)
			)
			(layer "F.SilkS")
		)
		(fp_line
			(start -0.7874 0.4064)
			(end -0.7874 -0.4064)
			(stroke
				(width 0.1524)
				(type default)
			)
			(layer "F.SilkS")
		)
		(fp_line
			(start 0.7874 -0.4064)
			(end 0.7874 0.4064)
			(stroke
				(width 0.1524)
				(type default)
			)
			(layer "F.SilkS")
		)
		(fp_line
			(start 0.7874 0.4064)
			(end -0.7874 0.4064)
			(stroke
				(width 0.1524)
				(type default)
			)
			(layer "F.SilkS")
		)
		(fp_line
			(start -0.67945 -0.305054)
			(end -0.12065 -0.305054)
			(stroke
				(width 0.1)
				(type default)
			)
			(layer "F.Fab")
		)
		(fp_line
			(start -0.67945 0.3048)
			(end -0.67945 -0.305054)
			(stroke
				(width 0.1)
				(type default)
			)
			(layer "F.Fab")
		)
		(fp_line
			(start -0.12065 -0.305054)
			(end -0.12065 -0.2794)
			(stroke
				(width 0.1)
				(type default)
			)
			(layer "F.Fab")
		)
		(fp_line
			(start -0.12065 -0.2794)
			(end 0.12065 -0.2794)
			(stroke
				(width 0.1)
				(type default)
			)
			(layer "F.Fab")
		)
		(fp_line
			(start -0.12065 0.2794)
			(end -0.12065 0.3048)
			(stroke
				(width 0.1)
				(type default)
			)
			(layer "F.Fab")
		)
		(fp_line
			(start -0.12065 0.3048)
			(end -0.67945 0.3048)
			(stroke
				(width 0.1)
				(type default)
			)
			(layer "F.Fab")
		)
		(fp_line
			(start 0.120396 0.2794)
			(end -0.12065 0.2794)
			(stroke
				(width 0.1)
				(type default)
			)
			(layer "F.Fab")
		)
		(fp_line
			(start 0.120396 0.3048)
			(end 0.120396 0.2794)
			(stroke
				(width 0.1)
				(type default)
			)
			(layer "F.Fab")
		)
		(fp_line
			(start 0.12065 -0.3048)
			(end 0.67945 -0.3048)
			(stroke
				(width 0.1)
				(type default)
			)
			(layer "F.Fab")
		)
		(fp_line
			(start 0.12065 -0.2794)
			(end 0.12065 -0.3048)
			(stroke
				(width 0.1)
				(type default)
			)
			(layer "F.Fab")
		)
		(fp_line
			(start 0.67945 -0.3048)
			(end 0.67945 0.3048)
			(stroke
				(width 0.1)
				(type default)
			)
			(layer "F.Fab")
		)
		(fp_line
			(start 0.67945 0.3048)
			(end 0.120396 0.3048)
			(stroke
				(width 0.1)
				(type default)
			)
			(layer "F.Fab")
		)
		(pad "1" smd circle
			(at -0.40005 0)
			(size 0 0)
			(layers "F.Cu" "F.Mask" "F.Paste")
			(net "PWRGD_P1V8_AUX")
		)
		(pad "2" smd circle
			(at 0.40005 0)
			(size 0 0)
			(layers "F.Cu" "F.Mask" "F.Paste")
			(net "PWRGD_P1V8_AUX_R2")
		)
	)
	(footprint ""
		(layer "F.Cu")
		(at 85.654642 -58.942478 -90)
		(property "Reference" "PC255"
			(at 0 0 270)
			(layer "F.SilkS")
			(hide yes)
			(effects
				(font
					(size 1.27 1.27)
				)
			)
		)
		(property "Value" ""
			(at 0 0 270)
			(layer "F.Fab")
			(effects
				(font
					(size 1.27 1.27)
				)
			)
		)
		(duplicate_pad_numbers_are_jumpers no)
		(fp_line
			(start -0.7874 0.4064)
			(end -0.7874 -0.4064)
			(stroke
				(width 0.1524)
				(type default)
			)
			(layer "F.SilkS")
		)
		(fp_line
			(start 0.7874 0.4064)
			(end -0.7874 0.4064)
			(stroke
				(width 0.1524)
				(type default)
			)
			(layer "F.SilkS")
		)
		(fp_line
			(start -0.7874 -0.4064)
			(end 0.7874 -0.4064)
			(stroke
				(width 0.1524)
				(type default)
			)
			(layer "F.SilkS")
		)
		(fp_line
			(start 0.7874 -0.4064)
			(end 0.7874 0.4064)
			(stroke
				(width 0.1524)
				(type default)
			)
			(layer "F.SilkS")
		)
		(fp_line
			(start -0.67945 0.3048)
			(end -0.67945 -0.305054)
			(stroke
				(width 0.1)
				(type default)
			)
			(layer "F.Fab")
		)
		(fp_line
			(start -0.12065 0.3048)
			(end -0.67945 0.3048)
			(stroke
				(width 0.1)
				(type default)
			)
			(layer "F.Fab")
		)
		(fp_line
			(start 0.120396 0.3048)
			(end 0.120396 0.2794)
			(stroke
				(width 0.1)
				(type default)
			)
			(layer "F.Fab")
		)
		(fp_line
			(start 0.67945 0.3048)
			(end 0.120396 0.3048)
			(stroke
				(width 0.1)
				(type default)
			)
			(layer "F.Fab")
		)
		(fp_line
			(start -0.12065 0.2794)
			(end -0.12065 0.3048)
			(stroke
				(width 0.1)
				(type default)
			)
			(layer "F.Fab")
		)
		(fp_line
			(start 0.120396 0.2794)
			(end -0.12065 0.2794)
			(stroke
				(width 0.1)
				(type default)
			)
			(layer "F.Fab")
		)
		(fp_line
			(start -0.12065 -0.2794)
			(end 0.12065 -0.2794)
			(stroke
				(width 0.1)
				(type default)
			)
			(layer "F.Fab")
		)
		(fp_line
			(start 0.12065 -0.2794)
			(end 0.12065 -0.3048)
			(stroke
				(width 0.1)
				(type default)
			)
			(layer "F.Fab")
		)
		(fp_line
			(start 0.12065 -0.3048)
			(end 0.67945 -0.3048)
			(stroke
				(width 0.1)
				(type default)
			)
			(layer "F.Fab")
		)
		(fp_line
			(start 0.67945 -0.3048)
			(end 0.67945 0.3048)
			(stroke
				(width 0.1)
				(type default)
			)
			(layer "F.Fab")
		)
		(fp_line
			(start -0.67945 -0.305054)
			(end -0.12065 -0.305054)
			(stroke
				(width 0.1)
				(type default)
			)
			(layer "F.Fab")
		)
		(fp_line
			(start -0.12065 -0.305054)
			(end -0.12065 -0.2794)
			(stroke
				(width 0.1)
				(type default)
			)
			(layer "F.Fab")
		)
		(pad "1" smd circle
			(at -0.40005 0 270)
			(size 0 0)
			(layers "F.Cu" "F.Mask" "F.Paste")
			(net "P1V2_AUX")
		)
		(pad "2" smd circle
			(at 0.40005 0 270)
			(size 0 0)
			(layers "F.Cu" "F.Mask" "F.Paste")
			(net "GND")
		)
	)
	(footprint ""
		(layer "F.Cu")
		(at 80.755744 -37.559488 90)
		(property "Reference" "C18"
			(at 0 0 90)
			(layer "F.SilkS")
			(hide yes)
			(effects
				(font
					(size 1.27 1.27)
				)
			)
		)
		(property "Value" ""
			(at 0 0 90)
			(layer "F.Fab")
			(effects
				(font
					(size 1.27 1.27)
				)
			)
		)
		(duplicate_pad_numbers_are_jumpers no)
		(fp_line
			(start 0.7874 -0.4064)
			(end 0.7874 0.4064)
			(stroke
				(width 0.1524)
				(type default)
			)
			(layer "F.SilkS")
		)
		(fp_line
			(start -0.7874 -0.4064)
			(end 0.7874 -0.4064)
			(stroke
				(width 0.1524)
				(type default)
			)
			(layer "F.SilkS")
		)
		(fp_line
			(start 0.7874 0.4064)
			(end -0.7874 0.4064)
			(stroke
				(width 0.1524)
				(type default)
			)
			(layer "F.SilkS")
		)
		(fp_line
			(start -0.7874 0.4064)
			(end -0.7874 -0.4064)
			(stroke
				(width 0.1524)
				(type default)
			)
			(layer "F.SilkS")
		)
		(fp_line
			(start -0.12065 -0.305054)
			(end -0.12065 -0.2794)
			(stroke
				(width 0.1)
				(type default)
			)
			(layer "F.Fab")
		)
		(fp_line
			(start -0.67945 -0.305054)
			(end -0.12065 -0.305054)
			(stroke
				(width 0.1)
				(type default)
			)
			(layer "F.Fab")
		)
		(fp_line
			(start 0.67945 -0.3048)
			(end 0.67945 0.3048)
			(stroke
				(width 0.1)
				(type default)
			)
			(layer "F.Fab")
		)
		(fp_line
			(start 0.12065 -0.3048)
			(end 0.67945 -0.3048)
			(stroke
				(width 0.1)
				(type default)
			)
			(layer "F.Fab")
		)
		(fp_line
			(start 0.12065 -0.2794)
			(end 0.12065 -0.3048)
			(stroke
				(width 0.1)
				(type default)
			)
			(layer "F.Fab")
		)
		(fp_line
			(start -0.12065 -0.2794)
			(end 0.12065 -0.2794)
			(stroke
				(width 0.1)
				(type default)
			)
			(layer "F.Fab")
		)
		(fp_line
			(start 0.120396 0.2794)
			(end -0.12065 0.2794)
			(stroke
				(width 0.1)
				(type default)
			)
			(layer "F.Fab")
		)
		(fp_line
			(start -0.12065 0.2794)
			(end -0.12065 0.3048)
			(stroke
				(width 0.1)
				(type default)
			)
			(layer "F.Fab")
		)
		(fp_line
			(start 0.67945 0.3048)
			(end 0.120396 0.3048)
			(stroke
				(width 0.1)
				(type default)
			)
			(layer "F.Fab")
		)
		(fp_line
			(start 0.120396 0.3048)
			(end 0.120396 0.2794)
			(stroke
				(width 0.1)
				(type default)
			)
			(layer "F.Fab")
		)
		(fp_line
			(start -0.12065 0.3048)
			(end -0.67945 0.3048)
			(stroke
				(width 0.1)
				(type default)
			)
			(layer "F.Fab")
		)
		(fp_line
			(start -0.67945 0.3048)
			(end -0.67945 -0.305054)
			(stroke
				(width 0.1)
				(type default)
			)
			(layer "F.Fab")
		)
		(pad "1" smd circle
			(at -0.40005 0 90)
			(size 0 0)
			(layers "F.Cu" "F.Mask" "F.Paste")
			(net "P1V2_AUX")
		)
		(pad "2" smd circle
			(at 0.40005 0 90)
			(size 0 0)
			(layers "F.Cu" "F.Mask" "F.Paste")
			(net "GND")
		)
	)
	(footprint ""
		(layer "F.Cu")
		(at 15.748 -36.7792 -90)
		(property "Reference" "U53"
			(at 3.17627 1.397 0)
			(unlocked yes)
			(layer "F.SilkS")
			(effects
				(font
					(size 0.7874 0.5842)
					(thickness 0.1524)
				)
			)
		)
		(property "Value" ""
			(at 0 0 270)
			(layer "F.Fab")
			(effects
				(font
					(size 1.27 1.27)
				)
			)
		)
		(duplicate_pad_numbers_are_jumpers no)
		(fp_line
			(start -1.7018 1.1176)
			(end -1.7018 -1.1176)
			(stroke
				(width 0.1524)
				(type default)
			)
			(layer "F.SilkS")
		)
		(fp_line
			(start 1.7018 1.1176)
			(end -1.7018 1.1176)
			(stroke
				(width 0.1524)
				(type default)
			)
			(layer "F.SilkS")
		)
		(fp_line
			(start 0 -0.7112)
			(end -0.254 -1.1176)
			(stroke
				(width 0.1524)
				(type default)
			)
			(layer "F.SilkS")
		)
		(fp_line
			(start -0.254 -1.1176)
			(end -1.7018 -1.1176)
			(stroke
				(width 0.1524)
				(type default)
			)
			(layer "F.SilkS")
		)
		(fp_line
			(start 0.254 -1.1176)
			(end 0 -0.7112)
			(stroke
				(width 0.1524)
				(type default)
			)
			(layer "F.SilkS")
		)
		(fp_line
			(start 1.7018 -1.1176)
			(end 1.7018 1.1176)
			(stroke
				(width 0.1524)
				(type default)
			)
			(layer "F.SilkS")
		)
		(fp_line
			(start 1.7018 -1.1176)
			(end 0.254 -1.1176)
			(stroke
				(width 0.1524)
				(type default)
			)
			(layer "F.SilkS")
		)
		(fp_poly
			(pts
				(xy -1.8161 -0.675386) (xy -2.4003 -0.446786) (xy -2.4003 -0.878586)
			)
			(stroke
				(width 0)
				(type default)
			)
			(fill yes)
			(layer "F.SilkS")
		)
		(fp_line
			(start -1.5494 1.1176)
			(end -1.5494 -1.1176)
			(stroke
				(width 0.1)
				(type default)
			)
			(layer "F.Fab")
		)
		(fp_line
			(start 1.5494 1.1176)
			(end -1.5494 1.1176)
			(stroke
				(width 0.1)
				(type default)
			)
			(layer "F.Fab")
		)
		(fp_line
			(start -0.254 -1.1176)
			(end -1.5494 -1.1176)
			(stroke
				(width 0.1)
				(type default)
			)
			(layer "F.Fab")
		)
		(fp_line
			(start 0.254 -1.1176)
			(end -0.254 -1.1176)
			(stroke
				(width 0.1)
				(type default)
			)
			(layer "F.Fab")
		)
		(fp_line
			(start 1.5494 -1.1176)
			(end 1.5494 1.1176)
			(stroke
				(width 0.1)
				(type default)
			)
			(layer "F.Fab")
		)
		(fp_line
			(start 1.5494 -1.1176)
			(end 0.254 -1.1176)
			(stroke
				(width 0.1)
				(type default)
			)
			(layer "F.Fab")
		)
		(fp_poly
			(pts
				(xy -1.8161 -0.675386) (xy -2.4003 -0.446786) (xy -2.4003 -0.878586)
			)
			(stroke
				(width 0)
				(type default)
			)
			(fill yes)
			(layer "F.Fab")
		)
		(pad "1" smd rect
			(at -0.962406 -0.649986 180)
			(size 0.3302 1.1684)
			(layers "F.Cu" "F.Mask" "F.Paste")
			(net "PWRGD_P5V_AUX")
		)
		(pad "2" smd rect
			(at -0.962406 0 180)
			(size 0.3302 1.1684)
			(layers "F.Cu" "F.Mask" "F.Paste")
			(net "PWRGD_P1V2_AUX")
		)
		(pad "3" smd rect
			(at -0.962406 0.649986 180)
			(size 0.3302 1.1684)
			(layers "F.Cu" "F.Mask" "F.Paste")
			(net "GND")
		)
		(pad "4" smd rect
			(at 0.962406 0.649986 180)
			(size 0.3302 1.1684)
			(layers "F.Cu" "F.Mask" "F.Paste")
			(net "EN_P1V0_AUX")
		)
		(pad "5" smd rect
			(at 0.962406 -0.649986 180)
			(size 0.3302 1.1684)
			(layers "F.Cu" "F.Mask" "F.Paste")
			(net "P3V3_LDO")
		)
	)
	(footprint ""
		(layer "F.Cu")
		(at 67.5386 -28.321 90)
		(property "Reference" "R380"
			(at 0 0 90)
			(layer "F.SilkS")
			(hide yes)
			(effects
				(font
					(size 1.27 1.27)
				)
			)
		)
		(property "Value" ""
			(at 0 0 90)
			(layer "F.Fab")
			(effects
				(font
					(size 1.27 1.27)
				)
			)
		)
		(duplicate_pad_numbers_are_jumpers no)
		(fp_line
			(start 0.7874 -0.4064)
			(end 0.7874 0.4064)
			(stroke
				(width 0.1524)
				(type default)
			)
			(layer "F.SilkS")
		)
		(fp_line
			(start -0.7874 -0.4064)
			(end 0.7874 -0.4064)
			(stroke
				(width 0.1524)
				(type default)
			)
			(layer "F.SilkS")
		)
		(fp_line
			(start 0.7874 0.4064)
			(end -0.7874 0.4064)
			(stroke
				(width 0.1524)
				(type default)
			)
			(layer "F.SilkS")
		)
		(fp_line
			(start -0.7874 0.4064)
			(end -0.7874 -0.4064)
			(stroke
				(width 0.1524)
				(type default)
			)
			(layer "F.SilkS")
		)
		(fp_line
			(start -0.12065 -0.305054)
			(end -0.12065 -0.2794)
			(stroke
				(width 0.1)
				(type default)
			)
			(layer "F.Fab")
		)
		(fp_line
			(start -0.67945 -0.305054)
			(end -0.12065 -0.305054)
			(stroke
				(width 0.1)
				(type default)
			)
			(layer "F.Fab")
		)
		(fp_line
			(start 0.67945 -0.3048)
			(end 0.67945 0.3048)
			(stroke
				(width 0.1)
				(type default)
			)
			(layer "F.Fab")
		)
		(fp_line
			(start 0.12065 -0.3048)
			(end 0.67945 -0.3048)
			(stroke
				(width 0.1)
				(type default)
			)
			(layer "F.Fab")
		)
		(fp_line
			(start 0.12065 -0.2794)
			(end 0.12065 -0.3048)
			(stroke
				(width 0.1)
				(type default)
			)
			(layer "F.Fab")
		)
		(fp_line
			(start -0.12065 -0.2794)
			(end 0.12065 -0.2794)
			(stroke
				(width 0.1)
				(type default)
			)
			(layer "F.Fab")
		)
		(fp_line
			(start 0.120396 0.2794)
			(end -0.12065 0.2794)
			(stroke
				(width 0.1)
				(type default)
			)
			(layer "F.Fab")
		)
		(fp_line
			(start -0.12065 0.2794)
			(end -0.12065 0.3048)
			(stroke
				(width 0.1)
				(type default)
			)
			(layer "F.Fab")
		)
		(fp_line
			(start 0.67945 0.3048)
			(end 0.120396 0.3048)
			(stroke
				(width 0.1)
				(type default)
			)
			(layer "F.Fab")
		)
		(fp_line
			(start 0.120396 0.3048)
			(end 0.120396 0.2794)
			(stroke
				(width 0.1)
				(type default)
			)
			(layer "F.Fab")
		)
		(fp_line
			(start -0.12065 0.3048)
			(end -0.67945 0.3048)
			(stroke
				(width 0.1)
				(type default)
			)
			(layer "F.Fab")
		)
		(fp_line
			(start -0.67945 0.3048)
			(end -0.67945 -0.305054)
			(stroke
				(width 0.1)
				(type default)
			)
			(layer "F.Fab")
		)
		(pad "1" smd circle
			(at -0.40005 0 90)
			(size 0 0)
			(layers "F.Cu" "F.Mask" "F.Paste")
			(net "EN_P3V3_RGM")
		)
		(pad "2" smd circle
			(at 0.40005 0 90)
			(size 0 0)
			(layers "F.Cu" "F.Mask" "F.Paste")
			(net "EN_P3V3_RGM_R")
		)
	)
	(footprint ""
		(layer "F.Cu")
		(at 85.471 -76.6572 90)
		(property "Reference" "R877"
			(at 0 0 90)
			(layer "F.SilkS")
			(hide yes)
			(effects
				(font
					(size 1.27 1.27)
				)
			)
		)
		(property "Value" ""
			(at 0 0 90)
			(layer "F.Fab")
			(effects
				(font
					(size 1.27 1.27)
				)
			)
		)
		(duplicate_pad_numbers_are_jumpers no)
		(fp_line
			(start 0.7874 -0.4064)
			(end 0.7874 0.4064)
			(stroke
				(width 0.1524)
				(type default)
			)
			(layer "F.SilkS")
		)
		(fp_line
			(start -0.7874 -0.4064)
			(end 0.7874 -0.4064)
			(stroke
				(width 0.1524)
				(type default)
			)
			(layer "F.SilkS")
		)
		(fp_line
			(start 0.7874 0.4064)
			(end -0.7874 0.4064)
			(stroke
				(width 0.1524)
				(type default)
			)
			(layer "F.SilkS")
		)
		(fp_line
			(start -0.7874 0.4064)
			(end -0.7874 -0.4064)
			(stroke
				(width 0.1524)
				(type default)
			)
			(layer "F.SilkS")
		)
		(fp_line
			(start -0.12065 -0.305054)
			(end -0.12065 -0.2794)
			(stroke
				(width 0.1)
				(type default)
			)
			(layer "F.Fab")
		)
		(fp_line
			(start -0.67945 -0.305054)
			(end -0.12065 -0.305054)
			(stroke
				(width 0.1)
				(type default)
			)
			(layer "F.Fab")
		)
		(fp_line
			(start 0.67945 -0.3048)
			(end 0.67945 0.3048)
			(stroke
				(width 0.1)
				(type default)
			)
			(layer "F.Fab")
		)
		(fp_line
			(start 0.12065 -0.3048)
			(end 0.67945 -0.3048)
			(stroke
				(width 0.1)
				(type default)
			)
			(layer "F.Fab")
		)
		(fp_line
			(start 0.12065 -0.2794)
			(end 0.12065 -0.3048)
			(stroke
				(width 0.1)
				(type default)
			)
			(layer "F.Fab")
		)
		(fp_line
			(start -0.12065 -0.2794)
			(end 0.12065 -0.2794)
			(stroke
				(width 0.1)
				(type default)
			)
			(layer "F.Fab")
		)
		(fp_line
			(start 0.120396 0.2794)
			(end -0.12065 0.2794)
			(stroke
				(width 0.1)
				(type default)
			)
			(layer "F.Fab")
		)
		(fp_line
			(start -0.12065 0.2794)
			(end -0.12065 0.3048)
			(stroke
				(width 0.1)
				(type default)
			)
			(layer "F.Fab")
		)
		(fp_line
			(start 0.67945 0.3048)
			(end 0.120396 0.3048)
			(stroke
				(width 0.1)
				(type default)
			)
			(layer "F.Fab")
		)
		(fp_line
			(start 0.120396 0.3048)
			(end 0.120396 0.2794)
			(stroke
				(width 0.1)
				(type default)
			)
			(layer "F.Fab")
		)
		(fp_line
			(start -0.12065 0.3048)
			(end -0.67945 0.3048)
			(stroke
				(width 0.1)
				(type default)
			)
			(layer "F.Fab")
		)
		(fp_line
			(start -0.67945 0.3048)
			(end -0.67945 -0.305054)
			(stroke
				(width 0.1)
				(type default)
			)
			(layer "F.Fab")
		)
		(pad "1" smd circle
			(at -0.40005 0 90)
			(size 0 0)
			(layers "F.Cu" "F.Mask" "F.Paste")
			(net "PWRGD_P1V2_AUX_R")
		)
		(pad "2" smd circle
			(at 0.40005 0 90)
			(size 0 0)
			(layers "F.Cu" "F.Mask" "F.Paste")
			(net "PWRGD_P1V2_AUX_R2")
		)
	)
	(footprint ""
		(layer "F.Cu")
		(at 19.812 -65.8368)
		(property "Reference" "R737"
			(at 0 0 0)
			(layer "F.SilkS")
			(hide yes)
			(effects
				(font
					(size 1.27 1.27)
				)
			)
		)
		(property "Value" ""
			(at 0 0 0)
			(layer "F.Fab")
			(effects
				(font
					(size 1.27 1.27)
				)
			)
		)
		(duplicate_pad_numbers_are_jumpers no)
		(fp_line
			(start -0.7874 -0.4064)
			(end 0.7874 -0.4064)
			(stroke
				(width 0.1524)
				(type default)
			)
			(layer "F.SilkS")
		)
		(fp_line
			(start -0.7874 0.4064)
			(end -0.7874 -0.4064)
			(stroke
				(width 0.1524)
				(type default)
			)
			(layer "F.SilkS")
		)
		(fp_line
			(start 0.7874 -0.4064)
			(end 0.7874 0.4064)
			(stroke
				(width 0.1524)
				(type default)
			)
			(layer "F.SilkS")
		)
		(fp_line
			(start 0.7874 0.4064)
			(end -0.7874 0.4064)
			(stroke
				(width 0.1524)
				(type default)
			)
			(layer "F.SilkS")
		)
		(fp_line
			(start -0.67945 -0.305054)
			(end -0.12065 -0.305054)
			(stroke
				(width 0.1)
				(type default)
			)
			(layer "F.Fab")
		)
		(fp_line
			(start -0.67945 0.3048)
			(end -0.67945 -0.305054)
			(stroke
				(width 0.1)
				(type default)
			)
			(layer "F.Fab")
		)
		(fp_line
			(start -0.12065 -0.305054)
			(end -0.12065 -0.2794)
			(stroke
				(width 0.1)
				(type default)
			)
			(layer "F.Fab")
		)
		(fp_line
			(start -0.12065 -0.2794)
			(end 0.12065 -0.2794)
			(stroke
				(width 0.1)
				(type default)
			)
			(layer "F.Fab")
		)
		(fp_line
			(start -0.12065 0.2794)
			(end -0.12065 0.3048)
			(stroke
				(width 0.1)
				(type default)
			)
			(layer "F.Fab")
		)
		(fp_line
			(start -0.12065 0.3048)
			(end -0.67945 0.3048)
			(stroke
				(width 0.1)
				(type default)
			)
			(layer "F.Fab")
		)
		(fp_line
			(start 0.120396 0.2794)
			(end -0.12065 0.2794)
			(stroke
				(width 0.1)
				(type default)
			)
			(layer "F.Fab")
		)
		(fp_line
			(start 0.120396 0.3048)
			(end 0.120396 0.2794)
			(stroke
				(width 0.1)
				(type default)
			)
			(layer "F.Fab")
		)
		(fp_line
			(start 0.12065 -0.3048)
			(end 0.67945 -0.3048)
			(stroke
				(width 0.1)
				(type default)
			)
			(layer "F.Fab")
		)
		(fp_line
			(start 0.12065 -0.2794)
			(end 0.12065 -0.3048)
			(stroke
				(width 0.1)
				(type default)
			)
			(layer "F.Fab")
		)
		(fp_line
			(start 0.67945 -0.3048)
			(end 0.67945 0.3048)
			(stroke
				(width 0.1)
				(type default)
			)
			(layer "F.Fab")
		)
		(fp_line
			(start 0.67945 0.3048)
			(end 0.120396 0.3048)
			(stroke
				(width 0.1)
				(type default)
			)
			(layer "F.Fab")
		)
		(pad "1" smd circle
			(at -0.40005 0)
			(size 0 0)
			(layers "F.Cu" "F.Mask" "F.Paste")
			(net "P3V3_AUX")
		)
		(pad "2" smd circle
			(at 0.40005 0)
			(size 0 0)
			(layers "F.Cu" "F.Mask" "F.Paste")
			(net "SPA_SIN_SW_BUF")
		)
	)
	(footprint ""
		(layer "F.Cu")
		(at 78.000098 -74.476356 90)
		(property "Reference" "R616"
			(at 0 0 90)
			(layer "F.SilkS")
			(hide yes)
			(effects
				(font
					(size 1.27 1.27)
				)
			)
		)
		(property "Value" ""
			(at 0 0 90)
			(layer "F.Fab")
			(effects
				(font
					(size 1.27 1.27)
				)
			)
		)
		(duplicate_pad_numbers_are_jumpers no)
		(fp_line
			(start 0.7874 -0.4064)
			(end 0.7874 0.4064)
			(stroke
				(width 0.1524)
				(type default)
			)
			(layer "F.SilkS")
		)
		(fp_line
			(start -0.7874 -0.4064)
			(end 0.7874 -0.4064)
			(stroke
				(width 0.1524)
				(type default)
			)
			(layer "F.SilkS")
		)
		(fp_line
			(start 0.7874 0.4064)
			(end -0.7874 0.4064)
			(stroke
				(width 0.1524)
				(type default)
			)
			(layer "F.SilkS")
		)
		(fp_line
			(start -0.7874 0.4064)
			(end -0.7874 -0.4064)
			(stroke
				(width 0.1524)
				(type default)
			)
			(layer "F.SilkS")
		)
		(fp_line
			(start -0.12065 -0.305054)
			(end -0.12065 -0.2794)
			(stroke
				(width 0.1)
				(type default)
			)
			(layer "F.Fab")
		)
		(fp_line
			(start -0.67945 -0.305054)
			(end -0.12065 -0.305054)
			(stroke
				(width 0.1)
				(type default)
			)
			(layer "F.Fab")
		)
		(fp_line
			(start 0.67945 -0.3048)
			(end 0.67945 0.3048)
			(stroke
				(width 0.1)
				(type default)
			)
			(layer "F.Fab")
		)
		(fp_line
			(start 0.12065 -0.3048)
			(end 0.67945 -0.3048)
			(stroke
				(width 0.1)
				(type default)
			)
			(layer "F.Fab")
		)
		(fp_line
			(start 0.12065 -0.2794)
			(end 0.12065 -0.3048)
			(stroke
				(width 0.1)
				(type default)
			)
			(layer "F.Fab")
		)
		(fp_line
			(start -0.12065 -0.2794)
			(end 0.12065 -0.2794)
			(stroke
				(width 0.1)
				(type default)
			)
			(layer "F.Fab")
		)
		(fp_line
			(start 0.120396 0.2794)
			(end -0.12065 0.2794)
			(stroke
				(width 0.1)
				(type default)
			)
			(layer "F.Fab")
		)
		(fp_line
			(start -0.12065 0.2794)
			(end -0.12065 0.3048)
			(stroke
				(width 0.1)
				(type default)
			)
			(layer "F.Fab")
		)
		(fp_line
			(start 0.67945 0.3048)
			(end 0.120396 0.3048)
			(stroke
				(width 0.1)
				(type default)
			)
			(layer "F.Fab")
		)
		(fp_line
			(start 0.120396 0.3048)
			(end 0.120396 0.2794)
			(stroke
				(width 0.1)
				(type default)
			)
			(layer "F.Fab")
		)
		(fp_line
			(start -0.12065 0.3048)
			(end -0.67945 0.3048)
			(stroke
				(width 0.1)
				(type default)
			)
			(layer "F.Fab")
		)
		(fp_line
			(start -0.67945 0.3048)
			(end -0.67945 -0.305054)
			(stroke
				(width 0.1)
				(type default)
			)
			(layer "F.Fab")
		)
		(pad "1" smd circle
			(at -0.40005 0 90)
			(size 0 0)
			(layers "F.Cu" "F.Mask" "F.Paste")
			(net "FM_JTAG_TCK_MUX_BMC_SEL_R")
		)
		(pad "2" smd circle
			(at 0.40005 0 90)
			(size 0 0)
			(layers "F.Cu" "F.Mask" "F.Paste")
			(net "FM_JTAG_TCK_MUX_BMC_SEL")
		)
	)
	(footprint ""
		(layer "F.Cu")
		(at 70.4088 -29.845 -90)
		(property "Reference" "C252"
			(at 0 0 270)
			(layer "F.SilkS")
			(hide yes)
			(effects
				(font
					(size 1.27 1.27)
				)
			)
		)
		(property "Value" ""
			(at 0 0 270)
			(layer "F.Fab")
			(effects
				(font
					(size 1.27 1.27)
				)
			)
		)
		(duplicate_pad_numbers_are_jumpers no)
		(fp_line
			(start -0.7874 0.4064)
			(end -0.7874 -0.4064)
			(stroke
				(width 0.1524)
				(type default)
			)
			(layer "F.SilkS")
		)
		(fp_line
			(start 0.7874 0.4064)
			(end -0.7874 0.4064)
			(stroke
				(width 0.1524)
				(type default)
			)
			(layer "F.SilkS")
		)
		(fp_line
			(start -0.7874 -0.4064)
			(end 0.7874 -0.4064)
			(stroke
				(width 0.1524)
				(type default)
			)
			(layer "F.SilkS")
		)
		(fp_line
			(start 0.7874 -0.4064)
			(end 0.7874 0.4064)
			(stroke
				(width 0.1524)
				(type default)
			)
			(layer "F.SilkS")
		)
		(fp_line
			(start -0.67945 0.3048)
			(end -0.67945 -0.305054)
			(stroke
				(width 0.1)
				(type default)
			)
			(layer "F.Fab")
		)
		(fp_line
			(start -0.12065 0.3048)
			(end -0.67945 0.3048)
			(stroke
				(width 0.1)
				(type default)
			)
			(layer "F.Fab")
		)
		(fp_line
			(start 0.120396 0.3048)
			(end 0.120396 0.2794)
			(stroke
				(width 0.1)
				(type default)
			)
			(layer "F.Fab")
		)
		(fp_line
			(start 0.67945 0.3048)
			(end 0.120396 0.3048)
			(stroke
				(width 0.1)
				(type default)
			)
			(layer "F.Fab")
		)
		(fp_line
			(start -0.12065 0.2794)
			(end -0.12065 0.3048)
			(stroke
				(width 0.1)
				(type default)
			)
			(layer "F.Fab")
		)
		(fp_line
			(start 0.120396 0.2794)
			(end -0.12065 0.2794)
			(stroke
				(width 0.1)
				(type default)
			)
			(layer "F.Fab")
		)
		(fp_line
			(start -0.12065 -0.2794)
			(end 0.12065 -0.2794)
			(stroke
				(width 0.1)
				(type default)
			)
			(layer "F.Fab")
		)
		(fp_line
			(start 0.12065 -0.2794)
			(end 0.12065 -0.3048)
			(stroke
				(width 0.1)
				(type default)
			)
			(layer "F.Fab")
		)
		(fp_line
			(start 0.12065 -0.3048)
			(end 0.67945 -0.3048)
			(stroke
				(width 0.1)
				(type default)
			)
			(layer "F.Fab")
		)
		(fp_line
			(start 0.67945 -0.3048)
			(end 0.67945 0.3048)
			(stroke
				(width 0.1)
				(type default)
			)
			(layer "F.Fab")
		)
		(fp_line
			(start -0.67945 -0.305054)
			(end -0.12065 -0.305054)
			(stroke
				(width 0.1)
				(type default)
			)
			(layer "F.Fab")
		)
		(fp_line
			(start -0.12065 -0.305054)
			(end -0.12065 -0.2794)
			(stroke
				(width 0.1)
				(type default)
			)
			(layer "F.Fab")
		)
		(pad "1" smd circle
			(at -0.40005 0 270)
			(size 0 0)
			(layers "F.Cu" "F.Mask" "F.Paste")
			(net "PWRGD_P3V3_RGM_R")
		)
		(pad "2" smd circle
			(at 0.40005 0 270)
			(size 0 0)
			(layers "F.Cu" "F.Mask" "F.Paste")
			(net "GND")
		)
	)
	(footprint ""
		(layer "F.Cu")
		(at 85.2932 -17.78 180)
		(property "Reference" "R504"
			(at 0 0 180)
			(layer "F.SilkS")
			(hide yes)
			(effects
				(font
					(size 1.27 1.27)
				)
			)
		)
		(property "Value" ""
			(at 0 0 180)
			(layer "F.Fab")
			(effects
				(font
					(size 1.27 1.27)
				)
			)
		)
		(duplicate_pad_numbers_are_jumpers no)
		(fp_line
			(start 0.7874 0.4064)
			(end -0.7874 0.4064)
			(stroke
				(width 0.1524)
				(type default)
			)
			(layer "F.SilkS")
		)
		(fp_line
			(start 0.7874 -0.4064)
			(end 0.7874 0.4064)
			(stroke
				(width 0.1524)
				(type default)
			)
			(layer "F.SilkS")
		)
		(fp_line
			(start -0.7874 0.4064)
			(end -0.7874 -0.4064)
			(stroke
				(width 0.1524)
				(type default)
			)
			(layer "F.SilkS")
		)
		(fp_line
			(start -0.7874 -0.4064)
			(end 0.7874 -0.4064)
			(stroke
				(width 0.1524)
				(type default)
			)
			(layer "F.SilkS")
		)
		(fp_line
			(start 0.67945 0.3048)
			(end 0.120396 0.3048)
			(stroke
				(width 0.1)
				(type default)
			)
			(layer "F.Fab")
		)
		(fp_line
			(start 0.67945 -0.3048)
			(end 0.67945 0.3048)
			(stroke
				(width 0.1)
				(type default)
			)
			(layer "F.Fab")
		)
		(fp_line
			(start 0.12065 -0.2794)
			(end 0.12065 -0.3048)
			(stroke
				(width 0.1)
				(type default)
			)
			(layer "F.Fab")
		)
		(fp_line
			(start 0.12065 -0.3048)
			(end 0.67945 -0.3048)
			(stroke
				(width 0.1)
				(type default)
			)
			(layer "F.Fab")
		)
		(fp_line
			(start 0.120396 0.3048)
			(end 0.120396 0.2794)
			(stroke
				(width 0.1)
				(type default)
			)
			(layer "F.Fab")
		)
		(fp_line
			(start 0.120396 0.2794)
			(end -0.12065 0.2794)
			(stroke
				(width 0.1)
				(type default)
			)
			(layer "F.Fab")
		)
		(fp_line
			(start -0.12065 0.3048)
			(end -0.67945 0.3048)
			(stroke
				(width 0.1)
				(type default)
			)
			(layer "F.Fab")
		)
		(fp_line
			(start -0.12065 0.2794)
			(end -0.12065 0.3048)
			(stroke
				(width 0.1)
				(type default)
			)
			(layer "F.Fab")
		)
		(fp_line
			(start -0.12065 -0.2794)
			(end 0.12065 -0.2794)
			(stroke
				(width 0.1)
				(type default)
			)
			(layer "F.Fab")
		)
		(fp_line
			(start -0.12065 -0.305054)
			(end -0.12065 -0.2794)
			(stroke
				(width 0.1)
				(type default)
			)
			(layer "F.Fab")
		)
		(fp_line
			(start -0.67945 0.3048)
			(end -0.67945 -0.305054)
			(stroke
				(width 0.1)
				(type default)
			)
			(layer "F.Fab")
		)
		(fp_line
			(start -0.67945 -0.305054)
			(end -0.12065 -0.305054)
			(stroke
				(width 0.1)
				(type default)
			)
			(layer "F.Fab")
		)
		(pad "1" smd circle
			(at -0.40005 0 180)
			(size 0 0)
			(layers "F.Cu" "F.Mask" "F.Paste")
			(net "P3V3_AUX")
		)
		(pad "2" smd circle
			(at 0.40005 0 180)
			(size 0 0)
			(layers "F.Cu" "F.Mask" "F.Paste")
			(net "REAR_ID_RST_BTN_N")
		)
	)
	(footprint ""
		(layer "F.Cu")
		(at 8.128 -82.55)
		(property "Reference" "U6"
			(at 2.45237 0.3048 90)
			(unlocked yes)
			(layer "F.SilkS")
			(effects
				(font
					(size 0.7874 0.5842)
					(thickness 0.1524)
				)
				(justify left)
			)
		)
		(property "Value" ""
			(at 0 0 0)
			(layer "F.Fab")
			(effects
				(font
					(size 1.27 1.27)
				)
			)
		)
		(duplicate_pad_numbers_are_jumpers no)
		(fp_line
			(start -1.38176 -1.100074)
			(end -1.38176 1.100074)
			(stroke
				(width 0.1524)
				(type default)
			)
			(layer "F.SilkS")
		)
		(fp_line
			(start -1.38176 1.100074)
			(end 1.38176 1.100074)
			(stroke
				(width 0.1524)
				(type default)
			)
			(layer "F.SilkS")
		)
		(fp_line
			(start -0.592074 -1.100074)
			(end -1.38176 -1.100074)
			(stroke
				(width 0.1524)
				(type default)
			)
			(layer "F.SilkS")
		)
		(fp_line
			(start 0 -0.508)
			(end -0.592074 -1.100074)
			(stroke
				(width 0.1524)
				(type default)
			)
			(layer "F.SilkS")
		)
		(fp_line
			(start 0.592074 -1.100074)
			(end 0 -0.508)
			(stroke
				(width 0.1524)
				(type default)
			)
			(layer "F.SilkS")
		)
		(fp_line
			(start 1.38176 -1.100074)
			(end 0.592074 -1.100074)
			(stroke
				(width 0.1524)
				(type default)
			)
			(layer "F.SilkS")
		)
		(fp_line
			(start 1.38176 1.100074)
			(end 1.38176 -1.100074)
			(stroke
				(width 0.1524)
				(type default)
			)
			(layer "F.SilkS")
		)
		(fp_poly
			(pts
				(xy -1.9431 -0.870204) (xy -1.50241 -0.649986) (xy -1.9431 -0.429768)
			)
			(stroke
				(width 0)
				(type default)
			)
			(fill yes)
			(layer "F.SilkS")
		)
		(fp_line
			(start -0.674878 -1.100074)
			(end -0.674878 1.100074)
			(stroke
				(width 0.1)
				(type default)
			)
			(layer "F.Fab")
		)
		(fp_line
			(start -0.674878 1.100074)
			(end 0.674878 1.100074)
			(stroke
				(width 0.1)
				(type default)
			)
			(layer "F.Fab")
		)
		(fp_line
			(start 0.674878 -1.100074)
			(end -0.674878 -1.100074)
			(stroke
				(width 0.1)
				(type default)
			)
			(layer "F.Fab")
		)
		(fp_line
			(start 0.674878 1.100074)
			(end 0.674878 -1.100074)
			(stroke
				(width 0.1)
				(type default)
			)
			(layer "F.Fab")
		)
		(fp_poly
			(pts
				(xy -1.9431 -0.870204) (xy -1.50241 -0.649986) (xy -1.9431 -0.429768)
			)
			(stroke
				(width 0)
				(type default)
			)
			(fill yes)
			(layer "F.Fab")
		)
		(pad "1" smd rect
			(at -0.94996 -0.649986 270)
			(size 0.4318 0.6096)
			(layers "F.Cu" "F.Mask" "F.Paste")
			(net "PWRGD_P1V0_AUX_DELAY")
		)
		(pad "2" smd rect
			(at -0.94996 0 270)
			(size 0.4318 0.6096)
			(layers "F.Cu" "F.Mask" "F.Paste")
			(net "GND")
		)
		(pad "3" smd rect
			(at -0.94996 0.649986 270)
			(size 0.4318 0.6096)
			(layers "F.Cu" "F.Mask" "F.Paste")
			(net "RST_SRST_PLD_BMC_R1_N")
		)
		(pad "4" smd rect
			(at 0.94996 0.649986 270)
			(size 0.4318 0.6096)
			(layers "F.Cu" "F.Mask" "F.Paste")
			(net "RST_SRST_PLD_BMC_BUF_N")
		)
		(pad "5" smd rect
			(at 0.94996 0 270)
			(size 0.4318 0.6096)
			(layers "F.Cu" "F.Mask" "F.Paste")
			(net "P3V3_AUX")
		)
		(pad "6" smd rect
			(at 0.94996 -0.649986 270)
			(size 0.4318 0.6096)
			(layers "F.Cu" "F.Mask" "F.Paste")
			(net "PWRGD_P1V0_AUX_DELAY_BUF")
		)
	)
	(footprint ""
		(layer "F.Cu")
		(at 85.29955 -41.887394 180)
		(property "Reference" "R339"
			(at 0 0 180)
			(layer "F.SilkS")
			(hide yes)
			(effects
				(font
					(size 1.27 1.27)
				)
			)
		)
		(property "Value" ""
			(at 0 0 180)
			(layer "F.Fab")
			(effects
				(font
					(size 1.27 1.27)
				)
			)
		)
		(duplicate_pad_numbers_are_jumpers no)
		(fp_line
			(start 0.7874 0.4064)
			(end -0.7874 0.4064)
			(stroke
				(width 0.1524)
				(type default)
			)
			(layer "F.SilkS")
		)
		(fp_line
			(start 0.7874 -0.4064)
			(end 0.7874 0.4064)
			(stroke
				(width 0.1524)
				(type default)
			)
			(layer "F.SilkS")
		)
		(fp_line
			(start -0.7874 0.4064)
			(end -0.7874 -0.4064)
			(stroke
				(width 0.1524)
				(type default)
			)
			(layer "F.SilkS")
		)
		(fp_line
			(start -0.7874 -0.4064)
			(end 0.7874 -0.4064)
			(stroke
				(width 0.1524)
				(type default)
			)
			(layer "F.SilkS")
		)
		(fp_line
			(start 0.67945 0.3048)
			(end 0.120396 0.3048)
			(stroke
				(width 0.1)
				(type default)
			)
			(layer "F.Fab")
		)
		(fp_line
			(start 0.67945 -0.3048)
			(end 0.67945 0.3048)
			(stroke
				(width 0.1)
				(type default)
			)
			(layer "F.Fab")
		)
		(fp_line
			(start 0.12065 -0.2794)
			(end 0.12065 -0.3048)
			(stroke
				(width 0.1)
				(type default)
			)
			(layer "F.Fab")
		)
		(fp_line
			(start 0.12065 -0.3048)
			(end 0.67945 -0.3048)
			(stroke
				(width 0.1)
				(type default)
			)
			(layer "F.Fab")
		)
		(fp_line
			(start 0.120396 0.3048)
			(end 0.120396 0.2794)
			(stroke
				(width 0.1)
				(type default)
			)
			(layer "F.Fab")
		)
		(fp_line
			(start 0.120396 0.2794)
			(end -0.12065 0.2794)
			(stroke
				(width 0.1)
				(type default)
			)
			(layer "F.Fab")
		)
		(fp_line
			(start -0.12065 0.3048)
			(end -0.67945 0.3048)
			(stroke
				(width 0.1)
				(type default)
			)
			(layer "F.Fab")
		)
		(fp_line
			(start -0.12065 0.2794)
			(end -0.12065 0.3048)
			(stroke
				(width 0.1)
				(type default)
			)
			(layer "F.Fab")
		)
		(fp_line
			(start -0.12065 -0.2794)
			(end 0.12065 -0.2794)
			(stroke
				(width 0.1)
				(type default)
			)
			(layer "F.Fab")
		)
		(fp_line
			(start -0.12065 -0.305054)
			(end -0.12065 -0.2794)
			(stroke
				(width 0.1)
				(type default)
			)
			(layer "F.Fab")
		)
		(fp_line
			(start -0.67945 0.3048)
			(end -0.67945 -0.305054)
			(stroke
				(width 0.1)
				(type default)
			)
			(layer "F.Fab")
		)
		(fp_line
			(start -0.67945 -0.305054)
			(end -0.12065 -0.305054)
			(stroke
				(width 0.1)
				(type default)
			)
			(layer "F.Fab")
		)
		(pad "1" smd circle
			(at -0.40005 0 180)
			(size 0 0)
			(layers "F.Cu" "F.Mask" "F.Paste")
			(net "GND")
		)
		(pad "2" smd circle
			(at 0.40005 0 180)
			(size 0 0)
			(layers "F.Cu" "F.Mask" "F.Paste")
			(net "M_BMC_DDR4_MA<13>")
		)
	)
	(footprint ""
		(layer "F.Cu")
		(at 53.7718 -109.3978 -90)
		(property "Reference" "R861"
			(at 0 0 270)
			(layer "F.SilkS")
			(hide yes)
			(effects
				(font
					(size 1.27 1.27)
				)
			)
		)
		(property "Value" ""
			(at 0 0 270)
			(layer "F.Fab")
			(effects
				(font
					(size 1.27 1.27)
				)
			)
		)
		(duplicate_pad_numbers_are_jumpers no)
		(fp_line
			(start -0.7874 0.4064)
			(end -0.7874 -0.4064)
			(stroke
				(width 0.1524)
				(type default)
			)
			(layer "F.SilkS")
		)
		(fp_line
			(start 0.7874 0.4064)
			(end -0.7874 0.4064)
			(stroke
				(width 0.1524)
				(type default)
			)
			(layer "F.SilkS")
		)
		(fp_line
			(start -0.7874 -0.4064)
			(end 0.7874 -0.4064)
			(stroke
				(width 0.1524)
				(type default)
			)
			(layer "F.SilkS")
		)
		(fp_line
			(start 0.7874 -0.4064)
			(end 0.7874 0.4064)
			(stroke
				(width 0.1524)
				(type default)
			)
			(layer "F.SilkS")
		)
		(fp_line
			(start -0.67945 0.3048)
			(end -0.67945 -0.305054)
			(stroke
				(width 0.1)
				(type default)
			)
			(layer "F.Fab")
		)
		(fp_line
			(start -0.12065 0.3048)
			(end -0.67945 0.3048)
			(stroke
				(width 0.1)
				(type default)
			)
			(layer "F.Fab")
		)
		(fp_line
			(start 0.120396 0.3048)
			(end 0.120396 0.2794)
			(stroke
				(width 0.1)
				(type default)
			)
			(layer "F.Fab")
		)
		(fp_line
			(start 0.67945 0.3048)
			(end 0.120396 0.3048)
			(stroke
				(width 0.1)
				(type default)
			)
			(layer "F.Fab")
		)
		(fp_line
			(start -0.12065 0.2794)
			(end -0.12065 0.3048)
			(stroke
				(width 0.1)
				(type default)
			)
			(layer "F.Fab")
		)
		(fp_line
			(start 0.120396 0.2794)
			(end -0.12065 0.2794)
			(stroke
				(width 0.1)
				(type default)
			)
			(layer "F.Fab")
		)
		(fp_line
			(start -0.12065 -0.2794)
			(end 0.12065 -0.2794)
			(stroke
				(width 0.1)
				(type default)
			)
			(layer "F.Fab")
		)
		(fp_line
			(start 0.12065 -0.2794)
			(end 0.12065 -0.3048)
			(stroke
				(width 0.1)
				(type default)
			)
			(layer "F.Fab")
		)
		(fp_line
			(start 0.12065 -0.3048)
			(end 0.67945 -0.3048)
			(stroke
				(width 0.1)
				(type default)
			)
			(layer "F.Fab")
		)
		(fp_line
			(start 0.67945 -0.3048)
			(end 0.67945 0.3048)
			(stroke
				(width 0.1)
				(type default)
			)
			(layer "F.Fab")
		)
		(fp_line
			(start -0.67945 -0.305054)
			(end -0.12065 -0.305054)
			(stroke
				(width 0.1)
				(type default)
			)
			(layer "F.Fab")
		)
		(fp_line
			(start -0.12065 -0.305054)
			(end -0.12065 -0.2794)
			(stroke
				(width 0.1)
				(type default)
			)
			(layer "F.Fab")
		)
		(pad "1" smd circle
			(at -0.40005 0 270)
			(size 0 0)
			(layers "F.Cu" "F.Mask" "F.Paste")
			(net "SPI_SYS_R_MISO")
		)
		(pad "2" smd circle
			(at 0.40005 0 270)
			(size 0 0)
			(layers "F.Cu" "F.Mask" "F.Paste")
			(net "SPI_SYS_MUX_MISO")
		)
	)
	(footprint ""
		(layer "F.Cu")
		(at 30.5562 -86.995 180)
		(property "Reference" "R718"
			(at 0 0 180)
			(layer "F.SilkS")
			(hide yes)
			(effects
				(font
					(size 1.27 1.27)
				)
			)
		)
		(property "Value" ""
			(at 0 0 180)
			(layer "F.Fab")
			(effects
				(font
					(size 1.27 1.27)
				)
			)
		)
		(duplicate_pad_numbers_are_jumpers no)
		(fp_line
			(start 0.7874 0.4064)
			(end -0.7874 0.4064)
			(stroke
				(width 0.1524)
				(type default)
			)
			(layer "F.SilkS")
		)
		(fp_line
			(start 0.7874 -0.4064)
			(end 0.7874 0.4064)
			(stroke
				(width 0.1524)
				(type default)
			)
			(layer "F.SilkS")
		)
		(fp_line
			(start -0.7874 0.4064)
			(end -0.7874 -0.4064)
			(stroke
				(width 0.1524)
				(type default)
			)
			(layer "F.SilkS")
		)
		(fp_line
			(start -0.7874 -0.4064)
			(end 0.7874 -0.4064)
			(stroke
				(width 0.1524)
				(type default)
			)
			(layer "F.SilkS")
		)
		(fp_line
			(start 0.67945 0.3048)
			(end 0.120396 0.3048)
			(stroke
				(width 0.1)
				(type default)
			)
			(layer "F.Fab")
		)
		(fp_line
			(start 0.67945 -0.3048)
			(end 0.67945 0.3048)
			(stroke
				(width 0.1)
				(type default)
			)
			(layer "F.Fab")
		)
		(fp_line
			(start 0.12065 -0.2794)
			(end 0.12065 -0.3048)
			(stroke
				(width 0.1)
				(type default)
			)
			(layer "F.Fab")
		)
		(fp_line
			(start 0.12065 -0.3048)
			(end 0.67945 -0.3048)
			(stroke
				(width 0.1)
				(type default)
			)
			(layer "F.Fab")
		)
		(fp_line
			(start 0.120396 0.3048)
			(end 0.120396 0.2794)
			(stroke
				(width 0.1)
				(type default)
			)
			(layer "F.Fab")
		)
		(fp_line
			(start 0.120396 0.2794)
			(end -0.12065 0.2794)
			(stroke
				(width 0.1)
				(type default)
			)
			(layer "F.Fab")
		)
		(fp_line
			(start -0.12065 0.3048)
			(end -0.67945 0.3048)
			(stroke
				(width 0.1)
				(type default)
			)
			(layer "F.Fab")
		)
		(fp_line
			(start -0.12065 0.2794)
			(end -0.12065 0.3048)
			(stroke
				(width 0.1)
				(type default)
			)
			(layer "F.Fab")
		)
		(fp_line
			(start -0.12065 -0.2794)
			(end 0.12065 -0.2794)
			(stroke
				(width 0.1)
				(type default)
			)
			(layer "F.Fab")
		)
		(fp_line
			(start -0.12065 -0.305054)
			(end -0.12065 -0.2794)
			(stroke
				(width 0.1)
				(type default)
			)
			(layer "F.Fab")
		)
		(fp_line
			(start -0.67945 0.3048)
			(end -0.67945 -0.305054)
			(stroke
				(width 0.1)
				(type default)
			)
			(layer "F.Fab")
		)
		(fp_line
			(start -0.67945 -0.305054)
			(end -0.12065 -0.305054)
			(stroke
				(width 0.1)
				(type default)
			)
			(layer "F.Fab")
		)
		(pad "1" smd circle
			(at -0.40005 0 180)
			(size 0 0)
			(layers "F.Cu" "F.Mask" "F.Paste")
			(net "RST_PLTRST_N")
		)
		(pad "2" smd circle
			(at 0.40005 0 180)
			(size 0 0)
			(layers "F.Cu" "F.Mask" "F.Paste")
			(net "RST_PLTRST_R1_N")
		)
	)
	(footprint ""
		(layer "F.Cu")
		(at 61.469016 -79.632556)
		(property "Reference" "R624"
			(at 0 0 0)
			(layer "F.SilkS")
			(hide yes)
			(effects
				(font
					(size 1.27 1.27)
				)
			)
		)
		(property "Value" ""
			(at 0 0 0)
			(layer "F.Fab")
			(effects
				(font
					(size 1.27 1.27)
				)
			)
		)
		(duplicate_pad_numbers_are_jumpers no)
		(fp_line
			(start -0.7874 -0.4064)
			(end 0.7874 -0.4064)
			(stroke
				(width 0.1524)
				(type default)
			)
			(layer "F.SilkS")
		)
		(fp_line
			(start -0.7874 0.4064)
			(end -0.7874 -0.4064)
			(stroke
				(width 0.1524)
				(type default)
			)
			(layer "F.SilkS")
		)
		(fp_line
			(start 0.7874 -0.4064)
			(end 0.7874 0.4064)
			(stroke
				(width 0.1524)
				(type default)
			)
			(layer "F.SilkS")
		)
		(fp_line
			(start 0.7874 0.4064)
			(end -0.7874 0.4064)
			(stroke
				(width 0.1524)
				(type default)
			)
			(layer "F.SilkS")
		)
		(fp_line
			(start -0.67945 -0.305054)
			(end -0.12065 -0.305054)
			(stroke
				(width 0.1)
				(type default)
			)
			(layer "F.Fab")
		)
		(fp_line
			(start -0.67945 0.3048)
			(end -0.67945 -0.305054)
			(stroke
				(width 0.1)
				(type default)
			)
			(layer "F.Fab")
		)
		(fp_line
			(start -0.12065 -0.305054)
			(end -0.12065 -0.2794)
			(stroke
				(width 0.1)
				(type default)
			)
			(layer "F.Fab")
		)
		(fp_line
			(start -0.12065 -0.2794)
			(end 0.12065 -0.2794)
			(stroke
				(width 0.1)
				(type default)
			)
			(layer "F.Fab")
		)
		(fp_line
			(start -0.12065 0.2794)
			(end -0.12065 0.3048)
			(stroke
				(width 0.1)
				(type default)
			)
			(layer "F.Fab")
		)
		(fp_line
			(start -0.12065 0.3048)
			(end -0.67945 0.3048)
			(stroke
				(width 0.1)
				(type default)
			)
			(layer "F.Fab")
		)
		(fp_line
			(start 0.120396 0.2794)
			(end -0.12065 0.2794)
			(stroke
				(width 0.1)
				(type default)
			)
			(layer "F.Fab")
		)
		(fp_line
			(start 0.120396 0.3048)
			(end 0.120396 0.2794)
			(stroke
				(width 0.1)
				(type default)
			)
			(layer "F.Fab")
		)
		(fp_line
			(start 0.12065 -0.3048)
			(end 0.67945 -0.3048)
			(stroke
				(width 0.1)
				(type default)
			)
			(layer "F.Fab")
		)
		(fp_line
			(start 0.12065 -0.2794)
			(end 0.12065 -0.3048)
			(stroke
				(width 0.1)
				(type default)
			)
			(layer "F.Fab")
		)
		(fp_line
			(start 0.67945 -0.3048)
			(end 0.67945 0.3048)
			(stroke
				(width 0.1)
				(type default)
			)
			(layer "F.Fab")
		)
		(fp_line
			(start 0.67945 0.3048)
			(end 0.120396 0.3048)
			(stroke
				(width 0.1)
				(type default)
			)
			(layer "F.Fab")
		)
		(pad "1" smd circle
			(at -0.40005 0)
			(size 0 0)
			(layers "F.Cu" "F.Mask" "F.Paste")
			(net "P3V3_AUX")
		)
		(pad "2" smd circle
			(at 0.40005 0)
			(size 0 0)
			(layers "F.Cu" "F.Mask" "F.Paste")
			(net "FM_BMC_DEBUG_SW_N")
		)
	)
	(footprint ""
		(layer "F.Cu")
		(at 46.586902 -63.934594 -90)
		(property "Reference" "R25"
			(at 0 0 270)
			(layer "F.SilkS")
			(hide yes)
			(effects
				(font
					(size 1.27 1.27)
				)
			)
		)
		(property "Value" ""
			(at 0 0 270)
			(layer "F.Fab")
			(effects
				(font
					(size 1.27 1.27)
				)
			)
		)
		(duplicate_pad_numbers_are_jumpers no)
		(fp_line
			(start -0.7874 0.4064)
			(end -0.7874 -0.4064)
			(stroke
				(width 0.1524)
				(type default)
			)
			(layer "F.SilkS")
		)
		(fp_line
			(start 0.7874 0.4064)
			(end -0.7874 0.4064)
			(stroke
				(width 0.1524)
				(type default)
			)
			(layer "F.SilkS")
		)
		(fp_line
			(start -0.7874 -0.4064)
			(end 0.7874 -0.4064)
			(stroke
				(width 0.1524)
				(type default)
			)
			(layer "F.SilkS")
		)
		(fp_line
			(start 0.7874 -0.4064)
			(end 0.7874 0.4064)
			(stroke
				(width 0.1524)
				(type default)
			)
			(layer "F.SilkS")
		)
		(fp_line
			(start -0.67945 0.3048)
			(end -0.67945 -0.305054)
			(stroke
				(width 0.1)
				(type default)
			)
			(layer "F.Fab")
		)
		(fp_line
			(start -0.12065 0.3048)
			(end -0.67945 0.3048)
			(stroke
				(width 0.1)
				(type default)
			)
			(layer "F.Fab")
		)
		(fp_line
			(start 0.120396 0.3048)
			(end 0.120396 0.2794)
			(stroke
				(width 0.1)
				(type default)
			)
			(layer "F.Fab")
		)
		(fp_line
			(start 0.67945 0.3048)
			(end 0.120396 0.3048)
			(stroke
				(width 0.1)
				(type default)
			)
			(layer "F.Fab")
		)
		(fp_line
			(start -0.12065 0.2794)
			(end -0.12065 0.3048)
			(stroke
				(width 0.1)
				(type default)
			)
			(layer "F.Fab")
		)
		(fp_line
			(start 0.120396 0.2794)
			(end -0.12065 0.2794)
			(stroke
				(width 0.1)
				(type default)
			)
			(layer "F.Fab")
		)
		(fp_line
			(start -0.12065 -0.2794)
			(end 0.12065 -0.2794)
			(stroke
				(width 0.1)
				(type default)
			)
			(layer "F.Fab")
		)
		(fp_line
			(start 0.12065 -0.2794)
			(end 0.12065 -0.3048)
			(stroke
				(width 0.1)
				(type default)
			)
			(layer "F.Fab")
		)
		(fp_line
			(start 0.12065 -0.3048)
			(end 0.67945 -0.3048)
			(stroke
				(width 0.1)
				(type default)
			)
			(layer "F.Fab")
		)
		(fp_line
			(start 0.67945 -0.3048)
			(end 0.67945 0.3048)
			(stroke
				(width 0.1)
				(type default)
			)
			(layer "F.Fab")
		)
		(fp_line
			(start -0.67945 -0.305054)
			(end -0.12065 -0.305054)
			(stroke
				(width 0.1)
				(type default)
			)
			(layer "F.Fab")
		)
		(fp_line
			(start -0.12065 -0.305054)
			(end -0.12065 -0.2794)
			(stroke
				(width 0.1)
				(type default)
			)
			(layer "F.Fab")
		)
		(pad "1" smd circle
			(at -0.40005 0 270)
			(size 0 0)
			(layers "F.Cu" "F.Mask" "F.Paste")
			(net "V_DACR_R")
		)
		(pad "2" smd circle
			(at 0.40005 0 270)
			(size 0 0)
			(layers "F.Cu" "F.Mask" "F.Paste")
			(net "GND")
		)
	)
	(footprint ""
		(layer "F.Cu")
		(at 31.75 -31.115 180)
		(property "Reference" "U35"
			(at 1.016 3.30073 0)
			(unlocked yes)
			(layer "F.SilkS")
			(effects
				(font
					(size 0.7874 0.5842)
					(thickness 0.1524)
				)
				(justify left)
			)
		)
		(property "Value" ""
			(at 0 0 180)
			(layer "F.Fab")
			(effects
				(font
					(size 1.27 1.27)
				)
			)
		)
		(duplicate_pad_numbers_are_jumpers no)
		(fp_line
			(start 0.791464 1.287526)
			(end 0.791464 -1.287526)
			(stroke
				(width 0.1524)
				(type default)
			)
			(layer "F.SilkS")
		)
		(fp_line
			(start 0.791464 -1.287526)
			(end -0.791464 -1.287526)
			(stroke
				(width 0.1524)
				(type default)
			)
			(layer "F.SilkS")
		)
		(fp_line
			(start -0.791464 1.287526)
			(end 0.791464 1.287526)
			(stroke
				(width 0.1524)
				(type default)
			)
			(layer "F.SilkS")
		)
		(fp_line
			(start -0.791464 -1.287526)
			(end -0.791464 1.287526)
			(stroke
				(width 0.1524)
				(type default)
			)
			(layer "F.SilkS")
		)
		(fp_poly
			(pts
				(xy -1.651 -1.253998) (xy -1.651 -0.745998) (xy -1.143 -0.999998)
			)
			(stroke
				(width 0)
				(type default)
			)
			(fill yes)
			(layer "F.SilkS")
		)
		(fp_line
			(start 0.537464 1.287526)
			(end 0.537464 -1.287526)
			(stroke
				(width 0.1)
				(type default)
			)
			(layer "F.Fab")
		)
		(fp_line
			(start 0.537464 -1.287526)
			(end -0.537464 -1.287526)
			(stroke
				(width 0.1)
				(type default)
			)
			(layer "F.Fab")
		)
		(fp_line
			(start -0.537464 1.287526)
			(end 0.537464 1.287526)
			(stroke
				(width 0.1)
				(type default)
			)
			(layer "F.Fab")
		)
		(fp_line
			(start -0.537464 -1.287526)
			(end -0.537464 1.287526)
			(stroke
				(width 0.1)
				(type default)
			)
			(layer "F.Fab")
		)
		(fp_poly
			(pts
				(xy -1.651 -1.253998) (xy -1.651 -0.745998) (xy -1.143 -0.999998)
			)
			(stroke
				(width 0)
				(type default)
			)
			(fill yes)
			(layer "F.Fab")
		)
		(pad "1" smd rect
			(at -0.387604 -0.999998 270)
			(size 0.254 0.635)
			(layers "F.Cu" "F.Mask" "F.Paste")
			(net "V_DACB_IO")
		)
		(pad "2" smd rect
			(at -0.387604 -0.499872 270)
			(size 0.254 0.635)
			(layers "F.Cu" "F.Mask" "F.Paste")
			(net "V_DACG_IO")
		)
		(pad "3" smd rect
			(at -0.350012 0 270)
			(size 0.4572 0.6858)
			(layers "F.Cu" "F.Mask" "F.Paste")
			(net "GND")
		)
		(pad "4" smd rect
			(at -0.387604 0.499872 270)
			(size 0.254 0.635)
			(layers "F.Cu" "F.Mask" "F.Paste")
			(net "V_DACR_IO")
		)
		(pad "5" smd rect
			(at -0.387604 0.999998 270)
			(size 0.254 0.635)
			(layers "F.Cu" "F.Mask" "F.Paste")
			(net "TP4")
		)
		(pad "6" smd rect
			(at 0.387604 0.999998 270)
			(size 0.254 0.635)
			(layers "F.Cu" "F.Mask" "F.Paste")
			(net "TP_ESD_VGA_P4")
		)
		(pad "7" smd rect
			(at 0.387604 0.499872 270)
			(size 0.254 0.635)
			(layers "F.Cu" "F.Mask" "F.Paste")
			(net "V_DACR_IO")
		)
		(pad "8" smd rect
			(at 0.412496 0 270)
			(size 0.4572 0.5842)
			(layers "F.Cu" "F.Mask" "F.Paste")
			(net "GND")
		)
		(pad "9" smd rect
			(at 0.387604 -0.499872 270)
			(size 0.254 0.635)
			(layers "F.Cu" "F.Mask" "F.Paste")
			(net "V_DACG_IO")
		)
		(pad "10" smd rect
			(at 0.387604 -0.999998 270)
			(size 0.254 0.635)
			(layers "F.Cu" "F.Mask" "F.Paste")
			(net "V_DACB_IO")
		)
	)
	(footprint ""
		(layer "F.Cu")
		(at 52.578 -79.6544 180)
		(property "Reference" "U55"
			(at 2.8448 1.54813 0)
			(unlocked yes)
			(layer "F.SilkS")
			(effects
				(font
					(size 0.7874 0.5842)
					(thickness 0.1524)
				)
			)
		)
		(property "Value" ""
			(at 0 0 180)
			(layer "F.Fab")
			(effects
				(font
					(size 1.27 1.27)
				)
			)
		)
		(duplicate_pad_numbers_are_jumpers no)
		(fp_line
			(start 1.7018 1.1176)
			(end -1.7018 1.1176)
			(stroke
				(width 0.1524)
				(type default)
			)
			(layer "F.SilkS")
		)
		(fp_line
			(start 1.7018 -1.1176)
			(end 1.7018 1.1176)
			(stroke
				(width 0.1524)
				(type default)
			)
			(layer "F.SilkS")
		)
		(fp_line
			(start 1.7018 -1.1176)
			(end 0.254 -1.1176)
			(stroke
				(width 0.1524)
				(type default)
			)
			(layer "F.SilkS")
		)
		(fp_line
			(start 0.254 -1.1176)
			(end 0 -0.7112)
			(stroke
				(width 0.1524)
				(type default)
			)
			(layer "F.SilkS")
		)
		(fp_line
			(start 0 -0.7112)
			(end -0.254 -1.1176)
			(stroke
				(width 0.1524)
				(type default)
			)
			(layer "F.SilkS")
		)
		(fp_line
			(start -0.254 -1.1176)
			(end -1.7018 -1.1176)
			(stroke
				(width 0.1524)
				(type default)
			)
			(layer "F.SilkS")
		)
		(fp_line
			(start -1.7018 1.1176)
			(end -1.7018 -1.1176)
			(stroke
				(width 0.1524)
				(type default)
			)
			(layer "F.SilkS")
		)
		(fp_poly
			(pts
				(xy -1.8161 -0.675386) (xy -2.4003 -0.446786) (xy -2.4003 -0.878586)
			)
			(stroke
				(width 0)
				(type default)
			)
			(fill yes)
			(layer "F.SilkS")
		)
		(fp_line
			(start 1.5494 1.1176)
			(end -1.5494 1.1176)
			(stroke
				(width 0.1)
				(type default)
			)
			(layer "F.Fab")
		)
		(fp_line
			(start 1.5494 -1.1176)
			(end 1.5494 1.1176)
			(stroke
				(width 0.1)
				(type default)
			)
			(layer "F.Fab")
		)
		(fp_line
			(start 1.5494 -1.1176)
			(end 0.254 -1.1176)
			(stroke
				(width 0.1)
				(type default)
			)
			(layer "F.Fab")
		)
		(fp_line
			(start 0.254 -1.1176)
			(end -0.254 -1.1176)
			(stroke
				(width 0.1)
				(type default)
			)
			(layer "F.Fab")
		)
		(fp_line
			(start -0.254 -1.1176)
			(end -1.5494 -1.1176)
			(stroke
				(width 0.1)
				(type default)
			)
			(layer "F.Fab")
		)
		(fp_line
			(start -1.5494 1.1176)
			(end -1.5494 -1.1176)
			(stroke
				(width 0.1)
				(type default)
			)
			(layer "F.Fab")
		)
		(fp_poly
			(pts
				(xy -1.8161 -0.675386) (xy -2.4003 -0.446786) (xy -2.4003 -0.878586)
			)
			(stroke
				(width 0)
				(type default)
			)
			(fill yes)
			(layer "F.Fab")
		)
		(pad "1" smd rect
			(at -0.962406 -0.649986 90)
			(size 0.3302 1.1684)
			(layers "F.Cu" "F.Mask" "F.Paste")
			(net "NC_U55_P1")
		)
		(pad "2" smd rect
			(at -0.962406 0 90)
			(size 0.3302 1.1684)
			(layers "F.Cu" "F.Mask" "F.Paste")
			(net "FLASH_LATCH_Q_N_R2")
		)
		(pad "3" smd rect
			(at -0.962406 0.649986 90)
			(size 0.3302 1.1684)
			(layers "F.Cu" "F.Mask" "F.Paste")
			(net "GND")
		)
		(pad "4" smd rect
			(at 0.962406 0.649986 90)
			(size 0.3302 1.1684)
			(layers "F.Cu" "F.Mask" "F.Paste")
			(net "FLASH_R_WP_STATUS")
		)
		(pad "5" smd rect
			(at 0.962406 -0.649986 90)
			(size 0.3302 1.1684)
			(layers "F.Cu" "F.Mask" "F.Paste")
			(net "P3V3_AUX")
		)
	)
	(footprint ""
		(layer "F.Cu")
		(at 46.0756 -109.5248 -90)
		(property "Reference" "R64"
			(at 0 0 270)
			(layer "F.SilkS")
			(hide yes)
			(effects
				(font
					(size 1.27 1.27)
				)
			)
		)
		(property "Value" ""
			(at 0 0 270)
			(layer "F.Fab")
			(effects
				(font
					(size 1.27 1.27)
				)
			)
		)
		(duplicate_pad_numbers_are_jumpers no)
		(fp_line
			(start -0.7874 0.4064)
			(end -0.7874 -0.4064)
			(stroke
				(width 0.1524)
				(type default)
			)
			(layer "F.SilkS")
		)
		(fp_line
			(start 0.7874 0.4064)
			(end -0.7874 0.4064)
			(stroke
				(width 0.1524)
				(type default)
			)
			(layer "F.SilkS")
		)
		(fp_line
			(start -0.7874 -0.4064)
			(end 0.7874 -0.4064)
			(stroke
				(width 0.1524)
				(type default)
			)
			(layer "F.SilkS")
		)
		(fp_line
			(start 0.7874 -0.4064)
			(end 0.7874 0.4064)
			(stroke
				(width 0.1524)
				(type default)
			)
			(layer "F.SilkS")
		)
		(fp_line
			(start -0.67945 0.3048)
			(end -0.67945 -0.305054)
			(stroke
				(width 0.1)
				(type default)
			)
			(layer "F.Fab")
		)
		(fp_line
			(start -0.12065 0.3048)
			(end -0.67945 0.3048)
			(stroke
				(width 0.1)
				(type default)
			)
			(layer "F.Fab")
		)
		(fp_line
			(start 0.120396 0.3048)
			(end 0.120396 0.2794)
			(stroke
				(width 0.1)
				(type default)
			)
			(layer "F.Fab")
		)
		(fp_line
			(start 0.67945 0.3048)
			(end 0.120396 0.3048)
			(stroke
				(width 0.1)
				(type default)
			)
			(layer "F.Fab")
		)
		(fp_line
			(start -0.12065 0.2794)
			(end -0.12065 0.3048)
			(stroke
				(width 0.1)
				(type default)
			)
			(layer "F.Fab")
		)
		(fp_line
			(start 0.120396 0.2794)
			(end -0.12065 0.2794)
			(stroke
				(width 0.1)
				(type default)
			)
			(layer "F.Fab")
		)
		(fp_line
			(start -0.12065 -0.2794)
			(end 0.12065 -0.2794)
			(stroke
				(width 0.1)
				(type default)
			)
			(layer "F.Fab")
		)
		(fp_line
			(start 0.12065 -0.2794)
			(end 0.12065 -0.3048)
			(stroke
				(width 0.1)
				(type default)
			)
			(layer "F.Fab")
		)
		(fp_line
			(start 0.12065 -0.3048)
			(end 0.67945 -0.3048)
			(stroke
				(width 0.1)
				(type default)
			)
			(layer "F.Fab")
		)
		(fp_line
			(start 0.67945 -0.3048)
			(end 0.67945 0.3048)
			(stroke
				(width 0.1)
				(type default)
			)
			(layer "F.Fab")
		)
		(fp_line
			(start -0.67945 -0.305054)
			(end -0.12065 -0.305054)
			(stroke
				(width 0.1)
				(type default)
			)
			(layer "F.Fab")
		)
		(fp_line
			(start -0.12065 -0.305054)
			(end -0.12065 -0.2794)
			(stroke
				(width 0.1)
				(type default)
			)
			(layer "F.Fab")
		)
		(pad "1" smd circle
			(at -0.40005 0 270)
			(size 0 0)
			(layers "F.Cu" "F.Mask" "F.Paste")
			(net "SGPIO_CLK_0")
		)
		(pad "2" smd circle
			(at 0.40005 0 270)
			(size 0 0)
			(layers "F.Cu" "F.Mask" "F.Paste")
			(net "GND")
		)
	)
	(footprint ""
		(layer "F.Cu")
		(at 58.039 -87.9602 90)
		(property "Reference" "R140"
			(at 0 0 90)
			(layer "F.SilkS")
			(hide yes)
			(effects
				(font
					(size 1.27 1.27)
				)
			)
		)
		(property "Value" ""
			(at 0 0 90)
			(layer "F.Fab")
			(effects
				(font
					(size 1.27 1.27)
				)
			)
		)
		(duplicate_pad_numbers_are_jumpers no)
		(fp_line
			(start 0.7874 -0.4064)
			(end 0.7874 0.4064)
			(stroke
				(width 0.1524)
				(type default)
			)
			(layer "F.SilkS")
		)
		(fp_line
			(start -0.7874 -0.4064)
			(end 0.7874 -0.4064)
			(stroke
				(width 0.1524)
				(type default)
			)
			(layer "F.SilkS")
		)
		(fp_line
			(start 0.7874 0.4064)
			(end -0.7874 0.4064)
			(stroke
				(width 0.1524)
				(type default)
			)
			(layer "F.SilkS")
		)
		(fp_line
			(start -0.7874 0.4064)
			(end -0.7874 -0.4064)
			(stroke
				(width 0.1524)
				(type default)
			)
			(layer "F.SilkS")
		)
		(fp_line
			(start -0.12065 -0.305054)
			(end -0.12065 -0.2794)
			(stroke
				(width 0.1)
				(type default)
			)
			(layer "F.Fab")
		)
		(fp_line
			(start -0.67945 -0.305054)
			(end -0.12065 -0.305054)
			(stroke
				(width 0.1)
				(type default)
			)
			(layer "F.Fab")
		)
		(fp_line
			(start 0.67945 -0.3048)
			(end 0.67945 0.3048)
			(stroke
				(width 0.1)
				(type default)
			)
			(layer "F.Fab")
		)
		(fp_line
			(start 0.12065 -0.3048)
			(end 0.67945 -0.3048)
			(stroke
				(width 0.1)
				(type default)
			)
			(layer "F.Fab")
		)
		(fp_line
			(start 0.12065 -0.2794)
			(end 0.12065 -0.3048)
			(stroke
				(width 0.1)
				(type default)
			)
			(layer "F.Fab")
		)
		(fp_line
			(start -0.12065 -0.2794)
			(end 0.12065 -0.2794)
			(stroke
				(width 0.1)
				(type default)
			)
			(layer "F.Fab")
		)
		(fp_line
			(start 0.120396 0.2794)
			(end -0.12065 0.2794)
			(stroke
				(width 0.1)
				(type default)
			)
			(layer "F.Fab")
		)
		(fp_line
			(start -0.12065 0.2794)
			(end -0.12065 0.3048)
			(stroke
				(width 0.1)
				(type default)
			)
			(layer "F.Fab")
		)
		(fp_line
			(start 0.67945 0.3048)
			(end 0.120396 0.3048)
			(stroke
				(width 0.1)
				(type default)
			)
			(layer "F.Fab")
		)
		(fp_line
			(start 0.120396 0.3048)
			(end 0.120396 0.2794)
			(stroke
				(width 0.1)
				(type default)
			)
			(layer "F.Fab")
		)
		(fp_line
			(start -0.12065 0.3048)
			(end -0.67945 0.3048)
			(stroke
				(width 0.1)
				(type default)
			)
			(layer "F.Fab")
		)
		(fp_line
			(start -0.67945 0.3048)
			(end -0.67945 -0.305054)
			(stroke
				(width 0.1)
				(type default)
			)
			(layer "F.Fab")
		)
		(pad "1" smd circle
			(at -0.40005 0 90)
			(size 0 0)
			(layers "F.Cu" "F.Mask" "F.Paste")
			(net "P3V3_AUX")
		)
		(pad "2" smd circle
			(at 0.40005 0 90)
			(size 0 0)
			(layers "F.Cu" "F.Mask" "F.Paste")
			(net "SPI_BMC_BOOT_MOSI")
		)
	)
	(footprint ""
		(layer "F.Cu")
		(at 69.4055 -69.596 -90)
		(property "Reference" "R460"
			(at 0 0 270)
			(layer "F.SilkS")
			(hide yes)
			(effects
				(font
					(size 1.27 1.27)
				)
			)
		)
		(property "Value" ""
			(at 0 0 270)
			(layer "F.Fab")
			(effects
				(font
					(size 1.27 1.27)
				)
			)
		)
		(duplicate_pad_numbers_are_jumpers no)
		(fp_line
			(start -0.7874 0.4064)
			(end -0.7874 -0.4064)
			(stroke
				(width 0.1524)
				(type default)
			)
			(layer "F.SilkS")
		)
		(fp_line
			(start 0.7874 0.4064)
			(end -0.7874 0.4064)
			(stroke
				(width 0.1524)
				(type default)
			)
			(layer "F.SilkS")
		)
		(fp_line
			(start -0.7874 -0.4064)
			(end 0.7874 -0.4064)
			(stroke
				(width 0.1524)
				(type default)
			)
			(layer "F.SilkS")
		)
		(fp_line
			(start 0.7874 -0.4064)
			(end 0.7874 0.4064)
			(stroke
				(width 0.1524)
				(type default)
			)
			(layer "F.SilkS")
		)
		(fp_line
			(start -0.67945 0.3048)
			(end -0.67945 -0.305054)
			(stroke
				(width 0.1)
				(type default)
			)
			(layer "F.Fab")
		)
		(fp_line
			(start -0.12065 0.3048)
			(end -0.67945 0.3048)
			(stroke
				(width 0.1)
				(type default)
			)
			(layer "F.Fab")
		)
		(fp_line
			(start 0.120396 0.3048)
			(end 0.120396 0.2794)
			(stroke
				(width 0.1)
				(type default)
			)
			(layer "F.Fab")
		)
		(fp_line
			(start 0.67945 0.3048)
			(end 0.120396 0.3048)
			(stroke
				(width 0.1)
				(type default)
			)
			(layer "F.Fab")
		)
		(fp_line
			(start -0.12065 0.2794)
			(end -0.12065 0.3048)
			(stroke
				(width 0.1)
				(type default)
			)
			(layer "F.Fab")
		)
		(fp_line
			(start 0.120396 0.2794)
			(end -0.12065 0.2794)
			(stroke
				(width 0.1)
				(type default)
			)
			(layer "F.Fab")
		)
		(fp_line
			(start -0.12065 -0.2794)
			(end 0.12065 -0.2794)
			(stroke
				(width 0.1)
				(type default)
			)
			(layer "F.Fab")
		)
		(fp_line
			(start 0.12065 -0.2794)
			(end 0.12065 -0.3048)
			(stroke
				(width 0.1)
				(type default)
			)
			(layer "F.Fab")
		)
		(fp_line
			(start 0.12065 -0.3048)
			(end 0.67945 -0.3048)
			(stroke
				(width 0.1)
				(type default)
			)
			(layer "F.Fab")
		)
		(fp_line
			(start 0.67945 -0.3048)
			(end 0.67945 0.3048)
			(stroke
				(width 0.1)
				(type default)
			)
			(layer "F.Fab")
		)
		(fp_line
			(start -0.67945 -0.305054)
			(end -0.12065 -0.305054)
			(stroke
				(width 0.1)
				(type default)
			)
			(layer "F.Fab")
		)
		(fp_line
			(start -0.12065 -0.305054)
			(end -0.12065 -0.2794)
			(stroke
				(width 0.1)
				(type default)
			)
			(layer "F.Fab")
		)
		(pad "1" smd circle
			(at -0.40005 0 270)
			(size 0 0)
			(layers "F.Cu" "F.Mask" "F.Paste")
			(net "SPI_BMC_TPM_CS2_R_N")
		)
		(pad "2" smd circle
			(at 0.40005 0 270)
			(size 0 0)
			(layers "F.Cu" "F.Mask" "F.Paste")
			(net "SPI_BMC_TPM_CS2_R1_N")
		)
	)
	(footprint ""
		(layer "F.Cu")
		(at 37.6936 -42.1894 -90)
		(property "Reference" "R268"
			(at 0 0 270)
			(layer "F.SilkS")
			(hide yes)
			(effects
				(font
					(size 1.27 1.27)
				)
			)
		)
		(property "Value" ""
			(at 0 0 270)
			(layer "F.Fab")
			(effects
				(font
					(size 1.27 1.27)
				)
			)
		)
		(duplicate_pad_numbers_are_jumpers no)
		(fp_line
			(start -0.7874 0.4064)
			(end -0.7874 -0.4064)
			(stroke
				(width 0.1524)
				(type default)
			)
			(layer "F.SilkS")
		)
		(fp_line
			(start 0.7874 0.4064)
			(end -0.7874 0.4064)
			(stroke
				(width 0.1524)
				(type default)
			)
			(layer "F.SilkS")
		)
		(fp_line
			(start -0.7874 -0.4064)
			(end 0.7874 -0.4064)
			(stroke
				(width 0.1524)
				(type default)
			)
			(layer "F.SilkS")
		)
		(fp_line
			(start 0.7874 -0.4064)
			(end 0.7874 0.4064)
			(stroke
				(width 0.1524)
				(type default)
			)
			(layer "F.SilkS")
		)
		(fp_line
			(start -0.67945 0.3048)
			(end -0.67945 -0.305054)
			(stroke
				(width 0.1)
				(type default)
			)
			(layer "F.Fab")
		)
		(fp_line
			(start -0.12065 0.3048)
			(end -0.67945 0.3048)
			(stroke
				(width 0.1)
				(type default)
			)
			(layer "F.Fab")
		)
		(fp_line
			(start 0.120396 0.3048)
			(end 0.120396 0.2794)
			(stroke
				(width 0.1)
				(type default)
			)
			(layer "F.Fab")
		)
		(fp_line
			(start 0.67945 0.3048)
			(end 0.120396 0.3048)
			(stroke
				(width 0.1)
				(type default)
			)
			(layer "F.Fab")
		)
		(fp_line
			(start -0.12065 0.2794)
			(end -0.12065 0.3048)
			(stroke
				(width 0.1)
				(type default)
			)
			(layer "F.Fab")
		)
		(fp_line
			(start 0.120396 0.2794)
			(end -0.12065 0.2794)
			(stroke
				(width 0.1)
				(type default)
			)
			(layer "F.Fab")
		)
		(fp_line
			(start -0.12065 -0.2794)
			(end 0.12065 -0.2794)
			(stroke
				(width 0.1)
				(type default)
			)
			(layer "F.Fab")
		)
		(fp_line
			(start 0.12065 -0.2794)
			(end 0.12065 -0.3048)
			(stroke
				(width 0.1)
				(type default)
			)
			(layer "F.Fab")
		)
		(fp_line
			(start 0.12065 -0.3048)
			(end 0.67945 -0.3048)
			(stroke
				(width 0.1)
				(type default)
			)
			(layer "F.Fab")
		)
		(fp_line
			(start 0.67945 -0.3048)
			(end 0.67945 0.3048)
			(stroke
				(width 0.1)
				(type default)
			)
			(layer "F.Fab")
		)
		(fp_line
			(start -0.67945 -0.305054)
			(end -0.12065 -0.305054)
			(stroke
				(width 0.1)
				(type default)
			)
			(layer "F.Fab")
		)
		(fp_line
			(start -0.12065 -0.305054)
			(end -0.12065 -0.2794)
			(stroke
				(width 0.1)
				(type default)
			)
			(layer "F.Fab")
		)
		(pad "1" smd circle
			(at -0.40005 0 270)
			(size 0 0)
			(layers "F.Cu" "F.Mask" "F.Paste")
			(net "P3V3_AUX")
		)
		(pad "2" smd circle
			(at 0.40005 0 270)
			(size 0 0)
			(layers "F.Cu" "F.Mask" "F.Paste")
			(net "SMB_BMC_ALERT3_N")
		)
	)
	(footprint ""
		(layer "F.Cu")
		(at 29.591 -102.7684 -90)
		(property "Reference" "R45"
			(at 0 0 270)
			(layer "F.SilkS")
			(hide yes)
			(effects
				(font
					(size 1.27 1.27)
				)
			)
		)
		(property "Value" ""
			(at 0 0 270)
			(layer "F.Fab")
			(effects
				(font
					(size 1.27 1.27)
				)
			)
		)
		(duplicate_pad_numbers_are_jumpers no)
		(fp_line
			(start -0.7874 0.4064)
			(end -0.7874 -0.4064)
			(stroke
				(width 0.1524)
				(type default)
			)
			(layer "F.SilkS")
		)
		(fp_line
			(start 0.7874 0.4064)
			(end -0.7874 0.4064)
			(stroke
				(width 0.1524)
				(type default)
			)
			(layer "F.SilkS")
		)
		(fp_line
			(start -0.7874 -0.4064)
			(end 0.7874 -0.4064)
			(stroke
				(width 0.1524)
				(type default)
			)
			(layer "F.SilkS")
		)
		(fp_line
			(start 0.7874 -0.4064)
			(end 0.7874 0.4064)
			(stroke
				(width 0.1524)
				(type default)
			)
			(layer "F.SilkS")
		)
		(fp_line
			(start -0.67945 0.3048)
			(end -0.67945 -0.305054)
			(stroke
				(width 0.1)
				(type default)
			)
			(layer "F.Fab")
		)
		(fp_line
			(start -0.12065 0.3048)
			(end -0.67945 0.3048)
			(stroke
				(width 0.1)
				(type default)
			)
			(layer "F.Fab")
		)
		(fp_line
			(start 0.120396 0.3048)
			(end 0.120396 0.2794)
			(stroke
				(width 0.1)
				(type default)
			)
			(layer "F.Fab")
		)
		(fp_line
			(start 0.67945 0.3048)
			(end 0.120396 0.3048)
			(stroke
				(width 0.1)
				(type default)
			)
			(layer "F.Fab")
		)
		(fp_line
			(start -0.12065 0.2794)
			(end -0.12065 0.3048)
			(stroke
				(width 0.1)
				(type default)
			)
			(layer "F.Fab")
		)
		(fp_line
			(start 0.120396 0.2794)
			(end -0.12065 0.2794)
			(stroke
				(width 0.1)
				(type default)
			)
			(layer "F.Fab")
		)
		(fp_line
			(start -0.12065 -0.2794)
			(end 0.12065 -0.2794)
			(stroke
				(width 0.1)
				(type default)
			)
			(layer "F.Fab")
		)
		(fp_line
			(start 0.12065 -0.2794)
			(end 0.12065 -0.3048)
			(stroke
				(width 0.1)
				(type default)
			)
			(layer "F.Fab")
		)
		(fp_line
			(start 0.12065 -0.3048)
			(end 0.67945 -0.3048)
			(stroke
				(width 0.1)
				(type default)
			)
			(layer "F.Fab")
		)
		(fp_line
			(start 0.67945 -0.3048)
			(end 0.67945 0.3048)
			(stroke
				(width 0.1)
				(type default)
			)
			(layer "F.Fab")
		)
		(fp_line
			(start -0.67945 -0.305054)
			(end -0.12065 -0.305054)
			(stroke
				(width 0.1)
				(type default)
			)
			(layer "F.Fab")
		)
		(fp_line
			(start -0.12065 -0.305054)
			(end -0.12065 -0.2794)
			(stroke
				(width 0.1)
				(type default)
			)
			(layer "F.Fab")
		)
		(pad "1" smd circle
			(at -0.40005 0 270)
			(size 0 0)
			(layers "F.Cu" "F.Mask" "F.Paste")
			(net "P3V3_AUX")
		)
		(pad "2" smd circle
			(at 0.40005 0 270)
			(size 0 0)
			(layers "F.Cu" "F.Mask" "F.Paste")
			(net "FM_THROTTLE_N")
		)
	)
	(footprint ""
		(layer "F.Cu")
		(at 41.7576 -30.861 90)
		(property "Reference" "R455"
			(at 0 0 90)
			(layer "F.SilkS")
			(hide yes)
			(effects
				(font
					(size 1.27 1.27)
				)
			)
		)
		(property "Value" ""
			(at 0 0 90)
			(layer "F.Fab")
			(effects
				(font
					(size 1.27 1.27)
				)
			)
		)
		(duplicate_pad_numbers_are_jumpers no)
		(fp_line
			(start 0.7874 -0.4064)
			(end 0.7874 0.4064)
			(stroke
				(width 0.1524)
				(type default)
			)
			(layer "F.SilkS")
		)
		(fp_line
			(start -0.7874 -0.4064)
			(end 0.7874 -0.4064)
			(stroke
				(width 0.1524)
				(type default)
			)
			(layer "F.SilkS")
		)
		(fp_line
			(start 0.7874 0.4064)
			(end -0.7874 0.4064)
			(stroke
				(width 0.1524)
				(type default)
			)
			(layer "F.SilkS")
		)
		(fp_line
			(start -0.7874 0.4064)
			(end -0.7874 -0.4064)
			(stroke
				(width 0.1524)
				(type default)
			)
			(layer "F.SilkS")
		)
		(fp_line
			(start -0.12065 -0.305054)
			(end -0.12065 -0.2794)
			(stroke
				(width 0.1)
				(type default)
			)
			(layer "F.Fab")
		)
		(fp_line
			(start -0.67945 -0.305054)
			(end -0.12065 -0.305054)
			(stroke
				(width 0.1)
				(type default)
			)
			(layer "F.Fab")
		)
		(fp_line
			(start 0.67945 -0.3048)
			(end 0.67945 0.3048)
			(stroke
				(width 0.1)
				(type default)
			)
			(layer "F.Fab")
		)
		(fp_line
			(start 0.12065 -0.3048)
			(end 0.67945 -0.3048)
			(stroke
				(width 0.1)
				(type default)
			)
			(layer "F.Fab")
		)
		(fp_line
			(start 0.12065 -0.2794)
			(end 0.12065 -0.3048)
			(stroke
				(width 0.1)
				(type default)
			)
			(layer "F.Fab")
		)
		(fp_line
			(start -0.12065 -0.2794)
			(end 0.12065 -0.2794)
			(stroke
				(width 0.1)
				(type default)
			)
			(layer "F.Fab")
		)
		(fp_line
			(start 0.120396 0.2794)
			(end -0.12065 0.2794)
			(stroke
				(width 0.1)
				(type default)
			)
			(layer "F.Fab")
		)
		(fp_line
			(start -0.12065 0.2794)
			(end -0.12065 0.3048)
			(stroke
				(width 0.1)
				(type default)
			)
			(layer "F.Fab")
		)
		(fp_line
			(start 0.67945 0.3048)
			(end 0.120396 0.3048)
			(stroke
				(width 0.1)
				(type default)
			)
			(layer "F.Fab")
		)
		(fp_line
			(start 0.120396 0.3048)
			(end 0.120396 0.2794)
			(stroke
				(width 0.1)
				(type default)
			)
			(layer "F.Fab")
		)
		(fp_line
			(start -0.12065 0.3048)
			(end -0.67945 0.3048)
			(stroke
				(width 0.1)
				(type default)
			)
			(layer "F.Fab")
		)
		(fp_line
			(start -0.67945 0.3048)
			(end -0.67945 -0.305054)
			(stroke
				(width 0.1)
				(type default)
			)
			(layer "F.Fab")
		)
		(pad "1" smd circle
			(at -0.40005 0 90)
			(size 0 0)
			(layers "F.Cu" "F.Mask" "F.Paste")
			(net "SMB_BMC_MM2_SCL")
		)
		(pad "2" smd circle
			(at 0.40005 0 90)
			(size 0 0)
			(layers "F.Cu" "F.Mask" "F.Paste")
			(net "SMB_BMC_MM2_SCL_R1")
		)
	)
	(footprint ""
		(layer "F.Cu")
		(at 12.319 -91.44 180)
		(property "Reference" "R888"
			(at 0 0 180)
			(layer "F.SilkS")
			(hide yes)
			(effects
				(font
					(size 1.27 1.27)
				)
			)
		)
		(property "Value" ""
			(at 0 0 180)
			(layer "F.Fab")
			(effects
				(font
					(size 1.27 1.27)
				)
			)
		)
		(duplicate_pad_numbers_are_jumpers no)
		(fp_line
			(start 0.7874 0.4064)
			(end -0.7874 0.4064)
			(stroke
				(width 0.1524)
				(type default)
			)
			(layer "F.SilkS")
		)
		(fp_line
			(start 0.7874 -0.4064)
			(end 0.7874 0.4064)
			(stroke
				(width 0.1524)
				(type default)
			)
			(layer "F.SilkS")
		)
		(fp_line
			(start -0.7874 0.4064)
			(end -0.7874 -0.4064)
			(stroke
				(width 0.1524)
				(type default)
			)
			(layer "F.SilkS")
		)
		(fp_line
			(start -0.7874 -0.4064)
			(end 0.7874 -0.4064)
			(stroke
				(width 0.1524)
				(type default)
			)
			(layer "F.SilkS")
		)
		(fp_line
			(start 0.67945 0.3048)
			(end 0.120396 0.3048)
			(stroke
				(width 0.1)
				(type default)
			)
			(layer "F.Fab")
		)
		(fp_line
			(start 0.67945 -0.3048)
			(end 0.67945 0.3048)
			(stroke
				(width 0.1)
				(type default)
			)
			(layer "F.Fab")
		)
		(fp_line
			(start 0.12065 -0.2794)
			(end 0.12065 -0.3048)
			(stroke
				(width 0.1)
				(type default)
			)
			(layer "F.Fab")
		)
		(fp_line
			(start 0.12065 -0.3048)
			(end 0.67945 -0.3048)
			(stroke
				(width 0.1)
				(type default)
			)
			(layer "F.Fab")
		)
		(fp_line
			(start 0.120396 0.3048)
			(end 0.120396 0.2794)
			(stroke
				(width 0.1)
				(type default)
			)
			(layer "F.Fab")
		)
		(fp_line
			(start 0.120396 0.2794)
			(end -0.12065 0.2794)
			(stroke
				(width 0.1)
				(type default)
			)
			(layer "F.Fab")
		)
		(fp_line
			(start -0.12065 0.3048)
			(end -0.67945 0.3048)
			(stroke
				(width 0.1)
				(type default)
			)
			(layer "F.Fab")
		)
		(fp_line
			(start -0.12065 0.2794)
			(end -0.12065 0.3048)
			(stroke
				(width 0.1)
				(type default)
			)
			(layer "F.Fab")
		)
		(fp_line
			(start -0.12065 -0.2794)
			(end 0.12065 -0.2794)
			(stroke
				(width 0.1)
				(type default)
			)
			(layer "F.Fab")
		)
		(fp_line
			(start -0.12065 -0.305054)
			(end -0.12065 -0.2794)
			(stroke
				(width 0.1)
				(type default)
			)
			(layer "F.Fab")
		)
		(fp_line
			(start -0.67945 0.3048)
			(end -0.67945 -0.305054)
			(stroke
				(width 0.1)
				(type default)
			)
			(layer "F.Fab")
		)
		(fp_line
			(start -0.67945 -0.305054)
			(end -0.12065 -0.305054)
			(stroke
				(width 0.1)
				(type default)
			)
			(layer "F.Fab")
		)
		(pad "1" smd rect
			(at -0.40005 0)
			(size 0.4572 0.508)
			(layers "F.Cu" "F.Mask" "F.Paste")
			(net "P3V3_AUX")
		)
		(pad "2" smd rect
			(at 0.40005 0)
			(size 0.4572 0.508)
			(layers "F.Cu" "F.Mask" "F.Paste")
			(net "RST_BMC_SELF_HW")
		)
	)
	(footprint ""
		(layer "F.Cu")
		(at 11.171936 -54.538372 180)
		(property "Reference" "PR241"
			(at 0 0 180)
			(layer "F.SilkS")
			(hide yes)
			(effects
				(font
					(size 1.27 1.27)
				)
			)
		)
		(property "Value" ""
			(at 0 0 180)
			(layer "F.Fab")
			(effects
				(font
					(size 1.27 1.27)
				)
			)
		)
		(duplicate_pad_numbers_are_jumpers no)
		(fp_line
			(start 0.7874 0.4064)
			(end -0.7874 0.4064)
			(stroke
				(width 0.1524)
				(type default)
			)
			(layer "F.SilkS")
		)
		(fp_line
			(start 0.7874 -0.4064)
			(end 0.7874 0.4064)
			(stroke
				(width 0.1524)
				(type default)
			)
			(layer "F.SilkS")
		)
		(fp_line
			(start -0.7874 0.4064)
			(end -0.7874 -0.4064)
			(stroke
				(width 0.1524)
				(type default)
			)
			(layer "F.SilkS")
		)
		(fp_line
			(start -0.7874 -0.4064)
			(end 0.7874 -0.4064)
			(stroke
				(width 0.1524)
				(type default)
			)
			(layer "F.SilkS")
		)
		(fp_line
			(start 0.67945 0.3048)
			(end 0.120396 0.3048)
			(stroke
				(width 0.1)
				(type default)
			)
			(layer "F.Fab")
		)
		(fp_line
			(start 0.67945 -0.3048)
			(end 0.67945 0.3048)
			(stroke
				(width 0.1)
				(type default)
			)
			(layer "F.Fab")
		)
		(fp_line
			(start 0.12065 -0.2794)
			(end 0.12065 -0.3048)
			(stroke
				(width 0.1)
				(type default)
			)
			(layer "F.Fab")
		)
		(fp_line
			(start 0.12065 -0.3048)
			(end 0.67945 -0.3048)
			(stroke
				(width 0.1)
				(type default)
			)
			(layer "F.Fab")
		)
		(fp_line
			(start 0.120396 0.3048)
			(end 0.120396 0.2794)
			(stroke
				(width 0.1)
				(type default)
			)
			(layer "F.Fab")
		)
		(fp_line
			(start 0.120396 0.2794)
			(end -0.12065 0.2794)
			(stroke
				(width 0.1)
				(type default)
			)
			(layer "F.Fab")
		)
		(fp_line
			(start -0.12065 0.3048)
			(end -0.67945 0.3048)
			(stroke
				(width 0.1)
				(type default)
			)
			(layer "F.Fab")
		)
		(fp_line
			(start -0.12065 0.2794)
			(end -0.12065 0.3048)
			(stroke
				(width 0.1)
				(type default)
			)
			(layer "F.Fab")
		)
		(fp_line
			(start -0.12065 -0.2794)
			(end 0.12065 -0.2794)
			(stroke
				(width 0.1)
				(type default)
			)
			(layer "F.Fab")
		)
		(fp_line
			(start -0.12065 -0.305054)
			(end -0.12065 -0.2794)
			(stroke
				(width 0.1)
				(type default)
			)
			(layer "F.Fab")
		)
		(fp_line
			(start -0.67945 0.3048)
			(end -0.67945 -0.305054)
			(stroke
				(width 0.1)
				(type default)
			)
			(layer "F.Fab")
		)
		(fp_line
			(start -0.67945 -0.305054)
			(end -0.12065 -0.305054)
			(stroke
				(width 0.1)
				(type default)
			)
			(layer "F.Fab")
		)
		(pad "1" smd circle
			(at -0.40005 0 180)
			(size 0 0)
			(layers "F.Cu" "F.Mask" "F.Paste")
			(net "P5V_AUX_VCC")
		)
		(pad "2" smd circle
			(at 0.40005 0 180)
			(size 0 0)
			(layers "F.Cu" "F.Mask" "F.Paste")
			(net "PWRGD_P5V_AUX_R")
		)
	)
	(footprint ""
		(layer "F.Cu")
		(at 22.225 -62.3062 90)
		(property "Reference" "U50"
			(at -3.40487 1.016 0)
			(unlocked yes)
			(layer "F.SilkS")
			(effects
				(font
					(size 0.7874 0.5842)
					(thickness 0.1524)
				)
			)
		)
		(property "Value" ""
			(at 0 0 90)
			(layer "F.Fab")
			(effects
				(font
					(size 1.27 1.27)
				)
			)
		)
		(duplicate_pad_numbers_are_jumpers no)
		(fp_line
			(start 1.7272 -1.1176)
			(end 0.254 -1.1176)
			(stroke
				(width 0.1524)
				(type default)
			)
			(layer "F.SilkS")
		)
		(fp_line
			(start 1.7272 -1.1176)
			(end 1.7272 1.1176)
			(stroke
				(width 0.1524)
				(type default)
			)
			(layer "F.SilkS")
		)
		(fp_line
			(start 0.254 -1.1176)
			(end 0 -0.7366)
			(stroke
				(width 0.1524)
				(type default)
			)
			(layer "F.SilkS")
		)
		(fp_line
			(start -0.254 -1.1176)
			(end -1.7272 -1.1176)
			(stroke
				(width 0.1524)
				(type default)
			)
			(layer "F.SilkS")
		)
		(fp_line
			(start 0 -0.7366)
			(end -0.254 -1.1176)
			(stroke
				(width 0.1524)
				(type default)
			)
			(layer "F.SilkS")
		)
		(fp_line
			(start 1.7272 1.1176)
			(end -1.7272 1.1176)
			(stroke
				(width 0.1524)
				(type default)
			)
			(layer "F.SilkS")
		)
		(fp_line
			(start -1.7272 1.1176)
			(end -1.7272 -1.1176)
			(stroke
				(width 0.1524)
				(type default)
			)
			(layer "F.SilkS")
		)
		(fp_poly
			(pts
				(xy -1.9558 -0.649986) (xy -2.7178 -0.268986) (xy -2.7178 -1.030986)
			)
			(stroke
				(width 0)
				(type default)
			)
			(fill yes)
			(layer "F.SilkS")
		)
		(fp_line
			(start 1.5748 -1.1176)
			(end -1.5748 -1.1176)
			(stroke
				(width 0.1)
				(type default)
			)
			(layer "F.Fab")
		)
		(fp_line
			(start -1.5748 -1.1176)
			(end -1.5748 1.1176)
			(stroke
				(width 0.1)
				(type default)
			)
			(layer "F.Fab")
		)
		(fp_line
			(start 1.5748 1.1176)
			(end 1.5748 -1.1176)
			(stroke
				(width 0.1)
				(type default)
			)
			(layer "F.Fab")
		)
		(fp_line
			(start -1.5748 1.1176)
			(end 1.5748 1.1176)
			(stroke
				(width 0.1)
				(type default)
			)
			(layer "F.Fab")
		)
		(fp_poly
			(pts
				(xy -1.9558 -0.649986) (xy -2.7178 -0.268986) (xy -2.7178 -1.030986)
			)
			(stroke
				(width 0)
				(type default)
			)
			(fill yes)
			(layer "F.Fab")
		)
		(pad "1" smd rect
			(at -0.999998 -0.649986)
			(size 0.3556 1.1176)
			(layers "F.Cu" "F.Mask" "F.Paste")
			(net "UART_BIC_DBG_TX_R")
		)
		(pad "2" smd rect
			(at -0.999998 0)
			(size 0.3556 1.1176)
			(layers "F.Cu" "F.Mask" "F.Paste")
			(net "GND")
		)
		(pad "3" smd rect
			(at -0.999998 0.649986)
			(size 0.3556 1.1176)
			(layers "F.Cu" "F.Mask" "F.Paste")
			(net "UART_6_BMC_RXD_R")
		)
		(pad "4" smd rect
			(at 0.999998 0.649986)
			(size 0.3556 1.1176)
			(layers "F.Cu" "F.Mask" "F.Paste")
			(net "UART_BIC_GF_RXD")
		)
		(pad "5" smd rect
			(at 0.999998 0)
			(size 0.3556 1.1176)
			(layers "F.Cu" "F.Mask" "F.Paste")
			(net "P3V3_AUX")
		)
		(pad "6" smd rect
			(at 0.999998 -0.649986)
			(size 0.3556 1.1176)
			(layers "F.Cu" "F.Mask" "F.Paste")
			(net "FM_BIC_DEBUG_SW_N")
		)
	)
	(footprint ""
		(layer "F.Cu")
		(at 27.1272 -21.971 -90)
		(property "Reference" "R91"
			(at 0 0 270)
			(layer "F.SilkS")
			(hide yes)
			(effects
				(font
					(size 1.27 1.27)
				)
			)
		)
		(property "Value" ""
			(at 0 0 270)
			(layer "F.Fab")
			(effects
				(font
					(size 1.27 1.27)
				)
			)
		)
		(duplicate_pad_numbers_are_jumpers no)
		(fp_line
			(start -0.7874 0.4064)
			(end -0.7874 -0.4064)
			(stroke
				(width 0.1524)
				(type default)
			)
			(layer "F.SilkS")
		)
		(fp_line
			(start 0.7874 0.4064)
			(end -0.7874 0.4064)
			(stroke
				(width 0.1524)
				(type default)
			)
			(layer "F.SilkS")
		)
		(fp_line
			(start -0.7874 -0.4064)
			(end 0.7874 -0.4064)
			(stroke
				(width 0.1524)
				(type default)
			)
			(layer "F.SilkS")
		)
		(fp_line
			(start 0.7874 -0.4064)
			(end 0.7874 0.4064)
			(stroke
				(width 0.1524)
				(type default)
			)
			(layer "F.SilkS")
		)
		(fp_line
			(start -0.67945 0.3048)
			(end -0.67945 -0.305054)
			(stroke
				(width 0.1)
				(type default)
			)
			(layer "F.Fab")
		)
		(fp_line
			(start -0.12065 0.3048)
			(end -0.67945 0.3048)
			(stroke
				(width 0.1)
				(type default)
			)
			(layer "F.Fab")
		)
		(fp_line
			(start 0.120396 0.3048)
			(end 0.120396 0.2794)
			(stroke
				(width 0.1)
				(type default)
			)
			(layer "F.Fab")
		)
		(fp_line
			(start 0.67945 0.3048)
			(end 0.120396 0.3048)
			(stroke
				(width 0.1)
				(type default)
			)
			(layer "F.Fab")
		)
		(fp_line
			(start -0.12065 0.2794)
			(end -0.12065 0.3048)
			(stroke
				(width 0.1)
				(type default)
			)
			(layer "F.Fab")
		)
		(fp_line
			(start 0.120396 0.2794)
			(end -0.12065 0.2794)
			(stroke
				(width 0.1)
				(type default)
			)
			(layer "F.Fab")
		)
		(fp_line
			(start -0.12065 -0.2794)
			(end 0.12065 -0.2794)
			(stroke
				(width 0.1)
				(type default)
			)
			(layer "F.Fab")
		)
		(fp_line
			(start 0.12065 -0.2794)
			(end 0.12065 -0.3048)
			(stroke
				(width 0.1)
				(type default)
			)
			(layer "F.Fab")
		)
		(fp_line
			(start 0.12065 -0.3048)
			(end 0.67945 -0.3048)
			(stroke
				(width 0.1)
				(type default)
			)
			(layer "F.Fab")
		)
		(fp_line
			(start 0.67945 -0.3048)
			(end 0.67945 0.3048)
			(stroke
				(width 0.1)
				(type default)
			)
			(layer "F.Fab")
		)
		(fp_line
			(start -0.67945 -0.305054)
			(end -0.12065 -0.305054)
			(stroke
				(width 0.1)
				(type default)
			)
			(layer "F.Fab")
		)
		(fp_line
			(start -0.12065 -0.305054)
			(end -0.12065 -0.2794)
			(stroke
				(width 0.1)
				(type default)
			)
			(layer "F.Fab")
		)
		(pad "1" smd circle
			(at -0.40005 0 270)
			(size 0 0)
			(layers "F.Cu" "F.Mask" "F.Paste")
			(net "CRT_VCC5")
		)
		(pad "2" smd circle
			(at 0.40005 0 270)
			(size 0 0)
			(layers "F.Cu" "F.Mask" "F.Paste")
			(net "V_BMC_LS_DDC_SDA")
		)
	)
	(footprint ""
		(layer "F.Cu")
		(at 41.913302 -63.756794 90)
		(property "Reference" "R201"
			(at 0 0 90)
			(layer "F.SilkS")
			(hide yes)
			(effects
				(font
					(size 1.27 1.27)
				)
			)
		)
		(property "Value" ""
			(at 0 0 90)
			(layer "F.Fab")
			(effects
				(font
					(size 1.27 1.27)
				)
			)
		)
		(duplicate_pad_numbers_are_jumpers no)
		(fp_line
			(start 0.7874 -0.4064)
			(end 0.7874 0.4064)
			(stroke
				(width 0.1524)
				(type default)
			)
			(layer "F.SilkS")
		)
		(fp_line
			(start -0.7874 -0.4064)
			(end 0.7874 -0.4064)
			(stroke
				(width 0.1524)
				(type default)
			)
			(layer "F.SilkS")
		)
		(fp_line
			(start 0.7874 0.4064)
			(end -0.7874 0.4064)
			(stroke
				(width 0.1524)
				(type default)
			)
			(layer "F.SilkS")
		)
		(fp_line
			(start -0.7874 0.4064)
			(end -0.7874 -0.4064)
			(stroke
				(width 0.1524)
				(type default)
			)
			(layer "F.SilkS")
		)
		(fp_line
			(start -0.12065 -0.305054)
			(end -0.12065 -0.2794)
			(stroke
				(width 0.1)
				(type default)
			)
			(layer "F.Fab")
		)
		(fp_line
			(start -0.67945 -0.305054)
			(end -0.12065 -0.305054)
			(stroke
				(width 0.1)
				(type default)
			)
			(layer "F.Fab")
		)
		(fp_line
			(start 0.67945 -0.3048)
			(end 0.67945 0.3048)
			(stroke
				(width 0.1)
				(type default)
			)
			(layer "F.Fab")
		)
		(fp_line
			(start 0.12065 -0.3048)
			(end 0.67945 -0.3048)
			(stroke
				(width 0.1)
				(type default)
			)
			(layer "F.Fab")
		)
		(fp_line
			(start 0.12065 -0.2794)
			(end 0.12065 -0.3048)
			(stroke
				(width 0.1)
				(type default)
			)
			(layer "F.Fab")
		)
		(fp_line
			(start -0.12065 -0.2794)
			(end 0.12065 -0.2794)
			(stroke
				(width 0.1)
				(type default)
			)
			(layer "F.Fab")
		)
		(fp_line
			(start 0.120396 0.2794)
			(end -0.12065 0.2794)
			(stroke
				(width 0.1)
				(type default)
			)
			(layer "F.Fab")
		)
		(fp_line
			(start -0.12065 0.2794)
			(end -0.12065 0.3048)
			(stroke
				(width 0.1)
				(type default)
			)
			(layer "F.Fab")
		)
		(fp_line
			(start 0.67945 0.3048)
			(end 0.120396 0.3048)
			(stroke
				(width 0.1)
				(type default)
			)
			(layer "F.Fab")
		)
		(fp_line
			(start 0.120396 0.3048)
			(end 0.120396 0.2794)
			(stroke
				(width 0.1)
				(type default)
			)
			(layer "F.Fab")
		)
		(fp_line
			(start -0.12065 0.3048)
			(end -0.67945 0.3048)
			(stroke
				(width 0.1)
				(type default)
			)
			(layer "F.Fab")
		)
		(fp_line
			(start -0.67945 0.3048)
			(end -0.67945 -0.305054)
			(stroke
				(width 0.1)
				(type default)
			)
			(layer "F.Fab")
		)
		(pad "1" smd circle
			(at -0.40005 0 90)
			(size 0 0)
			(layers "F.Cu" "F.Mask" "F.Paste")
			(net "I3C4_SDA_R")
		)
		(pad "2" smd circle
			(at 0.40005 0 90)
			(size 0 0)
			(layers "F.Cu" "F.Mask" "F.Paste")
			(net "I3C4_SPD_SDA")
		)
	)
	(footprint ""
		(layer "F.Cu")
		(at 11.551666 -12.546838 90)
		(property "Reference" "U31"
			(at -0.608838 -1.618996 90)
			(unlocked yes)
			(layer "F.SilkS")
			(effects
				(font
					(size 0.7874 0.5842)
					(thickness 0.1524)
				)
				(justify left)
			)
		)
		(property "Value" ""
			(at 0 0 90)
			(layer "F.Fab")
			(effects
				(font
					(size 1.27 1.27)
				)
			)
		)
		(duplicate_pad_numbers_are_jumpers no)
		(fp_line
			(start 1.4986 -1.100074)
			(end 1.4986 1.100074)
			(stroke
				(width 0.1524)
				(type default)
			)
			(layer "F.SilkS")
		)
		(fp_line
			(start -1.4986 -1.100074)
			(end 1.4986 -1.100074)
			(stroke
				(width 0.1524)
				(type default)
			)
			(layer "F.SilkS")
		)
		(fp_line
			(start 1.4986 1.100074)
			(end -1.4986 1.100074)
			(stroke
				(width 0.1524)
				(type default)
			)
			(layer "F.SilkS")
		)
		(fp_line
			(start -1.4986 1.100074)
			(end -1.4986 -1.100074)
			(stroke
				(width 0.1524)
				(type default)
			)
			(layer "F.SilkS")
		)
		(fp_poly
			(pts
				(xy -2.321052 -1.41732) (xy -1.879346 -1.859026) (xy -1.719834 -1.235456)
			)
			(stroke
				(width 0)
				(type default)
			)
			(fill yes)
			(layer "F.SilkS")
		)
		(fp_line
			(start 0.67437 -1.100074)
			(end 0.67437 1.100074)
			(stroke
				(width 0.1)
				(type default)
			)
			(layer "F.Fab")
		)
		(fp_line
			(start -0.67437 -1.100074)
			(end 0.67437 -1.100074)
			(stroke
				(width 0.1)
				(type default)
			)
			(layer "F.Fab")
		)
		(fp_line
			(start 0.67437 1.100074)
			(end -0.67437 1.100074)
			(stroke
				(width 0.1)
				(type default)
			)
			(layer "F.Fab")
		)
		(fp_line
			(start -0.67437 1.100074)
			(end -0.67437 -1.100074)
			(stroke
				(width 0.1)
				(type default)
			)
			(layer "F.Fab")
		)
		(fp_poly
			(pts
				(xy -2.20472 -0.338328) (xy -2.20472 -0.963168) (xy -1.651 -0.635)
			)
			(stroke
				(width 0)
				(type default)
			)
			(fill yes)
			(layer "F.Fab")
		)
		(pad "1" smd rect
			(at -0.889 -0.649986 90)
			(size 1.016 0.381)
			(layers "F.Cu" "F.Mask" "F.Paste")
			(net "TP_PWR_BUF")
		)
		(pad "2" smd rect
			(at -0.889 0 90)
			(size 1.016 0.381)
			(layers "F.Cu" "F.Mask" "F.Paste")
			(net "REAR_PWR_BTN_N")
		)
		(pad "3" smd rect
			(at -0.889 0.649986 90)
			(size 1.016 0.381)
			(layers "F.Cu" "F.Mask" "F.Paste")
			(net "GND")
		)
		(pad "4" smd rect
			(at 0.889 0.649986 90)
			(size 1.016 0.381)
			(layers "F.Cu" "F.Mask" "F.Paste")
			(net "PWR_BTN_BMC_N")
		)
		(pad "5" smd rect
			(at 0.889 -0.649986 90)
			(size 1.016 0.381)
			(layers "F.Cu" "F.Mask" "F.Paste")
			(net "P3V3_AUX")
		)
	)
	(footprint ""
		(layer "F.Cu")
		(at 12.4206 -101.0539)
		(property "Reference" "R472"
			(at 0 0 0)
			(layer "F.SilkS")
			(hide yes)
			(effects
				(font
					(size 1.27 1.27)
				)
			)
		)
		(property "Value" ""
			(at 0 0 0)
			(layer "F.Fab")
			(effects
				(font
					(size 1.27 1.27)
				)
			)
		)
		(duplicate_pad_numbers_are_jumpers no)
		(fp_line
			(start -0.7874 -0.4064)
			(end 0.7874 -0.4064)
			(stroke
				(width 0.1524)
				(type default)
			)
			(layer "F.SilkS")
		)
		(fp_line
			(start -0.7874 0.4064)
			(end -0.7874 -0.4064)
			(stroke
				(width 0.1524)
				(type default)
			)
			(layer "F.SilkS")
		)
		(fp_line
			(start 0.7874 -0.4064)
			(end 0.7874 0.4064)
			(stroke
				(width 0.1524)
				(type default)
			)
			(layer "F.SilkS")
		)
		(fp_line
			(start 0.7874 0.4064)
			(end -0.7874 0.4064)
			(stroke
				(width 0.1524)
				(type default)
			)
			(layer "F.SilkS")
		)
		(fp_line
			(start -0.67945 -0.305054)
			(end -0.12065 -0.305054)
			(stroke
				(width 0.1)
				(type default)
			)
			(layer "F.Fab")
		)
		(fp_line
			(start -0.67945 0.3048)
			(end -0.67945 -0.305054)
			(stroke
				(width 0.1)
				(type default)
			)
			(layer "F.Fab")
		)
		(fp_line
			(start -0.12065 -0.305054)
			(end -0.12065 -0.2794)
			(stroke
				(width 0.1)
				(type default)
			)
			(layer "F.Fab")
		)
		(fp_line
			(start -0.12065 -0.2794)
			(end 0.12065 -0.2794)
			(stroke
				(width 0.1)
				(type default)
			)
			(layer "F.Fab")
		)
		(fp_line
			(start -0.12065 0.2794)
			(end -0.12065 0.3048)
			(stroke
				(width 0.1)
				(type default)
			)
			(layer "F.Fab")
		)
		(fp_line
			(start -0.12065 0.3048)
			(end -0.67945 0.3048)
			(stroke
				(width 0.1)
				(type default)
			)
			(layer "F.Fab")
		)
		(fp_line
			(start 0.120396 0.2794)
			(end -0.12065 0.2794)
			(stroke
				(width 0.1)
				(type default)
			)
			(layer "F.Fab")
		)
		(fp_line
			(start 0.120396 0.3048)
			(end 0.120396 0.2794)
			(stroke
				(width 0.1)
				(type default)
			)
			(layer "F.Fab")
		)
		(fp_line
			(start 0.12065 -0.3048)
			(end 0.67945 -0.3048)
			(stroke
				(width 0.1)
				(type default)
			)
			(layer "F.Fab")
		)
		(fp_line
			(start 0.12065 -0.2794)
			(end 0.12065 -0.3048)
			(stroke
				(width 0.1)
				(type default)
			)
			(layer "F.Fab")
		)
		(fp_line
			(start 0.67945 -0.3048)
			(end 0.67945 0.3048)
			(stroke
				(width 0.1)
				(type default)
			)
			(layer "F.Fab")
		)
		(fp_line
			(start 0.67945 0.3048)
			(end 0.120396 0.3048)
			(stroke
				(width 0.1)
				(type default)
			)
			(layer "F.Fab")
		)
		(pad "1" smd circle
			(at -0.40005 0)
			(size 0 0)
			(layers "F.Cu" "F.Mask" "F.Paste")
			(net "P3V3_AUX")
		)
		(pad "2" smd circle
			(at 0.40005 0)
			(size 0 0)
			(layers "F.Cu" "F.Mask" "F.Paste")
			(net "AC_PWR_BTN_R1_N")
		)
	)
	(footprint ""
		(layer "F.Cu")
		(at 84.455 -76.6572 90)
		(property "Reference" "R276"
			(at 0 0 90)
			(layer "F.SilkS")
			(hide yes)
			(effects
				(font
					(size 1.27 1.27)
				)
			)
		)
		(property "Value" ""
			(at 0 0 90)
			(layer "F.Fab")
			(effects
				(font
					(size 1.27 1.27)
				)
			)
		)
		(duplicate_pad_numbers_are_jumpers no)
		(fp_line
			(start 0.7874 -0.4064)
			(end 0.7874 0.4064)
			(stroke
				(width 0.1524)
				(type default)
			)
			(layer "F.SilkS")
		)
		(fp_line
			(start -0.7874 -0.4064)
			(end 0.7874 -0.4064)
			(stroke
				(width 0.1524)
				(type default)
			)
			(layer "F.SilkS")
		)
		(fp_line
			(start 0.7874 0.4064)
			(end -0.7874 0.4064)
			(stroke
				(width 0.1524)
				(type default)
			)
			(layer "F.SilkS")
		)
		(fp_line
			(start -0.7874 0.4064)
			(end -0.7874 -0.4064)
			(stroke
				(width 0.1524)
				(type default)
			)
			(layer "F.SilkS")
		)
		(fp_line
			(start -0.12065 -0.305054)
			(end -0.12065 -0.2794)
			(stroke
				(width 0.1)
				(type default)
			)
			(layer "F.Fab")
		)
		(fp_line
			(start -0.67945 -0.305054)
			(end -0.12065 -0.305054)
			(stroke
				(width 0.1)
				(type default)
			)
			(layer "F.Fab")
		)
		(fp_line
			(start 0.67945 -0.3048)
			(end 0.67945 0.3048)
			(stroke
				(width 0.1)
				(type default)
			)
			(layer "F.Fab")
		)
		(fp_line
			(start 0.12065 -0.3048)
			(end 0.67945 -0.3048)
			(stroke
				(width 0.1)
				(type default)
			)
			(layer "F.Fab")
		)
		(fp_line
			(start 0.12065 -0.2794)
			(end 0.12065 -0.3048)
			(stroke
				(width 0.1)
				(type default)
			)
			(layer "F.Fab")
		)
		(fp_line
			(start -0.12065 -0.2794)
			(end 0.12065 -0.2794)
			(stroke
				(width 0.1)
				(type default)
			)
			(layer "F.Fab")
		)
		(fp_line
			(start 0.120396 0.2794)
			(end -0.12065 0.2794)
			(stroke
				(width 0.1)
				(type default)
			)
			(layer "F.Fab")
		)
		(fp_line
			(start -0.12065 0.2794)
			(end -0.12065 0.3048)
			(stroke
				(width 0.1)
				(type default)
			)
			(layer "F.Fab")
		)
		(fp_line
			(start 0.67945 0.3048)
			(end 0.120396 0.3048)
			(stroke
				(width 0.1)
				(type default)
			)
			(layer "F.Fab")
		)
		(fp_line
			(start 0.120396 0.3048)
			(end 0.120396 0.2794)
			(stroke
				(width 0.1)
				(type default)
			)
			(layer "F.Fab")
		)
		(fp_line
			(start -0.12065 0.3048)
			(end -0.67945 0.3048)
			(stroke
				(width 0.1)
				(type default)
			)
			(layer "F.Fab")
		)
		(fp_line
			(start -0.67945 0.3048)
			(end -0.67945 -0.305054)
			(stroke
				(width 0.1)
				(type default)
			)
			(layer "F.Fab")
		)
		(pad "1" smd circle
			(at -0.40005 0 90)
			(size 0 0)
			(layers "F.Cu" "F.Mask" "F.Paste")
			(net "PWRGD_P1V2_AUX_R")
		)
		(pad "2" smd circle
			(at 0.40005 0 90)
			(size 0 0)
			(layers "F.Cu" "F.Mask" "F.Paste")
			(net "PWRGD_P1V2_AUX")
		)
	)
	(footprint ""
		(layer "F.Cu")
		(at 11.171936 -53.518054)
		(property "Reference" "PR245"
			(at 0 0 0)
			(layer "F.SilkS")
			(hide yes)
			(effects
				(font
					(size 1.27 1.27)
				)
			)
		)
		(property "Value" ""
			(at 0 0 0)
			(layer "F.Fab")
			(effects
				(font
					(size 1.27 1.27)
				)
			)
		)
		(duplicate_pad_numbers_are_jumpers no)
		(fp_line
			(start -0.7874 -0.4064)
			(end 0.7874 -0.4064)
			(stroke
				(width 0.1524)
				(type default)
			)
			(layer "F.SilkS")
		)
		(fp_line
			(start -0.7874 0.4064)
			(end -0.7874 -0.4064)
			(stroke
				(width 0.1524)
				(type default)
			)
			(layer "F.SilkS")
		)
		(fp_line
			(start 0.7874 -0.4064)
			(end 0.7874 0.4064)
			(stroke
				(width 0.1524)
				(type default)
			)
			(layer "F.SilkS")
		)
		(fp_line
			(start 0.7874 0.4064)
			(end -0.7874 0.4064)
			(stroke
				(width 0.1524)
				(type default)
			)
			(layer "F.SilkS")
		)
		(fp_line
			(start -0.67945 -0.305054)
			(end -0.12065 -0.305054)
			(stroke
				(width 0.1)
				(type default)
			)
			(layer "F.Fab")
		)
		(fp_line
			(start -0.67945 0.3048)
			(end -0.67945 -0.305054)
			(stroke
				(width 0.1)
				(type default)
			)
			(layer "F.Fab")
		)
		(fp_line
			(start -0.12065 -0.305054)
			(end -0.12065 -0.2794)
			(stroke
				(width 0.1)
				(type default)
			)
			(layer "F.Fab")
		)
		(fp_line
			(start -0.12065 -0.2794)
			(end 0.12065 -0.2794)
			(stroke
				(width 0.1)
				(type default)
			)
			(layer "F.Fab")
		)
		(fp_line
			(start -0.12065 0.2794)
			(end -0.12065 0.3048)
			(stroke
				(width 0.1)
				(type default)
			)
			(layer "F.Fab")
		)
		(fp_line
			(start -0.12065 0.3048)
			(end -0.67945 0.3048)
			(stroke
				(width 0.1)
				(type default)
			)
			(layer "F.Fab")
		)
		(fp_line
			(start 0.120396 0.2794)
			(end -0.12065 0.2794)
			(stroke
				(width 0.1)
				(type default)
			)
			(layer "F.Fab")
		)
		(fp_line
			(start 0.120396 0.3048)
			(end 0.120396 0.2794)
			(stroke
				(width 0.1)
				(type default)
			)
			(layer "F.Fab")
		)
		(fp_line
			(start 0.12065 -0.3048)
			(end 0.67945 -0.3048)
			(stroke
				(width 0.1)
				(type default)
			)
			(layer "F.Fab")
		)
		(fp_line
			(start 0.12065 -0.2794)
			(end 0.12065 -0.3048)
			(stroke
				(width 0.1)
				(type default)
			)
			(layer "F.Fab")
		)
		(fp_line
			(start 0.67945 -0.3048)
			(end 0.67945 0.3048)
			(stroke
				(width 0.1)
				(type default)
			)
			(layer "F.Fab")
		)
		(fp_line
			(start 0.67945 0.3048)
			(end 0.120396 0.3048)
			(stroke
				(width 0.1)
				(type default)
			)
			(layer "F.Fab")
		)
		(pad "1" smd circle
			(at -0.40005 0)
			(size 0 0)
			(layers "F.Cu" "F.Mask" "F.Paste")
			(net "PWRGD_P5V_AUX_R")
		)
		(pad "2" smd circle
			(at 0.40005 0)
			(size 0 0)
			(layers "F.Cu" "F.Mask" "F.Paste")
			(net "GND")
		)
	)
	(footprint ""
		(layer "F.Cu")
		(at 76.981558 -74.476356 90)
		(property "Reference" "R620"
			(at 0 0 90)
			(layer "F.SilkS")
			(hide yes)
			(effects
				(font
					(size 1.27 1.27)
				)
			)
		)
		(property "Value" ""
			(at 0 0 90)
			(layer "F.Fab")
			(effects
				(font
					(size 1.27 1.27)
				)
			)
		)
		(duplicate_pad_numbers_are_jumpers no)
		(fp_line
			(start 0.7874 -0.4064)
			(end 0.7874 0.4064)
			(stroke
				(width 0.1524)
				(type default)
			)
			(layer "F.SilkS")
		)
		(fp_line
			(start -0.7874 -0.4064)
			(end 0.7874 -0.4064)
			(stroke
				(width 0.1524)
				(type default)
			)
			(layer "F.SilkS")
		)
		(fp_line
			(start 0.7874 0.4064)
			(end -0.7874 0.4064)
			(stroke
				(width 0.1524)
				(type default)
			)
			(layer "F.SilkS")
		)
		(fp_line
			(start -0.7874 0.4064)
			(end -0.7874 -0.4064)
			(stroke
				(width 0.1524)
				(type default)
			)
			(layer "F.SilkS")
		)
		(fp_line
			(start -0.12065 -0.305054)
			(end -0.12065 -0.2794)
			(stroke
				(width 0.1)
				(type default)
			)
			(layer "F.Fab")
		)
		(fp_line
			(start -0.67945 -0.305054)
			(end -0.12065 -0.305054)
			(stroke
				(width 0.1)
				(type default)
			)
			(layer "F.Fab")
		)
		(fp_line
			(start 0.67945 -0.3048)
			(end 0.67945 0.3048)
			(stroke
				(width 0.1)
				(type default)
			)
			(layer "F.Fab")
		)
		(fp_line
			(start 0.12065 -0.3048)
			(end 0.67945 -0.3048)
			(stroke
				(width 0.1)
				(type default)
			)
			(layer "F.Fab")
		)
		(fp_line
			(start 0.12065 -0.2794)
			(end 0.12065 -0.3048)
			(stroke
				(width 0.1)
				(type default)
			)
			(layer "F.Fab")
		)
		(fp_line
			(start -0.12065 -0.2794)
			(end 0.12065 -0.2794)
			(stroke
				(width 0.1)
				(type default)
			)
			(layer "F.Fab")
		)
		(fp_line
			(start 0.120396 0.2794)
			(end -0.12065 0.2794)
			(stroke
				(width 0.1)
				(type default)
			)
			(layer "F.Fab")
		)
		(fp_line
			(start -0.12065 0.2794)
			(end -0.12065 0.3048)
			(stroke
				(width 0.1)
				(type default)
			)
			(layer "F.Fab")
		)
		(fp_line
			(start 0.67945 0.3048)
			(end 0.120396 0.3048)
			(stroke
				(width 0.1)
				(type default)
			)
			(layer "F.Fab")
		)
		(fp_line
			(start 0.120396 0.3048)
			(end 0.120396 0.2794)
			(stroke
				(width 0.1)
				(type default)
			)
			(layer "F.Fab")
		)
		(fp_line
			(start -0.12065 0.3048)
			(end -0.67945 0.3048)
			(stroke
				(width 0.1)
				(type default)
			)
			(layer "F.Fab")
		)
		(fp_line
			(start -0.67945 0.3048)
			(end -0.67945 -0.305054)
			(stroke
				(width 0.1)
				(type default)
			)
			(layer "F.Fab")
		)
		(pad "1" smd circle
			(at -0.40005 0 90)
			(size 0 0)
			(layers "F.Cu" "F.Mask" "F.Paste")
			(net "FM_JTAG_TCK_MUX_BMC_SEL")
		)
		(pad "2" smd circle
			(at 0.40005 0 90)
			(size 0 0)
			(layers "F.Cu" "F.Mask" "F.Paste")
			(net "GND")
		)
	)
	(footprint ""
		(layer "F.Cu")
		(at 28.1432 -65.7098 90)
		(property "Reference" "R67"
			(at 0 0 90)
			(layer "F.SilkS")
			(hide yes)
			(effects
				(font
					(size 1.27 1.27)
				)
			)
		)
		(property "Value" ""
			(at 0 0 90)
			(layer "F.Fab")
			(effects
				(font
					(size 1.27 1.27)
				)
			)
		)
		(duplicate_pad_numbers_are_jumpers no)
		(fp_line
			(start 0.7874 -0.4064)
			(end 0.7874 0.4064)
			(stroke
				(width 0.1524)
				(type default)
			)
			(layer "F.SilkS")
		)
		(fp_line
			(start -0.7874 -0.4064)
			(end 0.7874 -0.4064)
			(stroke
				(width 0.1524)
				(type default)
			)
			(layer "F.SilkS")
		)
		(fp_line
			(start 0.7874 0.4064)
			(end -0.7874 0.4064)
			(stroke
				(width 0.1524)
				(type default)
			)
			(layer "F.SilkS")
		)
		(fp_line
			(start -0.7874 0.4064)
			(end -0.7874 -0.4064)
			(stroke
				(width 0.1524)
				(type default)
			)
			(layer "F.SilkS")
		)
		(fp_line
			(start -0.12065 -0.305054)
			(end -0.12065 -0.2794)
			(stroke
				(width 0.1)
				(type default)
			)
			(layer "F.Fab")
		)
		(fp_line
			(start -0.67945 -0.305054)
			(end -0.12065 -0.305054)
			(stroke
				(width 0.1)
				(type default)
			)
			(layer "F.Fab")
		)
		(fp_line
			(start 0.67945 -0.3048)
			(end 0.67945 0.3048)
			(stroke
				(width 0.1)
				(type default)
			)
			(layer "F.Fab")
		)
		(fp_line
			(start 0.12065 -0.3048)
			(end 0.67945 -0.3048)
			(stroke
				(width 0.1)
				(type default)
			)
			(layer "F.Fab")
		)
		(fp_line
			(start 0.12065 -0.2794)
			(end 0.12065 -0.3048)
			(stroke
				(width 0.1)
				(type default)
			)
			(layer "F.Fab")
		)
		(fp_line
			(start -0.12065 -0.2794)
			(end 0.12065 -0.2794)
			(stroke
				(width 0.1)
				(type default)
			)
			(layer "F.Fab")
		)
		(fp_line
			(start 0.120396 0.2794)
			(end -0.12065 0.2794)
			(stroke
				(width 0.1)
				(type default)
			)
			(layer "F.Fab")
		)
		(fp_line
			(start -0.12065 0.2794)
			(end -0.12065 0.3048)
			(stroke
				(width 0.1)
				(type default)
			)
			(layer "F.Fab")
		)
		(fp_line
			(start 0.67945 0.3048)
			(end 0.120396 0.3048)
			(stroke
				(width 0.1)
				(type default)
			)
			(layer "F.Fab")
		)
		(fp_line
			(start 0.120396 0.3048)
			(end 0.120396 0.2794)
			(stroke
				(width 0.1)
				(type default)
			)
			(layer "F.Fab")
		)
		(fp_line
			(start -0.12065 0.3048)
			(end -0.67945 0.3048)
			(stroke
				(width 0.1)
				(type default)
			)
			(layer "F.Fab")
		)
		(fp_line
			(start -0.67945 0.3048)
			(end -0.67945 -0.305054)
			(stroke
				(width 0.1)
				(type default)
			)
			(layer "F.Fab")
		)
		(pad "1" smd circle
			(at -0.40005 0 90)
			(size 0 0)
			(layers "F.Cu" "F.Mask" "F.Paste")
			(net "P3V3_AUX")
		)
		(pad "2" smd circle
			(at 0.40005 0 90)
			(size 0 0)
			(layers "F.Cu" "F.Mask" "F.Paste")
			(net "UART_BMC_5_TXD_BUF1_R")
		)
	)
	(footprint ""
		(layer "F.Cu")
		(at 85.1662 -75.1586)
		(property "Reference" "C155"
			(at 0 0 0)
			(layer "F.SilkS")
			(hide yes)
			(effects
				(font
					(size 1.27 1.27)
				)
			)
		)
		(property "Value" ""
			(at 0 0 0)
			(layer "F.Fab")
			(effects
				(font
					(size 1.27 1.27)
				)
			)
		)
		(duplicate_pad_numbers_are_jumpers no)
		(fp_line
			(start -0.7874 -0.4064)
			(end 0.7874 -0.4064)
			(stroke
				(width 0.1524)
				(type default)
			)
			(layer "F.SilkS")
		)
		(fp_line
			(start -0.7874 0.4064)
			(end -0.7874 -0.4064)
			(stroke
				(width 0.1524)
				(type default)
			)
			(layer "F.SilkS")
		)
		(fp_line
			(start 0.7874 -0.4064)
			(end 0.7874 0.4064)
			(stroke
				(width 0.1524)
				(type default)
			)
			(layer "F.SilkS")
		)
		(fp_line
			(start 0.7874 0.4064)
			(end -0.7874 0.4064)
			(stroke
				(width 0.1524)
				(type default)
			)
			(layer "F.SilkS")
		)
		(fp_line
			(start -0.67945 -0.305054)
			(end -0.12065 -0.305054)
			(stroke
				(width 0.1)
				(type default)
			)
			(layer "F.Fab")
		)
		(fp_line
			(start -0.67945 0.3048)
			(end -0.67945 -0.305054)
			(stroke
				(width 0.1)
				(type default)
			)
			(layer "F.Fab")
		)
		(fp_line
			(start -0.12065 -0.305054)
			(end -0.12065 -0.2794)
			(stroke
				(width 0.1)
				(type default)
			)
			(layer "F.Fab")
		)
		(fp_line
			(start -0.12065 -0.2794)
			(end 0.12065 -0.2794)
			(stroke
				(width 0.1)
				(type default)
			)
			(layer "F.Fab")
		)
		(fp_line
			(start -0.12065 0.2794)
			(end -0.12065 0.3048)
			(stroke
				(width 0.1)
				(type default)
			)
			(layer "F.Fab")
		)
		(fp_line
			(start -0.12065 0.3048)
			(end -0.67945 0.3048)
			(stroke
				(width 0.1)
				(type default)
			)
			(layer "F.Fab")
		)
		(fp_line
			(start 0.120396 0.2794)
			(end -0.12065 0.2794)
			(stroke
				(width 0.1)
				(type default)
			)
			(layer "F.Fab")
		)
		(fp_line
			(start 0.120396 0.3048)
			(end 0.120396 0.2794)
			(stroke
				(width 0.1)
				(type default)
			)
			(layer "F.Fab")
		)
		(fp_line
			(start 0.12065 -0.3048)
			(end 0.67945 -0.3048)
			(stroke
				(width 0.1)
				(type default)
			)
			(layer "F.Fab")
		)
		(fp_line
			(start 0.12065 -0.2794)
			(end 0.12065 -0.3048)
			(stroke
				(width 0.1)
				(type default)
			)
			(layer "F.Fab")
		)
		(fp_line
			(start 0.67945 -0.3048)
			(end 0.67945 0.3048)
			(stroke
				(width 0.1)
				(type default)
			)
			(layer "F.Fab")
		)
		(fp_line
			(start 0.67945 0.3048)
			(end 0.120396 0.3048)
			(stroke
				(width 0.1)
				(type default)
			)
			(layer "F.Fab")
		)
		(pad "1" smd circle
			(at -0.40005 0)
			(size 0 0)
			(layers "F.Cu" "F.Mask" "F.Paste")
			(net "PWRGD_P1V2_AUX_R")
		)
		(pad "2" smd circle
			(at 0.40005 0)
			(size 0 0)
			(layers "F.Cu" "F.Mask" "F.Paste")
			(net "GND")
		)
	)
	(footprint ""
		(layer "F.Cu")
		(at 49.80051 -30.867604 90)
		(property "Reference" "R249"
			(at 0 0 90)
			(layer "F.SilkS")
			(hide yes)
			(effects
				(font
					(size 1.27 1.27)
				)
			)
		)
		(property "Value" ""
			(at 0 0 90)
			(layer "F.Fab")
			(effects
				(font
					(size 1.27 1.27)
				)
			)
		)
		(duplicate_pad_numbers_are_jumpers no)
		(fp_line
			(start 0.7874 -0.4064)
			(end 0.7874 0.4064)
			(stroke
				(width 0.1524)
				(type default)
			)
			(layer "F.SilkS")
		)
		(fp_line
			(start -0.7874 -0.4064)
			(end 0.7874 -0.4064)
			(stroke
				(width 0.1524)
				(type default)
			)
			(layer "F.SilkS")
		)
		(fp_line
			(start 0.7874 0.4064)
			(end -0.7874 0.4064)
			(stroke
				(width 0.1524)
				(type default)
			)
			(layer "F.SilkS")
		)
		(fp_line
			(start -0.7874 0.4064)
			(end -0.7874 -0.4064)
			(stroke
				(width 0.1524)
				(type default)
			)
			(layer "F.SilkS")
		)
		(fp_line
			(start -0.12065 -0.305054)
			(end -0.12065 -0.2794)
			(stroke
				(width 0.1)
				(type default)
			)
			(layer "F.Fab")
		)
		(fp_line
			(start -0.67945 -0.305054)
			(end -0.12065 -0.305054)
			(stroke
				(width 0.1)
				(type default)
			)
			(layer "F.Fab")
		)
		(fp_line
			(start 0.67945 -0.3048)
			(end 0.67945 0.3048)
			(stroke
				(width 0.1)
				(type default)
			)
			(layer "F.Fab")
		)
		(fp_line
			(start 0.12065 -0.3048)
			(end 0.67945 -0.3048)
			(stroke
				(width 0.1)
				(type default)
			)
			(layer "F.Fab")
		)
		(fp_line
			(start 0.12065 -0.2794)
			(end 0.12065 -0.3048)
			(stroke
				(width 0.1)
				(type default)
			)
			(layer "F.Fab")
		)
		(fp_line
			(start -0.12065 -0.2794)
			(end 0.12065 -0.2794)
			(stroke
				(width 0.1)
				(type default)
			)
			(layer "F.Fab")
		)
		(fp_line
			(start 0.120396 0.2794)
			(end -0.12065 0.2794)
			(stroke
				(width 0.1)
				(type default)
			)
			(layer "F.Fab")
		)
		(fp_line
			(start -0.12065 0.2794)
			(end -0.12065 0.3048)
			(stroke
				(width 0.1)
				(type default)
			)
			(layer "F.Fab")
		)
		(fp_line
			(start 0.67945 0.3048)
			(end 0.120396 0.3048)
			(stroke
				(width 0.1)
				(type default)
			)
			(layer "F.Fab")
		)
		(fp_line
			(start 0.120396 0.3048)
			(end 0.120396 0.2794)
			(stroke
				(width 0.1)
				(type default)
			)
			(layer "F.Fab")
		)
		(fp_line
			(start -0.12065 0.3048)
			(end -0.67945 0.3048)
			(stroke
				(width 0.1)
				(type default)
			)
			(layer "F.Fab")
		)
		(fp_line
			(start -0.67945 0.3048)
			(end -0.67945 -0.305054)
			(stroke
				(width 0.1)
				(type default)
			)
			(layer "F.Fab")
		)
		(pad "1" smd circle
			(at -0.40005 0 90)
			(size 0 0)
			(layers "F.Cu" "F.Mask" "F.Paste")
			(net "P3V3_AUX")
		)
		(pad "2" smd circle
			(at 0.40005 0 90)
			(size 0 0)
			(layers "F.Cu" "F.Mask" "F.Paste")
			(net "SMB_BMC_MM3_SDA")
		)
	)
	(footprint ""
		(layer "F.Cu")
		(at 84.652612 -37.303456 90)
		(property "Reference" "C291"
			(at 0 0 90)
			(layer "F.SilkS")
			(hide yes)
			(effects
				(font
					(size 1.27 1.27)
				)
			)
		)
		(property "Value" ""
			(at 0 0 90)
			(layer "F.Fab")
			(effects
				(font
					(size 1.27 1.27)
				)
			)
		)
		(duplicate_pad_numbers_are_jumpers no)
		(fp_line
			(start 0.7874 -0.4064)
			(end 0.7874 0.4064)
			(stroke
				(width 0.1524)
				(type default)
			)
			(layer "F.SilkS")
		)
		(fp_line
			(start -0.7874 -0.4064)
			(end 0.7874 -0.4064)
			(stroke
				(width 0.1524)
				(type default)
			)
			(layer "F.SilkS")
		)
		(fp_line
			(start 0.7874 0.4064)
			(end -0.7874 0.4064)
			(stroke
				(width 0.1524)
				(type default)
			)
			(layer "F.SilkS")
		)
		(fp_line
			(start -0.7874 0.4064)
			(end -0.7874 -0.4064)
			(stroke
				(width 0.1524)
				(type default)
			)
			(layer "F.SilkS")
		)
		(fp_line
			(start -0.12065 -0.305054)
			(end -0.12065 -0.2794)
			(stroke
				(width 0.1)
				(type default)
			)
			(layer "F.Fab")
		)
		(fp_line
			(start -0.67945 -0.305054)
			(end -0.12065 -0.305054)
			(stroke
				(width 0.1)
				(type default)
			)
			(layer "F.Fab")
		)
		(fp_line
			(start 0.67945 -0.3048)
			(end 0.67945 0.3048)
			(stroke
				(width 0.1)
				(type default)
			)
			(layer "F.Fab")
		)
		(fp_line
			(start 0.12065 -0.3048)
			(end 0.67945 -0.3048)
			(stroke
				(width 0.1)
				(type default)
			)
			(layer "F.Fab")
		)
		(fp_line
			(start 0.12065 -0.2794)
			(end 0.12065 -0.3048)
			(stroke
				(width 0.1)
				(type default)
			)
			(layer "F.Fab")
		)
		(fp_line
			(start -0.12065 -0.2794)
			(end 0.12065 -0.2794)
			(stroke
				(width 0.1)
				(type default)
			)
			(layer "F.Fab")
		)
		(fp_line
			(start 0.120396 0.2794)
			(end -0.12065 0.2794)
			(stroke
				(width 0.1)
				(type default)
			)
			(layer "F.Fab")
		)
		(fp_line
			(start -0.12065 0.2794)
			(end -0.12065 0.3048)
			(stroke
				(width 0.1)
				(type default)
			)
			(layer "F.Fab")
		)
		(fp_line
			(start 0.67945 0.3048)
			(end 0.120396 0.3048)
			(stroke
				(width 0.1)
				(type default)
			)
			(layer "F.Fab")
		)
		(fp_line
			(start 0.120396 0.3048)
			(end 0.120396 0.2794)
			(stroke
				(width 0.1)
				(type default)
			)
			(layer "F.Fab")
		)
		(fp_line
			(start -0.12065 0.3048)
			(end -0.67945 0.3048)
			(stroke
				(width 0.1)
				(type default)
			)
			(layer "F.Fab")
		)
		(fp_line
			(start -0.67945 0.3048)
			(end -0.67945 -0.305054)
			(stroke
				(width 0.1)
				(type default)
			)
			(layer "F.Fab")
		)
		(pad "1" smd circle
			(at -0.40005 0 90)
			(size 0 0)
			(layers "F.Cu" "F.Mask" "F.Paste")
			(net "P2V5_AUX")
		)
		(pad "2" smd circle
			(at 0.40005 0 90)
			(size 0 0)
			(layers "F.Cu" "F.Mask" "F.Paste")
			(net "GND")
		)
	)
	(footprint ""
		(layer "F.Cu")
		(at 66.3702 -63.9572 90)
		(property "Reference" "R175"
			(at 0 0 90)
			(layer "F.SilkS")
			(hide yes)
			(effects
				(font
					(size 1.27 1.27)
				)
			)
		)
		(property "Value" ""
			(at 0 0 90)
			(layer "F.Fab")
			(effects
				(font
					(size 1.27 1.27)
				)
			)
		)
		(duplicate_pad_numbers_are_jumpers no)
		(fp_line
			(start 0.7874 -0.4064)
			(end 0.7874 0.4064)
			(stroke
				(width 0.1524)
				(type default)
			)
			(layer "F.SilkS")
		)
		(fp_line
			(start -0.7874 -0.4064)
			(end 0.7874 -0.4064)
			(stroke
				(width 0.1524)
				(type default)
			)
			(layer "F.SilkS")
		)
		(fp_line
			(start 0.7874 0.4064)
			(end -0.7874 0.4064)
			(stroke
				(width 0.1524)
				(type default)
			)
			(layer "F.SilkS")
		)
		(fp_line
			(start -0.7874 0.4064)
			(end -0.7874 -0.4064)
			(stroke
				(width 0.1524)
				(type default)
			)
			(layer "F.SilkS")
		)
		(fp_line
			(start -0.12065 -0.305054)
			(end -0.12065 -0.2794)
			(stroke
				(width 0.1)
				(type default)
			)
			(layer "F.Fab")
		)
		(fp_line
			(start -0.67945 -0.305054)
			(end -0.12065 -0.305054)
			(stroke
				(width 0.1)
				(type default)
			)
			(layer "F.Fab")
		)
		(fp_line
			(start 0.67945 -0.3048)
			(end 0.67945 0.3048)
			(stroke
				(width 0.1)
				(type default)
			)
			(layer "F.Fab")
		)
		(fp_line
			(start 0.12065 -0.3048)
			(end 0.67945 -0.3048)
			(stroke
				(width 0.1)
				(type default)
			)
			(layer "F.Fab")
		)
		(fp_line
			(start 0.12065 -0.2794)
			(end 0.12065 -0.3048)
			(stroke
				(width 0.1)
				(type default)
			)
			(layer "F.Fab")
		)
		(fp_line
			(start -0.12065 -0.2794)
			(end 0.12065 -0.2794)
			(stroke
				(width 0.1)
				(type default)
			)
			(layer "F.Fab")
		)
		(fp_line
			(start 0.120396 0.2794)
			(end -0.12065 0.2794)
			(stroke
				(width 0.1)
				(type default)
			)
			(layer "F.Fab")
		)
		(fp_line
			(start -0.12065 0.2794)
			(end -0.12065 0.3048)
			(stroke
				(width 0.1)
				(type default)
			)
			(layer "F.Fab")
		)
		(fp_line
			(start 0.67945 0.3048)
			(end 0.120396 0.3048)
			(stroke
				(width 0.1)
				(type default)
			)
			(layer "F.Fab")
		)
		(fp_line
			(start 0.120396 0.3048)
			(end 0.120396 0.2794)
			(stroke
				(width 0.1)
				(type default)
			)
			(layer "F.Fab")
		)
		(fp_line
			(start -0.12065 0.3048)
			(end -0.67945 0.3048)
			(stroke
				(width 0.1)
				(type default)
			)
			(layer "F.Fab")
		)
		(fp_line
			(start -0.67945 0.3048)
			(end -0.67945 -0.305054)
			(stroke
				(width 0.1)
				(type default)
			)
			(layer "F.Fab")
		)
		(pad "1" smd circle
			(at -0.40005 0 90)
			(size 0 0)
			(layers "F.Cu" "F.Mask" "F.Paste")
			(net "SPI_BMC_BIOS_ROM_MOSI")
		)
		(pad "2" smd circle
			(at 0.40005 0 90)
			(size 0 0)
			(layers "F.Cu" "F.Mask" "F.Paste")
			(net "SPI_BMC_BIOS_ROM_R_MOSI")
		)
	)
	(footprint ""
		(layer "F.Cu")
		(at 54.229 -96.012 90)
		(property "Reference" "R106"
			(at 0 0 90)
			(layer "F.SilkS")
			(hide yes)
			(effects
				(font
					(size 1.27 1.27)
				)
			)
		)
		(property "Value" ""
			(at 0 0 90)
			(layer "F.Fab")
			(effects
				(font
					(size 1.27 1.27)
				)
			)
		)
		(duplicate_pad_numbers_are_jumpers no)
		(fp_line
			(start 0.7874 -0.4064)
			(end 0.7874 0.4064)
			(stroke
				(width 0.1524)
				(type default)
			)
			(layer "F.SilkS")
		)
		(fp_line
			(start -0.7874 -0.4064)
			(end 0.7874 -0.4064)
			(stroke
				(width 0.1524)
				(type default)
			)
			(layer "F.SilkS")
		)
		(fp_line
			(start 0.7874 0.4064)
			(end -0.7874 0.4064)
			(stroke
				(width 0.1524)
				(type default)
			)
			(layer "F.SilkS")
		)
		(fp_line
			(start -0.7874 0.4064)
			(end -0.7874 -0.4064)
			(stroke
				(width 0.1524)
				(type default)
			)
			(layer "F.SilkS")
		)
		(fp_line
			(start -0.12065 -0.305054)
			(end -0.12065 -0.2794)
			(stroke
				(width 0.1)
				(type default)
			)
			(layer "F.Fab")
		)
		(fp_line
			(start -0.67945 -0.305054)
			(end -0.12065 -0.305054)
			(stroke
				(width 0.1)
				(type default)
			)
			(layer "F.Fab")
		)
		(fp_line
			(start 0.67945 -0.3048)
			(end 0.67945 0.3048)
			(stroke
				(width 0.1)
				(type default)
			)
			(layer "F.Fab")
		)
		(fp_line
			(start 0.12065 -0.3048)
			(end 0.67945 -0.3048)
			(stroke
				(width 0.1)
				(type default)
			)
			(layer "F.Fab")
		)
		(fp_line
			(start 0.12065 -0.2794)
			(end 0.12065 -0.3048)
			(stroke
				(width 0.1)
				(type default)
			)
			(layer "F.Fab")
		)
		(fp_line
			(start -0.12065 -0.2794)
			(end 0.12065 -0.2794)
			(stroke
				(width 0.1)
				(type default)
			)
			(layer "F.Fab")
		)
		(fp_line
			(start 0.120396 0.2794)
			(end -0.12065 0.2794)
			(stroke
				(width 0.1)
				(type default)
			)
			(layer "F.Fab")
		)
		(fp_line
			(start -0.12065 0.2794)
			(end -0.12065 0.3048)
			(stroke
				(width 0.1)
				(type default)
			)
			(layer "F.Fab")
		)
		(fp_line
			(start 0.67945 0.3048)
			(end 0.120396 0.3048)
			(stroke
				(width 0.1)
				(type default)
			)
			(layer "F.Fab")
		)
		(fp_line
			(start 0.120396 0.3048)
			(end 0.120396 0.2794)
			(stroke
				(width 0.1)
				(type default)
			)
			(layer "F.Fab")
		)
		(fp_line
			(start -0.12065 0.3048)
			(end -0.67945 0.3048)
			(stroke
				(width 0.1)
				(type default)
			)
			(layer "F.Fab")
		)
		(fp_line
			(start -0.67945 0.3048)
			(end -0.67945 -0.305054)
			(stroke
				(width 0.1)
				(type default)
			)
			(layer "F.Fab")
		)
		(pad "1" smd circle
			(at -0.40005 0 90)
			(size 0 0)
			(layers "F.Cu" "F.Mask" "F.Paste")
			(net "RST_BMC_SRST_N")
		)
		(pad "2" smd circle
			(at 0.40005 0 90)
			(size 0 0)
			(layers "F.Cu" "F.Mask" "F.Paste")
			(net "RST_BMC_EXTRST_R2_N")
		)
	)
	(footprint ""
		(layer "F.Cu")
		(at 7.239 -61.087 180)
		(property "Reference" "PC218"
			(at 0 0 180)
			(layer "F.SilkS")
			(hide yes)
			(effects
				(font
					(size 1.27 1.27)
				)
			)
		)
		(property "Value" ""
			(at 0 0 180)
			(layer "F.Fab")
			(effects
				(font
					(size 1.27 1.27)
				)
			)
		)
		(duplicate_pad_numbers_are_jumpers no)
		(fp_line
			(start 1.524 0.762)
			(end -1.524 0.762)
			(stroke
				(width 0.1524)
				(type default)
			)
			(layer "F.SilkS")
		)
		(fp_line
			(start 1.524 -0.762)
			(end 1.524 0.762)
			(stroke
				(width 0.1524)
				(type default)
			)
			(layer "F.SilkS")
		)
		(fp_line
			(start -1.524 0.762)
			(end -1.524 -0.762)
			(stroke
				(width 0.1524)
				(type default)
			)
			(layer "F.SilkS")
		)
		(fp_line
			(start -1.524 -0.762)
			(end 1.524 -0.762)
			(stroke
				(width 0.1524)
				(type default)
			)
			(layer "F.SilkS")
		)
		(fp_line
			(start 1.1049 0.724916)
			(end 1.1049 -0.724916)
			(stroke
				(width 0.1)
				(type default)
			)
			(layer "F.Fab")
		)
		(fp_line
			(start 1.1049 -0.724916)
			(end -1.1049 -0.724916)
			(stroke
				(width 0.1)
				(type default)
			)
			(layer "F.Fab")
		)
		(fp_line
			(start -1.1049 0.724916)
			(end 1.1049 0.724916)
			(stroke
				(width 0.1)
				(type default)
			)
			(layer "F.Fab")
		)
		(fp_line
			(start -1.1049 -0.724916)
			(end -1.1049 0.724916)
			(stroke
				(width 0.1)
				(type default)
			)
			(layer "F.Fab")
		)
		(pad "1" smd rect
			(at -0.889 0)
			(size 1.016 1.27)
			(layers "F.Cu" "F.Mask" "F.Paste")
			(net "SW_P3V3_AUX_FLT")
		)
		(pad "2" smd rect
			(at 0.889 0)
			(size 1.016 1.27)
			(layers "F.Cu" "F.Mask" "F.Paste")
			(net "GND")
		)
	)
	(footprint ""
		(layer "F.Cu")
		(at 51.816 -76.3524 180)
		(property "Reference" "U54"
			(at 1.0414 -2.23647 0)
			(unlocked yes)
			(layer "F.SilkS")
			(effects
				(font
					(size 0.7874 0.5842)
					(thickness 0.1524)
				)
				(justify left)
			)
		)
		(property "Value" ""
			(at 0 0 180)
			(layer "F.Fab")
			(effects
				(font
					(size 1.27 1.27)
				)
			)
		)
		(duplicate_pad_numbers_are_jumpers no)
		(fp_line
			(start 1.207008 1.549908)
			(end 1.207008 -1.549908)
			(stroke
				(width 0.1524)
				(type default)
			)
			(layer "F.SilkS")
		)
		(fp_line
			(start 1.207008 -1.549908)
			(end 0.762508 -1.549908)
			(stroke
				(width 0.1524)
				(type default)
			)
			(layer "F.SilkS")
		)
		(fp_line
			(start 0.762508 -1.549908)
			(end 0 -0.635)
			(stroke
				(width 0.1524)
				(type default)
			)
			(layer "F.SilkS")
		)
		(fp_line
			(start 0 -0.635)
			(end -0.762508 -1.549908)
			(stroke
				(width 0.1524)
				(type default)
			)
			(layer "F.SilkS")
		)
		(fp_line
			(start -0.762508 -1.549908)
			(end -1.207008 -1.549908)
			(stroke
				(width 0.1524)
				(type default)
			)
			(layer "F.SilkS")
		)
		(fp_line
			(start -1.207008 1.549908)
			(end 1.207008 1.549908)
			(stroke
				(width 0.1524)
				(type default)
			)
			(layer "F.SilkS")
		)
		(fp_line
			(start -1.207008 -1.549908)
			(end -1.207008 1.549908)
			(stroke
				(width 0.1524)
				(type default)
			)
			(layer "F.SilkS")
		)
		(fp_poly
			(pts
				(xy -2.699258 -2.852166) (xy -3.41757 -2.1336) (xy -2.340102 -1.774444)
			)
			(stroke
				(width 0)
				(type default)
			)
			(fill yes)
			(layer "F.SilkS")
		)
		(fp_line
			(start 1.549908 1.549908)
			(end 1.549908 -1.549908)
			(stroke
				(width 0.1)
				(type default)
			)
			(layer "F.Fab")
		)
		(fp_line
			(start 1.549908 -1.549908)
			(end -1.549908 -1.549908)
			(stroke
				(width 0.1)
				(type default)
			)
			(layer "F.Fab")
		)
		(fp_line
			(start -1.549908 1.549908)
			(end 1.549908 1.549908)
			(stroke
				(width 0.1)
				(type default)
			)
			(layer "F.Fab")
		)
		(fp_line
			(start -1.549908 -1.549908)
			(end -1.549908 1.549908)
			(stroke
				(width 0.1)
				(type default)
			)
			(layer "F.Fab")
		)
		(fp_poly
			(pts
				(xy -3.4036 -1.53289) (xy -3.4036 -0.51689) (xy -2.3876 -1.02489)
			)
			(stroke
				(width 0)
				(type default)
			)
			(fill yes)
			(layer "F.Fab")
		)
		(pad "1" smd rect
			(at -1.774952 -1.02489 90)
			(size 0.508 0.8636)
			(layers "F.Cu" "F.Mask" "F.Paste")
			(net "FLASH_LATCH_CP")
		)
		(pad "2" smd rect
			(at -1.774952 -0.32512 90)
			(size 0.4064 0.8636)
			(layers "F.Cu" "F.Mask" "F.Paste")
			(net "FLASH_LATCH_D")
		)
		(pad "3" smd rect
			(at -1.774952 0.32512 90)
			(size 0.4064 0.8636)
			(layers "F.Cu" "F.Mask" "F.Paste")
			(net "FLASH_LATCH_Q_N_R")
		)
		(pad "4" smd rect
			(at -1.774952 1.02489 90)
			(size 0.508 0.8636)
			(layers "F.Cu" "F.Mask" "F.Paste")
			(net "GND")
		)
		(pad "5" smd rect
			(at 1.774952 1.02489 90)
			(size 0.508 0.8636)
			(layers "F.Cu" "F.Mask" "F.Paste")
			(net "NC_U54_P1")
		)
		(pad "6" smd rect
			(at 1.774952 0.32512 90)
			(size 0.4064 0.8636)
			(layers "F.Cu" "F.Mask" "F.Paste")
			(net "RD_N")
		)
		(pad "7" smd rect
			(at 1.774952 -0.32512 90)
			(size 0.4064 0.8636)
			(layers "F.Cu" "F.Mask" "F.Paste")
			(net "FM_FLASH_LATCH_N")
		)
		(pad "8" smd rect
			(at 1.774952 -1.02489 90)
			(size 0.508 0.8636)
			(layers "F.Cu" "F.Mask" "F.Paste")
			(net "P3V3_AUX")
		)
	)
	(footprint ""
		(layer "F.Cu")
		(at 9.271 -85.852)
		(property "Reference" "R711"
			(at 0 0 0)
			(layer "F.SilkS")
			(hide yes)
			(effects
				(font
					(size 1.27 1.27)
				)
			)
		)
		(property "Value" ""
			(at 0 0 0)
			(layer "F.Fab")
			(effects
				(font
					(size 1.27 1.27)
				)
			)
		)
		(duplicate_pad_numbers_are_jumpers no)
		(fp_line
			(start -0.7874 -0.4064)
			(end 0.7874 -0.4064)
			(stroke
				(width 0.1524)
				(type default)
			)
			(layer "F.SilkS")
		)
		(fp_line
			(start -0.7874 0.4064)
			(end -0.7874 -0.4064)
			(stroke
				(width 0.1524)
				(type default)
			)
			(layer "F.SilkS")
		)
		(fp_line
			(start 0.7874 -0.4064)
			(end 0.7874 0.4064)
			(stroke
				(width 0.1524)
				(type default)
			)
			(layer "F.SilkS")
		)
		(fp_line
			(start 0.7874 0.4064)
			(end -0.7874 0.4064)
			(stroke
				(width 0.1524)
				(type default)
			)
			(layer "F.SilkS")
		)
		(fp_line
			(start -0.67945 -0.305054)
			(end -0.12065 -0.305054)
			(stroke
				(width 0.1)
				(type default)
			)
			(layer "F.Fab")
		)
		(fp_line
			(start -0.67945 0.3048)
			(end -0.67945 -0.305054)
			(stroke
				(width 0.1)
				(type default)
			)
			(layer "F.Fab")
		)
		(fp_line
			(start -0.12065 -0.305054)
			(end -0.12065 -0.2794)
			(stroke
				(width 0.1)
				(type default)
			)
			(layer "F.Fab")
		)
		(fp_line
			(start -0.12065 -0.2794)
			(end 0.12065 -0.2794)
			(stroke
				(width 0.1)
				(type default)
			)
			(layer "F.Fab")
		)
		(fp_line
			(start -0.12065 0.2794)
			(end -0.12065 0.3048)
			(stroke
				(width 0.1)
				(type default)
			)
			(layer "F.Fab")
		)
		(fp_line
			(start -0.12065 0.3048)
			(end -0.67945 0.3048)
			(stroke
				(width 0.1)
				(type default)
			)
			(layer "F.Fab")
		)
		(fp_line
			(start 0.120396 0.2794)
			(end -0.12065 0.2794)
			(stroke
				(width 0.1)
				(type default)
			)
			(layer "F.Fab")
		)
		(fp_line
			(start 0.120396 0.3048)
			(end 0.120396 0.2794)
			(stroke
				(width 0.1)
				(type default)
			)
			(layer "F.Fab")
		)
		(fp_line
			(start 0.12065 -0.3048)
			(end 0.67945 -0.3048)
			(stroke
				(width 0.1)
				(type default)
			)
			(layer "F.Fab")
		)
		(fp_line
			(start 0.12065 -0.2794)
			(end 0.12065 -0.3048)
			(stroke
				(width 0.1)
				(type default)
			)
			(layer "F.Fab")
		)
		(fp_line
			(start 0.67945 -0.3048)
			(end 0.67945 0.3048)
			(stroke
				(width 0.1)
				(type default)
			)
			(layer "F.Fab")
		)
		(fp_line
			(start 0.67945 0.3048)
			(end 0.120396 0.3048)
			(stroke
				(width 0.1)
				(type default)
			)
			(layer "F.Fab")
		)
		(pad "1" smd circle
			(at -0.40005 0)
			(size 0 0)
			(layers "F.Cu" "F.Mask" "F.Paste")
			(net "PWRGD_PSU_AC_PWROK")
		)
		(pad "2" smd circle
			(at 0.40005 0)
			(size 0 0)
			(layers "F.Cu" "F.Mask" "F.Paste")
			(net "PWRGD_P1V0_AUX_DELAY")
		)
	)
	(footprint ""
		(layer "F.Cu")
		(at 42.346626 -18.1864 90)
		(property "Reference" "U27"
			(at -0.8509 2.015744 90)
			(unlocked yes)
			(layer "F.SilkS")
			(effects
				(font
					(size 0.7874 0.5842)
					(thickness 0.1524)
				)
				(justify left)
			)
		)
		(property "Value" ""
			(at 0 0 90)
			(layer "F.Fab")
			(effects
				(font
					(size 1.27 1.27)
				)
			)
		)
		(duplicate_pad_numbers_are_jumpers no)
		(fp_line
			(start 0.791464 -1.287526)
			(end -0.791464 -1.287526)
			(stroke
				(width 0.1524)
				(type default)
			)
			(layer "F.SilkS")
		)
		(fp_line
			(start -0.791464 -1.287526)
			(end -0.791464 -1.147826)
			(stroke
				(width 0.1524)
				(type default)
			)
			(layer "F.SilkS")
		)
		(fp_line
			(start 0.791464 -1.147826)
			(end 0.791464 -1.287526)
			(stroke
				(width 0.1524)
				(type default)
			)
			(layer "F.SilkS")
		)
		(fp_line
			(start -0.791464 -0.385826)
			(end -0.791464 0.325374)
			(stroke
				(width 0.1524)
				(type default)
			)
			(layer "F.SilkS")
		)
		(fp_line
			(start 0.791464 0.401574)
			(end 0.791464 -0.335026)
			(stroke
				(width 0.1524)
				(type default)
			)
			(layer "F.SilkS")
		)
		(fp_line
			(start -0.791464 1.112774)
			(end -0.791464 1.287526)
			(stroke
				(width 0.1524)
				(type default)
			)
			(layer "F.SilkS")
		)
		(fp_line
			(start 0.791464 1.287526)
			(end 0.791464 1.112774)
			(stroke
				(width 0.1524)
				(type default)
			)
			(layer "F.SilkS")
		)
		(fp_line
			(start -0.791464 1.287526)
			(end 0.791464 1.287526)
			(stroke
				(width 0.1524)
				(type default)
			)
			(layer "F.SilkS")
		)
		(fp_poly
			(pts
				(xy -1.006602 -2.022602) (xy -1.365758 -1.663446) (xy -0.827024 -1.483868)
			)
			(stroke
				(width 0)
				(type default)
			)
			(fill yes)
			(layer "F.SilkS")
		)
		(fp_line
			(start 0.537464 -1.287526)
			(end -0.537464 -1.287526)
			(stroke
				(width 0.1)
				(type default)
			)
			(layer "F.Fab")
		)
		(fp_line
			(start -0.537464 -1.287526)
			(end -0.537464 1.287526)
			(stroke
				(width 0.1)
				(type default)
			)
			(layer "F.Fab")
		)
		(fp_line
			(start 0.537464 1.287526)
			(end 0.537464 -1.287526)
			(stroke
				(width 0.1)
				(type default)
			)
			(layer "F.Fab")
		)
		(fp_line
			(start -0.537464 1.287526)
			(end 0.537464 1.287526)
			(stroke
				(width 0.1)
				(type default)
			)
			(layer "F.Fab")
		)
		(fp_poly
			(pts
				(xy -1.651 -1.253998) (xy -1.651 -0.745998) (xy -1.143 -0.999998)
			)
			(stroke
				(width 0)
				(type default)
			)
			(fill yes)
			(layer "F.Fab")
		)
		(pad "1" smd rect
			(at -0.387604 -0.999998 180)
			(size 0.254 0.635)
			(layers "F.Cu" "F.Mask" "F.Paste")
			(net "USB3_01_FB_TXP")
		)
		(pad "2" smd rect
			(at -0.387604 -0.499872 180)
			(size 0.254 0.635)
			(layers "F.Cu" "F.Mask" "F.Paste")
			(net "USB3_01_FB_TXN")
		)
		(pad "3" smd rect
			(at -0.350012 0 180)
			(size 0.4572 0.6858)
			(layers "F.Cu" "F.Mask" "F.Paste")
			(net "GND")
		)
		(pad "4" smd rect
			(at -0.387604 0.499872 180)
			(size 0.254 0.635)
			(layers "F.Cu" "F.Mask" "F.Paste")
			(net "USB3_01_FB_RXP")
		)
		(pad "5" smd rect
			(at -0.387604 0.999998 180)
			(size 0.254 0.635)
			(layers "F.Cu" "F.Mask" "F.Paste")
			(net "USB3_01_FB_RXN")
		)
		(pad "6" smd rect
			(at 0.387604 0.999998 180)
			(size 0.254 0.635)
			(layers "F.Cu" "F.Mask" "F.Paste")
			(net "USB3_01_FB_RXN")
		)
		(pad "7" smd rect
			(at 0.387604 0.499872 180)
			(size 0.254 0.635)
			(layers "F.Cu" "F.Mask" "F.Paste")
			(net "USB3_01_FB_RXP")
		)
		(pad "8" smd rect
			(at 0.412496 0 180)
			(size 0.4572 0.5842)
			(layers "F.Cu" "F.Mask" "F.Paste")
			(net "GND")
		)
		(pad "9" smd rect
			(at 0.387604 -0.499872 180)
			(size 0.254 0.635)
			(layers "F.Cu" "F.Mask" "F.Paste")
			(net "USB3_01_FB_TXN")
		)
		(pad "10" smd rect
			(at 0.387604 -0.999998 180)
			(size 0.254 0.635)
			(layers "F.Cu" "F.Mask" "F.Paste")
			(net "USB3_01_FB_TXP")
		)
	)
	(footprint ""
		(layer "F.Cu")
		(at 112.014 62.23 90)
		(property "Reference" "X17"
			(at -2.07137 1.0795 0)
			(unlocked yes)
			(layer "F.SilkS")
			(effects
				(font
					(size 0.7874 0.5842)
					(thickness 0.1524)
				)
				(justify left)
			)
		)
		(property "Value" ""
			(at 0 0 90)
			(layer "F.Fab")
			(effects
				(font
					(size 1.27 1.27)
				)
			)
		)
		(property "Device Type" "TP_TDR_4P_FTS_TH-TP_TDR_4P_DIPA"
			(at 1.30175 1.27 180)
			(unlocked yes)
			(layer "F.Fab")
			(hide yes)
			(effects
				(font
					(size 0.635 0.4064)
					(thickness 0.1524)
				)
			)
		)
		(property "User Part Number" "N_A"
			(at 1.30175 1.27 180)
			(unlocked yes)
			(layer "Cmts.User")
			(hide yes)
			(effects
				(font
					(size 0.635 0.4064)
					(thickness 0.1524)
				)
			)
		)
		(duplicate_pad_numbers_are_jumpers no)
		(fp_line
			(start 2.54 -1.27)
			(end 0 -1.27)
			(stroke
				(width 0.1524)
				(type default)
			)
			(layer "F.SilkS")
		)
		(fp_line
			(start 0 -1.27)
			(end 0 -0.635)
			(stroke
				(width 0.1524)
				(type default)
			)
			(layer "F.SilkS")
		)
		(fp_line
			(start 2.54 -1.1303)
			(end 2.54 -1.27)
			(stroke
				(width 0.1524)
				(type default)
			)
			(layer "F.SilkS")
		)
		(fp_line
			(start 0 0.635)
			(end 0 1.905)
			(stroke
				(width 0.1524)
				(type default)
			)
			(layer "F.SilkS")
		)
		(fp_line
			(start 2.54 1.4097)
			(end 2.54 1.1303)
			(stroke
				(width 0.1524)
				(type default)
			)
			(layer "F.SilkS")
		)
		(fp_line
			(start 0 3.175)
			(end 0 3.81)
			(stroke
				(width 0.1524)
				(type default)
			)
			(layer "F.SilkS")
		)
		(fp_line
			(start 2.54 3.81)
			(end 2.54 3.6703)
			(stroke
				(width 0.1524)
				(type default)
			)
			(layer "F.SilkS")
		)
		(fp_line
			(start 0 3.81)
			(end 2.54 3.81)
			(stroke
				(width 0.1524)
				(type default)
			)
			(layer "F.SilkS")
		)
		(fp_poly
			(pts
				(xy -0.761746 0) (xy -2.285746 -0.762) (xy -2.285746 0.762)
			)
			(stroke
				(width 0)
				(type default)
			)
			(fill yes)
			(layer "F.SilkS")
		)
		(fp_line
			(start 2.54 -1.27)
			(end 0 -1.27)
			(stroke
				(width 0.1)
				(type default)
			)
			(layer "F.Fab")
		)
		(fp_line
			(start 0 -1.27)
			(end 0 3.81)
			(stroke
				(width 0.1)
				(type default)
			)
			(layer "F.Fab")
		)
		(fp_line
			(start 2.54 3.81)
			(end 2.54 -1.27)
			(stroke
				(width 0.1)
				(type default)
			)
			(layer "F.Fab")
		)
		(fp_line
			(start 0 3.81)
			(end 2.54 3.81)
			(stroke
				(width 0.1)
				(type default)
			)
			(layer "F.Fab")
		)
		(fp_poly
			(pts
				(xy -0.761746 0) (xy -2.285746 -0.762) (xy -2.285746 0.762)
			)
			(stroke
				(width 0)
				(type default)
			)
			(fill yes)
			(layer "F.Fab")
		)
		(pad "1" thru_hole circle
			(at 0 0 90)
			(size 1.0033 1.0033)
			(drill 0.249936)
			(layers "*.Cu" "*.Mask")
			(remove_unused_layers no)
			(net "TDR_DIFF_100_IN4_DP")
			(clearance 0.10795)
			(thermal_gap 0.10795)
			(padstack
				(mode front_inner_back)
				(layer "Inner"
					(shape circle)
					(size 0.8001 0.8001)
					(clearance 0.1524)
				)
				(layer "B.Cu"
					(shape circle)
					(size 1.0033 1.0033)
					(clearance 0.10795)
				)
			)
		)
		(pad "2" thru_hole circle
			(at 2.54 0 90)
			(size 1.9939 1.9939)
			(drill 0.249936)
			(layers "*.Cu" "*.Mask")
			(remove_unused_layers no)
			(net "GND_P1")
			(clearance 0.10795)
			(thermal_gap 0.10795)
			(padstack
				(mode front_inner_back)
				(layer "Inner"
					(shape circle)
					(size 0.8001 0.8001)
					(clearance 0.1524)
				)
				(layer "B.Cu"
					(shape circle)
					(size 1.9939 1.9939)
					(clearance 0.10795)
				)
			)
		)
		(pad "3" thru_hole circle
			(at 2.54 2.54 90)
			(size 1.9939 1.9939)
			(drill 0.249936)
			(layers "*.Cu" "*.Mask")
			(remove_unused_layers no)
			(net "GND_P1")
			(clearance 0.10795)
			(thermal_gap 0.10795)
			(padstack
				(mode front_inner_back)
				(layer "Inner"
					(shape circle)
					(size 0.8001 0.8001)
					(clearance 0.1524)
				)
				(layer "B.Cu"
					(shape circle)
					(size 1.9939 1.9939)
					(clearance 0.10795)
				)
			)
		)
		(pad "4" thru_hole circle
			(at 0 2.54 90)
			(size 1.0033 1.0033)
			(drill 0.249936)
			(layers "*.Cu" "*.Mask")
			(remove_unused_layers no)
			(net "TDR_DIFF_100_IN4_DN")
			(clearance 0.10795)
			(thermal_gap 0.10795)
			(padstack
				(mode front_inner_back)
				(layer "Inner"
					(shape circle)
					(size 0.8001 0.8001)
					(clearance 0.1524)
				)
				(layer "B.Cu"
					(shape circle)
					(size 1.0033 1.0033)
					(clearance 0.10795)
				)
			)
		)
	)
	(footprint ""
		(layer "F.Cu")
		(at 60.36437 -34.637726 90)
		(property "Reference" "R203"
			(at 0 0 90)
			(layer "F.SilkS")
			(hide yes)
			(effects
				(font
					(size 1.27 1.27)
				)
			)
		)
		(property "Value" ""
			(at 0 0 90)
			(layer "F.Fab")
			(effects
				(font
					(size 1.27 1.27)
				)
			)
		)
		(duplicate_pad_numbers_are_jumpers no)
		(fp_line
			(start 0.7874 -0.4064)
			(end 0.7874 0.4064)
			(stroke
				(width 0.1524)
				(type default)
			)
			(layer "F.SilkS")
		)
		(fp_line
			(start -0.7874 -0.4064)
			(end 0.7874 -0.4064)
			(stroke
				(width 0.1524)
				(type default)
			)
			(layer "F.SilkS")
		)
		(fp_line
			(start 0.7874 0.4064)
			(end -0.7874 0.4064)
			(stroke
				(width 0.1524)
				(type default)
			)
			(layer "F.SilkS")
		)
		(fp_line
			(start -0.7874 0.4064)
			(end -0.7874 -0.4064)
			(stroke
				(width 0.1524)
				(type default)
			)
			(layer "F.SilkS")
		)
		(fp_line
			(start -0.12065 -0.305054)
			(end -0.12065 -0.2794)
			(stroke
				(width 0.1)
				(type default)
			)
			(layer "F.Fab")
		)
		(fp_line
			(start -0.67945 -0.305054)
			(end -0.12065 -0.305054)
			(stroke
				(width 0.1)
				(type default)
			)
			(layer "F.Fab")
		)
		(fp_line
			(start 0.67945 -0.3048)
			(end 0.67945 0.3048)
			(stroke
				(width 0.1)
				(type default)
			)
			(layer "F.Fab")
		)
		(fp_line
			(start 0.12065 -0.3048)
			(end 0.67945 -0.3048)
			(stroke
				(width 0.1)
				(type default)
			)
			(layer "F.Fab")
		)
		(fp_line
			(start 0.12065 -0.2794)
			(end 0.12065 -0.3048)
			(stroke
				(width 0.1)
				(type default)
			)
			(layer "F.Fab")
		)
		(fp_line
			(start -0.12065 -0.2794)
			(end 0.12065 -0.2794)
			(stroke
				(width 0.1)
				(type default)
			)
			(layer "F.Fab")
		)
		(fp_line
			(start 0.120396 0.2794)
			(end -0.12065 0.2794)
			(stroke
				(width 0.1)
				(type default)
			)
			(layer "F.Fab")
		)
		(fp_line
			(start -0.12065 0.2794)
			(end -0.12065 0.3048)
			(stroke
				(width 0.1)
				(type default)
			)
			(layer "F.Fab")
		)
		(fp_line
			(start 0.67945 0.3048)
			(end 0.120396 0.3048)
			(stroke
				(width 0.1)
				(type default)
			)
			(layer "F.Fab")
		)
		(fp_line
			(start 0.120396 0.3048)
			(end 0.120396 0.2794)
			(stroke
				(width 0.1)
				(type default)
			)
			(layer "F.Fab")
		)
		(fp_line
			(start -0.12065 0.3048)
			(end -0.67945 0.3048)
			(stroke
				(width 0.1)
				(type default)
			)
			(layer "F.Fab")
		)
		(fp_line
			(start -0.67945 0.3048)
			(end -0.67945 -0.305054)
			(stroke
				(width 0.1)
				(type default)
			)
			(layer "F.Fab")
		)
		(pad "1" smd circle
			(at -0.40005 0 90)
			(size 0 0)
			(layers "F.Cu" "F.Mask" "F.Paste")
			(net "P3V3_RGM")
		)
		(pad "2" smd circle
			(at 0.40005 0 90)
			(size 0 0)
			(layers "F.Cu" "F.Mask" "F.Paste")
			(net "JTAG_SCM_TMS")
		)
	)
	(footprint ""
		(layer "F.Cu")
		(at 45.72 -34.6202 90)
		(property "Reference" "R705"
			(at 0 0 90)
			(layer "F.SilkS")
			(hide yes)
			(effects
				(font
					(size 1.27 1.27)
				)
			)
		)
		(property "Value" ""
			(at 0 0 90)
			(layer "F.Fab")
			(effects
				(font
					(size 1.27 1.27)
				)
			)
		)
		(duplicate_pad_numbers_are_jumpers no)
		(fp_line
			(start 0.7874 -0.4064)
			(end 0.7874 0.4064)
			(stroke
				(width 0.1524)
				(type default)
			)
			(layer "F.SilkS")
		)
		(fp_line
			(start -0.7874 -0.4064)
			(end 0.7874 -0.4064)
			(stroke
				(width 0.1524)
				(type default)
			)
			(layer "F.SilkS")
		)
		(fp_line
			(start 0.7874 0.4064)
			(end -0.7874 0.4064)
			(stroke
				(width 0.1524)
				(type default)
			)
			(layer "F.SilkS")
		)
		(fp_line
			(start -0.7874 0.4064)
			(end -0.7874 -0.4064)
			(stroke
				(width 0.1524)
				(type default)
			)
			(layer "F.SilkS")
		)
		(fp_line
			(start -0.12065 -0.305054)
			(end -0.12065 -0.2794)
			(stroke
				(width 0.1)
				(type default)
			)
			(layer "F.Fab")
		)
		(fp_line
			(start -0.67945 -0.305054)
			(end -0.12065 -0.305054)
			(stroke
				(width 0.1)
				(type default)
			)
			(layer "F.Fab")
		)
		(fp_line
			(start 0.67945 -0.3048)
			(end 0.67945 0.3048)
			(stroke
				(width 0.1)
				(type default)
			)
			(layer "F.Fab")
		)
		(fp_line
			(start 0.12065 -0.3048)
			(end 0.67945 -0.3048)
			(stroke
				(width 0.1)
				(type default)
			)
			(layer "F.Fab")
		)
		(fp_line
			(start 0.12065 -0.2794)
			(end 0.12065 -0.3048)
			(stroke
				(width 0.1)
				(type default)
			)
			(layer "F.Fab")
		)
		(fp_line
			(start -0.12065 -0.2794)
			(end 0.12065 -0.2794)
			(stroke
				(width 0.1)
				(type default)
			)
			(layer "F.Fab")
		)
		(fp_line
			(start 0.120396 0.2794)
			(end -0.12065 0.2794)
			(stroke
				(width 0.1)
				(type default)
			)
			(layer "F.Fab")
		)
		(fp_line
			(start -0.12065 0.2794)
			(end -0.12065 0.3048)
			(stroke
				(width 0.1)
				(type default)
			)
			(layer "F.Fab")
		)
		(fp_line
			(start 0.67945 0.3048)
			(end 0.120396 0.3048)
			(stroke
				(width 0.1)
				(type default)
			)
			(layer "F.Fab")
		)
		(fp_line
			(start 0.120396 0.3048)
			(end 0.120396 0.2794)
			(stroke
				(width 0.1)
				(type default)
			)
			(layer "F.Fab")
		)
		(fp_line
			(start -0.12065 0.3048)
			(end -0.67945 0.3048)
			(stroke
				(width 0.1)
				(type default)
			)
			(layer "F.Fab")
		)
		(fp_line
			(start -0.67945 0.3048)
			(end -0.67945 -0.305054)
			(stroke
				(width 0.1)
				(type default)
			)
			(layer "F.Fab")
		)
		(pad "1" smd circle
			(at -0.40005 0 90)
			(size 0 0)
			(layers "F.Cu" "F.Mask" "F.Paste")
			(net "FM_BMC_DBP_PRESENT_N")
		)
		(pad "2" smd circle
			(at 0.40005 0 90)
			(size 0 0)
			(layers "F.Cu" "F.Mask" "F.Paste")
			(net "FM_BMC_DBP_PRESENT_R_N")
		)
	)
	(footprint ""
		(layer "F.Cu")
		(at 54.040278 -34.637726 -90)
		(property "Reference" "R20"
			(at 0 0 270)
			(layer "F.SilkS")
			(hide yes)
			(effects
				(font
					(size 1.27 1.27)
				)
			)
		)
		(property "Value" ""
			(at 0 0 270)
			(layer "F.Fab")
			(effects
				(font
					(size 1.27 1.27)
				)
			)
		)
		(duplicate_pad_numbers_are_jumpers no)
		(fp_line
			(start -0.7874 0.4064)
			(end -0.7874 -0.4064)
			(stroke
				(width 0.1524)
				(type default)
			)
			(layer "F.SilkS")
		)
		(fp_line
			(start 0.7874 0.4064)
			(end -0.7874 0.4064)
			(stroke
				(width 0.1524)
				(type default)
			)
			(layer "F.SilkS")
		)
		(fp_line
			(start -0.7874 -0.4064)
			(end 0.7874 -0.4064)
			(stroke
				(width 0.1524)
				(type default)
			)
			(layer "F.SilkS")
		)
		(fp_line
			(start 0.7874 -0.4064)
			(end 0.7874 0.4064)
			(stroke
				(width 0.1524)
				(type default)
			)
			(layer "F.SilkS")
		)
		(fp_line
			(start -0.67945 0.3048)
			(end -0.67945 -0.305054)
			(stroke
				(width 0.1)
				(type default)
			)
			(layer "F.Fab")
		)
		(fp_line
			(start -0.12065 0.3048)
			(end -0.67945 0.3048)
			(stroke
				(width 0.1)
				(type default)
			)
			(layer "F.Fab")
		)
		(fp_line
			(start 0.120396 0.3048)
			(end 0.120396 0.2794)
			(stroke
				(width 0.1)
				(type default)
			)
			(layer "F.Fab")
		)
		(fp_line
			(start 0.67945 0.3048)
			(end 0.120396 0.3048)
			(stroke
				(width 0.1)
				(type default)
			)
			(layer "F.Fab")
		)
		(fp_line
			(start -0.12065 0.2794)
			(end -0.12065 0.3048)
			(stroke
				(width 0.1)
				(type default)
			)
			(layer "F.Fab")
		)
		(fp_line
			(start 0.120396 0.2794)
			(end -0.12065 0.2794)
			(stroke
				(width 0.1)
				(type default)
			)
			(layer "F.Fab")
		)
		(fp_line
			(start -0.12065 -0.2794)
			(end 0.12065 -0.2794)
			(stroke
				(width 0.1)
				(type default)
			)
			(layer "F.Fab")
		)
		(fp_line
			(start 0.12065 -0.2794)
			(end 0.12065 -0.3048)
			(stroke
				(width 0.1)
				(type default)
			)
			(layer "F.Fab")
		)
		(fp_line
			(start 0.12065 -0.3048)
			(end 0.67945 -0.3048)
			(stroke
				(width 0.1)
				(type default)
			)
			(layer "F.Fab")
		)
		(fp_line
			(start 0.67945 -0.3048)
			(end 0.67945 0.3048)
			(stroke
				(width 0.1)
				(type default)
			)
			(layer "F.Fab")
		)
		(fp_line
			(start -0.67945 -0.305054)
			(end -0.12065 -0.305054)
			(stroke
				(width 0.1)
				(type default)
			)
			(layer "F.Fab")
		)
		(fp_line
			(start -0.12065 -0.305054)
			(end -0.12065 -0.2794)
			(stroke
				(width 0.1)
				(type default)
			)
			(layer "F.Fab")
		)
		(pad "1" smd circle
			(at -0.40005 0 270)
			(size 0 0)
			(layers "F.Cu" "F.Mask" "F.Paste")
			(net "V_VGAVS_R")
		)
		(pad "2" smd circle
			(at 0.40005 0 270)
			(size 0 0)
			(layers "F.Cu" "F.Mask" "F.Paste")
			(net "V_VGAVS")
		)
	)
	(footprint ""
		(layer "F.Cu")
		(at 74.168 -74.295 -90)
		(property "Reference" "R615"
			(at 0 0 270)
			(layer "F.SilkS")
			(hide yes)
			(effects
				(font
					(size 1.27 1.27)
				)
			)
		)
		(property "Value" ""
			(at 0 0 270)
			(layer "F.Fab")
			(effects
				(font
					(size 1.27 1.27)
				)
			)
		)
		(duplicate_pad_numbers_are_jumpers no)
		(fp_line
			(start -0.7874 0.4064)
			(end -0.7874 -0.4064)
			(stroke
				(width 0.1524)
				(type default)
			)
			(layer "F.SilkS")
		)
		(fp_line
			(start 0.7874 0.4064)
			(end -0.7874 0.4064)
			(stroke
				(width 0.1524)
				(type default)
			)
			(layer "F.SilkS")
		)
		(fp_line
			(start -0.7874 -0.4064)
			(end 0.7874 -0.4064)
			(stroke
				(width 0.1524)
				(type default)
			)
			(layer "F.SilkS")
		)
		(fp_line
			(start 0.7874 -0.4064)
			(end 0.7874 0.4064)
			(stroke
				(width 0.1524)
				(type default)
			)
			(layer "F.SilkS")
		)
		(fp_line
			(start -0.67945 0.3048)
			(end -0.67945 -0.305054)
			(stroke
				(width 0.1)
				(type default)
			)
			(layer "F.Fab")
		)
		(fp_line
			(start -0.12065 0.3048)
			(end -0.67945 0.3048)
			(stroke
				(width 0.1)
				(type default)
			)
			(layer "F.Fab")
		)
		(fp_line
			(start 0.120396 0.3048)
			(end 0.120396 0.2794)
			(stroke
				(width 0.1)
				(type default)
			)
			(layer "F.Fab")
		)
		(fp_line
			(start 0.67945 0.3048)
			(end 0.120396 0.3048)
			(stroke
				(width 0.1)
				(type default)
			)
			(layer "F.Fab")
		)
		(fp_line
			(start -0.12065 0.2794)
			(end -0.12065 0.3048)
			(stroke
				(width 0.1)
				(type default)
			)
			(layer "F.Fab")
		)
		(fp_line
			(start 0.120396 0.2794)
			(end -0.12065 0.2794)
			(stroke
				(width 0.1)
				(type default)
			)
			(layer "F.Fab")
		)
		(fp_line
			(start -0.12065 -0.2794)
			(end 0.12065 -0.2794)
			(stroke
				(width 0.1)
				(type default)
			)
			(layer "F.Fab")
		)
		(fp_line
			(start 0.12065 -0.2794)
			(end 0.12065 -0.3048)
			(stroke
				(width 0.1)
				(type default)
			)
			(layer "F.Fab")
		)
		(fp_line
			(start 0.12065 -0.3048)
			(end 0.67945 -0.3048)
			(stroke
				(width 0.1)
				(type default)
			)
			(layer "F.Fab")
		)
		(fp_line
			(start 0.67945 -0.3048)
			(end 0.67945 0.3048)
			(stroke
				(width 0.1)
				(type default)
			)
			(layer "F.Fab")
		)
		(fp_line
			(start -0.67945 -0.305054)
			(end -0.12065 -0.305054)
			(stroke
				(width 0.1)
				(type default)
			)
			(layer "F.Fab")
		)
		(fp_line
			(start -0.12065 -0.305054)
			(end -0.12065 -0.2794)
			(stroke
				(width 0.1)
				(type default)
			)
			(layer "F.Fab")
		)
		(pad "1" smd circle
			(at -0.40005 0 270)
			(size 0 0)
			(layers "F.Cu" "F.Mask" "F.Paste")
			(net "P3V3_AUX")
		)
		(pad "2" smd circle
			(at 0.40005 0 270)
			(size 0 0)
			(layers "F.Cu" "F.Mask" "F.Paste")
			(net "FM_BMC_DISABLE")
		)
	)
	(footprint ""
		(layer "F.Cu")
		(at 44.4754 -107.9246 -90)
		(property "Reference" "R483"
			(at 0 0 270)
			(layer "F.SilkS")
			(hide yes)
			(effects
				(font
					(size 1.27 1.27)
				)
			)
		)
		(property "Value" ""
			(at 0 0 270)
			(layer "F.Fab")
			(effects
				(font
					(size 1.27 1.27)
				)
			)
		)
		(duplicate_pad_numbers_are_jumpers no)
		(fp_line
			(start -0.7874 0.4064)
			(end -0.7874 -0.4064)
			(stroke
				(width 0.1524)
				(type default)
			)
			(layer "F.SilkS")
		)
		(fp_line
			(start 0.7874 0.4064)
			(end -0.7874 0.4064)
			(stroke
				(width 0.1524)
				(type default)
			)
			(layer "F.SilkS")
		)
		(fp_line
			(start -0.7874 -0.4064)
			(end 0.7874 -0.4064)
			(stroke
				(width 0.1524)
				(type default)
			)
			(layer "F.SilkS")
		)
		(fp_line
			(start 0.7874 -0.4064)
			(end 0.7874 0.4064)
			(stroke
				(width 0.1524)
				(type default)
			)
			(layer "F.SilkS")
		)
		(fp_line
			(start -0.67945 0.3048)
			(end -0.67945 -0.305054)
			(stroke
				(width 0.1)
				(type default)
			)
			(layer "F.Fab")
		)
		(fp_line
			(start -0.12065 0.3048)
			(end -0.67945 0.3048)
			(stroke
				(width 0.1)
				(type default)
			)
			(layer "F.Fab")
		)
		(fp_line
			(start 0.120396 0.3048)
			(end 0.120396 0.2794)
			(stroke
				(width 0.1)
				(type default)
			)
			(layer "F.Fab")
		)
		(fp_line
			(start 0.67945 0.3048)
			(end 0.120396 0.3048)
			(stroke
				(width 0.1)
				(type default)
			)
			(layer "F.Fab")
		)
		(fp_line
			(start -0.12065 0.2794)
			(end -0.12065 0.3048)
			(stroke
				(width 0.1)
				(type default)
			)
			(layer "F.Fab")
		)
		(fp_line
			(start 0.120396 0.2794)
			(end -0.12065 0.2794)
			(stroke
				(width 0.1)
				(type default)
			)
			(layer "F.Fab")
		)
		(fp_line
			(start -0.12065 -0.2794)
			(end 0.12065 -0.2794)
			(stroke
				(width 0.1)
				(type default)
			)
			(layer "F.Fab")
		)
		(fp_line
			(start 0.12065 -0.2794)
			(end 0.12065 -0.3048)
			(stroke
				(width 0.1)
				(type default)
			)
			(layer "F.Fab")
		)
		(fp_line
			(start 0.12065 -0.3048)
			(end 0.67945 -0.3048)
			(stroke
				(width 0.1)
				(type default)
			)
			(layer "F.Fab")
		)
		(fp_line
			(start 0.67945 -0.3048)
			(end 0.67945 0.3048)
			(stroke
				(width 0.1)
				(type default)
			)
			(layer "F.Fab")
		)
		(fp_line
			(start -0.67945 -0.305054)
			(end -0.12065 -0.305054)
			(stroke
				(width 0.1)
				(type default)
			)
			(layer "F.Fab")
		)
		(fp_line
			(start -0.12065 -0.305054)
			(end -0.12065 -0.2794)
			(stroke
				(width 0.1)
				(type default)
			)
			(layer "F.Fab")
		)
		(pad "1" smd circle
			(at -0.40005 0 270)
			(size 0 0)
			(layers "F.Cu" "F.Mask" "F.Paste")
			(net "SPI_PCH_MUXED_IO2")
		)
		(pad "2" smd circle
			(at 0.40005 0 270)
			(size 0 0)
			(layers "F.Cu" "F.Mask" "F.Paste")
			(net "SPI_PCH_IO2_FLASH_R1")
		)
	)
	(footprint ""
		(layer "F.Cu")
		(at 10.767568 -50.110898 -90)
		(property "Reference" "PR526"
			(at 0 0 270)
			(layer "F.SilkS")
			(hide yes)
			(effects
				(font
					(size 1.27 1.27)
				)
			)
		)
		(property "Value" ""
			(at 0 0 270)
			(layer "F.Fab")
			(effects
				(font
					(size 1.27 1.27)
				)
			)
		)
		(duplicate_pad_numbers_are_jumpers no)
		(fp_line
			(start -0.7874 0.4064)
			(end -0.7874 -0.4064)
			(stroke
				(width 0.1524)
				(type default)
			)
			(layer "F.SilkS")
		)
		(fp_line
			(start 0.7874 0.4064)
			(end -0.7874 0.4064)
			(stroke
				(width 0.1524)
				(type default)
			)
			(layer "F.SilkS")
		)
		(fp_line
			(start -0.7874 -0.4064)
			(end 0.7874 -0.4064)
			(stroke
				(width 0.1524)
				(type default)
			)
			(layer "F.SilkS")
		)
		(fp_line
			(start 0.7874 -0.4064)
			(end 0.7874 0.4064)
			(stroke
				(width 0.1524)
				(type default)
			)
			(layer "F.SilkS")
		)
		(fp_line
			(start -0.67945 0.3048)
			(end -0.67945 -0.305054)
			(stroke
				(width 0.1)
				(type default)
			)
			(layer "F.Fab")
		)
		(fp_line
			(start -0.12065 0.3048)
			(end -0.67945 0.3048)
			(stroke
				(width 0.1)
				(type default)
			)
			(layer "F.Fab")
		)
		(fp_line
			(start 0.120396 0.3048)
			(end 0.120396 0.2794)
			(stroke
				(width 0.1)
				(type default)
			)
			(layer "F.Fab")
		)
		(fp_line
			(start 0.67945 0.3048)
			(end 0.120396 0.3048)
			(stroke
				(width 0.1)
				(type default)
			)
			(layer "F.Fab")
		)
		(fp_line
			(start -0.12065 0.2794)
			(end -0.12065 0.3048)
			(stroke
				(width 0.1)
				(type default)
			)
			(layer "F.Fab")
		)
		(fp_line
			(start 0.120396 0.2794)
			(end -0.12065 0.2794)
			(stroke
				(width 0.1)
				(type default)
			)
			(layer "F.Fab")
		)
		(fp_line
			(start -0.12065 -0.2794)
			(end 0.12065 -0.2794)
			(stroke
				(width 0.1)
				(type default)
			)
			(layer "F.Fab")
		)
		(fp_line
			(start 0.12065 -0.2794)
			(end 0.12065 -0.3048)
			(stroke
				(width 0.1)
				(type default)
			)
			(layer "F.Fab")
		)
		(fp_line
			(start 0.12065 -0.3048)
			(end 0.67945 -0.3048)
			(stroke
				(width 0.1)
				(type default)
			)
			(layer "F.Fab")
		)
		(fp_line
			(start 0.67945 -0.3048)
			(end 0.67945 0.3048)
			(stroke
				(width 0.1)
				(type default)
			)
			(layer "F.Fab")
		)
		(fp_line
			(start -0.67945 -0.305054)
			(end -0.12065 -0.305054)
			(stroke
				(width 0.1)
				(type default)
			)
			(layer "F.Fab")
		)
		(fp_line
			(start -0.12065 -0.305054)
			(end -0.12065 -0.2794)
			(stroke
				(width 0.1)
				(type default)
			)
			(layer "F.Fab")
		)
		(pad "1" smd circle
			(at -0.40005 0 270)
			(size 0 0)
			(layers "F.Cu" "F.Mask" "F.Paste")
			(net "P5V_AUX_FB")
		)
		(pad "2" smd circle
			(at 0.40005 0 270)
			(size 0 0)
			(layers "F.Cu" "F.Mask" "F.Paste")
			(net "GND")
		)
	)
	(footprint ""
		(layer "F.Cu")
		(at 49.2125 -98.298 90)
		(property "Reference" "R287"
			(at 0 0 90)
			(layer "F.SilkS")
			(hide yes)
			(effects
				(font
					(size 1.27 1.27)
				)
			)
		)
		(property "Value" ""
			(at 0 0 90)
			(layer "F.Fab")
			(effects
				(font
					(size 1.27 1.27)
				)
			)
		)
		(duplicate_pad_numbers_are_jumpers no)
		(fp_line
			(start 0.7874 -0.4064)
			(end 0.7874 0.4064)
			(stroke
				(width 0.1524)
				(type default)
			)
			(layer "F.SilkS")
		)
		(fp_line
			(start -0.7874 -0.4064)
			(end 0.7874 -0.4064)
			(stroke
				(width 0.1524)
				(type default)
			)
			(layer "F.SilkS")
		)
		(fp_line
			(start 0.7874 0.4064)
			(end -0.7874 0.4064)
			(stroke
				(width 0.1524)
				(type default)
			)
			(layer "F.SilkS")
		)
		(fp_line
			(start -0.7874 0.4064)
			(end -0.7874 -0.4064)
			(stroke
				(width 0.1524)
				(type default)
			)
			(layer "F.SilkS")
		)
		(fp_line
			(start -0.12065 -0.305054)
			(end -0.12065 -0.2794)
			(stroke
				(width 0.1)
				(type default)
			)
			(layer "F.Fab")
		)
		(fp_line
			(start -0.67945 -0.305054)
			(end -0.12065 -0.305054)
			(stroke
				(width 0.1)
				(type default)
			)
			(layer "F.Fab")
		)
		(fp_line
			(start 0.67945 -0.3048)
			(end 0.67945 0.3048)
			(stroke
				(width 0.1)
				(type default)
			)
			(layer "F.Fab")
		)
		(fp_line
			(start 0.12065 -0.3048)
			(end 0.67945 -0.3048)
			(stroke
				(width 0.1)
				(type default)
			)
			(layer "F.Fab")
		)
		(fp_line
			(start 0.12065 -0.2794)
			(end 0.12065 -0.3048)
			(stroke
				(width 0.1)
				(type default)
			)
			(layer "F.Fab")
		)
		(fp_line
			(start -0.12065 -0.2794)
			(end 0.12065 -0.2794)
			(stroke
				(width 0.1)
				(type default)
			)
			(layer "F.Fab")
		)
		(fp_line
			(start 0.120396 0.2794)
			(end -0.12065 0.2794)
			(stroke
				(width 0.1)
				(type default)
			)
			(layer "F.Fab")
		)
		(fp_line
			(start -0.12065 0.2794)
			(end -0.12065 0.3048)
			(stroke
				(width 0.1)
				(type default)
			)
			(layer "F.Fab")
		)
		(fp_line
			(start 0.67945 0.3048)
			(end 0.120396 0.3048)
			(stroke
				(width 0.1)
				(type default)
			)
			(layer "F.Fab")
		)
		(fp_line
			(start 0.120396 0.3048)
			(end 0.120396 0.2794)
			(stroke
				(width 0.1)
				(type default)
			)
			(layer "F.Fab")
		)
		(fp_line
			(start -0.12065 0.3048)
			(end -0.67945 0.3048)
			(stroke
				(width 0.1)
				(type default)
			)
			(layer "F.Fab")
		)
		(fp_line
			(start -0.67945 0.3048)
			(end -0.67945 -0.305054)
			(stroke
				(width 0.1)
				(type default)
			)
			(layer "F.Fab")
		)
		(pad "1" smd circle
			(at -0.40005 0 90)
			(size 0 0)
			(layers "F.Cu" "F.Mask" "F.Paste")
			(net "P3V3_RGM")
		)
		(pad "2" smd circle
			(at 0.40005 0 90)
			(size 0 0)
			(layers "F.Cu" "F.Mask" "F.Paste")
			(net "RST_BMC_EXTRST_R2_N")
		)
	)
	(footprint ""
		(layer "F.Cu")
		(at 21.971 -66.1162 90)
		(property "Reference" "C500"
			(at 0 0 90)
			(layer "F.SilkS")
			(hide yes)
			(effects
				(font
					(size 1.27 1.27)
				)
			)
		)
		(property "Value" ""
			(at 0 0 90)
			(layer "F.Fab")
			(effects
				(font
					(size 1.27 1.27)
				)
			)
		)
		(duplicate_pad_numbers_are_jumpers no)
		(fp_line
			(start 0.7874 -0.4064)
			(end 0.7874 0.4064)
			(stroke
				(width 0.1524)
				(type default)
			)
			(layer "F.SilkS")
		)
		(fp_line
			(start -0.7874 -0.4064)
			(end 0.7874 -0.4064)
			(stroke
				(width 0.1524)
				(type default)
			)
			(layer "F.SilkS")
		)
		(fp_line
			(start 0.7874 0.4064)
			(end -0.7874 0.4064)
			(stroke
				(width 0.1524)
				(type default)
			)
			(layer "F.SilkS")
		)
		(fp_line
			(start -0.7874 0.4064)
			(end -0.7874 -0.4064)
			(stroke
				(width 0.1524)
				(type default)
			)
			(layer "F.SilkS")
		)
		(fp_line
			(start -0.12065 -0.305054)
			(end -0.12065 -0.2794)
			(stroke
				(width 0.1)
				(type default)
			)
			(layer "F.Fab")
		)
		(fp_line
			(start -0.67945 -0.305054)
			(end -0.12065 -0.305054)
			(stroke
				(width 0.1)
				(type default)
			)
			(layer "F.Fab")
		)
		(fp_line
			(start 0.67945 -0.3048)
			(end 0.67945 0.3048)
			(stroke
				(width 0.1)
				(type default)
			)
			(layer "F.Fab")
		)
		(fp_line
			(start 0.12065 -0.3048)
			(end 0.67945 -0.3048)
			(stroke
				(width 0.1)
				(type default)
			)
			(layer "F.Fab")
		)
		(fp_line
			(start 0.12065 -0.2794)
			(end 0.12065 -0.3048)
			(stroke
				(width 0.1)
				(type default)
			)
			(layer "F.Fab")
		)
		(fp_line
			(start -0.12065 -0.2794)
			(end 0.12065 -0.2794)
			(stroke
				(width 0.1)
				(type default)
			)
			(layer "F.Fab")
		)
		(fp_line
			(start 0.120396 0.2794)
			(end -0.12065 0.2794)
			(stroke
				(width 0.1)
				(type default)
			)
			(layer "F.Fab")
		)
		(fp_line
			(start -0.12065 0.2794)
			(end -0.12065 0.3048)
			(stroke
				(width 0.1)
				(type default)
			)
			(layer "F.Fab")
		)
		(fp_line
			(start 0.67945 0.3048)
			(end 0.120396 0.3048)
			(stroke
				(width 0.1)
				(type default)
			)
			(layer "F.Fab")
		)
		(fp_line
			(start 0.120396 0.3048)
			(end 0.120396 0.2794)
			(stroke
				(width 0.1)
				(type default)
			)
			(layer "F.Fab")
		)
		(fp_line
			(start -0.12065 0.3048)
			(end -0.67945 0.3048)
			(stroke
				(width 0.1)
				(type default)
			)
			(layer "F.Fab")
		)
		(fp_line
			(start -0.67945 0.3048)
			(end -0.67945 -0.305054)
			(stroke
				(width 0.1)
				(type default)
			)
			(layer "F.Fab")
		)
		(pad "1" smd circle
			(at -0.40005 0 90)
			(size 0 0)
			(layers "F.Cu" "F.Mask" "F.Paste")
			(net "P3V3_AUX")
		)
		(pad "2" smd circle
			(at 0.40005 0 90)
			(size 0 0)
			(layers "F.Cu" "F.Mask" "F.Paste")
			(net "GND")
		)
	)
	(footprint ""
		(layer "F.Cu")
		(at 61.469016 -81.10474)
		(property "Reference" "R508"
			(at 0 0 0)
			(layer "F.SilkS")
			(hide yes)
			(effects
				(font
					(size 1.27 1.27)
				)
			)
		)
		(property "Value" ""
			(at 0 0 0)
			(layer "F.Fab")
			(effects
				(font
					(size 1.27 1.27)
				)
			)
		)
		(duplicate_pad_numbers_are_jumpers no)
		(fp_line
			(start -0.7874 -0.4064)
			(end 0.7874 -0.4064)
			(stroke
				(width 0.1524)
				(type default)
			)
			(layer "F.SilkS")
		)
		(fp_line
			(start -0.7874 0.4064)
			(end -0.7874 -0.4064)
			(stroke
				(width 0.1524)
				(type default)
			)
			(layer "F.SilkS")
		)
		(fp_line
			(start 0.7874 -0.4064)
			(end 0.7874 0.4064)
			(stroke
				(width 0.1524)
				(type default)
			)
			(layer "F.SilkS")
		)
		(fp_line
			(start 0.7874 0.4064)
			(end -0.7874 0.4064)
			(stroke
				(width 0.1524)
				(type default)
			)
			(layer "F.SilkS")
		)
		(fp_line
			(start -0.67945 -0.305054)
			(end -0.12065 -0.305054)
			(stroke
				(width 0.1)
				(type default)
			)
			(layer "F.Fab")
		)
		(fp_line
			(start -0.67945 0.3048)
			(end -0.67945 -0.305054)
			(stroke
				(width 0.1)
				(type default)
			)
			(layer "F.Fab")
		)
		(fp_line
			(start -0.12065 -0.305054)
			(end -0.12065 -0.2794)
			(stroke
				(width 0.1)
				(type default)
			)
			(layer "F.Fab")
		)
		(fp_line
			(start -0.12065 -0.2794)
			(end 0.12065 -0.2794)
			(stroke
				(width 0.1)
				(type default)
			)
			(layer "F.Fab")
		)
		(fp_line
			(start -0.12065 0.2794)
			(end -0.12065 0.3048)
			(stroke
				(width 0.1)
				(type default)
			)
			(layer "F.Fab")
		)
		(fp_line
			(start -0.12065 0.3048)
			(end -0.67945 0.3048)
			(stroke
				(width 0.1)
				(type default)
			)
			(layer "F.Fab")
		)
		(fp_line
			(start 0.120396 0.2794)
			(end -0.12065 0.2794)
			(stroke
				(width 0.1)
				(type default)
			)
			(layer "F.Fab")
		)
		(fp_line
			(start 0.120396 0.3048)
			(end 0.120396 0.2794)
			(stroke
				(width 0.1)
				(type default)
			)
			(layer "F.Fab")
		)
		(fp_line
			(start 0.12065 -0.3048)
			(end 0.67945 -0.3048)
			(stroke
				(width 0.1)
				(type default)
			)
			(layer "F.Fab")
		)
		(fp_line
			(start 0.12065 -0.2794)
			(end 0.12065 -0.3048)
			(stroke
				(width 0.1)
				(type default)
			)
			(layer "F.Fab")
		)
		(fp_line
			(start 0.67945 -0.3048)
			(end 0.67945 0.3048)
			(stroke
				(width 0.1)
				(type default)
			)
			(layer "F.Fab")
		)
		(fp_line
			(start 0.67945 0.3048)
			(end 0.120396 0.3048)
			(stroke
				(width 0.1)
				(type default)
			)
			(layer "F.Fab")
		)
		(pad "1" smd circle
			(at -0.40005 0)
			(size 0 0)
			(layers "F.Cu" "F.Mask" "F.Paste")
			(net "P3V3_AUX")
		)
		(pad "2" smd circle
			(at 0.40005 0)
			(size 0 0)
			(layers "F.Cu" "F.Mask" "F.Paste")
			(net "MB_JTAG_PLD_R_JTAGEN")
		)
	)
	(footprint ""
		(layer "F.Cu")
		(at 86.522306 -109.933486 90)
		(property "Reference" "H2B1"
			(at -3.102356 -3.769106 0)
			(unlocked yes)
			(layer "F.SilkS")
			(effects
				(font
					(size 0.7874 0.5842)
					(thickness 0.1524)
				)
				(justify left)
			)
		)
		(property "Value" ""
			(at 0 0 90)
			(layer "F.Fab")
			(effects
				(font
					(size 1.27 1.27)
				)
			)
		)
		(duplicate_pad_numbers_are_jumpers no)
		(fp_circle
			(center 0 0)
			(end 0 2.4003)
			(stroke
				(width 0.1524)
				(type default)
			)
			(fill no)
			(layer "F.SilkS")
		)
		(fp_arc
			(start -6.015482 2.690876)
			(mid -2.409198 -6.133258)
			(end 6.23951 -2.124456)
			(stroke
				(width 0.1524)
				(type default)
			)
			(layer "B.SilkS")
		)
		(fp_circle
			(center 0 0)
			(end 0 6.5913)
			(stroke
				(width 0.1)
				(type default)
			)
			(fill no)
			(layer "B.Fab")
		)
		(fp_circle
			(center 0 0)
			(end 0 2.4003)
			(stroke
				(width 0.1)
				(type default)
			)
			(fill no)
			(layer "F.Fab")
		)
		(pad "" np_thru_hole circle
			(at 0 0 90)
			(size 3.175 3.175)
			(drill 3.175)
			(layers "*.Cu" "*.Mask")
			(clearance 0.381)
			(thermal_gap 0.381)
		)
		(zone
			(layers "F.Cu" "B.Cu" "In1.Cu" "In2.Cu" "In3.Cu" "In4.Cu" "In5.Cu" "In6.Cu"
				"In7.Cu" "In8.Cu" "In9.Cu" "In10.Cu"
			)
			(hatch none 0.5)
			(connect_pads
				(clearance 0)
			)
			(min_thickness 0.25)
			(keepout
				(tracks not_allowed)
				(vias allowed)
				(pads allowed)
				(copperpour not_allowed)
				(footprints allowed)
			)
			(placement
				(enabled no)
				(sheetname "")
			)
			(fill
				(thermal_gap 0.5)
				(thermal_bridge_width 0.5)
				(island_removal_mode 0)
			)
			(polygon
				(pts
					(arc
						(start 88.617806 -109.933486)
						(mid 84.426806 -109.933486)
						(end 88.617806 -109.933486)
					)
				)
			)
		)
	)
	(footprint ""
		(layer "F.Cu")
		(at 40.556942 -22.15642 -90)
		(property "Reference" "R673"
			(at 0 0 270)
			(layer "F.SilkS")
			(hide yes)
			(effects
				(font
					(size 1.27 1.27)
				)
			)
		)
		(property "Value" ""
			(at 0 0 270)
			(layer "F.Fab")
			(effects
				(font
					(size 1.27 1.27)
				)
			)
		)
		(duplicate_pad_numbers_are_jumpers no)
		(fp_line
			(start 0.7874 0.4064)
			(end -0.7874 0.4064)
			(stroke
				(width 0.1524)
				(type default)
			)
			(layer "F.SilkS")
		)
		(fp_line
			(start -0.7874 -0.4064)
			(end 0.7874 -0.4064)
			(stroke
				(width 0.1524)
				(type default)
			)
			(layer "F.SilkS")
		)
		(fp_line
			(start -0.67945 0.3048)
			(end -0.67945 -0.305054)
			(stroke
				(width 0.1)
				(type default)
			)
			(layer "F.Fab")
		)
		(fp_line
			(start -0.12065 0.3048)
			(end -0.67945 0.3048)
			(stroke
				(width 0.1)
				(type default)
			)
			(layer "F.Fab")
		)
		(fp_line
			(start 0.120396 0.3048)
			(end 0.120396 0.2794)
			(stroke
				(width 0.1)
				(type default)
			)
			(layer "F.Fab")
		)
		(fp_line
			(start 0.67945 0.3048)
			(end 0.120396 0.3048)
			(stroke
				(width 0.1)
				(type default)
			)
			(layer "F.Fab")
		)
		(fp_line
			(start -0.12065 0.2794)
			(end -0.12065 0.3048)
			(stroke
				(width 0.1)
				(type default)
			)
			(layer "F.Fab")
		)
		(fp_line
			(start 0.120396 0.2794)
			(end -0.12065 0.2794)
			(stroke
				(width 0.1)
				(type default)
			)
			(layer "F.Fab")
		)
		(fp_line
			(start -0.12065 -0.2794)
			(end 0.12065 -0.2794)
			(stroke
				(width 0.1)
				(type default)
			)
			(layer "F.Fab")
		)
		(fp_line
			(start 0.12065 -0.2794)
			(end 0.12065 -0.3048)
			(stroke
				(width 0.1)
				(type default)
			)
			(layer "F.Fab")
		)
		(fp_line
			(start 0.12065 -0.3048)
			(end 0.67945 -0.3048)
			(stroke
				(width 0.1)
				(type default)
			)
			(layer "F.Fab")
		)
		(fp_line
			(start 0.67945 -0.3048)
			(end 0.67945 0.3048)
			(stroke
				(width 0.1)
				(type default)
			)
			(layer "F.Fab")
		)
		(fp_line
			(start -0.67945 -0.305054)
			(end -0.12065 -0.305054)
			(stroke
				(width 0.1)
				(type default)
			)
			(layer "F.Fab")
		)
		(fp_line
			(start -0.12065 -0.305054)
			(end -0.12065 -0.2794)
			(stroke
				(width 0.1)
				(type default)
			)
			(layer "F.Fab")
		)
		(pad "1" smd circle
			(at -0.40005 0 270)
			(size 0 0)
			(layers "F.Cu" "F.Mask" "F.Paste")
			(net "USB3_01_MUX_FB_TXP")
		)
		(pad "2" smd circle
			(at 0.40005 0 270)
			(size 0 0)
			(layers "F.Cu" "F.Mask" "F.Paste")
			(net "USB3_01_FB_TXP")
		)
	)
	(footprint ""
		(layer "F.Cu")
		(at 67.900804 -31.191454 -90)
		(property "Reference" "U14"
			(at -2.019046 0.754634 90)
			(unlocked yes)
			(layer "F.SilkS")
			(effects
				(font
					(size 0.7874 0.5842)
					(thickness 0.1524)
				)
				(justify left)
			)
		)
		(property "Value" ""
			(at 0 0 270)
			(layer "F.Fab")
			(effects
				(font
					(size 1.27 1.27)
				)
			)
		)
		(duplicate_pad_numbers_are_jumpers no)
		(fp_line
			(start -1.733296 1.549908)
			(end 1.733296 1.549908)
			(stroke
				(width 0.1524)
				(type default)
			)
			(layer "F.SilkS")
		)
		(fp_line
			(start 1.733296 1.549908)
			(end 1.733296 -1.549908)
			(stroke
				(width 0.1524)
				(type default)
			)
			(layer "F.SilkS")
		)
		(fp_line
			(start 0 -0.889)
			(end -0.660908 -1.549908)
			(stroke
				(width 0.1524)
				(type default)
			)
			(layer "F.SilkS")
		)
		(fp_line
			(start -1.733296 -1.549908)
			(end -1.733296 1.549908)
			(stroke
				(width 0.1524)
				(type default)
			)
			(layer "F.SilkS")
		)
		(fp_line
			(start -0.660908 -1.549908)
			(end -1.733296 -1.549908)
			(stroke
				(width 0.1524)
				(type default)
			)
			(layer "F.SilkS")
		)
		(fp_line
			(start 0.660908 -1.549908)
			(end 0 -0.889)
			(stroke
				(width 0.1524)
				(type default)
			)
			(layer "F.SilkS")
		)
		(fp_line
			(start 1.733296 -1.549908)
			(end 0.660908 -1.549908)
			(stroke
				(width 0.1524)
				(type default)
			)
			(layer "F.SilkS")
		)
		(fp_poly
			(pts
				(xy -2.4384 -1.20396) (xy -2.4384 -0.69596) (xy -1.9304 -0.94996)
			)
			(stroke
				(width 0)
				(type default)
			)
			(fill yes)
			(layer "F.SilkS")
		)
		(fp_line
			(start -0.849884 1.549908)
			(end 0.849884 1.549908)
			(stroke
				(width 0.1)
				(type default)
			)
			(layer "F.Fab")
		)
		(fp_line
			(start 0.849884 1.549908)
			(end 0.849884 -1.549908)
			(stroke
				(width 0.1)
				(type default)
			)
			(layer "F.Fab")
		)
		(fp_line
			(start -0.849884 -1.549908)
			(end -0.849884 1.549908)
			(stroke
				(width 0.1)
				(type default)
			)
			(layer "F.Fab")
		)
		(fp_line
			(start 0.849884 -1.549908)
			(end -0.849884 -1.549908)
			(stroke
				(width 0.1)
				(type default)
			)
			(layer "F.Fab")
		)
		(fp_poly
			(pts
				(xy -2.4384 -1.20396) (xy -2.4384 -0.69596) (xy -1.9304 -0.94996)
			)
			(stroke
				(width 0)
				(type default)
			)
			(fill yes)
			(layer "F.Fab")
		)
		(pad "1" smd rect
			(at -1.199896 -0.94996 180)
			(size 0.5588 0.8128)
			(layers "F.Cu" "F.Mask" "F.Paste")
			(net "P3V3_RGM")
		)
		(pad "2" smd rect
			(at -1.199896 0 180)
			(size 0.5588 0.8128)
			(layers "F.Cu" "F.Mask" "F.Paste")
			(net "GND")
		)
		(pad "3" smd rect
			(at -1.199896 0.94996 180)
			(size 0.5588 0.8128)
			(layers "F.Cu" "F.Mask" "F.Paste")
			(net "TP_U14_FLAG_N")
		)
		(pad "4" smd rect
			(at 1.199896 0.94996 180)
			(size 0.5588 0.8128)
			(layers "F.Cu" "F.Mask" "F.Paste")
			(net "EN_P3V3_RGM_R")
		)
		(pad "5" smd rect
			(at 1.199896 -0.94996 180)
			(size 0.5588 0.8128)
			(layers "F.Cu" "F.Mask" "F.Paste")
			(net "P3V3_AUX")
		)
	)
	(footprint ""
		(layer "F.Cu")
		(at 12.319 -96.52 180)
		(property "Reference" "R638"
			(at 0 0 180)
			(layer "F.SilkS")
			(hide yes)
			(effects
				(font
					(size 1.27 1.27)
				)
			)
		)
		(property "Value" ""
			(at 0 0 180)
			(layer "F.Fab")
			(effects
				(font
					(size 1.27 1.27)
				)
			)
		)
		(duplicate_pad_numbers_are_jumpers no)
		(fp_line
			(start 0.7874 0.4064)
			(end -0.7874 0.4064)
			(stroke
				(width 0.1524)
				(type default)
			)
			(layer "F.SilkS")
		)
		(fp_line
			(start 0.7874 -0.4064)
			(end 0.7874 0.4064)
			(stroke
				(width 0.1524)
				(type default)
			)
			(layer "F.SilkS")
		)
		(fp_line
			(start -0.7874 0.4064)
			(end -0.7874 -0.4064)
			(stroke
				(width 0.1524)
				(type default)
			)
			(layer "F.SilkS")
		)
		(fp_line
			(start -0.7874 -0.4064)
			(end 0.7874 -0.4064)
			(stroke
				(width 0.1524)
				(type default)
			)
			(layer "F.SilkS")
		)
		(fp_line
			(start 0.67945 0.3048)
			(end 0.120396 0.3048)
			(stroke
				(width 0.1)
				(type default)
			)
			(layer "F.Fab")
		)
		(fp_line
			(start 0.67945 -0.3048)
			(end 0.67945 0.3048)
			(stroke
				(width 0.1)
				(type default)
			)
			(layer "F.Fab")
		)
		(fp_line
			(start 0.12065 -0.2794)
			(end 0.12065 -0.3048)
			(stroke
				(width 0.1)
				(type default)
			)
			(layer "F.Fab")
		)
		(fp_line
			(start 0.12065 -0.3048)
			(end 0.67945 -0.3048)
			(stroke
				(width 0.1)
				(type default)
			)
			(layer "F.Fab")
		)
		(fp_line
			(start 0.120396 0.3048)
			(end 0.120396 0.2794)
			(stroke
				(width 0.1)
				(type default)
			)
			(layer "F.Fab")
		)
		(fp_line
			(start 0.120396 0.2794)
			(end -0.12065 0.2794)
			(stroke
				(width 0.1)
				(type default)
			)
			(layer "F.Fab")
		)
		(fp_line
			(start -0.12065 0.3048)
			(end -0.67945 0.3048)
			(stroke
				(width 0.1)
				(type default)
			)
			(layer "F.Fab")
		)
		(fp_line
			(start -0.12065 0.2794)
			(end -0.12065 0.3048)
			(stroke
				(width 0.1)
				(type default)
			)
			(layer "F.Fab")
		)
		(fp_line
			(start -0.12065 -0.2794)
			(end 0.12065 -0.2794)
			(stroke
				(width 0.1)
				(type default)
			)
			(layer "F.Fab")
		)
		(fp_line
			(start -0.12065 -0.305054)
			(end -0.12065 -0.2794)
			(stroke
				(width 0.1)
				(type default)
			)
			(layer "F.Fab")
		)
		(fp_line
			(start -0.67945 0.3048)
			(end -0.67945 -0.305054)
			(stroke
				(width 0.1)
				(type default)
			)
			(layer "F.Fab")
		)
		(fp_line
			(start -0.67945 -0.305054)
			(end -0.12065 -0.305054)
			(stroke
				(width 0.1)
				(type default)
			)
			(layer "F.Fab")
		)
		(pad "1" smd circle
			(at -0.40005 0 180)
			(size 0 0)
			(layers "F.Cu" "F.Mask" "F.Paste")
			(net "RST_BMC_HW_R")
		)
		(pad "2" smd circle
			(at 0.40005 0 180)
			(size 0 0)
			(layers "F.Cu" "F.Mask" "F.Paste")
			(net "RST_BMC_HW")
		)
	)
	(footprint ""
		(layer "F.Cu")
		(at 19.05 -102.743 -90)
		(property "Reference" "R288"
			(at 0 0 270)
			(layer "F.SilkS")
			(hide yes)
			(effects
				(font
					(size 1.27 1.27)
				)
			)
		)
		(property "Value" ""
			(at 0 0 270)
			(layer "F.Fab")
			(effects
				(font
					(size 1.27 1.27)
				)
			)
		)
		(duplicate_pad_numbers_are_jumpers no)
		(fp_line
			(start -0.7874 0.4064)
			(end -0.7874 -0.4064)
			(stroke
				(width 0.1524)
				(type default)
			)
			(layer "F.SilkS")
		)
		(fp_line
			(start 0.7874 0.4064)
			(end -0.7874 0.4064)
			(stroke
				(width 0.1524)
				(type default)
			)
			(layer "F.SilkS")
		)
		(fp_line
			(start -0.7874 -0.4064)
			(end 0.7874 -0.4064)
			(stroke
				(width 0.1524)
				(type default)
			)
			(layer "F.SilkS")
		)
		(fp_line
			(start 0.7874 -0.4064)
			(end 0.7874 0.4064)
			(stroke
				(width 0.1524)
				(type default)
			)
			(layer "F.SilkS")
		)
		(fp_line
			(start -0.67945 0.3048)
			(end -0.67945 -0.305054)
			(stroke
				(width 0.1)
				(type default)
			)
			(layer "F.Fab")
		)
		(fp_line
			(start -0.12065 0.3048)
			(end -0.67945 0.3048)
			(stroke
				(width 0.1)
				(type default)
			)
			(layer "F.Fab")
		)
		(fp_line
			(start 0.120396 0.3048)
			(end 0.120396 0.2794)
			(stroke
				(width 0.1)
				(type default)
			)
			(layer "F.Fab")
		)
		(fp_line
			(start 0.67945 0.3048)
			(end 0.120396 0.3048)
			(stroke
				(width 0.1)
				(type default)
			)
			(layer "F.Fab")
		)
		(fp_line
			(start -0.12065 0.2794)
			(end -0.12065 0.3048)
			(stroke
				(width 0.1)
				(type default)
			)
			(layer "F.Fab")
		)
		(fp_line
			(start 0.120396 0.2794)
			(end -0.12065 0.2794)
			(stroke
				(width 0.1)
				(type default)
			)
			(layer "F.Fab")
		)
		(fp_line
			(start -0.12065 -0.2794)
			(end 0.12065 -0.2794)
			(stroke
				(width 0.1)
				(type default)
			)
			(layer "F.Fab")
		)
		(fp_line
			(start 0.12065 -0.2794)
			(end 0.12065 -0.3048)
			(stroke
				(width 0.1)
				(type default)
			)
			(layer "F.Fab")
		)
		(fp_line
			(start 0.12065 -0.3048)
			(end 0.67945 -0.3048)
			(stroke
				(width 0.1)
				(type default)
			)
			(layer "F.Fab")
		)
		(fp_line
			(start 0.67945 -0.3048)
			(end 0.67945 0.3048)
			(stroke
				(width 0.1)
				(type default)
			)
			(layer "F.Fab")
		)
		(fp_line
			(start -0.67945 -0.305054)
			(end -0.12065 -0.305054)
			(stroke
				(width 0.1)
				(type default)
			)
			(layer "F.Fab")
		)
		(fp_line
			(start -0.12065 -0.305054)
			(end -0.12065 -0.2794)
			(stroke
				(width 0.1)
				(type default)
			)
			(layer "F.Fab")
		)
		(pad "1" smd circle
			(at -0.40005 0 270)
			(size 0 0)
			(layers "F.Cu" "F.Mask" "F.Paste")
			(net "VCCIO2")
		)
		(pad "2" smd circle
			(at 0.40005 0 270)
			(size 0 0)
			(layers "F.Cu" "F.Mask" "F.Paste")
			(net "PU_PB25A")
		)
	)
	(footprint ""
		(layer "F.Cu")
		(at 29.845 -19.558 180)
		(property "Reference" "Q2"
			(at 2.921 -1.305052 0)
			(unlocked yes)
			(layer "F.SilkS")
			(effects
				(font
					(size 0.7874 0.5842)
					(thickness 0.1524)
				)
				(justify left)
			)
		)
		(property "Value" ""
			(at 0 0 180)
			(layer "F.Fab")
			(effects
				(font
					(size 1.27 1.27)
				)
			)
		)
		(duplicate_pad_numbers_are_jumpers no)
		(fp_line
			(start 1.332738 1.100074)
			(end -1.332738 1.100074)
			(stroke
				(width 0.1524)
				(type default)
			)
			(layer "F.SilkS")
		)
		(fp_line
			(start 1.332738 -1.100074)
			(end 1.332738 1.100074)
			(stroke
				(width 0.1524)
				(type default)
			)
			(layer "F.SilkS")
		)
		(fp_line
			(start 0.4826 -1.100074)
			(end 1.332738 -1.100074)
			(stroke
				(width 0.1524)
				(type default)
			)
			(layer "F.SilkS")
		)
		(fp_line
			(start 0 -0.541274)
			(end 0.4826 -1.100074)
			(stroke
				(width 0.1524)
				(type default)
			)
			(layer "F.SilkS")
		)
		(fp_line
			(start -0.4826 -1.100074)
			(end 0 -0.541274)
			(stroke
				(width 0.1524)
				(type default)
			)
			(layer "F.SilkS")
		)
		(fp_line
			(start -1.332738 1.100074)
			(end -1.332738 -1.100074)
			(stroke
				(width 0.1524)
				(type default)
			)
			(layer "F.SilkS")
		)
		(fp_line
			(start -1.332738 -1.100074)
			(end -0.4826 -1.100074)
			(stroke
				(width 0.1524)
				(type default)
			)
			(layer "F.SilkS")
		)
		(fp_poly
			(pts
				(xy -2.2352 -0.298958) (xy -2.2352 -1.001014) (xy -1.533144 -0.649986)
			)
			(stroke
				(width 0)
				(type default)
			)
			(fill yes)
			(layer "F.SilkS")
		)
		(fp_line
			(start 0.674878 1.100074)
			(end -0.674878 1.100074)
			(stroke
				(width 0.1)
				(type default)
			)
			(layer "F.Fab")
		)
		(fp_line
			(start 0.674878 -1.100074)
			(end 0.674878 1.100074)
			(stroke
				(width 0.1)
				(type default)
			)
			(layer "F.Fab")
		)
		(fp_line
			(start -0.674878 1.100074)
			(end -0.674878 -1.100074)
			(stroke
				(width 0.1)
				(type default)
			)
			(layer "F.Fab")
		)
		(fp_line
			(start -0.674878 -1.100074)
			(end 0.674878 -1.100074)
			(stroke
				(width 0.1)
				(type default)
			)
			(layer "F.Fab")
		)
		(fp_poly
			(pts
				(xy -2.2352 -0.298958) (xy -2.2352 -1.001014) (xy -1.533144 -0.649986)
			)
			(stroke
				(width 0)
				(type default)
			)
			(fill yes)
			(layer "F.Fab")
		)
		(pad "1" smd rect
			(at -0.94996 -0.649986 270)
			(size 0.4318 0.508)
			(layers "F.Cu" "F.Mask" "F.Paste")
			(net "V_BMC_DDC_SDA")
		)
		(pad "2" smd rect
			(at -0.94996 0 270)
			(size 0.4318 0.508)
			(layers "F.Cu" "F.Mask" "F.Paste")
			(net "V_BMC_DDC_LS_GATE")
		)
		(pad "3" smd rect
			(at -0.94996 0.649986 270)
			(size 0.4318 0.508)
			(layers "F.Cu" "F.Mask" "F.Paste")
			(net "V_BMC_LS_DDC_SCL")
		)
		(pad "4" smd rect
			(at 0.94996 0.649986 270)
			(size 0.4318 0.508)
			(layers "F.Cu" "F.Mask" "F.Paste")
			(net "V_BMC_DDC_SCL")
		)
		(pad "5" smd rect
			(at 0.94996 0 270)
			(size 0.4318 0.508)
			(layers "F.Cu" "F.Mask" "F.Paste")
			(net "V_BMC_DDC_LS_GATE")
		)
		(pad "6" smd rect
			(at 0.94996 -0.649986 270)
			(size 0.4318 0.508)
			(layers "F.Cu" "F.Mask" "F.Paste")
			(net "V_BMC_LS_DDC_SDA")
		)
	)
	(footprint ""
		(layer "F.Cu")
		(at 39.805102 -65.793366 90)
		(property "Reference" "R199"
			(at 0 0 90)
			(layer "F.SilkS")
			(hide yes)
			(effects
				(font
					(size 1.27 1.27)
				)
			)
		)
		(property "Value" ""
			(at 0 0 90)
			(layer "F.Fab")
			(effects
				(font
					(size 1.27 1.27)
				)
			)
		)
		(duplicate_pad_numbers_are_jumpers no)
		(fp_line
			(start 0.7874 -0.4064)
			(end 0.7874 0.4064)
			(stroke
				(width 0.1524)
				(type default)
			)
			(layer "F.SilkS")
		)
		(fp_line
			(start -0.7874 -0.4064)
			(end 0.7874 -0.4064)
			(stroke
				(width 0.1524)
				(type default)
			)
			(layer "F.SilkS")
		)
		(fp_line
			(start 0.7874 0.4064)
			(end -0.7874 0.4064)
			(stroke
				(width 0.1524)
				(type default)
			)
			(layer "F.SilkS")
		)
		(fp_line
			(start -0.7874 0.4064)
			(end -0.7874 -0.4064)
			(stroke
				(width 0.1524)
				(type default)
			)
			(layer "F.SilkS")
		)
		(fp_line
			(start -0.12065 -0.305054)
			(end -0.12065 -0.2794)
			(stroke
				(width 0.1)
				(type default)
			)
			(layer "F.Fab")
		)
		(fp_line
			(start -0.67945 -0.305054)
			(end -0.12065 -0.305054)
			(stroke
				(width 0.1)
				(type default)
			)
			(layer "F.Fab")
		)
		(fp_line
			(start 0.67945 -0.3048)
			(end 0.67945 0.3048)
			(stroke
				(width 0.1)
				(type default)
			)
			(layer "F.Fab")
		)
		(fp_line
			(start 0.12065 -0.3048)
			(end 0.67945 -0.3048)
			(stroke
				(width 0.1)
				(type default)
			)
			(layer "F.Fab")
		)
		(fp_line
			(start 0.12065 -0.2794)
			(end 0.12065 -0.3048)
			(stroke
				(width 0.1)
				(type default)
			)
			(layer "F.Fab")
		)
		(fp_line
			(start -0.12065 -0.2794)
			(end 0.12065 -0.2794)
			(stroke
				(width 0.1)
				(type default)
			)
			(layer "F.Fab")
		)
		(fp_line
			(start 0.120396 0.2794)
			(end -0.12065 0.2794)
			(stroke
				(width 0.1)
				(type default)
			)
			(layer "F.Fab")
		)
		(fp_line
			(start -0.12065 0.2794)
			(end -0.12065 0.3048)
			(stroke
				(width 0.1)
				(type default)
			)
			(layer "F.Fab")
		)
		(fp_line
			(start 0.67945 0.3048)
			(end 0.120396 0.3048)
			(stroke
				(width 0.1)
				(type default)
			)
			(layer "F.Fab")
		)
		(fp_line
			(start 0.120396 0.3048)
			(end 0.120396 0.2794)
			(stroke
				(width 0.1)
				(type default)
			)
			(layer "F.Fab")
		)
		(fp_line
			(start -0.12065 0.3048)
			(end -0.67945 0.3048)
			(stroke
				(width 0.1)
				(type default)
			)
			(layer "F.Fab")
		)
		(fp_line
			(start -0.67945 0.3048)
			(end -0.67945 -0.305054)
			(stroke
				(width 0.1)
				(type default)
			)
			(layer "F.Fab")
		)
		(pad "1" smd circle
			(at -0.40005 0 90)
			(size 0 0)
			(layers "F.Cu" "F.Mask" "F.Paste")
			(net "I3C3_SDA_R")
		)
		(pad "2" smd circle
			(at 0.40005 0 90)
			(size 0 0)
			(layers "F.Cu" "F.Mask" "F.Paste")
			(net "I3C3_SPD_SDA")
		)
	)
	(footprint ""
		(layer "F.Cu")
		(at 3.0734 -111.45266)
		(property "Reference" ""
			(at 0 0 0)
			(layer "F.SilkS")
			(hide yes)
			(effects
				(font
					(size 1.27 1.27)
				)
			)
		)
		(property "Value" ""
			(at 0 0 0)
			(layer "F.Fab")
			(effects
				(font
					(size 1.27 1.27)
				)
			)
		)
		(duplicate_pad_numbers_are_jumpers no)
		(pad "1" smd circle
			(at 0 0)
			(size 0.9906 0.9906)
			(layers "F.Cu" "F.Mask" "F.Paste")
			(net "Net_324")
		)
		(zone
			(layer "F.Cu")
			(hatch none 0.5)
			(connect_pads
				(clearance 0)
			)
			(min_thickness 0.25)
			(keepout
				(tracks not_allowed)
				(vias allowed)
				(pads allowed)
				(copperpour not_allowed)
				(footprints allowed)
			)
			(placement
				(enabled no)
				(sheetname "")
			)
			(fill
				(thermal_gap 0.5)
				(thermal_bridge_width 0.5)
				(island_removal_mode 0)
			)
			(polygon
				(pts
					(arc
						(start 4.699 -111.45266)
						(mid 1.4478 -111.45266)
						(end 4.699 -111.45266)
					)
				)
			)
		)
	)
	(footprint ""
		(layer "F.Cu")
		(at 16.256 -33.4518 -90)
		(property "Reference" "C302"
			(at 0 0 270)
			(layer "F.SilkS")
			(hide yes)
			(effects
				(font
					(size 1.27 1.27)
				)
			)
		)
		(property "Value" ""
			(at 0 0 270)
			(layer "F.Fab")
			(effects
				(font
					(size 1.27 1.27)
				)
			)
		)
		(duplicate_pad_numbers_are_jumpers no)
		(fp_line
			(start -0.7874 0.4064)
			(end -0.7874 -0.4064)
			(stroke
				(width 0.1524)
				(type default)
			)
			(layer "F.SilkS")
		)
		(fp_line
			(start 0.7874 0.4064)
			(end -0.7874 0.4064)
			(stroke
				(width 0.1524)
				(type default)
			)
			(layer "F.SilkS")
		)
		(fp_line
			(start -0.7874 -0.4064)
			(end 0.7874 -0.4064)
			(stroke
				(width 0.1524)
				(type default)
			)
			(layer "F.SilkS")
		)
		(fp_line
			(start 0.7874 -0.4064)
			(end 0.7874 0.4064)
			(stroke
				(width 0.1524)
				(type default)
			)
			(layer "F.SilkS")
		)
		(fp_line
			(start -0.67945 0.3048)
			(end -0.67945 -0.305054)
			(stroke
				(width 0.1)
				(type default)
			)
			(layer "F.Fab")
		)
		(fp_line
			(start -0.12065 0.3048)
			(end -0.67945 0.3048)
			(stroke
				(width 0.1)
				(type default)
			)
			(layer "F.Fab")
		)
		(fp_line
			(start 0.120396 0.3048)
			(end 0.120396 0.2794)
			(stroke
				(width 0.1)
				(type default)
			)
			(layer "F.Fab")
		)
		(fp_line
			(start 0.67945 0.3048)
			(end 0.120396 0.3048)
			(stroke
				(width 0.1)
				(type default)
			)
			(layer "F.Fab")
		)
		(fp_line
			(start -0.12065 0.2794)
			(end -0.12065 0.3048)
			(stroke
				(width 0.1)
				(type default)
			)
			(layer "F.Fab")
		)
		(fp_line
			(start 0.120396 0.2794)
			(end -0.12065 0.2794)
			(stroke
				(width 0.1)
				(type default)
			)
			(layer "F.Fab")
		)
		(fp_line
			(start -0.12065 -0.2794)
			(end 0.12065 -0.2794)
			(stroke
				(width 0.1)
				(type default)
			)
			(layer "F.Fab")
		)
		(fp_line
			(start 0.12065 -0.2794)
			(end 0.12065 -0.3048)
			(stroke
				(width 0.1)
				(type default)
			)
			(layer "F.Fab")
		)
		(fp_line
			(start 0.12065 -0.3048)
			(end 0.67945 -0.3048)
			(stroke
				(width 0.1)
				(type default)
			)
			(layer "F.Fab")
		)
		(fp_line
			(start 0.67945 -0.3048)
			(end 0.67945 0.3048)
			(stroke
				(width 0.1)
				(type default)
			)
			(layer "F.Fab")
		)
		(fp_line
			(start -0.67945 -0.305054)
			(end -0.12065 -0.305054)
			(stroke
				(width 0.1)
				(type default)
			)
			(layer "F.Fab")
		)
		(fp_line
			(start -0.12065 -0.305054)
			(end -0.12065 -0.2794)
			(stroke
				(width 0.1)
				(type default)
			)
			(layer "F.Fab")
		)
		(pad "1" smd circle
			(at -0.40005 0 270)
			(size 0 0)
			(layers "F.Cu" "F.Mask" "F.Paste")
			(net "P3V3_LDO")
		)
		(pad "2" smd circle
			(at 0.40005 0 270)
			(size 0 0)
			(layers "F.Cu" "F.Mask" "F.Paste")
			(net "GND")
		)
	)
	(footprint ""
		(layer "F.Cu")
		(at 25.273 -68.834 90)
		(property "Reference" "R543"
			(at 0 0 90)
			(layer "F.SilkS")
			(hide yes)
			(effects
				(font
					(size 1.27 1.27)
				)
			)
		)
		(property "Value" ""
			(at 0 0 90)
			(layer "F.Fab")
			(effects
				(font
					(size 1.27 1.27)
				)
			)
		)
		(duplicate_pad_numbers_are_jumpers no)
		(fp_line
			(start 0.7874 -0.4064)
			(end 0.7874 0.4064)
			(stroke
				(width 0.1524)
				(type default)
			)
			(layer "F.SilkS")
		)
		(fp_line
			(start -0.7874 -0.4064)
			(end 0.7874 -0.4064)
			(stroke
				(width 0.1524)
				(type default)
			)
			(layer "F.SilkS")
		)
		(fp_line
			(start 0.7874 0.4064)
			(end -0.7874 0.4064)
			(stroke
				(width 0.1524)
				(type default)
			)
			(layer "F.SilkS")
		)
		(fp_line
			(start -0.7874 0.4064)
			(end -0.7874 -0.4064)
			(stroke
				(width 0.1524)
				(type default)
			)
			(layer "F.SilkS")
		)
		(fp_line
			(start -0.12065 -0.305054)
			(end -0.12065 -0.2794)
			(stroke
				(width 0.1)
				(type default)
			)
			(layer "F.Fab")
		)
		(fp_line
			(start -0.67945 -0.305054)
			(end -0.12065 -0.305054)
			(stroke
				(width 0.1)
				(type default)
			)
			(layer "F.Fab")
		)
		(fp_line
			(start 0.67945 -0.3048)
			(end 0.67945 0.3048)
			(stroke
				(width 0.1)
				(type default)
			)
			(layer "F.Fab")
		)
		(fp_line
			(start 0.12065 -0.3048)
			(end 0.67945 -0.3048)
			(stroke
				(width 0.1)
				(type default)
			)
			(layer "F.Fab")
		)
		(fp_line
			(start 0.12065 -0.2794)
			(end 0.12065 -0.3048)
			(stroke
				(width 0.1)
				(type default)
			)
			(layer "F.Fab")
		)
		(fp_line
			(start -0.12065 -0.2794)
			(end 0.12065 -0.2794)
			(stroke
				(width 0.1)
				(type default)
			)
			(layer "F.Fab")
		)
		(fp_line
			(start 0.120396 0.2794)
			(end -0.12065 0.2794)
			(stroke
				(width 0.1)
				(type default)
			)
			(layer "F.Fab")
		)
		(fp_line
			(start -0.12065 0.2794)
			(end -0.12065 0.3048)
			(stroke
				(width 0.1)
				(type default)
			)
			(layer "F.Fab")
		)
		(fp_line
			(start 0.67945 0.3048)
			(end 0.120396 0.3048)
			(stroke
				(width 0.1)
				(type default)
			)
			(layer "F.Fab")
		)
		(fp_line
			(start 0.120396 0.3048)
			(end 0.120396 0.2794)
			(stroke
				(width 0.1)
				(type default)
			)
			(layer "F.Fab")
		)
		(fp_line
			(start -0.12065 0.3048)
			(end -0.67945 0.3048)
			(stroke
				(width 0.1)
				(type default)
			)
			(layer "F.Fab")
		)
		(fp_line
			(start -0.67945 0.3048)
			(end -0.67945 -0.305054)
			(stroke
				(width 0.1)
				(type default)
			)
			(layer "F.Fab")
		)
		(pad "1" smd circle
			(at -0.40005 0 90)
			(size 0 0)
			(layers "F.Cu" "F.Mask" "F.Paste")
			(net "P3V3_AUX")
		)
		(pad "2" smd circle
			(at 0.40005 0 90)
			(size 0 0)
			(layers "F.Cu" "F.Mask" "F.Paste")
			(net "SPI_BMC_HOLD1_N")
		)
	)
	(footprint ""
		(layer "F.Cu")
		(at 65.618106 -29.377132 -90)
		(property "Reference" "R218"
			(at 0 0 270)
			(layer "F.SilkS")
			(hide yes)
			(effects
				(font
					(size 1.27 1.27)
				)
			)
		)
		(property "Value" ""
			(at 0 0 270)
			(layer "F.Fab")
			(effects
				(font
					(size 1.27 1.27)
				)
			)
		)
		(duplicate_pad_numbers_are_jumpers no)
		(fp_line
			(start 0.458978 0.4064)
			(end -0.397002 0.4064)
			(stroke
				(width 0.1524)
				(type default)
			)
			(layer "F.SilkS")
		)
		(fp_line
			(start -0.7874 0.060706)
			(end -0.7874 -0.4064)
			(stroke
				(width 0.1524)
				(type default)
			)
			(layer "F.SilkS")
		)
		(fp_line
			(start -0.7874 -0.4064)
			(end 0.7874 -0.4064)
			(stroke
				(width 0.1524)
				(type default)
			)
			(layer "F.SilkS")
		)
		(fp_line
			(start 0.7874 -0.4064)
			(end 0.7874 -0.010414)
			(stroke
				(width 0.1524)
				(type default)
			)
			(layer "F.SilkS")
		)
		(fp_line
			(start -0.67945 0.3048)
			(end -0.67945 -0.305054)
			(stroke
				(width 0.1)
				(type default)
			)
			(layer "F.Fab")
		)
		(fp_line
			(start -0.12065 0.3048)
			(end -0.67945 0.3048)
			(stroke
				(width 0.1)
				(type default)
			)
			(layer "F.Fab")
		)
		(fp_line
			(start 0.120396 0.3048)
			(end 0.120396 0.2794)
			(stroke
				(width 0.1)
				(type default)
			)
			(layer "F.Fab")
		)
		(fp_line
			(start 0.67945 0.3048)
			(end 0.120396 0.3048)
			(stroke
				(width 0.1)
				(type default)
			)
			(layer "F.Fab")
		)
		(fp_line
			(start -0.12065 0.2794)
			(end -0.12065 0.3048)
			(stroke
				(width 0.1)
				(type default)
			)
			(layer "F.Fab")
		)
		(fp_line
			(start 0.120396 0.2794)
			(end -0.12065 0.2794)
			(stroke
				(width 0.1)
				(type default)
			)
			(layer "F.Fab")
		)
		(fp_line
			(start -0.12065 -0.2794)
			(end 0.12065 -0.2794)
			(stroke
				(width 0.1)
				(type default)
			)
			(layer "F.Fab")
		)
		(fp_line
			(start 0.12065 -0.2794)
			(end 0.12065 -0.3048)
			(stroke
				(width 0.1)
				(type default)
			)
			(layer "F.Fab")
		)
		(fp_line
			(start 0.12065 -0.3048)
			(end 0.67945 -0.3048)
			(stroke
				(width 0.1)
				(type default)
			)
			(layer "F.Fab")
		)
		(fp_line
			(start 0.67945 -0.3048)
			(end 0.67945 0.3048)
			(stroke
				(width 0.1)
				(type default)
			)
			(layer "F.Fab")
		)
		(fp_line
			(start -0.67945 -0.305054)
			(end -0.12065 -0.305054)
			(stroke
				(width 0.1)
				(type default)
			)
			(layer "F.Fab")
		)
		(fp_line
			(start -0.12065 -0.305054)
			(end -0.12065 -0.2794)
			(stroke
				(width 0.1)
				(type default)
			)
			(layer "F.Fab")
		)
		(pad "1" smd circle
			(at -0.40005 0 270)
			(size 0 0)
			(layers "F.Cu" "F.Mask" "F.Paste")
			(net "USB_HOST_BMC_A_R_DN")
		)
		(pad "2" smd circle
			(at 0.40005 0 270)
			(size 0 0)
			(layers "F.Cu" "F.Mask" "F.Paste")
			(net "USB_HOST_BMC_A_DN")
		)
	)
	(footprint ""
		(layer "F.Cu")
		(at 32.893 -36.195 90)
		(property "Reference" "R451"
			(at 0 0 90)
			(layer "F.SilkS")
			(hide yes)
			(effects
				(font
					(size 1.27 1.27)
				)
			)
		)
		(property "Value" ""
			(at 0 0 90)
			(layer "F.Fab")
			(effects
				(font
					(size 1.27 1.27)
				)
			)
		)
		(duplicate_pad_numbers_are_jumpers no)
		(fp_line
			(start 0.7874 -0.4064)
			(end 0.7874 0.4064)
			(stroke
				(width 0.1524)
				(type default)
			)
			(layer "F.SilkS")
		)
		(fp_line
			(start -0.7874 -0.4064)
			(end 0.7874 -0.4064)
			(stroke
				(width 0.1524)
				(type default)
			)
			(layer "F.SilkS")
		)
		(fp_line
			(start 0.7874 0.4064)
			(end -0.7874 0.4064)
			(stroke
				(width 0.1524)
				(type default)
			)
			(layer "F.SilkS")
		)
		(fp_line
			(start -0.7874 0.4064)
			(end -0.7874 -0.4064)
			(stroke
				(width 0.1524)
				(type default)
			)
			(layer "F.SilkS")
		)
		(fp_line
			(start -0.12065 -0.305054)
			(end -0.12065 -0.2794)
			(stroke
				(width 0.1)
				(type default)
			)
			(layer "F.Fab")
		)
		(fp_line
			(start -0.67945 -0.305054)
			(end -0.12065 -0.305054)
			(stroke
				(width 0.1)
				(type default)
			)
			(layer "F.Fab")
		)
		(fp_line
			(start 0.67945 -0.3048)
			(end 0.67945 0.3048)
			(stroke
				(width 0.1)
				(type default)
			)
			(layer "F.Fab")
		)
		(fp_line
			(start 0.12065 -0.3048)
			(end 0.67945 -0.3048)
			(stroke
				(width 0.1)
				(type default)
			)
			(layer "F.Fab")
		)
		(fp_line
			(start 0.12065 -0.2794)
			(end 0.12065 -0.3048)
			(stroke
				(width 0.1)
				(type default)
			)
			(layer "F.Fab")
		)
		(fp_line
			(start -0.12065 -0.2794)
			(end 0.12065 -0.2794)
			(stroke
				(width 0.1)
				(type default)
			)
			(layer "F.Fab")
		)
		(fp_line
			(start 0.120396 0.2794)
			(end -0.12065 0.2794)
			(stroke
				(width 0.1)
				(type default)
			)
			(layer "F.Fab")
		)
		(fp_line
			(start -0.12065 0.2794)
			(end -0.12065 0.3048)
			(stroke
				(width 0.1)
				(type default)
			)
			(layer "F.Fab")
		)
		(fp_line
			(start 0.67945 0.3048)
			(end 0.120396 0.3048)
			(stroke
				(width 0.1)
				(type default)
			)
			(layer "F.Fab")
		)
		(fp_line
			(start 0.120396 0.3048)
			(end 0.120396 0.2794)
			(stroke
				(width 0.1)
				(type default)
			)
			(layer "F.Fab")
		)
		(fp_line
			(start -0.12065 0.3048)
			(end -0.67945 0.3048)
			(stroke
				(width 0.1)
				(type default)
			)
			(layer "F.Fab")
		)
		(fp_line
			(start -0.67945 0.3048)
			(end -0.67945 -0.305054)
			(stroke
				(width 0.1)
				(type default)
			)
			(layer "F.Fab")
		)
		(pad "1" smd circle
			(at -0.40005 0 90)
			(size 0 0)
			(layers "F.Cu" "F.Mask" "F.Paste")
			(net "PWRGD_P1V0_AUX_DELAY")
		)
		(pad "2" smd circle
			(at 0.40005 0 90)
			(size 0 0)
			(layers "F.Cu" "F.Mask" "F.Paste")
			(net "PWRGD_P1V0_AUX_DELAY_R1")
		)
	)
	(footprint ""
		(layer "F.Cu")
		(at 43.948604 -87.679784 90)
		(property "Reference" "R484"
			(at 0 0 90)
			(layer "F.SilkS")
			(hide yes)
			(effects
				(font
					(size 1.27 1.27)
				)
			)
		)
		(property "Value" ""
			(at 0 0 90)
			(layer "F.Fab")
			(effects
				(font
					(size 1.27 1.27)
				)
			)
		)
		(duplicate_pad_numbers_are_jumpers no)
		(fp_line
			(start 0.7874 -0.4064)
			(end 0.7874 0.4064)
			(stroke
				(width 0.1524)
				(type default)
			)
			(layer "F.SilkS")
		)
		(fp_line
			(start -0.7874 -0.4064)
			(end 0.7874 -0.4064)
			(stroke
				(width 0.1524)
				(type default)
			)
			(layer "F.SilkS")
		)
		(fp_line
			(start 0.7874 0.4064)
			(end -0.7874 0.4064)
			(stroke
				(width 0.1524)
				(type default)
			)
			(layer "F.SilkS")
		)
		(fp_line
			(start -0.7874 0.4064)
			(end -0.7874 -0.4064)
			(stroke
				(width 0.1524)
				(type default)
			)
			(layer "F.SilkS")
		)
		(fp_line
			(start -0.12065 -0.305054)
			(end -0.12065 -0.2794)
			(stroke
				(width 0.1)
				(type default)
			)
			(layer "F.Fab")
		)
		(fp_line
			(start -0.67945 -0.305054)
			(end -0.12065 -0.305054)
			(stroke
				(width 0.1)
				(type default)
			)
			(layer "F.Fab")
		)
		(fp_line
			(start 0.67945 -0.3048)
			(end 0.67945 0.3048)
			(stroke
				(width 0.1)
				(type default)
			)
			(layer "F.Fab")
		)
		(fp_line
			(start 0.12065 -0.3048)
			(end 0.67945 -0.3048)
			(stroke
				(width 0.1)
				(type default)
			)
			(layer "F.Fab")
		)
		(fp_line
			(start 0.12065 -0.2794)
			(end 0.12065 -0.3048)
			(stroke
				(width 0.1)
				(type default)
			)
			(layer "F.Fab")
		)
		(fp_line
			(start -0.12065 -0.2794)
			(end 0.12065 -0.2794)
			(stroke
				(width 0.1)
				(type default)
			)
			(layer "F.Fab")
		)
		(fp_line
			(start 0.120396 0.2794)
			(end -0.12065 0.2794)
			(stroke
				(width 0.1)
				(type default)
			)
			(layer "F.Fab")
		)
		(fp_line
			(start -0.12065 0.2794)
			(end -0.12065 0.3048)
			(stroke
				(width 0.1)
				(type default)
			)
			(layer "F.Fab")
		)
		(fp_line
			(start 0.67945 0.3048)
			(end 0.120396 0.3048)
			(stroke
				(width 0.1)
				(type default)
			)
			(layer "F.Fab")
		)
		(fp_line
			(start 0.120396 0.3048)
			(end 0.120396 0.2794)
			(stroke
				(width 0.1)
				(type default)
			)
			(layer "F.Fab")
		)
		(fp_line
			(start -0.12065 0.3048)
			(end -0.67945 0.3048)
			(stroke
				(width 0.1)
				(type default)
			)
			(layer "F.Fab")
		)
		(fp_line
			(start -0.67945 0.3048)
			(end -0.67945 -0.305054)
			(stroke
				(width 0.1)
				(type default)
			)
			(layer "F.Fab")
		)
		(pad "1" smd circle
			(at -0.40005 0 90)
			(size 0 0)
			(layers "F.Cu" "F.Mask" "F.Paste")
			(net "SPI_PCH_MUXED_IO1")
		)
		(pad "2" smd circle
			(at 0.40005 0 90)
			(size 0 0)
			(layers "F.Cu" "F.Mask" "F.Paste")
			(net "SPI_PCH_IO1_FLASH_R1")
		)
	)
	(footprint ""
		(layer "F.Cu")
		(at 24.257 -68.834 90)
		(property "Reference" "R404"
			(at 0 0 90)
			(layer "F.SilkS")
			(hide yes)
			(effects
				(font
					(size 1.27 1.27)
				)
			)
		)
		(property "Value" ""
			(at 0 0 90)
			(layer "F.Fab")
			(effects
				(font
					(size 1.27 1.27)
				)
			)
		)
		(duplicate_pad_numbers_are_jumpers no)
		(fp_line
			(start 0.7874 -0.4064)
			(end 0.7874 0.4064)
			(stroke
				(width 0.1524)
				(type default)
			)
			(layer "F.SilkS")
		)
		(fp_line
			(start -0.7874 -0.4064)
			(end 0.7874 -0.4064)
			(stroke
				(width 0.1524)
				(type default)
			)
			(layer "F.SilkS")
		)
		(fp_line
			(start 0.7874 0.4064)
			(end -0.7874 0.4064)
			(stroke
				(width 0.1524)
				(type default)
			)
			(layer "F.SilkS")
		)
		(fp_line
			(start -0.7874 0.4064)
			(end -0.7874 -0.4064)
			(stroke
				(width 0.1524)
				(type default)
			)
			(layer "F.SilkS")
		)
		(fp_line
			(start -0.12065 -0.305054)
			(end -0.12065 -0.2794)
			(stroke
				(width 0.1)
				(type default)
			)
			(layer "F.Fab")
		)
		(fp_line
			(start -0.67945 -0.305054)
			(end -0.12065 -0.305054)
			(stroke
				(width 0.1)
				(type default)
			)
			(layer "F.Fab")
		)
		(fp_line
			(start 0.67945 -0.3048)
			(end 0.67945 0.3048)
			(stroke
				(width 0.1)
				(type default)
			)
			(layer "F.Fab")
		)
		(fp_line
			(start 0.12065 -0.3048)
			(end 0.67945 -0.3048)
			(stroke
				(width 0.1)
				(type default)
			)
			(layer "F.Fab")
		)
		(fp_line
			(start 0.12065 -0.2794)
			(end 0.12065 -0.3048)
			(stroke
				(width 0.1)
				(type default)
			)
			(layer "F.Fab")
		)
		(fp_line
			(start -0.12065 -0.2794)
			(end 0.12065 -0.2794)
			(stroke
				(width 0.1)
				(type default)
			)
			(layer "F.Fab")
		)
		(fp_line
			(start 0.120396 0.2794)
			(end -0.12065 0.2794)
			(stroke
				(width 0.1)
				(type default)
			)
			(layer "F.Fab")
		)
		(fp_line
			(start -0.12065 0.2794)
			(end -0.12065 0.3048)
			(stroke
				(width 0.1)
				(type default)
			)
			(layer "F.Fab")
		)
		(fp_line
			(start 0.67945 0.3048)
			(end 0.120396 0.3048)
			(stroke
				(width 0.1)
				(type default)
			)
			(layer "F.Fab")
		)
		(fp_line
			(start 0.120396 0.3048)
			(end 0.120396 0.2794)
			(stroke
				(width 0.1)
				(type default)
			)
			(layer "F.Fab")
		)
		(fp_line
			(start -0.12065 0.3048)
			(end -0.67945 0.3048)
			(stroke
				(width 0.1)
				(type default)
			)
			(layer "F.Fab")
		)
		(fp_line
			(start -0.67945 0.3048)
			(end -0.67945 -0.305054)
			(stroke
				(width 0.1)
				(type default)
			)
			(layer "F.Fab")
		)
		(pad "1" smd circle
			(at -0.40005 0 90)
			(size 0 0)
			(layers "F.Cu" "F.Mask" "F.Paste")
			(net "P3V3_AUX")
		)
		(pad "2" smd circle
			(at 0.40005 0 90)
			(size 0 0)
			(layers "F.Cu" "F.Mask" "F.Paste")
			(net "BSM_PRSNT_N")
		)
	)
	(footprint ""
		(layer "F.Cu")
		(at 81.755996 -78.151228 180)
		(property "Reference" "PC251"
			(at 0 0 180)
			(layer "F.SilkS")
			(hide yes)
			(effects
				(font
					(size 1.27 1.27)
				)
			)
		)
		(property "Value" ""
			(at 0 0 180)
			(layer "F.Fab")
			(effects
				(font
					(size 1.27 1.27)
				)
			)
		)
		(duplicate_pad_numbers_are_jumpers no)
		(fp_line
			(start 1.651 0.8382)
			(end -1.651 0.8382)
			(stroke
				(width 0.1524)
				(type default)
			)
			(layer "F.SilkS")
		)
		(fp_line
			(start 1.651 -0.8382)
			(end 1.651 0.8382)
			(stroke
				(width 0.1524)
				(type default)
			)
			(layer "F.SilkS")
		)
		(fp_line
			(start 0 0.8382)
			(end 0 -0.8382)
			(stroke
				(width 0.1524)
				(type default)
			)
			(layer "F.SilkS")
		)
		(fp_line
			(start -1.651 0.8382)
			(end -1.651 -0.8382)
			(stroke
				(width 0.1524)
				(type default)
			)
			(layer "F.SilkS")
		)
		(fp_line
			(start -1.651 -0.8382)
			(end 1.651 -0.8382)
			(stroke
				(width 0.1524)
				(type default)
			)
			(layer "F.SilkS")
		)
		(fp_line
			(start 1.55956 0.7366)
			(end 1.55956 -0.7366)
			(stroke
				(width 0.1)
				(type default)
			)
			(layer "F.Fab")
		)
		(fp_line
			(start 1.55956 -0.7366)
			(end 1.524 -0.7366)
			(stroke
				(width 0.1)
				(type default)
			)
			(layer "F.Fab")
		)
		(fp_line
			(start 1.524 0.7366)
			(end 1.55956 0.7366)
			(stroke
				(width 0.1)
				(type default)
			)
			(layer "F.Fab")
		)
		(fp_line
			(start 1.524 -0.7366)
			(end -1.524 -0.7366)
			(stroke
				(width 0.1)
				(type default)
			)
			(layer "F.Fab")
		)
		(fp_line
			(start -1.524 0.7366)
			(end 1.524 0.7366)
			(stroke
				(width 0.1)
				(type default)
			)
			(layer "F.Fab")
		)
		(fp_line
			(start -1.524 -0.7366)
			(end -1.55956 -0.7366)
			(stroke
				(width 0.1)
				(type default)
			)
			(layer "F.Fab")
		)
		(fp_line
			(start -1.55956 0.7366)
			(end -1.524 0.7366)
			(stroke
				(width 0.1)
				(type default)
			)
			(layer "F.Fab")
		)
		(fp_line
			(start -1.55956 -0.7366)
			(end -1.55956 0.7366)
			(stroke
				(width 0.1)
				(type default)
			)
			(layer "F.Fab")
		)
		(pad "1" smd rect
			(at -0.94996 0)
			(size 1.1176 1.3716)
			(layers "F.Cu" "F.Mask" "F.Paste")
			(net "SW_P1V2_AUX_FLT")
		)
		(pad "2" smd rect
			(at 0.94996 0)
			(size 1.1176 1.3716)
			(layers "F.Cu" "F.Mask" "F.Paste")
			(net "GND")
		)
	)
	(footprint ""
		(layer "F.Cu")
		(at 68.4276 -71.882 -90)
		(property "Reference" "R238"
			(at 0 0 270)
			(layer "F.SilkS")
			(hide yes)
			(effects
				(font
					(size 1.27 1.27)
				)
			)
		)
		(property "Value" ""
			(at 0 0 270)
			(layer "F.Fab")
			(effects
				(font
					(size 1.27 1.27)
				)
			)
		)
		(duplicate_pad_numbers_are_jumpers no)
		(fp_line
			(start -0.7874 0.4064)
			(end -0.7874 -0.4064)
			(stroke
				(width 0.1524)
				(type default)
			)
			(layer "F.SilkS")
		)
		(fp_line
			(start 0.7874 0.4064)
			(end -0.7874 0.4064)
			(stroke
				(width 0.1524)
				(type default)
			)
			(layer "F.SilkS")
		)
		(fp_line
			(start -0.7874 -0.4064)
			(end 0.7874 -0.4064)
			(stroke
				(width 0.1524)
				(type default)
			)
			(layer "F.SilkS")
		)
		(fp_line
			(start 0.7874 -0.4064)
			(end 0.7874 0.4064)
			(stroke
				(width 0.1524)
				(type default)
			)
			(layer "F.SilkS")
		)
		(fp_line
			(start -0.67945 0.3048)
			(end -0.67945 -0.305054)
			(stroke
				(width 0.1)
				(type default)
			)
			(layer "F.Fab")
		)
		(fp_line
			(start -0.12065 0.3048)
			(end -0.67945 0.3048)
			(stroke
				(width 0.1)
				(type default)
			)
			(layer "F.Fab")
		)
		(fp_line
			(start 0.120396 0.3048)
			(end 0.120396 0.2794)
			(stroke
				(width 0.1)
				(type default)
			)
			(layer "F.Fab")
		)
		(fp_line
			(start 0.67945 0.3048)
			(end 0.120396 0.3048)
			(stroke
				(width 0.1)
				(type default)
			)
			(layer "F.Fab")
		)
		(fp_line
			(start -0.12065 0.2794)
			(end -0.12065 0.3048)
			(stroke
				(width 0.1)
				(type default)
			)
			(layer "F.Fab")
		)
		(fp_line
			(start 0.120396 0.2794)
			(end -0.12065 0.2794)
			(stroke
				(width 0.1)
				(type default)
			)
			(layer "F.Fab")
		)
		(fp_line
			(start -0.12065 -0.2794)
			(end 0.12065 -0.2794)
			(stroke
				(width 0.1)
				(type default)
			)
			(layer "F.Fab")
		)
		(fp_line
			(start 0.12065 -0.2794)
			(end 0.12065 -0.3048)
			(stroke
				(width 0.1)
				(type default)
			)
			(layer "F.Fab")
		)
		(fp_line
			(start 0.12065 -0.3048)
			(end 0.67945 -0.3048)
			(stroke
				(width 0.1)
				(type default)
			)
			(layer "F.Fab")
		)
		(fp_line
			(start 0.67945 -0.3048)
			(end 0.67945 0.3048)
			(stroke
				(width 0.1)
				(type default)
			)
			(layer "F.Fab")
		)
		(fp_line
			(start -0.67945 -0.305054)
			(end -0.12065 -0.305054)
			(stroke
				(width 0.1)
				(type default)
			)
			(layer "F.Fab")
		)
		(fp_line
			(start -0.12065 -0.305054)
			(end -0.12065 -0.2794)
			(stroke
				(width 0.1)
				(type default)
			)
			(layer "F.Fab")
		)
		(pad "1" smd circle
			(at -0.40005 0 270)
			(size 0 0)
			(layers "F.Cu" "F.Mask" "F.Paste")
			(net "P3V3_AUX")
		)
		(pad "2" smd circle
			(at 0.40005 0 270)
			(size 0 0)
			(layers "F.Cu" "F.Mask" "F.Paste")
			(net "SPI_BMC_TPM_CS2_R_N")
		)
	)
	(footprint ""
		(layer "F.Cu")
		(at 12.319 -97.536 180)
		(property "Reference" "R841"
			(at 0 0 180)
			(layer "F.SilkS")
			(hide yes)
			(effects
				(font
					(size 1.27 1.27)
				)
			)
		)
		(property "Value" ""
			(at 0 0 180)
			(layer "F.Fab")
			(effects
				(font
					(size 1.27 1.27)
				)
			)
		)
		(duplicate_pad_numbers_are_jumpers no)
		(fp_line
			(start 0.7874 0.4064)
			(end -0.7874 0.4064)
			(stroke
				(width 0.1524)
				(type default)
			)
			(layer "F.SilkS")
		)
		(fp_line
			(start 0.7874 -0.4064)
			(end 0.7874 0.4064)
			(stroke
				(width 0.1524)
				(type default)
			)
			(layer "F.SilkS")
		)
		(fp_line
			(start -0.7874 0.4064)
			(end -0.7874 -0.4064)
			(stroke
				(width 0.1524)
				(type default)
			)
			(layer "F.SilkS")
		)
		(fp_line
			(start -0.7874 -0.4064)
			(end 0.7874 -0.4064)
			(stroke
				(width 0.1524)
				(type default)
			)
			(layer "F.SilkS")
		)
		(fp_line
			(start 0.67945 0.3048)
			(end 0.120396 0.3048)
			(stroke
				(width 0.1)
				(type default)
			)
			(layer "F.Fab")
		)
		(fp_line
			(start 0.67945 -0.3048)
			(end 0.67945 0.3048)
			(stroke
				(width 0.1)
				(type default)
			)
			(layer "F.Fab")
		)
		(fp_line
			(start 0.12065 -0.2794)
			(end 0.12065 -0.3048)
			(stroke
				(width 0.1)
				(type default)
			)
			(layer "F.Fab")
		)
		(fp_line
			(start 0.12065 -0.3048)
			(end 0.67945 -0.3048)
			(stroke
				(width 0.1)
				(type default)
			)
			(layer "F.Fab")
		)
		(fp_line
			(start 0.120396 0.3048)
			(end 0.120396 0.2794)
			(stroke
				(width 0.1)
				(type default)
			)
			(layer "F.Fab")
		)
		(fp_line
			(start 0.120396 0.2794)
			(end -0.12065 0.2794)
			(stroke
				(width 0.1)
				(type default)
			)
			(layer "F.Fab")
		)
		(fp_line
			(start -0.12065 0.3048)
			(end -0.67945 0.3048)
			(stroke
				(width 0.1)
				(type default)
			)
			(layer "F.Fab")
		)
		(fp_line
			(start -0.12065 0.2794)
			(end -0.12065 0.3048)
			(stroke
				(width 0.1)
				(type default)
			)
			(layer "F.Fab")
		)
		(fp_line
			(start -0.12065 -0.2794)
			(end 0.12065 -0.2794)
			(stroke
				(width 0.1)
				(type default)
			)
			(layer "F.Fab")
		)
		(fp_line
			(start -0.12065 -0.305054)
			(end -0.12065 -0.2794)
			(stroke
				(width 0.1)
				(type default)
			)
			(layer "F.Fab")
		)
		(fp_line
			(start -0.67945 0.3048)
			(end -0.67945 -0.305054)
			(stroke
				(width 0.1)
				(type default)
			)
			(layer "F.Fab")
		)
		(fp_line
			(start -0.67945 -0.305054)
			(end -0.12065 -0.305054)
			(stroke
				(width 0.1)
				(type default)
			)
			(layer "F.Fab")
		)
		(pad "1" smd circle
			(at -0.40005 0 180)
			(size 0 0)
			(layers "F.Cu" "F.Mask" "F.Paste")
			(net "PWRGD_SYS_PWROK_PLD")
		)
		(pad "2" smd circle
			(at 0.40005 0 180)
			(size 0 0)
			(layers "F.Cu" "F.Mask" "F.Paste")
			(net "PWRGD_SYS_PWROK")
		)
	)
	(footprint ""
		(layer "F.Cu")
		(at 16.235172 -31.66237 90)
		(property "Reference" "R399"
			(at 0 0 90)
			(layer "F.SilkS")
			(hide yes)
			(effects
				(font
					(size 1.27 1.27)
				)
			)
		)
		(property "Value" ""
			(at 0 0 90)
			(layer "F.Fab")
			(effects
				(font
					(size 1.27 1.27)
				)
			)
		)
		(duplicate_pad_numbers_are_jumpers no)
		(fp_line
			(start 0.7874 -0.4064)
			(end 0.7874 0.4064)
			(stroke
				(width 0.1524)
				(type default)
			)
			(layer "F.SilkS")
		)
		(fp_line
			(start -0.7874 -0.4064)
			(end 0.7874 -0.4064)
			(stroke
				(width 0.1524)
				(type default)
			)
			(layer "F.SilkS")
		)
		(fp_line
			(start 0.7874 0.4064)
			(end -0.7874 0.4064)
			(stroke
				(width 0.1524)
				(type default)
			)
			(layer "F.SilkS")
		)
		(fp_line
			(start -0.7874 0.4064)
			(end -0.7874 -0.4064)
			(stroke
				(width 0.1524)
				(type default)
			)
			(layer "F.SilkS")
		)
		(fp_line
			(start -0.12065 -0.305054)
			(end -0.12065 -0.2794)
			(stroke
				(width 0.1)
				(type default)
			)
			(layer "F.Fab")
		)
		(fp_line
			(start -0.67945 -0.305054)
			(end -0.12065 -0.305054)
			(stroke
				(width 0.1)
				(type default)
			)
			(layer "F.Fab")
		)
		(fp_line
			(start 0.67945 -0.3048)
			(end 0.67945 0.3048)
			(stroke
				(width 0.1)
				(type default)
			)
			(layer "F.Fab")
		)
		(fp_line
			(start 0.12065 -0.3048)
			(end 0.67945 -0.3048)
			(stroke
				(width 0.1)
				(type default)
			)
			(layer "F.Fab")
		)
		(fp_line
			(start 0.12065 -0.2794)
			(end 0.12065 -0.3048)
			(stroke
				(width 0.1)
				(type default)
			)
			(layer "F.Fab")
		)
		(fp_line
			(start -0.12065 -0.2794)
			(end 0.12065 -0.2794)
			(stroke
				(width 0.1)
				(type default)
			)
			(layer "F.Fab")
		)
		(fp_line
			(start 0.120396 0.2794)
			(end -0.12065 0.2794)
			(stroke
				(width 0.1)
				(type default)
			)
			(layer "F.Fab")
		)
		(fp_line
			(start -0.12065 0.2794)
			(end -0.12065 0.3048)
			(stroke
				(width 0.1)
				(type default)
			)
			(layer "F.Fab")
		)
		(fp_line
			(start 0.67945 0.3048)
			(end 0.120396 0.3048)
			(stroke
				(width 0.1)
				(type default)
			)
			(layer "F.Fab")
		)
		(fp_line
			(start 0.120396 0.3048)
			(end 0.120396 0.2794)
			(stroke
				(width 0.1)
				(type default)
			)
			(layer "F.Fab")
		)
		(fp_line
			(start -0.12065 0.3048)
			(end -0.67945 0.3048)
			(stroke
				(width 0.1)
				(type default)
			)
			(layer "F.Fab")
		)
		(fp_line
			(start -0.67945 0.3048)
			(end -0.67945 -0.305054)
			(stroke
				(width 0.1)
				(type default)
			)
			(layer "F.Fab")
		)
		(pad "1" smd circle
			(at -0.40005 0 90)
			(size 0 0)
			(layers "F.Cu" "F.Mask" "F.Paste")
			(net "EN_P1V0_AUX")
		)
		(pad "2" smd circle
			(at 0.40005 0 90)
			(size 0 0)
			(layers "F.Cu" "F.Mask" "F.Paste")
			(net "EN_P1V0_AUX_R")
		)
	)
	(footprint ""
		(layer "F.Cu")
		(at 82.804 -80.518 -90)
		(property "Reference" "PL29"
			(at 0 0 270)
			(layer "F.SilkS")
			(hide yes)
			(effects
				(font
					(size 1.27 1.27)
				)
			)
		)
		(property "Value" ""
			(at 0 0 270)
			(layer "F.Fab")
			(effects
				(font
					(size 1.27 1.27)
				)
			)
		)
		(duplicate_pad_numbers_are_jumpers no)
		(fp_line
			(start -1.27 0.5842)
			(end -1.27 -0.5842)
			(stroke
				(width 0.1524)
				(type default)
			)
			(layer "F.SilkS")
		)
		(fp_line
			(start -0.127 0.5842)
			(end -0.127 -0.5842)
			(stroke
				(width 0.1524)
				(type default)
			)
			(layer "F.SilkS")
		)
		(fp_line
			(start 0.127 0.5842)
			(end 0.127 -0.5842)
			(stroke
				(width 0.1524)
				(type default)
			)
			(layer "F.SilkS")
		)
		(fp_line
			(start 1.27 0.5842)
			(end -1.27 0.5842)
			(stroke
				(width 0.1524)
				(type default)
			)
			(layer "F.SilkS")
		)
		(fp_line
			(start 1.27 0.5842)
			(end 1.27 -0.5842)
			(stroke
				(width 0.1524)
				(type default)
			)
			(layer "F.SilkS")
		)
		(fp_line
			(start -1.27 -0.5588)
			(end -1.27 -0.5842)
			(stroke
				(width 0.1524)
				(type default)
			)
			(layer "F.SilkS")
		)
		(fp_line
			(start -1.27 -0.5842)
			(end 1.27 -0.5842)
			(stroke
				(width 0.1524)
				(type default)
			)
			(layer "F.SilkS")
		)
		(fp_line
			(start -0.9144 0.508)
			(end -0.9144 0.406654)
			(stroke
				(width 0.1)
				(type default)
			)
			(layer "F.Fab")
		)
		(fp_line
			(start 0.9144 0.508)
			(end -0.9144 0.508)
			(stroke
				(width 0.1)
				(type default)
			)
			(layer "F.Fab")
		)
		(fp_line
			(start -1.194308 0.406654)
			(end -1.194308 -0.406654)
			(stroke
				(width 0.1)
				(type default)
			)
			(layer "F.Fab")
		)
		(fp_line
			(start -0.9144 0.406654)
			(end -1.194308 0.406654)
			(stroke
				(width 0.1)
				(type default)
			)
			(layer "F.Fab")
		)
		(fp_line
			(start 0.9144 0.4064)
			(end 0.9144 0.508)
			(stroke
				(width 0.1)
				(type default)
			)
			(layer "F.Fab")
		)
		(fp_line
			(start 1.1938 0.4064)
			(end 0.9144 0.4064)
			(stroke
				(width 0.1)
				(type default)
			)
			(layer "F.Fab")
		)
		(fp_line
			(start -1.194308 -0.406654)
			(end -0.9144 -0.406654)
			(stroke
				(width 0.1)
				(type default)
			)
			(layer "F.Fab")
		)
		(fp_line
			(start -0.9144 -0.406654)
			(end -0.9144 -0.508)
			(stroke
				(width 0.1)
				(type default)
			)
			(layer "F.Fab")
		)
		(fp_line
			(start 0.9144 -0.406654)
			(end 1.1938 -0.406654)
			(stroke
				(width 0.1)
				(type default)
			)
			(layer "F.Fab")
		)
		(fp_line
			(start 1.1938 -0.406654)
			(end 1.1938 0.4064)
			(stroke
				(width 0.1)
				(type default)
			)
			(layer "F.Fab")
		)
		(fp_line
			(start -0.9144 -0.508)
			(end 0.9144 -0.508)
			(stroke
				(width 0.1)
				(type default)
			)
			(layer "F.Fab")
		)
		(fp_line
			(start 0.9144 -0.508)
			(end 0.9144 -0.406654)
			(stroke
				(width 0.1)
				(type default)
			)
			(layer "F.Fab")
		)
		(pad "1" smd rect
			(at -0.7366 0 180)
			(size 0.7112 0.8128)
			(layers "F.Cu" "F.Mask" "F.Paste")
			(net "P12V_AUX")
		)
		(pad "2" smd rect
			(at 0.7366 0 180)
			(size 0.7112 0.8128)
			(layers "F.Cu" "F.Mask" "F.Paste")
			(net "SW_P1V2_AUX_FLT")
		)
	)
	(footprint ""
		(layer "F.Cu")
		(at 22.979888 -6.290056)
		(property "Reference" "D15"
			(at -1.135888 -2.547874 0)
			(unlocked yes)
			(layer "F.SilkS")
			(effects
				(font
					(size 0.7874 0.5842)
					(thickness 0.1524)
				)
				(justify left)
			)
		)
		(property "Value" ""
			(at 0 0 0)
			(layer "F.Fab")
			(effects
				(font
					(size 1.27 1.27)
				)
			)
		)
		(duplicate_pad_numbers_are_jumpers no)
		(fp_line
			(start -1.080008 -1.999996)
			(end 3.620008 -1.999996)
			(stroke
				(width 0.1524)
				(type default)
			)
			(layer "F.SilkS")
		)
		(fp_line
			(start -1.080008 3.999992)
			(end -1.080008 -1.999996)
			(stroke
				(width 0.1524)
				(type default)
			)
			(layer "F.SilkS")
		)
		(fp_line
			(start -0.230124 3.999992)
			(end -1.080008 3.999992)
			(stroke
				(width 0.1524)
				(type default)
			)
			(layer "F.SilkS")
		)
		(fp_line
			(start -0.230124 5.199888)
			(end -0.230124 3.999992)
			(stroke
				(width 0.1524)
				(type default)
			)
			(layer "F.SilkS")
		)
		(fp_line
			(start 2.770124 3.999992)
			(end 2.770124 5.199888)
			(stroke
				(width 0.1524)
				(type default)
			)
			(layer "F.SilkS")
		)
		(fp_line
			(start 3.620008 -1.999996)
			(end 3.620008 3.999992)
			(stroke
				(width 0.1524)
				(type default)
			)
			(layer "F.SilkS")
		)
		(fp_line
			(start 3.620008 3.999992)
			(end 2.770124 3.999992)
			(stroke
				(width 0.1524)
				(type default)
			)
			(layer "F.SilkS")
		)
		(fp_arc
			(start 1.27 6.700012)
			(mid 0.209252 6.260636)
			(end -0.230124 5.199888)
			(stroke
				(width 0.1524)
				(type default)
			)
			(layer "F.SilkS")
		)
		(fp_arc
			(start 2.770124 5.199888)
			(mid 2.330748 6.260636)
			(end 1.27 6.700012)
			(stroke
				(width 0.1524)
				(type default)
			)
			(layer "F.SilkS")
		)
		(fp_line
			(start -1.080008 -1.999996)
			(end 3.620008 -1.999996)
			(stroke
				(width 0.1)
				(type default)
			)
			(layer "F.Fab")
		)
		(fp_line
			(start -1.080008 3.999992)
			(end -1.080008 -1.999996)
			(stroke
				(width 0.1)
				(type default)
			)
			(layer "F.Fab")
		)
		(fp_line
			(start -0.230124 3.999992)
			(end -1.080008 3.999992)
			(stroke
				(width 0.1)
				(type default)
			)
			(layer "F.Fab")
		)
		(fp_line
			(start -0.230124 5.199888)
			(end -0.230124 3.999992)
			(stroke
				(width 0.1)
				(type default)
			)
			(layer "F.Fab")
		)
		(fp_line
			(start 2.770124 3.999992)
			(end 2.770124 5.199888)
			(stroke
				(width 0.1)
				(type default)
			)
			(layer "F.Fab")
		)
		(fp_line
			(start 3.620008 -1.999996)
			(end 3.620008 3.999992)
			(stroke
				(width 0.1)
				(type default)
			)
			(layer "F.Fab")
		)
		(fp_line
			(start 3.620008 3.999992)
			(end 2.770124 3.999992)
			(stroke
				(width 0.1)
				(type default)
			)
			(layer "F.Fab")
		)
		(fp_arc
			(start 1.27 6.700012)
			(mid 0.209252 6.260636)
			(end -0.230124 5.199888)
			(stroke
				(width 0.1)
				(type default)
			)
			(layer "F.Fab")
		)
		(fp_arc
			(start 2.770124 5.199888)
			(mid 2.330748 6.260636)
			(end 1.27 6.700012)
			(stroke
				(width 0.1)
				(type default)
			)
			(layer "F.Fab")
		)
		(pad "A" thru_hole rect
			(at 0 0)
			(size 1.2192 1.2192)
			(drill 0.8128)
			(layers "*.Cu" "*.Mask")
			(remove_unused_layers no)
			(net "HDD_LED_P5V_AUX")
			(clearance 0.0508)
			(thermal_gap 0.0508)
			(padstack
				(mode front_inner_back)
				(layer "Inner"
					(shape circle)
					(size 1.2192 1.2192)
					(clearance 0.0508)
				)
				(layer "B.Cu"
					(shape rect)
					(size 1.2192 1.2192)
					(clearance 0.0508)
				)
			)
		)
		(pad "C" thru_hole circle
			(at 2.54 0)
			(size 1.2192 1.2192)
			(drill 0.8128)
			(layers "*.Cu" "*.Mask")
			(remove_unused_layers no)
			(net "HDD_LED_BUF_R")
			(clearance 0.0508)
			(thermal_gap 0.0508)
		)
	)
	(footprint ""
		(layer "F.Cu")
		(at 49.779682 -34.637726 -90)
		(property "Reference" "R590"
			(at 0 0 270)
			(layer "F.SilkS")
			(hide yes)
			(effects
				(font
					(size 1.27 1.27)
				)
			)
		)
		(property "Value" ""
			(at 0 0 270)
			(layer "F.Fab")
			(effects
				(font
					(size 1.27 1.27)
				)
			)
		)
		(duplicate_pad_numbers_are_jumpers no)
		(fp_line
			(start -0.7874 0.4064)
			(end -0.7874 -0.4064)
			(stroke
				(width 0.1524)
				(type default)
			)
			(layer "F.SilkS")
		)
		(fp_line
			(start 0.7874 0.4064)
			(end -0.7874 0.4064)
			(stroke
				(width 0.1524)
				(type default)
			)
			(layer "F.SilkS")
		)
		(fp_line
			(start -0.7874 -0.4064)
			(end 0.7874 -0.4064)
			(stroke
				(width 0.1524)
				(type default)
			)
			(layer "F.SilkS")
		)
		(fp_line
			(start 0.7874 -0.4064)
			(end 0.7874 0.4064)
			(stroke
				(width 0.1524)
				(type default)
			)
			(layer "F.SilkS")
		)
		(fp_line
			(start -0.67945 0.3048)
			(end -0.67945 -0.305054)
			(stroke
				(width 0.1)
				(type default)
			)
			(layer "F.Fab")
		)
		(fp_line
			(start -0.12065 0.3048)
			(end -0.67945 0.3048)
			(stroke
				(width 0.1)
				(type default)
			)
			(layer "F.Fab")
		)
		(fp_line
			(start 0.120396 0.3048)
			(end 0.120396 0.2794)
			(stroke
				(width 0.1)
				(type default)
			)
			(layer "F.Fab")
		)
		(fp_line
			(start 0.67945 0.3048)
			(end 0.120396 0.3048)
			(stroke
				(width 0.1)
				(type default)
			)
			(layer "F.Fab")
		)
		(fp_line
			(start -0.12065 0.2794)
			(end -0.12065 0.3048)
			(stroke
				(width 0.1)
				(type default)
			)
			(layer "F.Fab")
		)
		(fp_line
			(start 0.120396 0.2794)
			(end -0.12065 0.2794)
			(stroke
				(width 0.1)
				(type default)
			)
			(layer "F.Fab")
		)
		(fp_line
			(start -0.12065 -0.2794)
			(end 0.12065 -0.2794)
			(stroke
				(width 0.1)
				(type default)
			)
			(layer "F.Fab")
		)
		(fp_line
			(start 0.12065 -0.2794)
			(end 0.12065 -0.3048)
			(stroke
				(width 0.1)
				(type default)
			)
			(layer "F.Fab")
		)
		(fp_line
			(start 0.12065 -0.3048)
			(end 0.67945 -0.3048)
			(stroke
				(width 0.1)
				(type default)
			)
			(layer "F.Fab")
		)
		(fp_line
			(start 0.67945 -0.3048)
			(end 0.67945 0.3048)
			(stroke
				(width 0.1)
				(type default)
			)
			(layer "F.Fab")
		)
		(fp_line
			(start -0.67945 -0.305054)
			(end -0.12065 -0.305054)
			(stroke
				(width 0.1)
				(type default)
			)
			(layer "F.Fab")
		)
		(fp_line
			(start -0.12065 -0.305054)
			(end -0.12065 -0.2794)
			(stroke
				(width 0.1)
				(type default)
			)
			(layer "F.Fab")
		)
		(pad "1" smd circle
			(at -0.40005 0 270)
			(size 0 0)
			(layers "F.Cu" "F.Mask" "F.Paste")
			(net "SMB_BMC_MM3_R_SDA")
		)
		(pad "2" smd circle
			(at 0.40005 0 270)
			(size 0 0)
			(layers "F.Cu" "F.Mask" "F.Paste")
			(net "SMB_BMC_MM3_SDA")
		)
	)
	(footprint ""
		(layer "F.Cu")
		(at 10.033 -88.519)
		(property "Reference" "R192"
			(at 0 0 0)
			(layer "F.SilkS")
			(hide yes)
			(effects
				(font
					(size 1.27 1.27)
				)
			)
		)
		(property "Value" ""
			(at 0 0 0)
			(layer "F.Fab")
			(effects
				(font
					(size 1.27 1.27)
				)
			)
		)
		(duplicate_pad_numbers_are_jumpers no)
		(fp_line
			(start -0.7874 -0.4064)
			(end 0.7874 -0.4064)
			(stroke
				(width 0.1524)
				(type default)
			)
			(layer "F.SilkS")
		)
		(fp_line
			(start -0.7874 0.4064)
			(end -0.7874 -0.4064)
			(stroke
				(width 0.1524)
				(type default)
			)
			(layer "F.SilkS")
		)
		(fp_line
			(start 0.7874 -0.4064)
			(end 0.7874 0.4064)
			(stroke
				(width 0.1524)
				(type default)
			)
			(layer "F.SilkS")
		)
		(fp_line
			(start 0.7874 0.4064)
			(end -0.7874 0.4064)
			(stroke
				(width 0.1524)
				(type default)
			)
			(layer "F.SilkS")
		)
		(fp_line
			(start -0.67945 -0.305054)
			(end -0.12065 -0.305054)
			(stroke
				(width 0.1)
				(type default)
			)
			(layer "F.Fab")
		)
		(fp_line
			(start -0.67945 0.3048)
			(end -0.67945 -0.305054)
			(stroke
				(width 0.1)
				(type default)
			)
			(layer "F.Fab")
		)
		(fp_line
			(start -0.12065 -0.305054)
			(end -0.12065 -0.2794)
			(stroke
				(width 0.1)
				(type default)
			)
			(layer "F.Fab")
		)
		(fp_line
			(start -0.12065 -0.2794)
			(end 0.12065 -0.2794)
			(stroke
				(width 0.1)
				(type default)
			)
			(layer "F.Fab")
		)
		(fp_line
			(start -0.12065 0.2794)
			(end -0.12065 0.3048)
			(stroke
				(width 0.1)
				(type default)
			)
			(layer "F.Fab")
		)
		(fp_line
			(start -0.12065 0.3048)
			(end -0.67945 0.3048)
			(stroke
				(width 0.1)
				(type default)
			)
			(layer "F.Fab")
		)
		(fp_line
			(start 0.120396 0.2794)
			(end -0.12065 0.2794)
			(stroke
				(width 0.1)
				(type default)
			)
			(layer "F.Fab")
		)
		(fp_line
			(start 0.120396 0.3048)
			(end 0.120396 0.2794)
			(stroke
				(width 0.1)
				(type default)
			)
			(layer "F.Fab")
		)
		(fp_line
			(start 0.12065 -0.3048)
			(end 0.67945 -0.3048)
			(stroke
				(width 0.1)
				(type default)
			)
			(layer "F.Fab")
		)
		(fp_line
			(start 0.12065 -0.2794)
			(end 0.12065 -0.3048)
			(stroke
				(width 0.1)
				(type default)
			)
			(layer "F.Fab")
		)
		(fp_line
			(start 0.67945 -0.3048)
			(end 0.67945 0.3048)
			(stroke
				(width 0.1)
				(type default)
			)
			(layer "F.Fab")
		)
		(fp_line
			(start 0.67945 0.3048)
			(end 0.120396 0.3048)
			(stroke
				(width 0.1)
				(type default)
			)
			(layer "F.Fab")
		)
		(pad "1" smd circle
			(at -0.40005 0)
			(size 0 0)
			(layers "F.Cu" "F.Mask" "F.Paste")
			(net "PWRGD_P1V0_AUX_DELAY_BUF")
		)
		(pad "2" smd circle
			(at 0.40005 0)
			(size 0 0)
			(layers "F.Cu" "F.Mask" "F.Paste")
			(net "RST_BMC_SRST_BUF_R_N")
		)
	)
	(footprint ""
		(layer "F.Cu")
		(at 39.871142 -63.756794 90)
		(property "Reference" "R200"
			(at 0 0 90)
			(layer "F.SilkS")
			(hide yes)
			(effects
				(font
					(size 1.27 1.27)
				)
			)
		)
		(property "Value" ""
			(at 0 0 90)
			(layer "F.Fab")
			(effects
				(font
					(size 1.27 1.27)
				)
			)
		)
		(duplicate_pad_numbers_are_jumpers no)
		(fp_line
			(start 0.7874 -0.4064)
			(end 0.7874 0.4064)
			(stroke
				(width 0.1524)
				(type default)
			)
			(layer "F.SilkS")
		)
		(fp_line
			(start -0.7874 -0.4064)
			(end 0.7874 -0.4064)
			(stroke
				(width 0.1524)
				(type default)
			)
			(layer "F.SilkS")
		)
		(fp_line
			(start 0.7874 0.4064)
			(end -0.7874 0.4064)
			(stroke
				(width 0.1524)
				(type default)
			)
			(layer "F.SilkS")
		)
		(fp_line
			(start -0.7874 0.4064)
			(end -0.7874 -0.4064)
			(stroke
				(width 0.1524)
				(type default)
			)
			(layer "F.SilkS")
		)
		(fp_line
			(start -0.12065 -0.305054)
			(end -0.12065 -0.2794)
			(stroke
				(width 0.1)
				(type default)
			)
			(layer "F.Fab")
		)
		(fp_line
			(start -0.67945 -0.305054)
			(end -0.12065 -0.305054)
			(stroke
				(width 0.1)
				(type default)
			)
			(layer "F.Fab")
		)
		(fp_line
			(start 0.67945 -0.3048)
			(end 0.67945 0.3048)
			(stroke
				(width 0.1)
				(type default)
			)
			(layer "F.Fab")
		)
		(fp_line
			(start 0.12065 -0.3048)
			(end 0.67945 -0.3048)
			(stroke
				(width 0.1)
				(type default)
			)
			(layer "F.Fab")
		)
		(fp_line
			(start 0.12065 -0.2794)
			(end 0.12065 -0.3048)
			(stroke
				(width 0.1)
				(type default)
			)
			(layer "F.Fab")
		)
		(fp_line
			(start -0.12065 -0.2794)
			(end 0.12065 -0.2794)
			(stroke
				(width 0.1)
				(type default)
			)
			(layer "F.Fab")
		)
		(fp_line
			(start 0.120396 0.2794)
			(end -0.12065 0.2794)
			(stroke
				(width 0.1)
				(type default)
			)
			(layer "F.Fab")
		)
		(fp_line
			(start -0.12065 0.2794)
			(end -0.12065 0.3048)
			(stroke
				(width 0.1)
				(type default)
			)
			(layer "F.Fab")
		)
		(fp_line
			(start 0.67945 0.3048)
			(end 0.120396 0.3048)
			(stroke
				(width 0.1)
				(type default)
			)
			(layer "F.Fab")
		)
		(fp_line
			(start 0.120396 0.3048)
			(end 0.120396 0.2794)
			(stroke
				(width 0.1)
				(type default)
			)
			(layer "F.Fab")
		)
		(fp_line
			(start -0.12065 0.3048)
			(end -0.67945 0.3048)
			(stroke
				(width 0.1)
				(type default)
			)
			(layer "F.Fab")
		)
		(fp_line
			(start -0.67945 0.3048)
			(end -0.67945 -0.305054)
			(stroke
				(width 0.1)
				(type default)
			)
			(layer "F.Fab")
		)
		(pad "1" smd circle
			(at -0.40005 0 90)
			(size 0 0)
			(layers "F.Cu" "F.Mask" "F.Paste")
			(net "I3C4_SCL_R")
		)
		(pad "2" smd circle
			(at 0.40005 0 90)
			(size 0 0)
			(layers "F.Cu" "F.Mask" "F.Paste")
			(net "I3C4_SPD_SCL")
		)
	)
	(footprint ""
		(layer "F.Cu")
		(at 62.53607 -34.870898 -90)
		(property "Reference" "R527"
			(at 0 0 270)
			(layer "F.SilkS")
			(hide yes)
			(effects
				(font
					(size 1.27 1.27)
				)
			)
		)
		(property "Value" ""
			(at 0 0 270)
			(layer "F.Fab")
			(effects
				(font
					(size 1.27 1.27)
				)
			)
		)
		(duplicate_pad_numbers_are_jumpers no)
		(fp_line
			(start -0.7874 0.4064)
			(end -0.7874 -0.14097)
			(stroke
				(width 0.1524)
				(type default)
			)
			(layer "F.SilkS")
		)
		(fp_line
			(start 0.7874 0.4064)
			(end -0.7874 0.4064)
			(stroke
				(width 0.1524)
				(type default)
			)
			(layer "F.SilkS")
		)
		(fp_line
			(start 0.7874 -0.04191)
			(end 0.7874 0.4064)
			(stroke
				(width 0.1524)
				(type default)
			)
			(layer "F.SilkS")
		)
		(fp_line
			(start -0.054102 -0.4064)
			(end 0.420878 -0.4064)
			(stroke
				(width 0.1524)
				(type default)
			)
			(layer "F.SilkS")
		)
		(fp_line
			(start -0.67945 0.3048)
			(end -0.67945 -0.305054)
			(stroke
				(width 0.1)
				(type default)
			)
			(layer "F.Fab")
		)
		(fp_line
			(start -0.12065 0.3048)
			(end -0.67945 0.3048)
			(stroke
				(width 0.1)
				(type default)
			)
			(layer "F.Fab")
		)
		(fp_line
			(start 0.120396 0.3048)
			(end 0.120396 0.2794)
			(stroke
				(width 0.1)
				(type default)
			)
			(layer "F.Fab")
		)
		(fp_line
			(start 0.67945 0.3048)
			(end 0.120396 0.3048)
			(stroke
				(width 0.1)
				(type default)
			)
			(layer "F.Fab")
		)
		(fp_line
			(start -0.12065 0.2794)
			(end -0.12065 0.3048)
			(stroke
				(width 0.1)
				(type default)
			)
			(layer "F.Fab")
		)
		(fp_line
			(start 0.120396 0.2794)
			(end -0.12065 0.2794)
			(stroke
				(width 0.1)
				(type default)
			)
			(layer "F.Fab")
		)
		(fp_line
			(start -0.12065 -0.2794)
			(end 0.12065 -0.2794)
			(stroke
				(width 0.1)
				(type default)
			)
			(layer "F.Fab")
		)
		(fp_line
			(start 0.12065 -0.2794)
			(end 0.12065 -0.3048)
			(stroke
				(width 0.1)
				(type default)
			)
			(layer "F.Fab")
		)
		(fp_line
			(start 0.12065 -0.3048)
			(end 0.67945 -0.3048)
			(stroke
				(width 0.1)
				(type default)
			)
			(layer "F.Fab")
		)
		(fp_line
			(start 0.67945 -0.3048)
			(end 0.67945 0.3048)
			(stroke
				(width 0.1)
				(type default)
			)
			(layer "F.Fab")
		)
		(fp_line
			(start -0.67945 -0.305054)
			(end -0.12065 -0.305054)
			(stroke
				(width 0.1)
				(type default)
			)
			(layer "F.Fab")
		)
		(fp_line
			(start -0.12065 -0.305054)
			(end -0.12065 -0.2794)
			(stroke
				(width 0.1)
				(type default)
			)
			(layer "F.Fab")
		)
		(pad "1" smd circle
			(at -0.40005 0 270)
			(size 0 0)
			(layers "F.Cu" "F.Mask" "F.Paste")
			(net "USB_HOST_BMC_B_R_DP")
		)
		(pad "2" smd circle
			(at 0.40005 0 270)
			(size 0 0)
			(layers "F.Cu" "F.Mask" "F.Paste")
			(net "USB_HOST_BMC_B_DP")
		)
	)
	(footprint ""
		(layer "F.Cu")
		(at 77.707744 -37.559488 -90)
		(property "Reference" "R355"
			(at 0 0 270)
			(layer "F.SilkS")
			(hide yes)
			(effects
				(font
					(size 1.27 1.27)
				)
			)
		)
		(property "Value" ""
			(at 0 0 270)
			(layer "F.Fab")
			(effects
				(font
					(size 1.27 1.27)
				)
			)
		)
		(duplicate_pad_numbers_are_jumpers no)
		(fp_line
			(start -0.7874 0.4064)
			(end -0.7874 -0.4064)
			(stroke
				(width 0.1524)
				(type default)
			)
			(layer "F.SilkS")
		)
		(fp_line
			(start 0.7874 0.4064)
			(end -0.7874 0.4064)
			(stroke
				(width 0.1524)
				(type default)
			)
			(layer "F.SilkS")
		)
		(fp_line
			(start -0.7874 -0.4064)
			(end 0.7874 -0.4064)
			(stroke
				(width 0.1524)
				(type default)
			)
			(layer "F.SilkS")
		)
		(fp_line
			(start 0.7874 -0.4064)
			(end 0.7874 0.4064)
			(stroke
				(width 0.1524)
				(type default)
			)
			(layer "F.SilkS")
		)
		(fp_line
			(start -0.67945 0.3048)
			(end -0.67945 -0.305054)
			(stroke
				(width 0.1)
				(type default)
			)
			(layer "F.Fab")
		)
		(fp_line
			(start -0.12065 0.3048)
			(end -0.67945 0.3048)
			(stroke
				(width 0.1)
				(type default)
			)
			(layer "F.Fab")
		)
		(fp_line
			(start 0.120396 0.3048)
			(end 0.120396 0.2794)
			(stroke
				(width 0.1)
				(type default)
			)
			(layer "F.Fab")
		)
		(fp_line
			(start 0.67945 0.3048)
			(end 0.120396 0.3048)
			(stroke
				(width 0.1)
				(type default)
			)
			(layer "F.Fab")
		)
		(fp_line
			(start -0.12065 0.2794)
			(end -0.12065 0.3048)
			(stroke
				(width 0.1)
				(type default)
			)
			(layer "F.Fab")
		)
		(fp_line
			(start 0.120396 0.2794)
			(end -0.12065 0.2794)
			(stroke
				(width 0.1)
				(type default)
			)
			(layer "F.Fab")
		)
		(fp_line
			(start -0.12065 -0.2794)
			(end 0.12065 -0.2794)
			(stroke
				(width 0.1)
				(type default)
			)
			(layer "F.Fab")
		)
		(fp_line
			(start 0.12065 -0.2794)
			(end 0.12065 -0.3048)
			(stroke
				(width 0.1)
				(type default)
			)
			(layer "F.Fab")
		)
		(fp_line
			(start 0.12065 -0.3048)
			(end 0.67945 -0.3048)
			(stroke
				(width 0.1)
				(type default)
			)
			(layer "F.Fab")
		)
		(fp_line
			(start 0.67945 -0.3048)
			(end 0.67945 0.3048)
			(stroke
				(width 0.1)
				(type default)
			)
			(layer "F.Fab")
		)
		(fp_line
			(start -0.67945 -0.305054)
			(end -0.12065 -0.305054)
			(stroke
				(width 0.1)
				(type default)
			)
			(layer "F.Fab")
		)
		(fp_line
			(start -0.12065 -0.305054)
			(end -0.12065 -0.2794)
			(stroke
				(width 0.1)
				(type default)
			)
			(layer "F.Fab")
		)
		(pad "1" smd circle
			(at -0.40005 0 270)
			(size 0 0)
			(layers "F.Cu" "F.Mask" "F.Paste")
			(net "M_BMC_DDR4_MA<4>")
		)
		(pad "2" smd circle
			(at 0.40005 0 270)
			(size 0 0)
			(layers "F.Cu" "F.Mask" "F.Paste")
			(net "P1V2_AUX")
		)
	)
	(footprint ""
		(layer "F.Cu")
		(at 32.999172 -83.816952 90)
		(property "Reference" "R532"
			(at 0 0 90)
			(layer "F.SilkS")
			(hide yes)
			(effects
				(font
					(size 1.27 1.27)
				)
			)
		)
		(property "Value" ""
			(at 0 0 90)
			(layer "F.Fab")
			(effects
				(font
					(size 1.27 1.27)
				)
			)
		)
		(duplicate_pad_numbers_are_jumpers no)
		(fp_line
			(start 0.7874 -0.4064)
			(end 0.7874 0.4064)
			(stroke
				(width 0.1524)
				(type default)
			)
			(layer "F.SilkS")
		)
		(fp_line
			(start -0.7874 -0.4064)
			(end 0.7874 -0.4064)
			(stroke
				(width 0.1524)
				(type default)
			)
			(layer "F.SilkS")
		)
		(fp_line
			(start 0.7874 0.4064)
			(end -0.7874 0.4064)
			(stroke
				(width 0.1524)
				(type default)
			)
			(layer "F.SilkS")
		)
		(fp_line
			(start -0.7874 0.4064)
			(end -0.7874 -0.4064)
			(stroke
				(width 0.1524)
				(type default)
			)
			(layer "F.SilkS")
		)
		(fp_line
			(start -0.12065 -0.305054)
			(end -0.12065 -0.2794)
			(stroke
				(width 0.1)
				(type default)
			)
			(layer "F.Fab")
		)
		(fp_line
			(start -0.67945 -0.305054)
			(end -0.12065 -0.305054)
			(stroke
				(width 0.1)
				(type default)
			)
			(layer "F.Fab")
		)
		(fp_line
			(start 0.67945 -0.3048)
			(end 0.67945 0.3048)
			(stroke
				(width 0.1)
				(type default)
			)
			(layer "F.Fab")
		)
		(fp_line
			(start 0.12065 -0.3048)
			(end 0.67945 -0.3048)
			(stroke
				(width 0.1)
				(type default)
			)
			(layer "F.Fab")
		)
		(fp_line
			(start 0.12065 -0.2794)
			(end 0.12065 -0.3048)
			(stroke
				(width 0.1)
				(type default)
			)
			(layer "F.Fab")
		)
		(fp_line
			(start -0.12065 -0.2794)
			(end 0.12065 -0.2794)
			(stroke
				(width 0.1)
				(type default)
			)
			(layer "F.Fab")
		)
		(fp_line
			(start 0.120396 0.2794)
			(end -0.12065 0.2794)
			(stroke
				(width 0.1)
				(type default)
			)
			(layer "F.Fab")
		)
		(fp_line
			(start -0.12065 0.2794)
			(end -0.12065 0.3048)
			(stroke
				(width 0.1)
				(type default)
			)
			(layer "F.Fab")
		)
		(fp_line
			(start 0.67945 0.3048)
			(end 0.120396 0.3048)
			(stroke
				(width 0.1)
				(type default)
			)
			(layer "F.Fab")
		)
		(fp_line
			(start 0.120396 0.3048)
			(end 0.120396 0.2794)
			(stroke
				(width 0.1)
				(type default)
			)
			(layer "F.Fab")
		)
		(fp_line
			(start -0.12065 0.3048)
			(end -0.67945 0.3048)
			(stroke
				(width 0.1)
				(type default)
			)
			(layer "F.Fab")
		)
		(fp_line
			(start -0.67945 0.3048)
			(end -0.67945 -0.305054)
			(stroke
				(width 0.1)
				(type default)
			)
			(layer "F.Fab")
		)
		(pad "1" smd circle
			(at -0.40005 0 90)
			(size 0 0)
			(layers "F.Cu" "F.Mask" "F.Paste")
			(net "EMMC_DT3_R")
		)
		(pad "2" smd circle
			(at 0.40005 0 90)
			(size 0 0)
			(layers "F.Cu" "F.Mask" "F.Paste")
			(net "BMC_EMMC_DT3")
		)
	)
	(footprint ""
		(layer "F.Cu")
		(at 37.5666 -88.9254 -90)
		(property "Reference" "C246"
			(at 0 0 270)
			(layer "F.SilkS")
			(hide yes)
			(effects
				(font
					(size 1.27 1.27)
				)
			)
		)
		(property "Value" ""
			(at 0 0 270)
			(layer "F.Fab")
			(effects
				(font
					(size 1.27 1.27)
				)
			)
		)
		(duplicate_pad_numbers_are_jumpers no)
		(fp_line
			(start -0.7874 0.4064)
			(end -0.7874 -0.4064)
			(stroke
				(width 0.1524)
				(type default)
			)
			(layer "F.SilkS")
		)
		(fp_line
			(start 0.7874 0.4064)
			(end -0.7874 0.4064)
			(stroke
				(width 0.1524)
				(type default)
			)
			(layer "F.SilkS")
		)
		(fp_line
			(start -0.7874 -0.4064)
			(end 0.7874 -0.4064)
			(stroke
				(width 0.1524)
				(type default)
			)
			(layer "F.SilkS")
		)
		(fp_line
			(start 0.7874 -0.4064)
			(end 0.7874 0.4064)
			(stroke
				(width 0.1524)
				(type default)
			)
			(layer "F.SilkS")
		)
		(fp_line
			(start -0.67945 0.3048)
			(end -0.67945 -0.305054)
			(stroke
				(width 0.1)
				(type default)
			)
			(layer "F.Fab")
		)
		(fp_line
			(start -0.12065 0.3048)
			(end -0.67945 0.3048)
			(stroke
				(width 0.1)
				(type default)
			)
			(layer "F.Fab")
		)
		(fp_line
			(start 0.120396 0.3048)
			(end 0.120396 0.2794)
			(stroke
				(width 0.1)
				(type default)
			)
			(layer "F.Fab")
		)
		(fp_line
			(start 0.67945 0.3048)
			(end 0.120396 0.3048)
			(stroke
				(width 0.1)
				(type default)
			)
			(layer "F.Fab")
		)
		(fp_line
			(start -0.12065 0.2794)
			(end -0.12065 0.3048)
			(stroke
				(width 0.1)
				(type default)
			)
			(layer "F.Fab")
		)
		(fp_line
			(start 0.120396 0.2794)
			(end -0.12065 0.2794)
			(stroke
				(width 0.1)
				(type default)
			)
			(layer "F.Fab")
		)
		(fp_line
			(start -0.12065 -0.2794)
			(end 0.12065 -0.2794)
			(stroke
				(width 0.1)
				(type default)
			)
			(layer "F.Fab")
		)
		(fp_line
			(start 0.12065 -0.2794)
			(end 0.12065 -0.3048)
			(stroke
				(width 0.1)
				(type default)
			)
			(layer "F.Fab")
		)
		(fp_line
			(start 0.12065 -0.3048)
			(end 0.67945 -0.3048)
			(stroke
				(width 0.1)
				(type default)
			)
			(layer "F.Fab")
		)
		(fp_line
			(start 0.67945 -0.3048)
			(end 0.67945 0.3048)
			(stroke
				(width 0.1)
				(type default)
			)
			(layer "F.Fab")
		)
		(fp_line
			(start -0.67945 -0.305054)
			(end -0.12065 -0.305054)
			(stroke
				(width 0.1)
				(type default)
			)
			(layer "F.Fab")
		)
		(fp_line
			(start -0.12065 -0.305054)
			(end -0.12065 -0.2794)
			(stroke
				(width 0.1)
				(type default)
			)
			(layer "F.Fab")
		)
		(pad "1" smd circle
			(at -0.40005 0 270)
			(size 0 0)
			(layers "F.Cu" "F.Mask" "F.Paste")
			(net "P3V3_AUX")
		)
		(pad "2" smd circle
			(at 0.40005 0 270)
			(size 0 0)
			(layers "F.Cu" "F.Mask" "F.Paste")
			(net "GND")
		)
	)
	(footprint ""
		(layer "F.Cu")
		(at 19.177 -39.751 -90)
		(property "Reference" "C280"
			(at 0 0 270)
			(layer "F.SilkS")
			(hide yes)
			(effects
				(font
					(size 1.27 1.27)
				)
			)
		)
		(property "Value" ""
			(at 0 0 270)
			(layer "F.Fab")
			(effects
				(font
					(size 1.27 1.27)
				)
			)
		)
		(duplicate_pad_numbers_are_jumpers no)
		(fp_line
			(start -0.7874 0.4064)
			(end -0.7874 -0.4064)
			(stroke
				(width 0.1524)
				(type default)
			)
			(layer "F.SilkS")
		)
		(fp_line
			(start 0.7874 0.4064)
			(end -0.7874 0.4064)
			(stroke
				(width 0.1524)
				(type default)
			)
			(layer "F.SilkS")
		)
		(fp_line
			(start -0.7874 -0.4064)
			(end 0.7874 -0.4064)
			(stroke
				(width 0.1524)
				(type default)
			)
			(layer "F.SilkS")
		)
		(fp_line
			(start 0.7874 -0.4064)
			(end 0.7874 0.4064)
			(stroke
				(width 0.1524)
				(type default)
			)
			(layer "F.SilkS")
		)
		(fp_line
			(start -0.67945 0.3048)
			(end -0.67945 -0.305054)
			(stroke
				(width 0.1)
				(type default)
			)
			(layer "F.Fab")
		)
		(fp_line
			(start -0.12065 0.3048)
			(end -0.67945 0.3048)
			(stroke
				(width 0.1)
				(type default)
			)
			(layer "F.Fab")
		)
		(fp_line
			(start 0.120396 0.3048)
			(end 0.120396 0.2794)
			(stroke
				(width 0.1)
				(type default)
			)
			(layer "F.Fab")
		)
		(fp_line
			(start 0.67945 0.3048)
			(end 0.120396 0.3048)
			(stroke
				(width 0.1)
				(type default)
			)
			(layer "F.Fab")
		)
		(fp_line
			(start -0.12065 0.2794)
			(end -0.12065 0.3048)
			(stroke
				(width 0.1)
				(type default)
			)
			(layer "F.Fab")
		)
		(fp_line
			(start 0.120396 0.2794)
			(end -0.12065 0.2794)
			(stroke
				(width 0.1)
				(type default)
			)
			(layer "F.Fab")
		)
		(fp_line
			(start -0.12065 -0.2794)
			(end 0.12065 -0.2794)
			(stroke
				(width 0.1)
				(type default)
			)
			(layer "F.Fab")
		)
		(fp_line
			(start 0.12065 -0.2794)
			(end 0.12065 -0.3048)
			(stroke
				(width 0.1)
				(type default)
			)
			(layer "F.Fab")
		)
		(fp_line
			(start 0.12065 -0.3048)
			(end 0.67945 -0.3048)
			(stroke
				(width 0.1)
				(type default)
			)
			(layer "F.Fab")
		)
		(fp_line
			(start 0.67945 -0.3048)
			(end 0.67945 0.3048)
			(stroke
				(width 0.1)
				(type default)
			)
			(layer "F.Fab")
		)
		(fp_line
			(start -0.67945 -0.305054)
			(end -0.12065 -0.305054)
			(stroke
				(width 0.1)
				(type default)
			)
			(layer "F.Fab")
		)
		(fp_line
			(start -0.12065 -0.305054)
			(end -0.12065 -0.2794)
			(stroke
				(width 0.1)
				(type default)
			)
			(layer "F.Fab")
		)
		(pad "1" smd circle
			(at -0.40005 0 270)
			(size 0 0)
			(layers "F.Cu" "F.Mask" "F.Paste")
			(net "P12V_AUX")
		)
		(pad "2" smd circle
			(at 0.40005 0 270)
			(size 0 0)
			(layers "F.Cu" "F.Mask" "F.Paste")
			(net "GND")
		)
	)
	(footprint ""
		(layer "F.Cu")
		(at 23.064216 -84.28228 90)
		(property "Reference" "R634"
			(at 0 0 90)
			(layer "F.SilkS")
			(hide yes)
			(effects
				(font
					(size 1.27 1.27)
				)
			)
		)
		(property "Value" ""
			(at 0 0 90)
			(layer "F.Fab")
			(effects
				(font
					(size 1.27 1.27)
				)
			)
		)
		(duplicate_pad_numbers_are_jumpers no)
		(fp_line
			(start 0.7874 -0.4064)
			(end 0.7874 0.4064)
			(stroke
				(width 0.1524)
				(type default)
			)
			(layer "F.SilkS")
		)
		(fp_line
			(start -0.7874 -0.4064)
			(end 0.7874 -0.4064)
			(stroke
				(width 0.1524)
				(type default)
			)
			(layer "F.SilkS")
		)
		(fp_line
			(start 0.7874 0.4064)
			(end -0.7874 0.4064)
			(stroke
				(width 0.1524)
				(type default)
			)
			(layer "F.SilkS")
		)
		(fp_line
			(start -0.7874 0.4064)
			(end -0.7874 -0.4064)
			(stroke
				(width 0.1524)
				(type default)
			)
			(layer "F.SilkS")
		)
		(fp_line
			(start -0.12065 -0.305054)
			(end -0.12065 -0.2794)
			(stroke
				(width 0.1)
				(type default)
			)
			(layer "F.Fab")
		)
		(fp_line
			(start -0.67945 -0.305054)
			(end -0.12065 -0.305054)
			(stroke
				(width 0.1)
				(type default)
			)
			(layer "F.Fab")
		)
		(fp_line
			(start 0.67945 -0.3048)
			(end 0.67945 0.3048)
			(stroke
				(width 0.1)
				(type default)
			)
			(layer "F.Fab")
		)
		(fp_line
			(start 0.12065 -0.3048)
			(end 0.67945 -0.3048)
			(stroke
				(width 0.1)
				(type default)
			)
			(layer "F.Fab")
		)
		(fp_line
			(start 0.12065 -0.2794)
			(end 0.12065 -0.3048)
			(stroke
				(width 0.1)
				(type default)
			)
			(layer "F.Fab")
		)
		(fp_line
			(start -0.12065 -0.2794)
			(end 0.12065 -0.2794)
			(stroke
				(width 0.1)
				(type default)
			)
			(layer "F.Fab")
		)
		(fp_line
			(start 0.120396 0.2794)
			(end -0.12065 0.2794)
			(stroke
				(width 0.1)
				(type default)
			)
			(layer "F.Fab")
		)
		(fp_line
			(start -0.12065 0.2794)
			(end -0.12065 0.3048)
			(stroke
				(width 0.1)
				(type default)
			)
			(layer "F.Fab")
		)
		(fp_line
			(start 0.67945 0.3048)
			(end 0.120396 0.3048)
			(stroke
				(width 0.1)
				(type default)
			)
			(layer "F.Fab")
		)
		(fp_line
			(start 0.120396 0.3048)
			(end 0.120396 0.2794)
			(stroke
				(width 0.1)
				(type default)
			)
			(layer "F.Fab")
		)
		(fp_line
			(start -0.12065 0.3048)
			(end -0.67945 0.3048)
			(stroke
				(width 0.1)
				(type default)
			)
			(layer "F.Fab")
		)
		(fp_line
			(start -0.67945 0.3048)
			(end -0.67945 -0.305054)
			(stroke
				(width 0.1)
				(type default)
			)
			(layer "F.Fab")
		)
		(pad "1" smd circle
			(at -0.40005 0 90)
			(size 0 0)
			(layers "F.Cu" "F.Mask" "F.Paste")
			(net "FM_JTAG_BMC_MUX_SEL")
		)
		(pad "2" smd circle
			(at 0.40005 0 90)
			(size 0 0)
			(layers "F.Cu" "F.Mask" "F.Paste")
			(net "FM_JTAG_BMC_MUX_SEL_R2")
		)
	)
	(footprint ""
		(layer "F.Cu")
		(at 39.826946 -79.64424 180)
		(property "Reference" "R557"
			(at 0 0 180)
			(layer "F.SilkS")
			(hide yes)
			(effects
				(font
					(size 1.27 1.27)
				)
			)
		)
		(property "Value" ""
			(at 0 0 180)
			(layer "F.Fab")
			(effects
				(font
					(size 1.27 1.27)
				)
			)
		)
		(duplicate_pad_numbers_are_jumpers no)
		(fp_line
			(start 0.7874 0.4064)
			(end -0.7874 0.4064)
			(stroke
				(width 0.1524)
				(type default)
			)
			(layer "F.SilkS")
		)
		(fp_line
			(start 0.7874 -0.4064)
			(end 0.7874 0.4064)
			(stroke
				(width 0.1524)
				(type default)
			)
			(layer "F.SilkS")
		)
		(fp_line
			(start -0.7874 0.4064)
			(end -0.7874 -0.4064)
			(stroke
				(width 0.1524)
				(type default)
			)
			(layer "F.SilkS")
		)
		(fp_line
			(start -0.7874 -0.4064)
			(end 0.7874 -0.4064)
			(stroke
				(width 0.1524)
				(type default)
			)
			(layer "F.SilkS")
		)
		(fp_line
			(start 0.67945 0.3048)
			(end 0.120396 0.3048)
			(stroke
				(width 0.1)
				(type default)
			)
			(layer "F.Fab")
		)
		(fp_line
			(start 0.67945 -0.3048)
			(end 0.67945 0.3048)
			(stroke
				(width 0.1)
				(type default)
			)
			(layer "F.Fab")
		)
		(fp_line
			(start 0.12065 -0.2794)
			(end 0.12065 -0.3048)
			(stroke
				(width 0.1)
				(type default)
			)
			(layer "F.Fab")
		)
		(fp_line
			(start 0.12065 -0.3048)
			(end 0.67945 -0.3048)
			(stroke
				(width 0.1)
				(type default)
			)
			(layer "F.Fab")
		)
		(fp_line
			(start 0.120396 0.3048)
			(end 0.120396 0.2794)
			(stroke
				(width 0.1)
				(type default)
			)
			(layer "F.Fab")
		)
		(fp_line
			(start 0.120396 0.2794)
			(end -0.12065 0.2794)
			(stroke
				(width 0.1)
				(type default)
			)
			(layer "F.Fab")
		)
		(fp_line
			(start -0.12065 0.3048)
			(end -0.67945 0.3048)
			(stroke
				(width 0.1)
				(type default)
			)
			(layer "F.Fab")
		)
		(fp_line
			(start -0.12065 0.2794)
			(end -0.12065 0.3048)
			(stroke
				(width 0.1)
				(type default)
			)
			(layer "F.Fab")
		)
		(fp_line
			(start -0.12065 -0.2794)
			(end 0.12065 -0.2794)
			(stroke
				(width 0.1)
				(type default)
			)
			(layer "F.Fab")
		)
		(fp_line
			(start -0.12065 -0.305054)
			(end -0.12065 -0.2794)
			(stroke
				(width 0.1)
				(type default)
			)
			(layer "F.Fab")
		)
		(fp_line
			(start -0.67945 0.3048)
			(end -0.67945 -0.305054)
			(stroke
				(width 0.1)
				(type default)
			)
			(layer "F.Fab")
		)
		(fp_line
			(start -0.67945 -0.305054)
			(end -0.12065 -0.305054)
			(stroke
				(width 0.1)
				(type default)
			)
			(layer "F.Fab")
		)
		(pad "1" smd circle
			(at -0.40005 0 180)
			(size 0 0)
			(layers "F.Cu" "F.Mask" "F.Paste")
			(net "P3V3_AUX")
		)
		(pad "2" smd circle
			(at 0.40005 0 180)
			(size 0 0)
			(layers "F.Cu" "F.Mask" "F.Paste")
			(net "SPI_BMC_CS0_FLASH_R_N")
		)
	)
	(footprint ""
		(layer "F.Cu")
		(at 17.7165 -69.596 -90)
		(property "Reference" "C234"
			(at 0 0 270)
			(layer "F.SilkS")
			(hide yes)
			(effects
				(font
					(size 1.27 1.27)
				)
			)
		)
		(property "Value" ""
			(at 0 0 270)
			(layer "F.Fab")
			(effects
				(font
					(size 1.27 1.27)
				)
			)
		)
		(duplicate_pad_numbers_are_jumpers no)
		(fp_line
			(start -1.2954 0.5842)
			(end -1.2954 -0.5842)
			(stroke
				(width 0.1524)
				(type default)
			)
			(layer "F.SilkS")
		)
		(fp_line
			(start 1.2954 0.5842)
			(end -1.2954 0.5842)
			(stroke
				(width 0.1524)
				(type default)
			)
			(layer "F.SilkS")
		)
		(fp_line
			(start -1.2954 -0.5842)
			(end 1.2954 -0.5842)
			(stroke
				(width 0.1524)
				(type default)
			)
			(layer "F.SilkS")
		)
		(fp_line
			(start 0 -0.5842)
			(end 0 0.5842)
			(stroke
				(width 0.1524)
				(type default)
			)
			(layer "F.SilkS")
		)
		(fp_line
			(start 1.2954 -0.5842)
			(end 1.2954 0.5842)
			(stroke
				(width 0.1524)
				(type default)
			)
			(layer "F.SilkS")
		)
		(fp_line
			(start -0.8636 0.4572)
			(end -0.8636 0.4064)
			(stroke
				(width 0.1)
				(type default)
			)
			(layer "F.Fab")
		)
		(fp_line
			(start 0.8636 0.4572)
			(end -0.8636 0.4572)
			(stroke
				(width 0.1)
				(type default)
			)
			(layer "F.Fab")
		)
		(fp_line
			(start -1.1938 0.4064)
			(end -1.1938 -0.4064)
			(stroke
				(width 0.1)
				(type default)
			)
			(layer "F.Fab")
		)
		(fp_line
			(start -0.8636 0.4064)
			(end -1.1938 0.4064)
			(stroke
				(width 0.1)
				(type default)
			)
			(layer "F.Fab")
		)
		(fp_line
			(start 0.8636 0.4064)
			(end 0.8636 0.4572)
			(stroke
				(width 0.1)
				(type default)
			)
			(layer "F.Fab")
		)
		(fp_line
			(start 1.1938 0.4064)
			(end 0.8636 0.4064)
			(stroke
				(width 0.1)
				(type default)
			)
			(layer "F.Fab")
		)
		(fp_line
			(start -1.1938 -0.4064)
			(end -0.8636 -0.4064)
			(stroke
				(width 0.1)
				(type default)
			)
			(layer "F.Fab")
		)
		(fp_line
			(start -0.8636 -0.4064)
			(end -0.8636 -0.4572)
			(stroke
				(width 0.1)
				(type default)
			)
			(layer "F.Fab")
		)
		(fp_line
			(start 0.8636 -0.4064)
			(end 1.1938 -0.4064)
			(stroke
				(width 0.1)
				(type default)
			)
			(layer "F.Fab")
		)
		(fp_line
			(start 1.1938 -0.4064)
			(end 1.1938 0.4064)
			(stroke
				(width 0.1)
				(type default)
			)
			(layer "F.Fab")
		)
		(fp_line
			(start -0.8636 -0.4572)
			(end 0.8636 -0.4572)
			(stroke
				(width 0.1)
				(type default)
			)
			(layer "F.Fab")
		)
		(fp_line
			(start 0.8636 -0.4572)
			(end 0.8636 -0.4064)
			(stroke
				(width 0.1)
				(type default)
			)
			(layer "F.Fab")
		)
		(pad "1" smd rect
			(at -0.7366 0 180)
			(size 0.7112 0.8128)
			(layers "F.Cu" "F.Mask" "F.Paste")
			(net "P3V3_AUX")
		)
		(pad "2" smd rect
			(at 0.7366 0 180)
			(size 0.7112 0.8128)
			(layers "F.Cu" "F.Mask" "F.Paste")
			(net "GND")
		)
	)
	(footprint ""
		(layer "F.Cu")
		(at 5.599938 -11.789918)
		(property "Reference" "H6"
			(at -4.964938 0.005588 0)
			(unlocked yes)
			(layer "F.SilkS")
			(effects
				(font
					(size 0.7874 0.5842)
					(thickness 0.1524)
				)
				(justify left)
			)
		)
		(property "Value" ""
			(at 0 0 0)
			(layer "F.Fab")
			(effects
				(font
					(size 1.27 1.27)
				)
			)
		)
		(duplicate_pad_numbers_are_jumpers no)
		(pad "1" thru_hole circle
			(at 0 0)
			(size 6.5024 6.5024)
			(drill 3.2004)
			(layers "*.Cu" "*.Mask")
			(remove_unused_layers no)
			(net "GND")
			(clearance -1.397)
		)
	)
	(footprint ""
		(layer "F.Cu")
		(at 44.704 -34.6202 90)
		(property "Reference" "R762"
			(at 0 0 90)
			(layer "F.SilkS")
			(hide yes)
			(effects
				(font
					(size 1.27 1.27)
				)
			)
		)
		(property "Value" ""
			(at 0 0 90)
			(layer "F.Fab")
			(effects
				(font
					(size 1.27 1.27)
				)
			)
		)
		(duplicate_pad_numbers_are_jumpers no)
		(fp_line
			(start 0.7874 -0.4064)
			(end 0.7874 0.4064)
			(stroke
				(width 0.1524)
				(type default)
			)
			(layer "F.SilkS")
		)
		(fp_line
			(start -0.7874 -0.4064)
			(end 0.7874 -0.4064)
			(stroke
				(width 0.1524)
				(type default)
			)
			(layer "F.SilkS")
		)
		(fp_line
			(start 0.7874 0.4064)
			(end -0.7874 0.4064)
			(stroke
				(width 0.1524)
				(type default)
			)
			(layer "F.SilkS")
		)
		(fp_line
			(start -0.7874 0.4064)
			(end -0.7874 -0.4064)
			(stroke
				(width 0.1524)
				(type default)
			)
			(layer "F.SilkS")
		)
		(fp_line
			(start -0.12065 -0.305054)
			(end -0.12065 -0.2794)
			(stroke
				(width 0.1)
				(type default)
			)
			(layer "F.Fab")
		)
		(fp_line
			(start -0.67945 -0.305054)
			(end -0.12065 -0.305054)
			(stroke
				(width 0.1)
				(type default)
			)
			(layer "F.Fab")
		)
		(fp_line
			(start 0.67945 -0.3048)
			(end 0.67945 0.3048)
			(stroke
				(width 0.1)
				(type default)
			)
			(layer "F.Fab")
		)
		(fp_line
			(start 0.12065 -0.3048)
			(end 0.67945 -0.3048)
			(stroke
				(width 0.1)
				(type default)
			)
			(layer "F.Fab")
		)
		(fp_line
			(start 0.12065 -0.2794)
			(end 0.12065 -0.3048)
			(stroke
				(width 0.1)
				(type default)
			)
			(layer "F.Fab")
		)
		(fp_line
			(start -0.12065 -0.2794)
			(end 0.12065 -0.2794)
			(stroke
				(width 0.1)
				(type default)
			)
			(layer "F.Fab")
		)
		(fp_line
			(start 0.120396 0.2794)
			(end -0.12065 0.2794)
			(stroke
				(width 0.1)
				(type default)
			)
			(layer "F.Fab")
		)
		(fp_line
			(start -0.12065 0.2794)
			(end -0.12065 0.3048)
			(stroke
				(width 0.1)
				(type default)
			)
			(layer "F.Fab")
		)
		(fp_line
			(start 0.67945 0.3048)
			(end 0.120396 0.3048)
			(stroke
				(width 0.1)
				(type default)
			)
			(layer "F.Fab")
		)
		(fp_line
			(start 0.120396 0.3048)
			(end 0.120396 0.2794)
			(stroke
				(width 0.1)
				(type default)
			)
			(layer "F.Fab")
		)
		(fp_line
			(start -0.12065 0.3048)
			(end -0.67945 0.3048)
			(stroke
				(width 0.1)
				(type default)
			)
			(layer "F.Fab")
		)
		(fp_line
			(start -0.67945 0.3048)
			(end -0.67945 -0.305054)
			(stroke
				(width 0.1)
				(type default)
			)
			(layer "F.Fab")
		)
		(pad "1" smd circle
			(at -0.40005 0 90)
			(size 0 0)
			(layers "F.Cu" "F.Mask" "F.Paste")
			(net "UART_6_BMC_RXD")
		)
		(pad "2" smd circle
			(at 0.40005 0 90)
			(size 0 0)
			(layers "F.Cu" "F.Mask" "F.Paste")
			(net "UART_6_BMC_R_RXD")
		)
	)
	(footprint ""
		(layer "F.Cu")
		(at 76.581 -82.677 -90)
		(property "Reference" "U56"
			(at 1.5494 2.149348 90)
			(unlocked yes)
			(layer "F.SilkS")
			(effects
				(font
					(size 0.7874 0.5842)
					(thickness 0.1524)
				)
				(justify left)
			)
		)
		(property "Value" ""
			(at 0 0 270)
			(layer "F.Fab")
			(effects
				(font
					(size 1.27 1.27)
				)
			)
		)
		(duplicate_pad_numbers_are_jumpers no)
		(fp_line
			(start -1.934972 1.549908)
			(end 1.934972 1.549908)
			(stroke
				(width 0.1524)
				(type default)
			)
			(layer "F.SilkS")
		)
		(fp_line
			(start 1.934972 1.549908)
			(end 1.934972 -1.549908)
			(stroke
				(width 0.1524)
				(type default)
			)
			(layer "F.SilkS")
		)
		(fp_line
			(start 0 -0.82042)
			(end -0.475742 -1.549908)
			(stroke
				(width 0.1524)
				(type default)
			)
			(layer "F.SilkS")
		)
		(fp_line
			(start -1.934972 -1.549908)
			(end -1.934972 1.549908)
			(stroke
				(width 0.1524)
				(type default)
			)
			(layer "F.SilkS")
		)
		(fp_line
			(start -0.475742 -1.549908)
			(end -1.934972 -1.549908)
			(stroke
				(width 0.1524)
				(type default)
			)
			(layer "F.SilkS")
		)
		(fp_line
			(start 0.475742 -1.549908)
			(end 0 -0.82042)
			(stroke
				(width 0.1524)
				(type default)
			)
			(layer "F.SilkS")
		)
		(fp_line
			(start 1.934972 -1.549908)
			(end 0.475742 -1.549908)
			(stroke
				(width 0.1524)
				(type default)
			)
			(layer "F.SilkS")
		)
		(fp_poly
			(pts
				(xy -3.160522 -1.45796) (xy -3.160522 -0.44196) (xy -2.144522 -0.94996)
			)
			(stroke
				(width 0)
				(type default)
			)
			(fill yes)
			(layer "F.SilkS")
		)
		(fp_line
			(start -0.849884 1.549908)
			(end 0.849884 1.549908)
			(stroke
				(width 0.1)
				(type default)
			)
			(layer "F.Fab")
		)
		(fp_line
			(start 0.849884 1.549908)
			(end 0.849884 -1.549908)
			(stroke
				(width 0.1)
				(type default)
			)
			(layer "F.Fab")
		)
		(fp_line
			(start -0.849884 -1.549908)
			(end -0.849884 1.549908)
			(stroke
				(width 0.1)
				(type default)
			)
			(layer "F.Fab")
		)
		(fp_line
			(start 0.849884 -1.549908)
			(end -0.849884 -1.549908)
			(stroke
				(width 0.1)
				(type default)
			)
			(layer "F.Fab")
		)
		(fp_poly
			(pts
				(xy -3.160522 -1.45796) (xy -3.160522 -0.44196) (xy -2.144522 -0.94996)
			)
			(stroke
				(width 0)
				(type default)
			)
			(fill yes)
			(layer "F.Fab")
		)
		(pad "1" smd rect
			(at -1.299972 -0.94996 180)
			(size 0.7112 1.016)
			(layers "F.Cu" "F.Mask" "F.Paste")
			(net "P12V_AUX")
		)
		(pad "2" smd rect
			(at -1.299972 0 180)
			(size 0.7112 1.016)
			(layers "F.Cu" "F.Mask" "F.Paste")
			(net "GND")
		)
		(pad "3" smd rect
			(at -1.299972 0.94996 180)
			(size 0.7112 1.016)
			(layers "F.Cu" "F.Mask" "F.Paste")
			(net "P12V_AUX")
		)
		(pad "4" smd rect
			(at 1.299972 0.94996 180)
			(size 0.7112 1.016)
			(layers "F.Cu" "F.Mask" "F.Paste")
			(net "U56_ADJ_1")
		)
		(pad "5" smd rect
			(at 1.299972 -0.94996 180)
			(size 0.7112 1.016)
			(layers "F.Cu" "F.Mask" "F.Paste")
			(net "P3V3_LDO")
		)
	)
	(footprint ""
		(layer "F.Cu")
		(at 63.105792 -65.37071)
		(property "Reference" "R116"
			(at 0 0 0)
			(layer "F.SilkS")
			(hide yes)
			(effects
				(font
					(size 1.27 1.27)
				)
			)
		)
		(property "Value" ""
			(at 0 0 0)
			(layer "F.Fab")
			(effects
				(font
					(size 1.27 1.27)
				)
			)
		)
		(duplicate_pad_numbers_are_jumpers no)
		(fp_line
			(start -0.7874 -0.4064)
			(end 0.7874 -0.4064)
			(stroke
				(width 0.1524)
				(type default)
			)
			(layer "F.SilkS")
		)
		(fp_line
			(start -0.7874 0.4064)
			(end -0.7874 -0.4064)
			(stroke
				(width 0.1524)
				(type default)
			)
			(layer "F.SilkS")
		)
		(fp_line
			(start 0.7874 -0.4064)
			(end 0.7874 0.4064)
			(stroke
				(width 0.1524)
				(type default)
			)
			(layer "F.SilkS")
		)
		(fp_line
			(start 0.7874 0.4064)
			(end -0.7874 0.4064)
			(stroke
				(width 0.1524)
				(type default)
			)
			(layer "F.SilkS")
		)
		(fp_line
			(start -0.67945 -0.305054)
			(end -0.12065 -0.305054)
			(stroke
				(width 0.1)
				(type default)
			)
			(layer "F.Fab")
		)
		(fp_line
			(start -0.67945 0.3048)
			(end -0.67945 -0.305054)
			(stroke
				(width 0.1)
				(type default)
			)
			(layer "F.Fab")
		)
		(fp_line
			(start -0.12065 -0.305054)
			(end -0.12065 -0.2794)
			(stroke
				(width 0.1)
				(type default)
			)
			(layer "F.Fab")
		)
		(fp_line
			(start -0.12065 -0.2794)
			(end 0.12065 -0.2794)
			(stroke
				(width 0.1)
				(type default)
			)
			(layer "F.Fab")
		)
		(fp_line
			(start -0.12065 0.2794)
			(end -0.12065 0.3048)
			(stroke
				(width 0.1)
				(type default)
			)
			(layer "F.Fab")
		)
		(fp_line
			(start -0.12065 0.3048)
			(end -0.67945 0.3048)
			(stroke
				(width 0.1)
				(type default)
			)
			(layer "F.Fab")
		)
		(fp_line
			(start 0.120396 0.2794)
			(end -0.12065 0.2794)
			(stroke
				(width 0.1)
				(type default)
			)
			(layer "F.Fab")
		)
		(fp_line
			(start 0.120396 0.3048)
			(end 0.120396 0.2794)
			(stroke
				(width 0.1)
				(type default)
			)
			(layer "F.Fab")
		)
		(fp_line
			(start 0.12065 -0.3048)
			(end 0.67945 -0.3048)
			(stroke
				(width 0.1)
				(type default)
			)
			(layer "F.Fab")
		)
		(fp_line
			(start 0.12065 -0.2794)
			(end 0.12065 -0.3048)
			(stroke
				(width 0.1)
				(type default)
			)
			(layer "F.Fab")
		)
		(fp_line
			(start 0.67945 -0.3048)
			(end 0.67945 0.3048)
			(stroke
				(width 0.1)
				(type default)
			)
			(layer "F.Fab")
		)
		(fp_line
			(start 0.67945 0.3048)
			(end 0.120396 0.3048)
			(stroke
				(width 0.1)
				(type default)
			)
			(layer "F.Fab")
		)
		(pad "1" smd circle
			(at -0.40005 0)
			(size 0 0)
			(layers "F.Cu" "F.Mask" "F.Paste")
			(net "PGPPA_BMC_AUX")
		)
		(pad "2" smd circle
			(at 0.40005 0)
			(size 0 0)
			(layers "F.Cu" "F.Mask" "F.Paste")
			(net "IRQ_BMC_LPC_SERIRQ_ESPI_GF")
		)
	)
	(footprint ""
		(layer "F.Cu")
		(at 64.51854 -108.004356 90)
		(property "Reference" "R115"
			(at 0 0 90)
			(layer "F.SilkS")
			(hide yes)
			(effects
				(font
					(size 1.27 1.27)
				)
			)
		)
		(property "Value" ""
			(at 0 0 90)
			(layer "F.Fab")
			(effects
				(font
					(size 1.27 1.27)
				)
			)
		)
		(duplicate_pad_numbers_are_jumpers no)
		(fp_line
			(start 0.7874 -0.4064)
			(end 0.7874 0.4064)
			(stroke
				(width 0.1524)
				(type default)
			)
			(layer "F.SilkS")
		)
		(fp_line
			(start -0.7874 -0.4064)
			(end 0.7874 -0.4064)
			(stroke
				(width 0.1524)
				(type default)
			)
			(layer "F.SilkS")
		)
		(fp_line
			(start 0.7874 0.4064)
			(end -0.7874 0.4064)
			(stroke
				(width 0.1524)
				(type default)
			)
			(layer "F.SilkS")
		)
		(fp_line
			(start -0.7874 0.4064)
			(end -0.7874 -0.4064)
			(stroke
				(width 0.1524)
				(type default)
			)
			(layer "F.SilkS")
		)
		(fp_line
			(start -0.12065 -0.305054)
			(end -0.12065 -0.2794)
			(stroke
				(width 0.1)
				(type default)
			)
			(layer "F.Fab")
		)
		(fp_line
			(start -0.67945 -0.305054)
			(end -0.12065 -0.305054)
			(stroke
				(width 0.1)
				(type default)
			)
			(layer "F.Fab")
		)
		(fp_line
			(start 0.67945 -0.3048)
			(end 0.67945 0.3048)
			(stroke
				(width 0.1)
				(type default)
			)
			(layer "F.Fab")
		)
		(fp_line
			(start 0.12065 -0.3048)
			(end 0.67945 -0.3048)
			(stroke
				(width 0.1)
				(type default)
			)
			(layer "F.Fab")
		)
		(fp_line
			(start 0.12065 -0.2794)
			(end 0.12065 -0.3048)
			(stroke
				(width 0.1)
				(type default)
			)
			(layer "F.Fab")
		)
		(fp_line
			(start -0.12065 -0.2794)
			(end 0.12065 -0.2794)
			(stroke
				(width 0.1)
				(type default)
			)
			(layer "F.Fab")
		)
		(fp_line
			(start 0.120396 0.2794)
			(end -0.12065 0.2794)
			(stroke
				(width 0.1)
				(type default)
			)
			(layer "F.Fab")
		)
		(fp_line
			(start -0.12065 0.2794)
			(end -0.12065 0.3048)
			(stroke
				(width 0.1)
				(type default)
			)
			(layer "F.Fab")
		)
		(fp_line
			(start 0.67945 0.3048)
			(end 0.120396 0.3048)
			(stroke
				(width 0.1)
				(type default)
			)
			(layer "F.Fab")
		)
		(fp_line
			(start 0.120396 0.3048)
			(end 0.120396 0.2794)
			(stroke
				(width 0.1)
				(type default)
			)
			(layer "F.Fab")
		)
		(fp_line
			(start -0.12065 0.3048)
			(end -0.67945 0.3048)
			(stroke
				(width 0.1)
				(type default)
			)
			(layer "F.Fab")
		)
		(fp_line
			(start -0.67945 0.3048)
			(end -0.67945 -0.305054)
			(stroke
				(width 0.1)
				(type default)
			)
			(layer "F.Fab")
		)
		(pad "1" smd circle
			(at -0.40005 0 90)
			(size 0 0)
			(layers "F.Cu" "F.Mask" "F.Paste")
			(net "PGPPA_BMC_AUX")
		)
		(pad "2" smd circle
			(at 0.40005 0 90)
			(size 0 0)
			(layers "F.Cu" "F.Mask" "F.Paste")
			(net "ESPI_HOST_LPC_BMC_LFRAME_N")
		)
	)
	(footprint ""
		(layer "F.Cu")
		(at 55.7276 -105.664 180)
		(property "Reference" "R501"
			(at 0 0 180)
			(layer "F.SilkS")
			(hide yes)
			(effects
				(font
					(size 1.27 1.27)
				)
			)
		)
		(property "Value" ""
			(at 0 0 180)
			(layer "F.Fab")
			(effects
				(font
					(size 1.27 1.27)
				)
			)
		)
		(duplicate_pad_numbers_are_jumpers no)
		(fp_line
			(start 0.7874 0.4064)
			(end -0.7874 0.4064)
			(stroke
				(width 0.1524)
				(type default)
			)
			(layer "F.SilkS")
		)
		(fp_line
			(start 0.7874 -0.4064)
			(end 0.7874 0.4064)
			(stroke
				(width 0.1524)
				(type default)
			)
			(layer "F.SilkS")
		)
		(fp_line
			(start -0.7874 0.4064)
			(end -0.7874 -0.4064)
			(stroke
				(width 0.1524)
				(type default)
			)
			(layer "F.SilkS")
		)
		(fp_line
			(start -0.7874 -0.4064)
			(end 0.7874 -0.4064)
			(stroke
				(width 0.1524)
				(type default)
			)
			(layer "F.SilkS")
		)
		(fp_line
			(start 0.67945 0.3048)
			(end 0.120396 0.3048)
			(stroke
				(width 0.1)
				(type default)
			)
			(layer "F.Fab")
		)
		(fp_line
			(start 0.67945 -0.3048)
			(end 0.67945 0.3048)
			(stroke
				(width 0.1)
				(type default)
			)
			(layer "F.Fab")
		)
		(fp_line
			(start 0.12065 -0.2794)
			(end 0.12065 -0.3048)
			(stroke
				(width 0.1)
				(type default)
			)
			(layer "F.Fab")
		)
		(fp_line
			(start 0.12065 -0.3048)
			(end 0.67945 -0.3048)
			(stroke
				(width 0.1)
				(type default)
			)
			(layer "F.Fab")
		)
		(fp_line
			(start 0.120396 0.3048)
			(end 0.120396 0.2794)
			(stroke
				(width 0.1)
				(type default)
			)
			(layer "F.Fab")
		)
		(fp_line
			(start 0.120396 0.2794)
			(end -0.12065 0.2794)
			(stroke
				(width 0.1)
				(type default)
			)
			(layer "F.Fab")
		)
		(fp_line
			(start -0.12065 0.3048)
			(end -0.67945 0.3048)
			(stroke
				(width 0.1)
				(type default)
			)
			(layer "F.Fab")
		)
		(fp_line
			(start -0.12065 0.2794)
			(end -0.12065 0.3048)
			(stroke
				(width 0.1)
				(type default)
			)
			(layer "F.Fab")
		)
		(fp_line
			(start -0.12065 -0.2794)
			(end 0.12065 -0.2794)
			(stroke
				(width 0.1)
				(type default)
			)
			(layer "F.Fab")
		)
		(fp_line
			(start -0.12065 -0.305054)
			(end -0.12065 -0.2794)
			(stroke
				(width 0.1)
				(type default)
			)
			(layer "F.Fab")
		)
		(fp_line
			(start -0.67945 0.3048)
			(end -0.67945 -0.305054)
			(stroke
				(width 0.1)
				(type default)
			)
			(layer "F.Fab")
		)
		(fp_line
			(start -0.67945 -0.305054)
			(end -0.12065 -0.305054)
			(stroke
				(width 0.1)
				(type default)
			)
			(layer "F.Fab")
		)
		(pad "1" smd circle
			(at -0.40005 0 180)
			(size 0 0)
			(layers "F.Cu" "F.Mask" "F.Paste")
			(net "SPI_SYS_R1_CLK")
		)
		(pad "2" smd circle
			(at 0.40005 0 180)
			(size 0 0)
			(layers "F.Cu" "F.Mask" "F.Paste")
			(net "SPI_SYS_R_CLK")
		)
	)
	(footprint ""
		(layer "F.Cu")
		(at 36.399978 -25.619964)
		(property "Reference" "J8"
			(at -1.779778 -8.338566 0)
			(unlocked yes)
			(layer "F.SilkS")
			(effects
				(font
					(size 0.7874 0.5842)
					(thickness 0.1524)
				)
				(justify left)
			)
		)
		(property "Value" ""
			(at 0 0 0)
			(layer "F.Fab")
			(effects
				(font
					(size 1.27 1.27)
				)
			)
		)
		(duplicate_pad_numbers_are_jumpers no)
		(fp_line
			(start -1.450086 -7.549896)
			(end -1.450086 -6.4516)
			(stroke
				(width 0.1524)
				(type default)
			)
			(layer "F.SilkS")
		)
		(fp_line
			(start -1.450086 6.4516)
			(end -1.450086 7.549896)
			(stroke
				(width 0.1524)
				(type default)
			)
			(layer "F.SilkS")
		)
		(fp_line
			(start -1.450086 7.549896)
			(end -0.2794 7.549896)
			(stroke
				(width 0.1524)
				(type default)
			)
			(layer "F.SilkS")
		)
		(fp_line
			(start -0.2794 -7.549896)
			(end -1.450086 -7.549896)
			(stroke
				(width 0.1524)
				(type default)
			)
			(layer "F.SilkS")
		)
		(fp_line
			(start 1.450086 6.5532)
			(end 1.450086 -6.5532)
			(stroke
				(width 0.1524)
				(type default)
			)
			(layer "F.SilkS")
		)
		(fp_poly
			(pts
				(xy -3.7084 -5.491988) (xy -3.7084 -6.507988) (xy -2.6924 -5.999988)
			)
			(stroke
				(width 0)
				(type default)
			)
			(fill yes)
			(layer "F.SilkS")
		)
		(fp_line
			(start -1.450086 -7.549896)
			(end -1.450086 7.549896)
			(stroke
				(width 0.1)
				(type default)
			)
			(layer "F.Fab")
		)
		(fp_line
			(start -1.450086 7.549896)
			(end 1.450086 7.549896)
			(stroke
				(width 0.1)
				(type default)
			)
			(layer "F.Fab")
		)
		(fp_line
			(start 1.450086 -7.549896)
			(end -1.450086 -7.549896)
			(stroke
				(width 0.1)
				(type default)
			)
			(layer "F.Fab")
		)
		(fp_line
			(start 1.450086 7.549896)
			(end 1.450086 -7.549896)
			(stroke
				(width 0.1)
				(type default)
			)
			(layer "F.Fab")
		)
		(fp_poly
			(pts
				(xy -3.7084 -5.491988) (xy -3.7084 -6.507988) (xy -2.6924 -5.999988)
			)
			(stroke
				(width 0)
				(type default)
			)
			(fill yes)
			(layer "F.Fab")
		)
		(fp_text user "13"
			(at -3.235452 5.9944 270)
			(unlocked yes)
			(layer "F.SilkS")
			(effects
				(font
					(size 0.7874 0.5842)
					(thickness 0.1524)
				)
			)
		)
		(fp_text user "13"
			(at -3.235452 5.9944 270)
			(unlocked yes)
			(layer "F.Fab")
			(effects
				(font
					(size 0.7874 0.5842)
					(thickness 0.1524)
				)
			)
		)
		(pad "1" smd rect
			(at -1.774952 -5.999988 270)
			(size 0.6096 1.5494)
			(layers "F.Cu" "F.Mask" "F.Paste")
			(net "V_DACR_IO")
		)
		(pad "2" smd rect
			(at -1.774952 -4.99999 270)
			(size 0.6096 1.5494)
			(layers "F.Cu" "F.Mask" "F.Paste")
			(net "GND")
		)
		(pad "3" smd rect
			(at -1.774952 -3.999992 270)
			(size 0.6096 1.5494)
			(layers "F.Cu" "F.Mask" "F.Paste")
			(net "V_DACG_IO")
		)
		(pad "4" smd rect
			(at -1.774952 -2.999994 270)
			(size 0.6096 1.5494)
			(layers "F.Cu" "F.Mask" "F.Paste")
			(net "GND")
		)
		(pad "5" smd rect
			(at -1.774952 -1.999996 270)
			(size 0.6096 1.5494)
			(layers "F.Cu" "F.Mask" "F.Paste")
			(net "V_DACB_IO")
		)
		(pad "6" smd rect
			(at -1.774952 -0.999998 270)
			(size 0.6096 1.5494)
			(layers "F.Cu" "F.Mask" "F.Paste")
			(net "GND")
		)
		(pad "7" smd rect
			(at -1.774952 0 270)
			(size 0.6096 1.5494)
			(layers "F.Cu" "F.Mask" "F.Paste")
			(net "V_VGAVS_BUF")
		)
		(pad "8" smd rect
			(at -1.774952 0.999998 270)
			(size 0.6096 1.5494)
			(layers "F.Cu" "F.Mask" "F.Paste")
			(net "GND")
		)
		(pad "9" smd rect
			(at -1.774952 1.999996 270)
			(size 0.6096 1.5494)
			(layers "F.Cu" "F.Mask" "F.Paste")
			(net "V_VGAHS_BUF")
		)
		(pad "10" smd rect
			(at -1.774952 2.999994 270)
			(size 0.6096 1.5494)
			(layers "F.Cu" "F.Mask" "F.Paste")
			(net "GND")
		)
		(pad "11" smd rect
			(at -1.774952 3.999992 270)
			(size 0.6096 1.5494)
			(layers "F.Cu" "F.Mask" "F.Paste")
			(net "V_BMC_LS_DDC_SDA_R")
		)
		(pad "12" smd rect
			(at -1.774952 4.99999 270)
			(size 0.6096 1.5494)
			(layers "F.Cu" "F.Mask" "F.Paste")
			(net "V_BMC_LS_DDC_SCL_R")
		)
		(pad "13" smd rect
			(at -1.774952 5.999988 270)
			(size 0.6096 1.5494)
			(layers "F.Cu" "F.Mask" "F.Paste")
			(net "CRT_VCC5_2_FUSE")
		)
		(pad "G1" smd rect
			(at 0.750062 -7.29996 270)
			(size 1.2192 1.8034)
			(layers "F.Cu" "F.Mask" "F.Paste")
			(net "GND")
		)
		(pad "G2" smd rect
			(at 0.750062 7.29996 270)
			(size 1.2192 1.8034)
			(layers "F.Cu" "F.Mask" "F.Paste")
			(net "GND")
		)
	)
	(footprint ""
		(layer "F.Cu")
		(at 73.980294 -98.425 180)
		(property "Reference" "R47"
			(at 0 0 180)
			(layer "F.SilkS")
			(hide yes)
			(effects
				(font
					(size 1.27 1.27)
				)
			)
		)
		(property "Value" ""
			(at 0 0 180)
			(layer "F.Fab")
			(effects
				(font
					(size 1.27 1.27)
				)
			)
		)
		(duplicate_pad_numbers_are_jumpers no)
		(fp_line
			(start 0.7874 0.4064)
			(end -0.7874 0.4064)
			(stroke
				(width 0.1524)
				(type default)
			)
			(layer "F.SilkS")
		)
		(fp_line
			(start 0.7874 -0.4064)
			(end 0.7874 0.4064)
			(stroke
				(width 0.1524)
				(type default)
			)
			(layer "F.SilkS")
		)
		(fp_line
			(start -0.7874 0.4064)
			(end -0.7874 -0.4064)
			(stroke
				(width 0.1524)
				(type default)
			)
			(layer "F.SilkS")
		)
		(fp_line
			(start -0.7874 -0.4064)
			(end 0.7874 -0.4064)
			(stroke
				(width 0.1524)
				(type default)
			)
			(layer "F.SilkS")
		)
		(fp_line
			(start 0.67945 0.3048)
			(end 0.120396 0.3048)
			(stroke
				(width 0.1)
				(type default)
			)
			(layer "F.Fab")
		)
		(fp_line
			(start 0.67945 -0.3048)
			(end 0.67945 0.3048)
			(stroke
				(width 0.1)
				(type default)
			)
			(layer "F.Fab")
		)
		(fp_line
			(start 0.12065 -0.2794)
			(end 0.12065 -0.3048)
			(stroke
				(width 0.1)
				(type default)
			)
			(layer "F.Fab")
		)
		(fp_line
			(start 0.12065 -0.3048)
			(end 0.67945 -0.3048)
			(stroke
				(width 0.1)
				(type default)
			)
			(layer "F.Fab")
		)
		(fp_line
			(start 0.120396 0.3048)
			(end 0.120396 0.2794)
			(stroke
				(width 0.1)
				(type default)
			)
			(layer "F.Fab")
		)
		(fp_line
			(start 0.120396 0.2794)
			(end -0.12065 0.2794)
			(stroke
				(width 0.1)
				(type default)
			)
			(layer "F.Fab")
		)
		(fp_line
			(start -0.12065 0.3048)
			(end -0.67945 0.3048)
			(stroke
				(width 0.1)
				(type default)
			)
			(layer "F.Fab")
		)
		(fp_line
			(start -0.12065 0.2794)
			(end -0.12065 0.3048)
			(stroke
				(width 0.1)
				(type default)
			)
			(layer "F.Fab")
		)
		(fp_line
			(start -0.12065 -0.2794)
			(end 0.12065 -0.2794)
			(stroke
				(width 0.1)
				(type default)
			)
			(layer "F.Fab")
		)
		(fp_line
			(start -0.12065 -0.305054)
			(end -0.12065 -0.2794)
			(stroke
				(width 0.1)
				(type default)
			)
			(layer "F.Fab")
		)
		(fp_line
			(start -0.67945 0.3048)
			(end -0.67945 -0.305054)
			(stroke
				(width 0.1)
				(type default)
			)
			(layer "F.Fab")
		)
		(fp_line
			(start -0.67945 -0.305054)
			(end -0.12065 -0.305054)
			(stroke
				(width 0.1)
				(type default)
			)
			(layer "F.Fab")
		)
		(pad "1" smd circle
			(at -0.40005 0 180)
			(size 0 0)
			(layers "F.Cu" "F.Mask" "F.Paste")
			(net "SMB_BMC_TPM_MM16_SCL")
		)
		(pad "2" smd circle
			(at 0.40005 0 180)
			(size 0 0)
			(layers "F.Cu" "F.Mask" "F.Paste")
			(net "SMB_BMC_MM16_R5_SCL")
		)
	)
	(footprint ""
		(layer "F.Cu")
		(at 36.668456 -55.936388 180)
		(property "Reference" "U41"
			(at 6.534912 -0.325628 0)
			(unlocked yes)
			(layer "F.SilkS")
			(effects
				(font
					(size 0.7874 0.5842)
					(thickness 0.1524)
				)
				(justify left)
			)
		)
		(property "Value" ""
			(at 0 0 180)
			(layer "F.Fab")
			(effects
				(font
					(size 1.27 1.27)
				)
			)
		)
		(duplicate_pad_numbers_are_jumpers no)
		(fp_line
			(start 1.525016 1.525016)
			(end 1.525016 1.3208)
			(stroke
				(width 0.1524)
				(type default)
			)
			(layer "F.SilkS")
		)
		(fp_line
			(start 1.525016 1.525016)
			(end -1.525016 1.525016)
			(stroke
				(width 0.1524)
				(type default)
			)
			(layer "F.SilkS")
		)
		(fp_line
			(start 1.525016 -1.3208)
			(end 1.525016 -1.525016)
			(stroke
				(width 0.1524)
				(type default)
			)
			(layer "F.SilkS")
		)
		(fp_line
			(start 1.525016 -1.525016)
			(end 0.9398 -1.525016)
			(stroke
				(width 0.1524)
				(type default)
			)
			(layer "F.SilkS")
		)
		(fp_line
			(start 1.525016 -1.525016)
			(end -1.525016 -1.525016)
			(stroke
				(width 0.1524)
				(type default)
			)
			(layer "F.SilkS")
		)
		(fp_line
			(start 0.9906 1.525016)
			(end 1.525016 1.525016)
			(stroke
				(width 0.1524)
				(type default)
			)
			(layer "F.SilkS")
		)
		(fp_line
			(start -0.8636 -1.525016)
			(end -1.525016 -1.525016)
			(stroke
				(width 0.1524)
				(type default)
			)
			(layer "F.SilkS")
		)
		(fp_line
			(start -1.525016 1.525016)
			(end -0.889 1.525016)
			(stroke
				(width 0.1524)
				(type default)
			)
			(layer "F.SilkS")
		)
		(fp_line
			(start -1.525016 1.3208)
			(end -1.525016 1.525016)
			(stroke
				(width 0.1524)
				(type default)
			)
			(layer "F.SilkS")
		)
		(fp_line
			(start -1.525016 -1.525016)
			(end -1.525016 -1.3208)
			(stroke
				(width 0.1524)
				(type default)
			)
			(layer "F.SilkS")
		)
		(fp_poly
			(pts
				(xy -2.102104 -1.112774) (xy -2.29235 -2.042414) (xy -2.812034 -1.74244)
			)
			(stroke
				(width 0)
				(type default)
			)
			(fill yes)
			(layer "F.SilkS")
		)
		(fp_line
			(start 1.525016 1.525016)
			(end -1.525016 1.525016)
			(stroke
				(width 0.1)
				(type default)
			)
			(layer "F.Fab")
		)
		(fp_line
			(start 1.525016 -1.525016)
			(end 1.525016 1.525016)
			(stroke
				(width 0.1)
				(type default)
			)
			(layer "F.Fab")
		)
		(fp_line
			(start -1.525016 1.525016)
			(end -1.525016 -1.525016)
			(stroke
				(width 0.1)
				(type default)
			)
			(layer "F.Fab")
		)
		(fp_line
			(start -1.525016 -1.525016)
			(end 1.525016 -1.525016)
			(stroke
				(width 0.1)
				(type default)
			)
			(layer "F.Fab")
		)
		(fp_poly
			(pts
				(xy -2.0701 -0.999998) (xy -2.977896 -1.302512) (xy -2.977896 -0.697484)
			)
			(stroke
				(width 0)
				(type default)
			)
			(fill yes)
			(layer "F.Fab")
		)
		(pad "1" smd rect
			(at -1.550162 -0.999998 90)
			(size 0.2794 0.9144)
			(layers "F.Cu" "F.Mask" "F.Paste")
			(net "P1V8_AUX")
		)
		(pad "2" smd rect
			(at -1.550162 -0.500126 90)
			(size 0.2794 0.9144)
			(layers "F.Cu" "F.Mask" "F.Paste")
			(net "P1V8_AUX")
		)
		(pad "3" smd rect
			(at -1.550162 0 90)
			(size 0.2794 0.9144)
			(layers "F.Cu" "F.Mask" "F.Paste")
			(net "P1V8_AUX")
		)
		(pad "4" smd rect
			(at -1.550162 0.500126 90)
			(size 0.2794 0.9144)
			(layers "F.Cu" "F.Mask" "F.Paste")
			(net "U41_ADJ")
		)
		(pad "5" smd rect
			(at -1.550162 0.999998 270)
			(size 0.2794 0.9144)
			(layers "F.Cu" "F.Mask" "F.Paste")
			(net "PWRGD_P1V8_AUX_R")
		)
		(pad "6" smd rect
			(at 1.550162 0.999998 270)
			(size 0.2794 0.9144)
			(layers "F.Cu" "F.Mask" "F.Paste")
			(net "EN_P1V8_R")
		)
		(pad "7" smd rect
			(at 1.550162 0.500126 90)
			(size 0.2794 0.9144)
			(layers "F.Cu" "F.Mask" "F.Paste")
			(net "P3V3_AUX")
		)
		(pad "8" smd rect
			(at 1.550162 0 90)
			(size 0.2794 0.9144)
			(layers "F.Cu" "F.Mask" "F.Paste")
			(net "P3V3_AUX")
		)
		(pad "9" smd rect
			(at 1.550162 -0.500126 90)
			(size 0.2794 0.9144)
			(layers "F.Cu" "F.Mask" "F.Paste")
			(net "P3V3_AUX")
		)
		(pad "10" smd rect
			(at 1.550162 -0.999998 90)
			(size 0.2794 0.9144)
			(layers "F.Cu" "F.Mask" "F.Paste")
			(net "P5V_AUX")
		)
		(pad "TH" smd rect
			(at 0 0 180)
			(size 1.7526 2.667)
			(layers "F.Cu" "F.Mask" "F.Paste")
			(net "GND")
		)
		(zone
			(layer "F.Cu")
			(hatch none 0.5)
			(connect_pads
				(clearance 0)
			)
			(min_thickness 0.25)
			(keepout
				(tracks not_allowed)
				(vias allowed)
				(pads allowed)
				(copperpour not_allowed)
				(footprints allowed)
			)
			(placement
				(enabled no)
				(sheetname "")
			)
			(fill
				(thermal_gap 0.5)
				(thermal_bridge_width 0.5)
				(island_removal_mode 0)
			)
			(polygon
				(pts
					(xy 37.685218 -54.40299) (xy 37.685218 -57.45099) (xy 35.653218 -57.45099) (xy 35.653218 -54.40299)
					(xy 37.583618 -54.40299) (xy 37.583618 -54.52999) (xy 35.729418 -54.52999) (xy 35.729418 -57.34939)
					(xy 37.609018 -57.34939) (xy 37.609018 -54.40299)
				)
			)
		)
	)
	(footprint ""
		(layer "F.Cu")
		(at 40.132 -70.485 90)
		(property "Reference" "U15"
			(at -1.1684 -1.70053 90)
			(unlocked yes)
			(layer "F.SilkS")
			(effects
				(font
					(size 0.7874 0.5842)
					(thickness 0.1524)
				)
			)
		)
		(property "Value" ""
			(at 0 0 90)
			(layer "F.Fab")
			(effects
				(font
					(size 1.27 1.27)
				)
			)
		)
		(duplicate_pad_numbers_are_jumpers no)
		(fp_line
			(start 1.7018 -1.1176)
			(end 0.254 -1.1176)
			(stroke
				(width 0.1524)
				(type default)
			)
			(layer "F.SilkS")
		)
		(fp_line
			(start 1.7018 -1.1176)
			(end 1.7018 1.1176)
			(stroke
				(width 0.1524)
				(type default)
			)
			(layer "F.SilkS")
		)
		(fp_line
			(start 0.254 -1.1176)
			(end 0 -0.7112)
			(stroke
				(width 0.1524)
				(type default)
			)
			(layer "F.SilkS")
		)
		(fp_line
			(start -0.254 -1.1176)
			(end -1.7018 -1.1176)
			(stroke
				(width 0.1524)
				(type default)
			)
			(layer "F.SilkS")
		)
		(fp_line
			(start 0 -0.7112)
			(end -0.254 -1.1176)
			(stroke
				(width 0.1524)
				(type default)
			)
			(layer "F.SilkS")
		)
		(fp_line
			(start 1.7018 1.1176)
			(end -1.7018 1.1176)
			(stroke
				(width 0.1524)
				(type default)
			)
			(layer "F.SilkS")
		)
		(fp_line
			(start -1.7018 1.1176)
			(end -1.7018 -1.1176)
			(stroke
				(width 0.1524)
				(type default)
			)
			(layer "F.SilkS")
		)
		(fp_poly
			(pts
				(xy -1.8161 -0.675386) (xy -2.4003 -0.446786) (xy -2.4003 -0.878586)
			)
			(stroke
				(width 0)
				(type default)
			)
			(fill yes)
			(layer "F.SilkS")
		)
		(fp_line
			(start 1.5494 -1.1176)
			(end 0.254 -1.1176)
			(stroke
				(width 0.1)
				(type default)
			)
			(layer "F.Fab")
		)
		(fp_line
			(start 1.5494 -1.1176)
			(end 1.5494 1.1176)
			(stroke
				(width 0.1)
				(type default)
			)
			(layer "F.Fab")
		)
		(fp_line
			(start 0.254 -1.1176)
			(end -0.254 -1.1176)
			(stroke
				(width 0.1)
				(type default)
			)
			(layer "F.Fab")
		)
		(fp_line
			(start -0.254 -1.1176)
			(end -1.5494 -1.1176)
			(stroke
				(width 0.1)
				(type default)
			)
			(layer "F.Fab")
		)
		(fp_line
			(start 1.5494 1.1176)
			(end -1.5494 1.1176)
			(stroke
				(width 0.1)
				(type default)
			)
			(layer "F.Fab")
		)
		(fp_line
			(start -1.5494 1.1176)
			(end -1.5494 -1.1176)
			(stroke
				(width 0.1)
				(type default)
			)
			(layer "F.Fab")
		)
		(fp_poly
			(pts
				(xy -1.8161 -0.675386) (xy -2.4003 -0.446786) (xy -2.4003 -0.878586)
			)
			(stroke
				(width 0)
				(type default)
			)
			(fill yes)
			(layer "F.Fab")
		)
		(pad "1" smd rect
			(at -0.962406 -0.649986)
			(size 0.3302 1.1684)
			(layers "F.Cu" "F.Mask" "F.Paste")
			(net "SYS_BMC_PWRBTN_R_N")
		)
		(pad "2" smd rect
			(at -0.962406 0)
			(size 0.3302 1.1684)
			(layers "F.Cu" "F.Mask" "F.Paste")
			(net "PWR_BTN_BMC_N")
		)
		(pad "3" smd rect
			(at -0.962406 0.649986)
			(size 0.3302 1.1684)
			(layers "F.Cu" "F.Mask" "F.Paste")
			(net "GND")
		)
		(pad "4" smd rect
			(at 0.962406 0.649986)
			(size 0.3302 1.1684)
			(layers "F.Cu" "F.Mask" "F.Paste")
			(net "SYS_PWRBTN_N")
		)
		(pad "5" smd rect
			(at 0.962406 -0.649986)
			(size 0.3302 1.1684)
			(layers "F.Cu" "F.Mask" "F.Paste")
			(net "P3V3_AUX")
		)
	)
	(footprint ""
		(layer "F.Cu")
		(at 19.685 -56.1848 90)
		(property "Reference" "R901"
			(at 0 0 90)
			(layer "F.SilkS")
			(hide yes)
			(effects
				(font
					(size 1.27 1.27)
				)
			)
		)
		(property "Value" ""
			(at 0 0 90)
			(layer "F.Fab")
			(effects
				(font
					(size 1.27 1.27)
				)
			)
		)
		(duplicate_pad_numbers_are_jumpers no)
		(fp_line
			(start 0.7874 -0.4064)
			(end 0.7874 0.4064)
			(stroke
				(width 0.1524)
				(type default)
			)
			(layer "F.SilkS")
		)
		(fp_line
			(start -0.7874 -0.4064)
			(end 0.7874 -0.4064)
			(stroke
				(width 0.1524)
				(type default)
			)
			(layer "F.SilkS")
		)
		(fp_line
			(start 0.7874 0.4064)
			(end -0.7874 0.4064)
			(stroke
				(width 0.1524)
				(type default)
			)
			(layer "F.SilkS")
		)
		(fp_line
			(start -0.7874 0.4064)
			(end -0.7874 -0.4064)
			(stroke
				(width 0.1524)
				(type default)
			)
			(layer "F.SilkS")
		)
		(fp_line
			(start -0.12065 -0.305054)
			(end -0.12065 -0.2794)
			(stroke
				(width 0.1)
				(type default)
			)
			(layer "F.Fab")
		)
		(fp_line
			(start -0.67945 -0.305054)
			(end -0.12065 -0.305054)
			(stroke
				(width 0.1)
				(type default)
			)
			(layer "F.Fab")
		)
		(fp_line
			(start 0.67945 -0.3048)
			(end 0.67945 0.3048)
			(stroke
				(width 0.1)
				(type default)
			)
			(layer "F.Fab")
		)
		(fp_line
			(start 0.12065 -0.3048)
			(end 0.67945 -0.3048)
			(stroke
				(width 0.1)
				(type default)
			)
			(layer "F.Fab")
		)
		(fp_line
			(start 0.12065 -0.2794)
			(end 0.12065 -0.3048)
			(stroke
				(width 0.1)
				(type default)
			)
			(layer "F.Fab")
		)
		(fp_line
			(start -0.12065 -0.2794)
			(end 0.12065 -0.2794)
			(stroke
				(width 0.1)
				(type default)
			)
			(layer "F.Fab")
		)
		(fp_line
			(start 0.120396 0.2794)
			(end -0.12065 0.2794)
			(stroke
				(width 0.1)
				(type default)
			)
			(layer "F.Fab")
		)
		(fp_line
			(start -0.12065 0.2794)
			(end -0.12065 0.3048)
			(stroke
				(width 0.1)
				(type default)
			)
			(layer "F.Fab")
		)
		(fp_line
			(start 0.67945 0.3048)
			(end 0.120396 0.3048)
			(stroke
				(width 0.1)
				(type default)
			)
			(layer "F.Fab")
		)
		(fp_line
			(start 0.120396 0.3048)
			(end 0.120396 0.2794)
			(stroke
				(width 0.1)
				(type default)
			)
			(layer "F.Fab")
		)
		(fp_line
			(start -0.12065 0.3048)
			(end -0.67945 0.3048)
			(stroke
				(width 0.1)
				(type default)
			)
			(layer "F.Fab")
		)
		(fp_line
			(start -0.67945 0.3048)
			(end -0.67945 -0.305054)
			(stroke
				(width 0.1)
				(type default)
			)
			(layer "F.Fab")
		)
		(pad "1" smd circle
			(at -0.40005 0 90)
			(size 0 0)
			(layers "F.Cu" "F.Mask" "F.Paste")
			(net "UART_6_BMC_RXD")
		)
		(pad "2" smd circle
			(at 0.40005 0 90)
			(size 0 0)
			(layers "F.Cu" "F.Mask" "F.Paste")
			(net "UART_6_BMC_RXD_R")
		)
	)
	(footprint ""
		(layer "F.Cu")
		(at 70.619112 -35.258756 90)
		(property "Reference" "C114"
			(at 0 0 90)
			(layer "F.SilkS")
			(hide yes)
			(effects
				(font
					(size 1.27 1.27)
				)
			)
		)
		(property "Value" ""
			(at 0 0 90)
			(layer "F.Fab")
			(effects
				(font
					(size 1.27 1.27)
				)
			)
		)
		(duplicate_pad_numbers_are_jumpers no)
		(fp_line
			(start 0.7874 -0.4064)
			(end 0.7874 0.4064)
			(stroke
				(width 0.1524)
				(type default)
			)
			(layer "F.SilkS")
		)
		(fp_line
			(start -0.7874 -0.4064)
			(end 0.7874 -0.4064)
			(stroke
				(width 0.1524)
				(type default)
			)
			(layer "F.SilkS")
		)
		(fp_line
			(start 0.7874 0.4064)
			(end -0.7874 0.4064)
			(stroke
				(width 0.1524)
				(type default)
			)
			(layer "F.SilkS")
		)
		(fp_line
			(start -0.7874 0.4064)
			(end -0.7874 -0.4064)
			(stroke
				(width 0.1524)
				(type default)
			)
			(layer "F.SilkS")
		)
		(fp_line
			(start -0.12065 -0.305054)
			(end -0.12065 -0.2794)
			(stroke
				(width 0.1)
				(type default)
			)
			(layer "F.Fab")
		)
		(fp_line
			(start -0.67945 -0.305054)
			(end -0.12065 -0.305054)
			(stroke
				(width 0.1)
				(type default)
			)
			(layer "F.Fab")
		)
		(fp_line
			(start 0.67945 -0.3048)
			(end 0.67945 0.3048)
			(stroke
				(width 0.1)
				(type default)
			)
			(layer "F.Fab")
		)
		(fp_line
			(start 0.12065 -0.3048)
			(end 0.67945 -0.3048)
			(stroke
				(width 0.1)
				(type default)
			)
			(layer "F.Fab")
		)
		(fp_line
			(start 0.12065 -0.2794)
			(end 0.12065 -0.3048)
			(stroke
				(width 0.1)
				(type default)
			)
			(layer "F.Fab")
		)
		(fp_line
			(start -0.12065 -0.2794)
			(end 0.12065 -0.2794)
			(stroke
				(width 0.1)
				(type default)
			)
			(layer "F.Fab")
		)
		(fp_line
			(start 0.120396 0.2794)
			(end -0.12065 0.2794)
			(stroke
				(width 0.1)
				(type default)
			)
			(layer "F.Fab")
		)
		(fp_line
			(start -0.12065 0.2794)
			(end -0.12065 0.3048)
			(stroke
				(width 0.1)
				(type default)
			)
			(layer "F.Fab")
		)
		(fp_line
			(start 0.67945 0.3048)
			(end 0.120396 0.3048)
			(stroke
				(width 0.1)
				(type default)
			)
			(layer "F.Fab")
		)
		(fp_line
			(start 0.120396 0.3048)
			(end 0.120396 0.2794)
			(stroke
				(width 0.1)
				(type default)
			)
			(layer "F.Fab")
		)
		(fp_line
			(start -0.12065 0.3048)
			(end -0.67945 0.3048)
			(stroke
				(width 0.1)
				(type default)
			)
			(layer "F.Fab")
		)
		(fp_line
			(start -0.67945 0.3048)
			(end -0.67945 -0.305054)
			(stroke
				(width 0.1)
				(type default)
			)
			(layer "F.Fab")
		)
		(pad "1" smd circle
			(at -0.40005 0 90)
			(size 0 0)
			(layers "F.Cu" "F.Mask" "F.Paste")
			(net "P1V8_AUX")
		)
		(pad "2" smd circle
			(at 0.40005 0 90)
			(size 0 0)
			(layers "F.Cu" "F.Mask" "F.Paste")
			(net "GND")
		)
	)
	(footprint ""
		(layer "F.Cu")
		(at 29.27604 -68.504054 90)
		(property "Reference" "R662"
			(at 0 0 90)
			(layer "F.SilkS")
			(hide yes)
			(effects
				(font
					(size 1.27 1.27)
				)
			)
		)
		(property "Value" ""
			(at 0 0 90)
			(layer "F.Fab")
			(effects
				(font
					(size 1.27 1.27)
				)
			)
		)
		(duplicate_pad_numbers_are_jumpers no)
		(fp_line
			(start 0.7874 -0.4064)
			(end 0.7874 0.4064)
			(stroke
				(width 0.1524)
				(type default)
			)
			(layer "F.SilkS")
		)
		(fp_line
			(start -0.7874 -0.4064)
			(end 0.7874 -0.4064)
			(stroke
				(width 0.1524)
				(type default)
			)
			(layer "F.SilkS")
		)
		(fp_line
			(start 0.7874 0.4064)
			(end -0.7874 0.4064)
			(stroke
				(width 0.1524)
				(type default)
			)
			(layer "F.SilkS")
		)
		(fp_line
			(start -0.7874 0.4064)
			(end -0.7874 -0.4064)
			(stroke
				(width 0.1524)
				(type default)
			)
			(layer "F.SilkS")
		)
		(fp_line
			(start -0.12065 -0.305054)
			(end -0.12065 -0.2794)
			(stroke
				(width 0.1)
				(type default)
			)
			(layer "F.Fab")
		)
		(fp_line
			(start -0.67945 -0.305054)
			(end -0.12065 -0.305054)
			(stroke
				(width 0.1)
				(type default)
			)
			(layer "F.Fab")
		)
		(fp_line
			(start 0.67945 -0.3048)
			(end 0.67945 0.3048)
			(stroke
				(width 0.1)
				(type default)
			)
			(layer "F.Fab")
		)
		(fp_line
			(start 0.12065 -0.3048)
			(end 0.67945 -0.3048)
			(stroke
				(width 0.1)
				(type default)
			)
			(layer "F.Fab")
		)
		(fp_line
			(start 0.12065 -0.2794)
			(end 0.12065 -0.3048)
			(stroke
				(width 0.1)
				(type default)
			)
			(layer "F.Fab")
		)
		(fp_line
			(start -0.12065 -0.2794)
			(end 0.12065 -0.2794)
			(stroke
				(width 0.1)
				(type default)
			)
			(layer "F.Fab")
		)
		(fp_line
			(start 0.120396 0.2794)
			(end -0.12065 0.2794)
			(stroke
				(width 0.1)
				(type default)
			)
			(layer "F.Fab")
		)
		(fp_line
			(start -0.12065 0.2794)
			(end -0.12065 0.3048)
			(stroke
				(width 0.1)
				(type default)
			)
			(layer "F.Fab")
		)
		(fp_line
			(start 0.67945 0.3048)
			(end 0.120396 0.3048)
			(stroke
				(width 0.1)
				(type default)
			)
			(layer "F.Fab")
		)
		(fp_line
			(start 0.120396 0.3048)
			(end 0.120396 0.2794)
			(stroke
				(width 0.1)
				(type default)
			)
			(layer "F.Fab")
		)
		(fp_line
			(start -0.12065 0.3048)
			(end -0.67945 0.3048)
			(stroke
				(width 0.1)
				(type default)
			)
			(layer "F.Fab")
		)
		(fp_line
			(start -0.67945 0.3048)
			(end -0.67945 -0.305054)
			(stroke
				(width 0.1)
				(type default)
			)
			(layer "F.Fab")
		)
		(pad "1" smd circle
			(at -0.40005 0 90)
			(size 0 0)
			(layers "F.Cu" "F.Mask" "F.Paste")
			(net "P3V3_AUX")
		)
		(pad "2" smd circle
			(at 0.40005 0 90)
			(size 0 0)
			(layers "F.Cu" "F.Mask" "F.Paste")
			(net "EMMC_DT7_R")
		)
	)
	(footprint ""
		(layer "F.Cu")
		(at 84.201 -93.345)
		(property "Reference" "R110"
			(at 0 0 0)
			(layer "F.SilkS")
			(hide yes)
			(effects
				(font
					(size 1.27 1.27)
				)
			)
		)
		(property "Value" ""
			(at 0 0 0)
			(layer "F.Fab")
			(effects
				(font
					(size 1.27 1.27)
				)
			)
		)
		(duplicate_pad_numbers_are_jumpers no)
		(fp_line
			(start -0.7874 -0.4064)
			(end 0.7874 -0.4064)
			(stroke
				(width 0.1524)
				(type default)
			)
			(layer "F.SilkS")
		)
		(fp_line
			(start -0.7874 0.4064)
			(end -0.7874 -0.4064)
			(stroke
				(width 0.1524)
				(type default)
			)
			(layer "F.SilkS")
		)
		(fp_line
			(start 0.7874 -0.4064)
			(end 0.7874 0.4064)
			(stroke
				(width 0.1524)
				(type default)
			)
			(layer "F.SilkS")
		)
		(fp_line
			(start 0.7874 0.4064)
			(end -0.7874 0.4064)
			(stroke
				(width 0.1524)
				(type default)
			)
			(layer "F.SilkS")
		)
		(fp_line
			(start -0.67945 -0.305054)
			(end -0.12065 -0.305054)
			(stroke
				(width 0.1)
				(type default)
			)
			(layer "F.Fab")
		)
		(fp_line
			(start -0.67945 0.3048)
			(end -0.67945 -0.305054)
			(stroke
				(width 0.1)
				(type default)
			)
			(layer "F.Fab")
		)
		(fp_line
			(start -0.12065 -0.305054)
			(end -0.12065 -0.2794)
			(stroke
				(width 0.1)
				(type default)
			)
			(layer "F.Fab")
		)
		(fp_line
			(start -0.12065 -0.2794)
			(end 0.12065 -0.2794)
			(stroke
				(width 0.1)
				(type default)
			)
			(layer "F.Fab")
		)
		(fp_line
			(start -0.12065 0.2794)
			(end -0.12065 0.3048)
			(stroke
				(width 0.1)
				(type default)
			)
			(layer "F.Fab")
		)
		(fp_line
			(start -0.12065 0.3048)
			(end -0.67945 0.3048)
			(stroke
				(width 0.1)
				(type default)
			)
			(layer "F.Fab")
		)
		(fp_line
			(start 0.120396 0.2794)
			(end -0.12065 0.2794)
			(stroke
				(width 0.1)
				(type default)
			)
			(layer "F.Fab")
		)
		(fp_line
			(start 0.120396 0.3048)
			(end 0.120396 0.2794)
			(stroke
				(width 0.1)
				(type default)
			)
			(layer "F.Fab")
		)
		(fp_line
			(start 0.12065 -0.3048)
			(end 0.67945 -0.3048)
			(stroke
				(width 0.1)
				(type default)
			)
			(layer "F.Fab")
		)
		(fp_line
			(start 0.12065 -0.2794)
			(end 0.12065 -0.3048)
			(stroke
				(width 0.1)
				(type default)
			)
			(layer "F.Fab")
		)
		(fp_line
			(start 0.67945 -0.3048)
			(end 0.67945 0.3048)
			(stroke
				(width 0.1)
				(type default)
			)
			(layer "F.Fab")
		)
		(fp_line
			(start 0.67945 0.3048)
			(end 0.120396 0.3048)
			(stroke
				(width 0.1)
				(type default)
			)
			(layer "F.Fab")
		)
		(pad "1" smd circle
			(at -0.40005 0)
			(size 0 0)
			(layers "F.Cu" "F.Mask" "F.Paste")
			(net "RST_BMC_EXTRST_R3_N")
		)
		(pad "2" smd circle
			(at 0.40005 0)
			(size 0 0)
			(layers "F.Cu" "F.Mask" "F.Paste")
			(net "RST_BMC_EXTRST_R2_N")
		)
	)
	(footprint ""
		(layer "F.Cu")
		(at 14.1732 -83.693 90)
		(property "Reference" "R434"
			(at 0 0 90)
			(layer "F.SilkS")
			(hide yes)
			(effects
				(font
					(size 1.27 1.27)
				)
			)
		)
		(property "Value" ""
			(at 0 0 90)
			(layer "F.Fab")
			(effects
				(font
					(size 1.27 1.27)
				)
			)
		)
		(duplicate_pad_numbers_are_jumpers no)
		(fp_line
			(start 0.7874 -0.4064)
			(end 0.7874 0.4064)
			(stroke
				(width 0.1524)
				(type default)
			)
			(layer "F.SilkS")
		)
		(fp_line
			(start -0.7874 -0.4064)
			(end 0.7874 -0.4064)
			(stroke
				(width 0.1524)
				(type default)
			)
			(layer "F.SilkS")
		)
		(fp_line
			(start 0.7874 0.4064)
			(end -0.7874 0.4064)
			(stroke
				(width 0.1524)
				(type default)
			)
			(layer "F.SilkS")
		)
		(fp_line
			(start -0.7874 0.4064)
			(end -0.7874 -0.4064)
			(stroke
				(width 0.1524)
				(type default)
			)
			(layer "F.SilkS")
		)
		(fp_line
			(start -0.12065 -0.305054)
			(end -0.12065 -0.2794)
			(stroke
				(width 0.1)
				(type default)
			)
			(layer "F.Fab")
		)
		(fp_line
			(start -0.67945 -0.305054)
			(end -0.12065 -0.305054)
			(stroke
				(width 0.1)
				(type default)
			)
			(layer "F.Fab")
		)
		(fp_line
			(start 0.67945 -0.3048)
			(end 0.67945 0.3048)
			(stroke
				(width 0.1)
				(type default)
			)
			(layer "F.Fab")
		)
		(fp_line
			(start 0.12065 -0.3048)
			(end 0.67945 -0.3048)
			(stroke
				(width 0.1)
				(type default)
			)
			(layer "F.Fab")
		)
		(fp_line
			(start 0.12065 -0.2794)
			(end 0.12065 -0.3048)
			(stroke
				(width 0.1)
				(type default)
			)
			(layer "F.Fab")
		)
		(fp_line
			(start -0.12065 -0.2794)
			(end 0.12065 -0.2794)
			(stroke
				(width 0.1)
				(type default)
			)
			(layer "F.Fab")
		)
		(fp_line
			(start 0.120396 0.2794)
			(end -0.12065 0.2794)
			(stroke
				(width 0.1)
				(type default)
			)
			(layer "F.Fab")
		)
		(fp_line
			(start -0.12065 0.2794)
			(end -0.12065 0.3048)
			(stroke
				(width 0.1)
				(type default)
			)
			(layer "F.Fab")
		)
		(fp_line
			(start 0.67945 0.3048)
			(end 0.120396 0.3048)
			(stroke
				(width 0.1)
				(type default)
			)
			(layer "F.Fab")
		)
		(fp_line
			(start 0.120396 0.3048)
			(end 0.120396 0.2794)
			(stroke
				(width 0.1)
				(type default)
			)
			(layer "F.Fab")
		)
		(fp_line
			(start -0.12065 0.3048)
			(end -0.67945 0.3048)
			(stroke
				(width 0.1)
				(type default)
			)
			(layer "F.Fab")
		)
		(fp_line
			(start -0.67945 0.3048)
			(end -0.67945 -0.305054)
			(stroke
				(width 0.1)
				(type default)
			)
			(layer "F.Fab")
		)
		(pad "1" smd circle
			(at -0.40005 0 90)
			(size 0 0)
			(layers "F.Cu" "F.Mask" "F.Paste")
			(net "SGPIO_CLK_PLD_0")
		)
		(pad "2" smd circle
			(at 0.40005 0 90)
			(size 0 0)
			(layers "F.Cu" "F.Mask" "F.Paste")
			(net "SGPIO_CLK_0")
		)
	)
	(footprint ""
		(layer "F.Cu")
		(at 10.3632 -107.95 -90)
		(property "Reference" "R124"
			(at 0 0 270)
			(layer "F.SilkS")
			(hide yes)
			(effects
				(font
					(size 1.27 1.27)
				)
			)
		)
		(property "Value" ""
			(at 0 0 270)
			(layer "F.Fab")
			(effects
				(font
					(size 1.27 1.27)
				)
			)
		)
		(duplicate_pad_numbers_are_jumpers no)
		(fp_line
			(start -0.7874 0.4064)
			(end -0.7874 -0.4064)
			(stroke
				(width 0.1524)
				(type default)
			)
			(layer "F.SilkS")
		)
		(fp_line
			(start 0.7874 0.4064)
			(end -0.7874 0.4064)
			(stroke
				(width 0.1524)
				(type default)
			)
			(layer "F.SilkS")
		)
		(fp_line
			(start -0.7874 -0.4064)
			(end 0.7874 -0.4064)
			(stroke
				(width 0.1524)
				(type default)
			)
			(layer "F.SilkS")
		)
		(fp_line
			(start 0.7874 -0.4064)
			(end 0.7874 0.4064)
			(stroke
				(width 0.1524)
				(type default)
			)
			(layer "F.SilkS")
		)
		(fp_line
			(start -0.67945 0.3048)
			(end -0.67945 -0.305054)
			(stroke
				(width 0.1)
				(type default)
			)
			(layer "F.Fab")
		)
		(fp_line
			(start -0.12065 0.3048)
			(end -0.67945 0.3048)
			(stroke
				(width 0.1)
				(type default)
			)
			(layer "F.Fab")
		)
		(fp_line
			(start 0.120396 0.3048)
			(end 0.120396 0.2794)
			(stroke
				(width 0.1)
				(type default)
			)
			(layer "F.Fab")
		)
		(fp_line
			(start 0.67945 0.3048)
			(end 0.120396 0.3048)
			(stroke
				(width 0.1)
				(type default)
			)
			(layer "F.Fab")
		)
		(fp_line
			(start -0.12065 0.2794)
			(end -0.12065 0.3048)
			(stroke
				(width 0.1)
				(type default)
			)
			(layer "F.Fab")
		)
		(fp_line
			(start 0.120396 0.2794)
			(end -0.12065 0.2794)
			(stroke
				(width 0.1)
				(type default)
			)
			(layer "F.Fab")
		)
		(fp_line
			(start -0.12065 -0.2794)
			(end 0.12065 -0.2794)
			(stroke
				(width 0.1)
				(type default)
			)
			(layer "F.Fab")
		)
		(fp_line
			(start 0.12065 -0.2794)
			(end 0.12065 -0.3048)
			(stroke
				(width 0.1)
				(type default)
			)
			(layer "F.Fab")
		)
		(fp_line
			(start 0.12065 -0.3048)
			(end 0.67945 -0.3048)
			(stroke
				(width 0.1)
				(type default)
			)
			(layer "F.Fab")
		)
		(fp_line
			(start 0.67945 -0.3048)
			(end 0.67945 0.3048)
			(stroke
				(width 0.1)
				(type default)
			)
			(layer "F.Fab")
		)
		(fp_line
			(start -0.67945 -0.305054)
			(end -0.12065 -0.305054)
			(stroke
				(width 0.1)
				(type default)
			)
			(layer "F.Fab")
		)
		(fp_line
			(start -0.12065 -0.305054)
			(end -0.12065 -0.2794)
			(stroke
				(width 0.1)
				(type default)
			)
			(layer "F.Fab")
		)
		(pad "1" smd circle
			(at -0.40005 0 270)
			(size 0 0)
			(layers "F.Cu" "F.Mask" "F.Paste")
			(net "P3V3_AUX")
		)
		(pad "2" smd circle
			(at 0.40005 0 270)
			(size 0 0)
			(layers "F.Cu" "F.Mask" "F.Paste")
			(net "RST_BMC_SRST_BUF_R_N")
		)
	)
	(footprint ""
		(layer "F.Cu")
		(at 68.072 -108.0262 90)
		(property "Reference" "R823"
			(at 0 0 90)
			(layer "F.SilkS")
			(hide yes)
			(effects
				(font
					(size 1.27 1.27)
				)
			)
		)
		(property "Value" ""
			(at 0 0 90)
			(layer "F.Fab")
			(effects
				(font
					(size 1.27 1.27)
				)
			)
		)
		(duplicate_pad_numbers_are_jumpers no)
		(fp_line
			(start 0.7874 -0.4064)
			(end 0.7874 0.4064)
			(stroke
				(width 0.1524)
				(type default)
			)
			(layer "F.SilkS")
		)
		(fp_line
			(start -0.7874 -0.4064)
			(end 0.7874 -0.4064)
			(stroke
				(width 0.1524)
				(type default)
			)
			(layer "F.SilkS")
		)
		(fp_line
			(start 0.7874 0.4064)
			(end -0.7874 0.4064)
			(stroke
				(width 0.1524)
				(type default)
			)
			(layer "F.SilkS")
		)
		(fp_line
			(start -0.7874 0.4064)
			(end -0.7874 -0.4064)
			(stroke
				(width 0.1524)
				(type default)
			)
			(layer "F.SilkS")
		)
		(fp_line
			(start -0.12065 -0.305054)
			(end -0.12065 -0.2794)
			(stroke
				(width 0.1)
				(type default)
			)
			(layer "F.Fab")
		)
		(fp_line
			(start -0.67945 -0.305054)
			(end -0.12065 -0.305054)
			(stroke
				(width 0.1)
				(type default)
			)
			(layer "F.Fab")
		)
		(fp_line
			(start 0.67945 -0.3048)
			(end 0.67945 0.3048)
			(stroke
				(width 0.1)
				(type default)
			)
			(layer "F.Fab")
		)
		(fp_line
			(start 0.12065 -0.3048)
			(end 0.67945 -0.3048)
			(stroke
				(width 0.1)
				(type default)
			)
			(layer "F.Fab")
		)
		(fp_line
			(start 0.12065 -0.2794)
			(end 0.12065 -0.3048)
			(stroke
				(width 0.1)
				(type default)
			)
			(layer "F.Fab")
		)
		(fp_line
			(start -0.12065 -0.2794)
			(end 0.12065 -0.2794)
			(stroke
				(width 0.1)
				(type default)
			)
			(layer "F.Fab")
		)
		(fp_line
			(start 0.120396 0.2794)
			(end -0.12065 0.2794)
			(stroke
				(width 0.1)
				(type default)
			)
			(layer "F.Fab")
		)
		(fp_line
			(start -0.12065 0.2794)
			(end -0.12065 0.3048)
			(stroke
				(width 0.1)
				(type default)
			)
			(layer "F.Fab")
		)
		(fp_line
			(start 0.67945 0.3048)
			(end 0.120396 0.3048)
			(stroke
				(width 0.1)
				(type default)
			)
			(layer "F.Fab")
		)
		(fp_line
			(start 0.120396 0.3048)
			(end 0.120396 0.2794)
			(stroke
				(width 0.1)
				(type default)
			)
			(layer "F.Fab")
		)
		(fp_line
			(start -0.12065 0.3048)
			(end -0.67945 0.3048)
			(stroke
				(width 0.1)
				(type default)
			)
			(layer "F.Fab")
		)
		(fp_line
			(start -0.67945 0.3048)
			(end -0.67945 -0.305054)
			(stroke
				(width 0.1)
				(type default)
			)
			(layer "F.Fab")
		)
		(pad "1" smd circle
			(at -0.40005 0 90)
			(size 0 0)
			(layers "F.Cu" "F.Mask" "F.Paste")
			(net "GND")
		)
		(pad "2" smd circle
			(at 0.40005 0 90)
			(size 0 0)
			(layers "F.Cu" "F.Mask" "F.Paste")
			(net "FM_VIRTUAL_RESEAT")
		)
	)
	(footprint ""
		(layer "F.Cu")
		(at 53.213 -69.723 90)
		(property "Reference" "R682"
			(at 0 0 90)
			(layer "F.SilkS")
			(hide yes)
			(effects
				(font
					(size 1.27 1.27)
				)
			)
		)
		(property "Value" ""
			(at 0 0 90)
			(layer "F.Fab")
			(effects
				(font
					(size 1.27 1.27)
				)
			)
		)
		(duplicate_pad_numbers_are_jumpers no)
		(fp_line
			(start 0.7874 -0.4064)
			(end 0.7874 0.4064)
			(stroke
				(width 0.1524)
				(type default)
			)
			(layer "F.SilkS")
		)
		(fp_line
			(start -0.7874 -0.4064)
			(end 0.7874 -0.4064)
			(stroke
				(width 0.1524)
				(type default)
			)
			(layer "F.SilkS")
		)
		(fp_line
			(start 0.7874 0.4064)
			(end -0.7874 0.4064)
			(stroke
				(width 0.1524)
				(type default)
			)
			(layer "F.SilkS")
		)
		(fp_line
			(start -0.7874 0.4064)
			(end -0.7874 -0.4064)
			(stroke
				(width 0.1524)
				(type default)
			)
			(layer "F.SilkS")
		)
		(fp_line
			(start -0.12065 -0.305054)
			(end -0.12065 -0.2794)
			(stroke
				(width 0.1)
				(type default)
			)
			(layer "F.Fab")
		)
		(fp_line
			(start -0.67945 -0.305054)
			(end -0.12065 -0.305054)
			(stroke
				(width 0.1)
				(type default)
			)
			(layer "F.Fab")
		)
		(fp_line
			(start 0.67945 -0.3048)
			(end 0.67945 0.3048)
			(stroke
				(width 0.1)
				(type default)
			)
			(layer "F.Fab")
		)
		(fp_line
			(start 0.12065 -0.3048)
			(end 0.67945 -0.3048)
			(stroke
				(width 0.1)
				(type default)
			)
			(layer "F.Fab")
		)
		(fp_line
			(start 0.12065 -0.2794)
			(end 0.12065 -0.3048)
			(stroke
				(width 0.1)
				(type default)
			)
			(layer "F.Fab")
		)
		(fp_line
			(start -0.12065 -0.2794)
			(end 0.12065 -0.2794)
			(stroke
				(width 0.1)
				(type default)
			)
			(layer "F.Fab")
		)
		(fp_line
			(start 0.120396 0.2794)
			(end -0.12065 0.2794)
			(stroke
				(width 0.1)
				(type default)
			)
			(layer "F.Fab")
		)
		(fp_line
			(start -0.12065 0.2794)
			(end -0.12065 0.3048)
			(stroke
				(width 0.1)
				(type default)
			)
			(layer "F.Fab")
		)
		(fp_line
			(start 0.67945 0.3048)
			(end 0.120396 0.3048)
			(stroke
				(width 0.1)
				(type default)
			)
			(layer "F.Fab")
		)
		(fp_line
			(start 0.120396 0.3048)
			(end 0.120396 0.2794)
			(stroke
				(width 0.1)
				(type default)
			)
			(layer "F.Fab")
		)
		(fp_line
			(start -0.12065 0.3048)
			(end -0.67945 0.3048)
			(stroke
				(width 0.1)
				(type default)
			)
			(layer "F.Fab")
		)
		(fp_line
			(start -0.67945 0.3048)
			(end -0.67945 -0.305054)
			(stroke
				(width 0.1)
				(type default)
			)
			(layer "F.Fab")
		)
		(pad "1" smd circle
			(at -0.40005 0 90)
			(size 0 0)
			(layers "F.Cu" "F.Mask" "F.Paste")
			(net "SPI_BMC_IO3_R")
		)
		(pad "2" smd circle
			(at 0.40005 0 90)
			(size 0 0)
			(layers "F.Cu" "F.Mask" "F.Paste")
			(net "QSPI_2_PLD_IO3")
		)
	)
	(footprint ""
		(layer "F.Cu")
		(at 81.755996 -76.258928 180)
		(property "Reference" "PC252"
			(at 0 0 180)
			(layer "F.SilkS")
			(hide yes)
			(effects
				(font
					(size 1.27 1.27)
				)
			)
		)
		(property "Value" ""
			(at 0 0 180)
			(layer "F.Fab")
			(effects
				(font
					(size 1.27 1.27)
				)
			)
		)
		(duplicate_pad_numbers_are_jumpers no)
		(fp_line
			(start 1.651 0.8382)
			(end -1.651 0.8382)
			(stroke
				(width 0.1524)
				(type default)
			)
			(layer "F.SilkS")
		)
		(fp_line
			(start 1.651 -0.8382)
			(end 1.651 0.8382)
			(stroke
				(width 0.1524)
				(type default)
			)
			(layer "F.SilkS")
		)
		(fp_line
			(start 0 0.8382)
			(end 0 -0.8382)
			(stroke
				(width 0.1524)
				(type default)
			)
			(layer "F.SilkS")
		)
		(fp_line
			(start -1.651 0.8382)
			(end -1.651 -0.8382)
			(stroke
				(width 0.1524)
				(type default)
			)
			(layer "F.SilkS")
		)
		(fp_line
			(start -1.651 -0.8382)
			(end 1.651 -0.8382)
			(stroke
				(width 0.1524)
				(type default)
			)
			(layer "F.SilkS")
		)
		(fp_line
			(start 1.55956 0.7366)
			(end 1.55956 -0.7366)
			(stroke
				(width 0.1)
				(type default)
			)
			(layer "F.Fab")
		)
		(fp_line
			(start 1.55956 -0.7366)
			(end 1.524 -0.7366)
			(stroke
				(width 0.1)
				(type default)
			)
			(layer "F.Fab")
		)
		(fp_line
			(start 1.524 0.7366)
			(end 1.55956 0.7366)
			(stroke
				(width 0.1)
				(type default)
			)
			(layer "F.Fab")
		)
		(fp_line
			(start 1.524 -0.7366)
			(end -1.524 -0.7366)
			(stroke
				(width 0.1)
				(type default)
			)
			(layer "F.Fab")
		)
		(fp_line
			(start -1.524 0.7366)
			(end 1.524 0.7366)
			(stroke
				(width 0.1)
				(type default)
			)
			(layer "F.Fab")
		)
		(fp_line
			(start -1.524 -0.7366)
			(end -1.55956 -0.7366)
			(stroke
				(width 0.1)
				(type default)
			)
			(layer "F.Fab")
		)
		(fp_line
			(start -1.55956 0.7366)
			(end -1.524 0.7366)
			(stroke
				(width 0.1)
				(type default)
			)
			(layer "F.Fab")
		)
		(fp_line
			(start -1.55956 -0.7366)
			(end -1.55956 0.7366)
			(stroke
				(width 0.1)
				(type default)
			)
			(layer "F.Fab")
		)
		(pad "1" smd rect
			(at -0.94996 0)
			(size 1.1176 1.3716)
			(layers "F.Cu" "F.Mask" "F.Paste")
			(net "SW_P1V2_AUX_FLT")
		)
		(pad "2" smd rect
			(at 0.94996 0)
			(size 1.1176 1.3716)
			(layers "F.Cu" "F.Mask" "F.Paste")
			(net "GND")
		)
	)
	(footprint ""
		(layer "F.Cu")
		(at 59.7154 -64.0588 90)
		(property "Reference" "R724"
			(at 0 0 90)
			(layer "F.SilkS")
			(hide yes)
			(effects
				(font
					(size 1.27 1.27)
				)
			)
		)
		(property "Value" ""
			(at 0 0 90)
			(layer "F.Fab")
			(effects
				(font
					(size 1.27 1.27)
				)
			)
		)
		(duplicate_pad_numbers_are_jumpers no)
		(fp_line
			(start 0.7874 -0.4064)
			(end 0.7874 0.4064)
			(stroke
				(width 0.1524)
				(type default)
			)
			(layer "F.SilkS")
		)
		(fp_line
			(start -0.7874 -0.4064)
			(end 0.7874 -0.4064)
			(stroke
				(width 0.1524)
				(type default)
			)
			(layer "F.SilkS")
		)
		(fp_line
			(start 0.7874 0.4064)
			(end -0.7874 0.4064)
			(stroke
				(width 0.1524)
				(type default)
			)
			(layer "F.SilkS")
		)
		(fp_line
			(start -0.7874 0.4064)
			(end -0.7874 -0.4064)
			(stroke
				(width 0.1524)
				(type default)
			)
			(layer "F.SilkS")
		)
		(fp_line
			(start -0.12065 -0.305054)
			(end -0.12065 -0.2794)
			(stroke
				(width 0.1)
				(type default)
			)
			(layer "F.Fab")
		)
		(fp_line
			(start -0.67945 -0.305054)
			(end -0.12065 -0.305054)
			(stroke
				(width 0.1)
				(type default)
			)
			(layer "F.Fab")
		)
		(fp_line
			(start 0.67945 -0.3048)
			(end 0.67945 0.3048)
			(stroke
				(width 0.1)
				(type default)
			)
			(layer "F.Fab")
		)
		(fp_line
			(start 0.12065 -0.3048)
			(end 0.67945 -0.3048)
			(stroke
				(width 0.1)
				(type default)
			)
			(layer "F.Fab")
		)
		(fp_line
			(start 0.12065 -0.2794)
			(end 0.12065 -0.3048)
			(stroke
				(width 0.1)
				(type default)
			)
			(layer "F.Fab")
		)
		(fp_line
			(start -0.12065 -0.2794)
			(end 0.12065 -0.2794)
			(stroke
				(width 0.1)
				(type default)
			)
			(layer "F.Fab")
		)
		(fp_line
			(start 0.120396 0.2794)
			(end -0.12065 0.2794)
			(stroke
				(width 0.1)
				(type default)
			)
			(layer "F.Fab")
		)
		(fp_line
			(start -0.12065 0.2794)
			(end -0.12065 0.3048)
			(stroke
				(width 0.1)
				(type default)
			)
			(layer "F.Fab")
		)
		(fp_line
			(start 0.67945 0.3048)
			(end 0.120396 0.3048)
			(stroke
				(width 0.1)
				(type default)
			)
			(layer "F.Fab")
		)
		(fp_line
			(start 0.120396 0.3048)
			(end 0.120396 0.2794)
			(stroke
				(width 0.1)
				(type default)
			)
			(layer "F.Fab")
		)
		(fp_line
			(start -0.12065 0.3048)
			(end -0.67945 0.3048)
			(stroke
				(width 0.1)
				(type default)
			)
			(layer "F.Fab")
		)
		(fp_line
			(start -0.67945 0.3048)
			(end -0.67945 -0.305054)
			(stroke
				(width 0.1)
				(type default)
			)
			(layer "F.Fab")
		)
		(pad "1" smd circle
			(at -0.40005 0 90)
			(size 0 0)
			(layers "F.Cu" "F.Mask" "F.Paste")
			(net "SPI_BMC_BIOS_ROM_IO2")
		)
		(pad "2" smd circle
			(at 0.40005 0 90)
			(size 0 0)
			(layers "F.Cu" "F.Mask" "F.Paste")
			(net "SPI_BMC_BIOS_ROM_R_IO2")
		)
	)
	(footprint ""
		(layer "F.Cu")
		(at 71.013828 -62.776608 -90)
		(property "Reference" "C61"
			(at 0 0 270)
			(layer "F.SilkS")
			(hide yes)
			(effects
				(font
					(size 1.27 1.27)
				)
			)
		)
		(property "Value" ""
			(at 0 0 270)
			(layer "F.Fab")
			(effects
				(font
					(size 1.27 1.27)
				)
			)
		)
		(duplicate_pad_numbers_are_jumpers no)
		(fp_line
			(start -0.7874 0.4064)
			(end -0.7874 -0.4064)
			(stroke
				(width 0.1524)
				(type default)
			)
			(layer "F.SilkS")
		)
		(fp_line
			(start 0.7874 0.4064)
			(end -0.7874 0.4064)
			(stroke
				(width 0.1524)
				(type default)
			)
			(layer "F.SilkS")
		)
		(fp_line
			(start -0.7874 -0.4064)
			(end 0.7874 -0.4064)
			(stroke
				(width 0.1524)
				(type default)
			)
			(layer "F.SilkS")
		)
		(fp_line
			(start 0.7874 -0.4064)
			(end 0.7874 0.4064)
			(stroke
				(width 0.1524)
				(type default)
			)
			(layer "F.SilkS")
		)
		(fp_line
			(start -0.67945 0.3048)
			(end -0.67945 -0.305054)
			(stroke
				(width 0.1)
				(type default)
			)
			(layer "F.Fab")
		)
		(fp_line
			(start -0.12065 0.3048)
			(end -0.67945 0.3048)
			(stroke
				(width 0.1)
				(type default)
			)
			(layer "F.Fab")
		)
		(fp_line
			(start 0.120396 0.3048)
			(end 0.120396 0.2794)
			(stroke
				(width 0.1)
				(type default)
			)
			(layer "F.Fab")
		)
		(fp_line
			(start 0.67945 0.3048)
			(end 0.120396 0.3048)
			(stroke
				(width 0.1)
				(type default)
			)
			(layer "F.Fab")
		)
		(fp_line
			(start -0.12065 0.2794)
			(end -0.12065 0.3048)
			(stroke
				(width 0.1)
				(type default)
			)
			(layer "F.Fab")
		)
		(fp_line
			(start 0.120396 0.2794)
			(end -0.12065 0.2794)
			(stroke
				(width 0.1)
				(type default)
			)
			(layer "F.Fab")
		)
		(fp_line
			(start -0.12065 -0.2794)
			(end 0.12065 -0.2794)
			(stroke
				(width 0.1)
				(type default)
			)
			(layer "F.Fab")
		)
		(fp_line
			(start 0.12065 -0.2794)
			(end 0.12065 -0.3048)
			(stroke
				(width 0.1)
				(type default)
			)
			(layer "F.Fab")
		)
		(fp_line
			(start 0.12065 -0.3048)
			(end 0.67945 -0.3048)
			(stroke
				(width 0.1)
				(type default)
			)
			(layer "F.Fab")
		)
		(fp_line
			(start 0.67945 -0.3048)
			(end 0.67945 0.3048)
			(stroke
				(width 0.1)
				(type default)
			)
			(layer "F.Fab")
		)
		(fp_line
			(start -0.67945 -0.305054)
			(end -0.12065 -0.305054)
			(stroke
				(width 0.1)
				(type default)
			)
			(layer "F.Fab")
		)
		(fp_line
			(start -0.12065 -0.305054)
			(end -0.12065 -0.2794)
			(stroke
				(width 0.1)
				(type default)
			)
			(layer "F.Fab")
		)
		(pad "1" smd circle
			(at -0.40005 0 270)
			(size 0 0)
			(layers "F.Cu" "F.Mask" "F.Paste")
			(net "P1V8_STBY_PE_VCC18A")
		)
		(pad "2" smd circle
			(at 0.40005 0 270)
			(size 0 0)
			(layers "F.Cu" "F.Mask" "F.Paste")
			(net "GND")
		)
	)
	(footprint ""
		(layer "F.Cu")
		(at 36.9824 -60.1726 -90)
		(property "Reference" "R565"
			(at 0 0 270)
			(layer "F.SilkS")
			(hide yes)
			(effects
				(font
					(size 1.27 1.27)
				)
			)
		)
		(property "Value" ""
			(at 0 0 270)
			(layer "F.Fab")
			(effects
				(font
					(size 1.27 1.27)
				)
			)
		)
		(duplicate_pad_numbers_are_jumpers no)
		(fp_line
			(start -0.7874 0.4064)
			(end -0.7874 -0.4064)
			(stroke
				(width 0.1524)
				(type default)
			)
			(layer "F.SilkS")
		)
		(fp_line
			(start 0.7874 0.4064)
			(end -0.7874 0.4064)
			(stroke
				(width 0.1524)
				(type default)
			)
			(layer "F.SilkS")
		)
		(fp_line
			(start -0.7874 -0.4064)
			(end 0.7874 -0.4064)
			(stroke
				(width 0.1524)
				(type default)
			)
			(layer "F.SilkS")
		)
		(fp_line
			(start 0.7874 -0.4064)
			(end 0.7874 0.4064)
			(stroke
				(width 0.1524)
				(type default)
			)
			(layer "F.SilkS")
		)
		(fp_line
			(start -0.67945 0.3048)
			(end -0.67945 -0.305054)
			(stroke
				(width 0.1)
				(type default)
			)
			(layer "F.Fab")
		)
		(fp_line
			(start -0.12065 0.3048)
			(end -0.67945 0.3048)
			(stroke
				(width 0.1)
				(type default)
			)
			(layer "F.Fab")
		)
		(fp_line
			(start 0.120396 0.3048)
			(end 0.120396 0.2794)
			(stroke
				(width 0.1)
				(type default)
			)
			(layer "F.Fab")
		)
		(fp_line
			(start 0.67945 0.3048)
			(end 0.120396 0.3048)
			(stroke
				(width 0.1)
				(type default)
			)
			(layer "F.Fab")
		)
		(fp_line
			(start -0.12065 0.2794)
			(end -0.12065 0.3048)
			(stroke
				(width 0.1)
				(type default)
			)
			(layer "F.Fab")
		)
		(fp_line
			(start 0.120396 0.2794)
			(end -0.12065 0.2794)
			(stroke
				(width 0.1)
				(type default)
			)
			(layer "F.Fab")
		)
		(fp_line
			(start -0.12065 -0.2794)
			(end 0.12065 -0.2794)
			(stroke
				(width 0.1)
				(type default)
			)
			(layer "F.Fab")
		)
		(fp_line
			(start 0.12065 -0.2794)
			(end 0.12065 -0.3048)
			(stroke
				(width 0.1)
				(type default)
			)
			(layer "F.Fab")
		)
		(fp_line
			(start 0.12065 -0.3048)
			(end 0.67945 -0.3048)
			(stroke
				(width 0.1)
				(type default)
			)
			(layer "F.Fab")
		)
		(fp_line
			(start 0.67945 -0.3048)
			(end 0.67945 0.3048)
			(stroke
				(width 0.1)
				(type default)
			)
			(layer "F.Fab")
		)
		(fp_line
			(start -0.67945 -0.305054)
			(end -0.12065 -0.305054)
			(stroke
				(width 0.1)
				(type default)
			)
			(layer "F.Fab")
		)
		(fp_line
			(start -0.12065 -0.305054)
			(end -0.12065 -0.2794)
			(stroke
				(width 0.1)
				(type default)
			)
			(layer "F.Fab")
		)
		(pad "1" smd circle
			(at -0.40005 0 270)
			(size 0 0)
			(layers "F.Cu" "F.Mask" "F.Paste")
			(net "ID_RST_BTN_BMC_R_N")
		)
		(pad "2" smd circle
			(at 0.40005 0 270)
			(size 0 0)
			(layers "F.Cu" "F.Mask" "F.Paste")
			(net "ID_RST_BTN_BMC_N")
		)
	)
	(footprint ""
		(layer "F.Cu")
		(at 32.69488 -57.45226 -90)
		(property "Reference" "R875"
			(at 0 0 270)
			(layer "F.SilkS")
			(hide yes)
			(effects
				(font
					(size 1.27 1.27)
				)
			)
		)
		(property "Value" ""
			(at 0 0 270)
			(layer "F.Fab")
			(effects
				(font
					(size 1.27 1.27)
				)
			)
		)
		(duplicate_pad_numbers_are_jumpers no)
		(fp_line
			(start -0.7874 0.4064)
			(end -0.7874 -0.4064)
			(stroke
				(width 0.1524)
				(type default)
			)
			(layer "F.SilkS")
		)
		(fp_line
			(start 0.7874 0.4064)
			(end -0.7874 0.4064)
			(stroke
				(width 0.1524)
				(type default)
			)
			(layer "F.SilkS")
		)
		(fp_line
			(start -0.7874 -0.4064)
			(end 0.7874 -0.4064)
			(stroke
				(width 0.1524)
				(type default)
			)
			(layer "F.SilkS")
		)
		(fp_line
			(start 0.7874 -0.4064)
			(end 0.7874 0.4064)
			(stroke
				(width 0.1524)
				(type default)
			)
			(layer "F.SilkS")
		)
		(fp_line
			(start -0.67945 0.3048)
			(end -0.67945 -0.305054)
			(stroke
				(width 0.1)
				(type default)
			)
			(layer "F.Fab")
		)
		(fp_line
			(start -0.12065 0.3048)
			(end -0.67945 0.3048)
			(stroke
				(width 0.1)
				(type default)
			)
			(layer "F.Fab")
		)
		(fp_line
			(start 0.120396 0.3048)
			(end 0.120396 0.2794)
			(stroke
				(width 0.1)
				(type default)
			)
			(layer "F.Fab")
		)
		(fp_line
			(start 0.67945 0.3048)
			(end 0.120396 0.3048)
			(stroke
				(width 0.1)
				(type default)
			)
			(layer "F.Fab")
		)
		(fp_line
			(start -0.12065 0.2794)
			(end -0.12065 0.3048)
			(stroke
				(width 0.1)
				(type default)
			)
			(layer "F.Fab")
		)
		(fp_line
			(start 0.120396 0.2794)
			(end -0.12065 0.2794)
			(stroke
				(width 0.1)
				(type default)
			)
			(layer "F.Fab")
		)
		(fp_line
			(start -0.12065 -0.2794)
			(end 0.12065 -0.2794)
			(stroke
				(width 0.1)
				(type default)
			)
			(layer "F.Fab")
		)
		(fp_line
			(start 0.12065 -0.2794)
			(end 0.12065 -0.3048)
			(stroke
				(width 0.1)
				(type default)
			)
			(layer "F.Fab")
		)
		(fp_line
			(start 0.12065 -0.3048)
			(end 0.67945 -0.3048)
			(stroke
				(width 0.1)
				(type default)
			)
			(layer "F.Fab")
		)
		(fp_line
			(start 0.67945 -0.3048)
			(end 0.67945 0.3048)
			(stroke
				(width 0.1)
				(type default)
			)
			(layer "F.Fab")
		)
		(fp_line
			(start -0.67945 -0.305054)
			(end -0.12065 -0.305054)
			(stroke
				(width 0.1)
				(type default)
			)
			(layer "F.Fab")
		)
		(fp_line
			(start -0.12065 -0.305054)
			(end -0.12065 -0.2794)
			(stroke
				(width 0.1)
				(type default)
			)
			(layer "F.Fab")
		)
		(pad "1" smd circle
			(at -0.40005 0 270)
			(size 0 0)
			(layers "F.Cu" "F.Mask" "F.Paste")
			(net "PWRGD_P2V5_AUX_R3")
		)
		(pad "2" smd circle
			(at 0.40005 0 270)
			(size 0 0)
			(layers "F.Cu" "F.Mask" "F.Paste")
			(net "EN_P1V8_R")
		)
	)
	(footprint ""
		(layer "F.Cu")
		(at 69.265292 -35.261296 90)
		(property "Reference" "C119"
			(at 0 0 90)
			(layer "F.SilkS")
			(hide yes)
			(effects
				(font
					(size 1.27 1.27)
				)
			)
		)
		(property "Value" ""
			(at 0 0 90)
			(layer "F.Fab")
			(effects
				(font
					(size 1.27 1.27)
				)
			)
		)
		(duplicate_pad_numbers_are_jumpers no)
		(fp_line
			(start 0.7874 -0.4064)
			(end 0.7874 0.4064)
			(stroke
				(width 0.1524)
				(type default)
			)
			(layer "F.SilkS")
		)
		(fp_line
			(start -0.7874 -0.4064)
			(end 0.7874 -0.4064)
			(stroke
				(width 0.1524)
				(type default)
			)
			(layer "F.SilkS")
		)
		(fp_line
			(start 0.7874 0.4064)
			(end -0.7874 0.4064)
			(stroke
				(width 0.1524)
				(type default)
			)
			(layer "F.SilkS")
		)
		(fp_line
			(start -0.7874 0.4064)
			(end -0.7874 -0.4064)
			(stroke
				(width 0.1524)
				(type default)
			)
			(layer "F.SilkS")
		)
		(fp_line
			(start -0.12065 -0.305054)
			(end -0.12065 -0.2794)
			(stroke
				(width 0.1)
				(type default)
			)
			(layer "F.Fab")
		)
		(fp_line
			(start -0.67945 -0.305054)
			(end -0.12065 -0.305054)
			(stroke
				(width 0.1)
				(type default)
			)
			(layer "F.Fab")
		)
		(fp_line
			(start 0.67945 -0.3048)
			(end 0.67945 0.3048)
			(stroke
				(width 0.1)
				(type default)
			)
			(layer "F.Fab")
		)
		(fp_line
			(start 0.12065 -0.3048)
			(end 0.67945 -0.3048)
			(stroke
				(width 0.1)
				(type default)
			)
			(layer "F.Fab")
		)
		(fp_line
			(start 0.12065 -0.2794)
			(end 0.12065 -0.3048)
			(stroke
				(width 0.1)
				(type default)
			)
			(layer "F.Fab")
		)
		(fp_line
			(start -0.12065 -0.2794)
			(end 0.12065 -0.2794)
			(stroke
				(width 0.1)
				(type default)
			)
			(layer "F.Fab")
		)
		(fp_line
			(start 0.120396 0.2794)
			(end -0.12065 0.2794)
			(stroke
				(width 0.1)
				(type default)
			)
			(layer "F.Fab")
		)
		(fp_line
			(start -0.12065 0.2794)
			(end -0.12065 0.3048)
			(stroke
				(width 0.1)
				(type default)
			)
			(layer "F.Fab")
		)
		(fp_line
			(start 0.67945 0.3048)
			(end 0.120396 0.3048)
			(stroke
				(width 0.1)
				(type default)
			)
			(layer "F.Fab")
		)
		(fp_line
			(start 0.120396 0.3048)
			(end 0.120396 0.2794)
			(stroke
				(width 0.1)
				(type default)
			)
			(layer "F.Fab")
		)
		(fp_line
			(start -0.12065 0.3048)
			(end -0.67945 0.3048)
			(stroke
				(width 0.1)
				(type default)
			)
			(layer "F.Fab")
		)
		(fp_line
			(start -0.67945 0.3048)
			(end -0.67945 -0.305054)
			(stroke
				(width 0.1)
				(type default)
			)
			(layer "F.Fab")
		)
		(pad "1" smd circle
			(at -0.40005 0 90)
			(size 0 0)
			(layers "F.Cu" "F.Mask" "F.Paste")
			(net "P1V8_AUX")
		)
		(pad "2" smd circle
			(at 0.40005 0 90)
			(size 0 0)
			(layers "F.Cu" "F.Mask" "F.Paste")
			(net "GND")
		)
	)
	(footprint ""
		(layer "F.Cu")
		(at 5.13207 -64.550798 -90)
		(property "Reference" "PC221"
			(at 0 0 270)
			(layer "F.SilkS")
			(hide yes)
			(effects
				(font
					(size 1.27 1.27)
				)
			)
		)
		(property "Value" ""
			(at 0 0 270)
			(layer "F.Fab")
			(effects
				(font
					(size 1.27 1.27)
				)
			)
		)
		(duplicate_pad_numbers_are_jumpers no)
		(fp_line
			(start -0.7874 0.4064)
			(end -0.7874 -0.4064)
			(stroke
				(width 0.1524)
				(type default)
			)
			(layer "F.SilkS")
		)
		(fp_line
			(start 0.7874 0.4064)
			(end -0.7874 0.4064)
			(stroke
				(width 0.1524)
				(type default)
			)
			(layer "F.SilkS")
		)
		(fp_line
			(start -0.7874 -0.4064)
			(end 0.7874 -0.4064)
			(stroke
				(width 0.1524)
				(type default)
			)
			(layer "F.SilkS")
		)
		(fp_line
			(start 0.7874 -0.4064)
			(end 0.7874 0.4064)
			(stroke
				(width 0.1524)
				(type default)
			)
			(layer "F.SilkS")
		)
		(fp_line
			(start -0.67945 0.3048)
			(end -0.67945 -0.305054)
			(stroke
				(width 0.1)
				(type default)
			)
			(layer "F.Fab")
		)
		(fp_line
			(start -0.12065 0.3048)
			(end -0.67945 0.3048)
			(stroke
				(width 0.1)
				(type default)
			)
			(layer "F.Fab")
		)
		(fp_line
			(start 0.120396 0.3048)
			(end 0.120396 0.2794)
			(stroke
				(width 0.1)
				(type default)
			)
			(layer "F.Fab")
		)
		(fp_line
			(start 0.67945 0.3048)
			(end 0.120396 0.3048)
			(stroke
				(width 0.1)
				(type default)
			)
			(layer "F.Fab")
		)
		(fp_line
			(start -0.12065 0.2794)
			(end -0.12065 0.3048)
			(stroke
				(width 0.1)
				(type default)
			)
			(layer "F.Fab")
		)
		(fp_line
			(start 0.120396 0.2794)
			(end -0.12065 0.2794)
			(stroke
				(width 0.1)
				(type default)
			)
			(layer "F.Fab")
		)
		(fp_line
			(start -0.12065 -0.2794)
			(end 0.12065 -0.2794)
			(stroke
				(width 0.1)
				(type default)
			)
			(layer "F.Fab")
		)
		(fp_line
			(start 0.12065 -0.2794)
			(end 0.12065 -0.3048)
			(stroke
				(width 0.1)
				(type default)
			)
			(layer "F.Fab")
		)
		(fp_line
			(start 0.12065 -0.3048)
			(end 0.67945 -0.3048)
			(stroke
				(width 0.1)
				(type default)
			)
			(layer "F.Fab")
		)
		(fp_line
			(start 0.67945 -0.3048)
			(end 0.67945 0.3048)
			(stroke
				(width 0.1)
				(type default)
			)
			(layer "F.Fab")
		)
		(fp_line
			(start -0.67945 -0.305054)
			(end -0.12065 -0.305054)
			(stroke
				(width 0.1)
				(type default)
			)
			(layer "F.Fab")
		)
		(fp_line
			(start -0.12065 -0.305054)
			(end -0.12065 -0.2794)
			(stroke
				(width 0.1)
				(type default)
			)
			(layer "F.Fab")
		)
		(pad "1" smd circle
			(at -0.40005 0 270)
			(size 0 0)
			(layers "F.Cu" "F.Mask" "F.Paste")
			(net "P3V3_AUX_VCC")
		)
		(pad "2" smd circle
			(at 0.40005 0 270)
			(size 0 0)
			(layers "F.Cu" "F.Mask" "F.Paste")
			(net "GND")
		)
	)
	(footprint ""
		(layer "F.Cu")
		(at 66.5226 -108.0008 -90)
		(property "Reference" "R310"
			(at 0 0 270)
			(layer "F.SilkS")
			(hide yes)
			(effects
				(font
					(size 1.27 1.27)
				)
			)
		)
		(property "Value" ""
			(at 0 0 270)
			(layer "F.Fab")
			(effects
				(font
					(size 1.27 1.27)
				)
			)
		)
		(duplicate_pad_numbers_are_jumpers no)
		(fp_line
			(start -0.7874 0.4064)
			(end -0.7874 -0.4064)
			(stroke
				(width 0.1524)
				(type default)
			)
			(layer "F.SilkS")
		)
		(fp_line
			(start 0.7874 0.4064)
			(end -0.7874 0.4064)
			(stroke
				(width 0.1524)
				(type default)
			)
			(layer "F.SilkS")
		)
		(fp_line
			(start -0.7874 -0.4064)
			(end 0.7874 -0.4064)
			(stroke
				(width 0.1524)
				(type default)
			)
			(layer "F.SilkS")
		)
		(fp_line
			(start 0.7874 -0.4064)
			(end 0.7874 0.4064)
			(stroke
				(width 0.1524)
				(type default)
			)
			(layer "F.SilkS")
		)
		(fp_line
			(start -0.67945 0.3048)
			(end -0.67945 -0.305054)
			(stroke
				(width 0.1)
				(type default)
			)
			(layer "F.Fab")
		)
		(fp_line
			(start -0.12065 0.3048)
			(end -0.67945 0.3048)
			(stroke
				(width 0.1)
				(type default)
			)
			(layer "F.Fab")
		)
		(fp_line
			(start 0.120396 0.3048)
			(end 0.120396 0.2794)
			(stroke
				(width 0.1)
				(type default)
			)
			(layer "F.Fab")
		)
		(fp_line
			(start 0.67945 0.3048)
			(end 0.120396 0.3048)
			(stroke
				(width 0.1)
				(type default)
			)
			(layer "F.Fab")
		)
		(fp_line
			(start -0.12065 0.2794)
			(end -0.12065 0.3048)
			(stroke
				(width 0.1)
				(type default)
			)
			(layer "F.Fab")
		)
		(fp_line
			(start 0.120396 0.2794)
			(end -0.12065 0.2794)
			(stroke
				(width 0.1)
				(type default)
			)
			(layer "F.Fab")
		)
		(fp_line
			(start -0.12065 -0.2794)
			(end 0.12065 -0.2794)
			(stroke
				(width 0.1)
				(type default)
			)
			(layer "F.Fab")
		)
		(fp_line
			(start 0.12065 -0.2794)
			(end 0.12065 -0.3048)
			(stroke
				(width 0.1)
				(type default)
			)
			(layer "F.Fab")
		)
		(fp_line
			(start 0.12065 -0.3048)
			(end 0.67945 -0.3048)
			(stroke
				(width 0.1)
				(type default)
			)
			(layer "F.Fab")
		)
		(fp_line
			(start 0.67945 -0.3048)
			(end 0.67945 0.3048)
			(stroke
				(width 0.1)
				(type default)
			)
			(layer "F.Fab")
		)
		(fp_line
			(start -0.67945 -0.305054)
			(end -0.12065 -0.305054)
			(stroke
				(width 0.1)
				(type default)
			)
			(layer "F.Fab")
		)
		(fp_line
			(start -0.12065 -0.305054)
			(end -0.12065 -0.2794)
			(stroke
				(width 0.1)
				(type default)
			)
			(layer "F.Fab")
		)
		(pad "1" smd circle
			(at -0.40005 0 270)
			(size 0 0)
			(layers "F.Cu" "F.Mask" "F.Paste")
			(net "ESPI_HOST_LPC_BMC_CLK")
		)
		(pad "2" smd circle
			(at 0.40005 0 270)
			(size 0 0)
			(layers "F.Cu" "F.Mask" "F.Paste")
			(net "ESPI_HOST_LPC_BMC_CLK_R")
		)
	)
	(footprint ""
		(layer "F.Cu")
		(at 54.55539 -28.026868 -90)
		(property "Reference" "R212"
			(at 0 0 270)
			(layer "F.SilkS")
			(hide yes)
			(effects
				(font
					(size 1.27 1.27)
				)
			)
		)
		(property "Value" ""
			(at 0 0 270)
			(layer "F.Fab")
			(effects
				(font
					(size 1.27 1.27)
				)
			)
		)
		(duplicate_pad_numbers_are_jumpers no)
		(fp_line
			(start -0.7874 0.4064)
			(end -0.7874 -0.4064)
			(stroke
				(width 0.1524)
				(type default)
			)
			(layer "F.SilkS")
		)
		(fp_line
			(start 0.7874 0.4064)
			(end -0.7874 0.4064)
			(stroke
				(width 0.1524)
				(type default)
			)
			(layer "F.SilkS")
		)
		(fp_line
			(start -0.7874 -0.4064)
			(end 0.7874 -0.4064)
			(stroke
				(width 0.1524)
				(type default)
			)
			(layer "F.SilkS")
		)
		(fp_line
			(start 0.7874 -0.4064)
			(end 0.7874 0.4064)
			(stroke
				(width 0.1524)
				(type default)
			)
			(layer "F.SilkS")
		)
		(fp_line
			(start -0.67945 0.3048)
			(end -0.67945 -0.305054)
			(stroke
				(width 0.1)
				(type default)
			)
			(layer "F.Fab")
		)
		(fp_line
			(start -0.12065 0.3048)
			(end -0.67945 0.3048)
			(stroke
				(width 0.1)
				(type default)
			)
			(layer "F.Fab")
		)
		(fp_line
			(start 0.120396 0.3048)
			(end 0.120396 0.2794)
			(stroke
				(width 0.1)
				(type default)
			)
			(layer "F.Fab")
		)
		(fp_line
			(start 0.67945 0.3048)
			(end 0.120396 0.3048)
			(stroke
				(width 0.1)
				(type default)
			)
			(layer "F.Fab")
		)
		(fp_line
			(start -0.12065 0.2794)
			(end -0.12065 0.3048)
			(stroke
				(width 0.1)
				(type default)
			)
			(layer "F.Fab")
		)
		(fp_line
			(start 0.120396 0.2794)
			(end -0.12065 0.2794)
			(stroke
				(width 0.1)
				(type default)
			)
			(layer "F.Fab")
		)
		(fp_line
			(start -0.12065 -0.2794)
			(end 0.12065 -0.2794)
			(stroke
				(width 0.1)
				(type default)
			)
			(layer "F.Fab")
		)
		(fp_line
			(start 0.12065 -0.2794)
			(end 0.12065 -0.3048)
			(stroke
				(width 0.1)
				(type default)
			)
			(layer "F.Fab")
		)
		(fp_line
			(start 0.12065 -0.3048)
			(end 0.67945 -0.3048)
			(stroke
				(width 0.1)
				(type default)
			)
			(layer "F.Fab")
		)
		(fp_line
			(start 0.67945 -0.3048)
			(end 0.67945 0.3048)
			(stroke
				(width 0.1)
				(type default)
			)
			(layer "F.Fab")
		)
		(fp_line
			(start -0.67945 -0.305054)
			(end -0.12065 -0.305054)
			(stroke
				(width 0.1)
				(type default)
			)
			(layer "F.Fab")
		)
		(fp_line
			(start -0.12065 -0.305054)
			(end -0.12065 -0.2794)
			(stroke
				(width 0.1)
				(type default)
			)
			(layer "F.Fab")
		)
		(pad "1" smd circle
			(at -0.40005 0 270)
			(size 0 0)
			(layers "F.Cu" "F.Mask" "F.Paste")
			(net "P3V3_RGM")
		)
		(pad "2" smd circle
			(at 0.40005 0 270)
			(size 0 0)
			(layers "F.Cu" "F.Mask" "F.Paste")
			(net "PU_25M_BMC_CLK_EN")
		)
	)
	(footprint ""
		(layer "F.Cu")
		(at 40.900604 -87.679784 90)
		(property "Reference" "R485"
			(at 0 0 90)
			(layer "F.SilkS")
			(hide yes)
			(effects
				(font
					(size 1.27 1.27)
				)
			)
		)
		(property "Value" ""
			(at 0 0 90)
			(layer "F.Fab")
			(effects
				(font
					(size 1.27 1.27)
				)
			)
		)
		(duplicate_pad_numbers_are_jumpers no)
		(fp_line
			(start 0.7874 -0.4064)
			(end 0.7874 0.4064)
			(stroke
				(width 0.1524)
				(type default)
			)
			(layer "F.SilkS")
		)
		(fp_line
			(start -0.7874 -0.4064)
			(end 0.7874 -0.4064)
			(stroke
				(width 0.1524)
				(type default)
			)
			(layer "F.SilkS")
		)
		(fp_line
			(start 0.7874 0.4064)
			(end -0.7874 0.4064)
			(stroke
				(width 0.1524)
				(type default)
			)
			(layer "F.SilkS")
		)
		(fp_line
			(start -0.7874 0.4064)
			(end -0.7874 -0.4064)
			(stroke
				(width 0.1524)
				(type default)
			)
			(layer "F.SilkS")
		)
		(fp_line
			(start -0.12065 -0.305054)
			(end -0.12065 -0.2794)
			(stroke
				(width 0.1)
				(type default)
			)
			(layer "F.Fab")
		)
		(fp_line
			(start -0.67945 -0.305054)
			(end -0.12065 -0.305054)
			(stroke
				(width 0.1)
				(type default)
			)
			(layer "F.Fab")
		)
		(fp_line
			(start 0.67945 -0.3048)
			(end 0.67945 0.3048)
			(stroke
				(width 0.1)
				(type default)
			)
			(layer "F.Fab")
		)
		(fp_line
			(start 0.12065 -0.3048)
			(end 0.67945 -0.3048)
			(stroke
				(width 0.1)
				(type default)
			)
			(layer "F.Fab")
		)
		(fp_line
			(start 0.12065 -0.2794)
			(end 0.12065 -0.3048)
			(stroke
				(width 0.1)
				(type default)
			)
			(layer "F.Fab")
		)
		(fp_line
			(start -0.12065 -0.2794)
			(end 0.12065 -0.2794)
			(stroke
				(width 0.1)
				(type default)
			)
			(layer "F.Fab")
		)
		(fp_line
			(start 0.120396 0.2794)
			(end -0.12065 0.2794)
			(stroke
				(width 0.1)
				(type default)
			)
			(layer "F.Fab")
		)
		(fp_line
			(start -0.12065 0.2794)
			(end -0.12065 0.3048)
			(stroke
				(width 0.1)
				(type default)
			)
			(layer "F.Fab")
		)
		(fp_line
			(start 0.67945 0.3048)
			(end 0.120396 0.3048)
			(stroke
				(width 0.1)
				(type default)
			)
			(layer "F.Fab")
		)
		(fp_line
			(start 0.120396 0.3048)
			(end 0.120396 0.2794)
			(stroke
				(width 0.1)
				(type default)
			)
			(layer "F.Fab")
		)
		(fp_line
			(start -0.12065 0.3048)
			(end -0.67945 0.3048)
			(stroke
				(width 0.1)
				(type default)
			)
			(layer "F.Fab")
		)
		(fp_line
			(start -0.67945 0.3048)
			(end -0.67945 -0.305054)
			(stroke
				(width 0.1)
				(type default)
			)
			(layer "F.Fab")
		)
		(pad "1" smd circle
			(at -0.40005 0 90)
			(size 0 0)
			(layers "F.Cu" "F.Mask" "F.Paste")
			(net "SPI_PCH_MUXED_CS0_N")
		)
		(pad "2" smd circle
			(at 0.40005 0 90)
			(size 0 0)
			(layers "F.Cu" "F.Mask" "F.Paste")
			(net "SPI_PCH_CS0_FLASH_R1_N")
		)
	)
	(footprint ""
		(layer "F.Cu")
		(at 11.4554 -61.214 180)
		(property "Reference" "C297"
			(at 0 0 180)
			(layer "F.SilkS")
			(hide yes)
			(effects
				(font
					(size 1.27 1.27)
				)
			)
		)
		(property "Value" ""
			(at 0 0 180)
			(layer "F.Fab")
			(effects
				(font
					(size 1.27 1.27)
				)
			)
		)
		(duplicate_pad_numbers_are_jumpers no)
		(fp_line
			(start 0.7874 0.4064)
			(end -0.7874 0.4064)
			(stroke
				(width 0.1524)
				(type default)
			)
			(layer "F.SilkS")
		)
		(fp_line
			(start 0.7874 -0.4064)
			(end 0.7874 0.4064)
			(stroke
				(width 0.1524)
				(type default)
			)
			(layer "F.SilkS")
		)
		(fp_line
			(start -0.7874 0.4064)
			(end -0.7874 -0.4064)
			(stroke
				(width 0.1524)
				(type default)
			)
			(layer "F.SilkS")
		)
		(fp_line
			(start -0.7874 -0.4064)
			(end 0.7874 -0.4064)
			(stroke
				(width 0.1524)
				(type default)
			)
			(layer "F.SilkS")
		)
		(fp_line
			(start 0.67945 0.3048)
			(end 0.120396 0.3048)
			(stroke
				(width 0.1)
				(type default)
			)
			(layer "F.Fab")
		)
		(fp_line
			(start 0.67945 -0.3048)
			(end 0.67945 0.3048)
			(stroke
				(width 0.1)
				(type default)
			)
			(layer "F.Fab")
		)
		(fp_line
			(start 0.12065 -0.2794)
			(end 0.12065 -0.3048)
			(stroke
				(width 0.1)
				(type default)
			)
			(layer "F.Fab")
		)
		(fp_line
			(start 0.12065 -0.3048)
			(end 0.67945 -0.3048)
			(stroke
				(width 0.1)
				(type default)
			)
			(layer "F.Fab")
		)
		(fp_line
			(start 0.120396 0.3048)
			(end 0.120396 0.2794)
			(stroke
				(width 0.1)
				(type default)
			)
			(layer "F.Fab")
		)
		(fp_line
			(start 0.120396 0.2794)
			(end -0.12065 0.2794)
			(stroke
				(width 0.1)
				(type default)
			)
			(layer "F.Fab")
		)
		(fp_line
			(start -0.12065 0.3048)
			(end -0.67945 0.3048)
			(stroke
				(width 0.1)
				(type default)
			)
			(layer "F.Fab")
		)
		(fp_line
			(start -0.12065 0.2794)
			(end -0.12065 0.3048)
			(stroke
				(width 0.1)
				(type default)
			)
			(layer "F.Fab")
		)
		(fp_line
			(start -0.12065 -0.2794)
			(end 0.12065 -0.2794)
			(stroke
				(width 0.1)
				(type default)
			)
			(layer "F.Fab")
		)
		(fp_line
			(start -0.12065 -0.305054)
			(end -0.12065 -0.2794)
			(stroke
				(width 0.1)
				(type default)
			)
			(layer "F.Fab")
		)
		(fp_line
			(start -0.67945 0.3048)
			(end -0.67945 -0.305054)
			(stroke
				(width 0.1)
				(type default)
			)
			(layer "F.Fab")
		)
		(fp_line
			(start -0.67945 -0.305054)
			(end -0.12065 -0.305054)
			(stroke
				(width 0.1)
				(type default)
			)
			(layer "F.Fab")
		)
		(pad "1" smd circle
			(at -0.40005 0 180)
			(size 0 0)
			(layers "F.Cu" "F.Mask" "F.Paste")
			(net "P3V3_LDO")
		)
		(pad "2" smd circle
			(at 0.40005 0 180)
			(size 0 0)
			(layers "F.Cu" "F.Mask" "F.Paste")
			(net "GND")
		)
	)
	(footprint ""
		(layer "F.Cu")
		(at 48.852836 -109.411008 90)
		(property "Reference" "R101"
			(at 0 0 90)
			(layer "F.SilkS")
			(hide yes)
			(effects
				(font
					(size 1.27 1.27)
				)
			)
		)
		(property "Value" ""
			(at 0 0 90)
			(layer "F.Fab")
			(effects
				(font
					(size 1.27 1.27)
				)
			)
		)
		(duplicate_pad_numbers_are_jumpers no)
		(fp_line
			(start 0.7874 -0.4064)
			(end 0.7874 0.4064)
			(stroke
				(width 0.1524)
				(type default)
			)
			(layer "F.SilkS")
		)
		(fp_line
			(start -0.7874 -0.4064)
			(end 0.7874 -0.4064)
			(stroke
				(width 0.1524)
				(type default)
			)
			(layer "F.SilkS")
		)
		(fp_line
			(start 0.7874 0.4064)
			(end -0.7874 0.4064)
			(stroke
				(width 0.1524)
				(type default)
			)
			(layer "F.SilkS")
		)
		(fp_line
			(start -0.7874 0.4064)
			(end -0.7874 -0.4064)
			(stroke
				(width 0.1524)
				(type default)
			)
			(layer "F.SilkS")
		)
		(fp_line
			(start -0.12065 -0.305054)
			(end -0.12065 -0.2794)
			(stroke
				(width 0.1)
				(type default)
			)
			(layer "F.Fab")
		)
		(fp_line
			(start -0.67945 -0.305054)
			(end -0.12065 -0.305054)
			(stroke
				(width 0.1)
				(type default)
			)
			(layer "F.Fab")
		)
		(fp_line
			(start 0.67945 -0.3048)
			(end 0.67945 0.3048)
			(stroke
				(width 0.1)
				(type default)
			)
			(layer "F.Fab")
		)
		(fp_line
			(start 0.12065 -0.3048)
			(end 0.67945 -0.3048)
			(stroke
				(width 0.1)
				(type default)
			)
			(layer "F.Fab")
		)
		(fp_line
			(start 0.12065 -0.2794)
			(end 0.12065 -0.3048)
			(stroke
				(width 0.1)
				(type default)
			)
			(layer "F.Fab")
		)
		(fp_line
			(start -0.12065 -0.2794)
			(end 0.12065 -0.2794)
			(stroke
				(width 0.1)
				(type default)
			)
			(layer "F.Fab")
		)
		(fp_line
			(start 0.120396 0.2794)
			(end -0.12065 0.2794)
			(stroke
				(width 0.1)
				(type default)
			)
			(layer "F.Fab")
		)
		(fp_line
			(start -0.12065 0.2794)
			(end -0.12065 0.3048)
			(stroke
				(width 0.1)
				(type default)
			)
			(layer "F.Fab")
		)
		(fp_line
			(start 0.67945 0.3048)
			(end 0.120396 0.3048)
			(stroke
				(width 0.1)
				(type default)
			)
			(layer "F.Fab")
		)
		(fp_line
			(start 0.120396 0.3048)
			(end 0.120396 0.2794)
			(stroke
				(width 0.1)
				(type default)
			)
			(layer "F.Fab")
		)
		(fp_line
			(start -0.12065 0.3048)
			(end -0.67945 0.3048)
			(stroke
				(width 0.1)
				(type default)
			)
			(layer "F.Fab")
		)
		(fp_line
			(start -0.67945 0.3048)
			(end -0.67945 -0.305054)
			(stroke
				(width 0.1)
				(type default)
			)
			(layer "F.Fab")
		)
		(pad "1" smd circle
			(at -0.40005 0 90)
			(size 0 0)
			(layers "F.Cu" "F.Mask" "F.Paste")
			(net "P3V3_AUX")
		)
		(pad "2" smd circle
			(at 0.40005 0 90)
			(size 0 0)
			(layers "F.Cu" "F.Mask" "F.Paste")
			(net "RMII_RXER")
		)
	)
	(footprint ""
		(layer "F.Cu")
		(at 16.0782 -62.3062 90)
		(property "Reference" "U51"
			(at 0.9398 1.72847 90)
			(unlocked yes)
			(layer "F.SilkS")
			(effects
				(font
					(size 0.7874 0.5842)
					(thickness 0.1524)
				)
			)
		)
		(property "Value" ""
			(at 0 0 90)
			(layer "F.Fab")
			(effects
				(font
					(size 1.27 1.27)
				)
			)
		)
		(duplicate_pad_numbers_are_jumpers no)
		(fp_line
			(start 1.7272 -1.1176)
			(end 0.254 -1.1176)
			(stroke
				(width 0.1524)
				(type default)
			)
			(layer "F.SilkS")
		)
		(fp_line
			(start 1.7272 -1.1176)
			(end 1.7272 1.1176)
			(stroke
				(width 0.1524)
				(type default)
			)
			(layer "F.SilkS")
		)
		(fp_line
			(start 0.254 -1.1176)
			(end 0 -0.7366)
			(stroke
				(width 0.1524)
				(type default)
			)
			(layer "F.SilkS")
		)
		(fp_line
			(start -0.254 -1.1176)
			(end -1.7272 -1.1176)
			(stroke
				(width 0.1524)
				(type default)
			)
			(layer "F.SilkS")
		)
		(fp_line
			(start 0 -0.7366)
			(end -0.254 -1.1176)
			(stroke
				(width 0.1524)
				(type default)
			)
			(layer "F.SilkS")
		)
		(fp_line
			(start 1.7272 1.1176)
			(end -1.7272 1.1176)
			(stroke
				(width 0.1524)
				(type default)
			)
			(layer "F.SilkS")
		)
		(fp_line
			(start -1.7272 1.1176)
			(end -1.7272 -1.1176)
			(stroke
				(width 0.1524)
				(type default)
			)
			(layer "F.SilkS")
		)
		(fp_poly
			(pts
				(xy -1.905 -0.954786) (xy -2.667 -0.573786) (xy -2.667 -1.335786)
			)
			(stroke
				(width 0)
				(type default)
			)
			(fill yes)
			(layer "F.SilkS")
		)
		(fp_line
			(start 1.5748 -1.1176)
			(end -1.5748 -1.1176)
			(stroke
				(width 0.1)
				(type default)
			)
			(layer "F.Fab")
		)
		(fp_line
			(start -1.5748 -1.1176)
			(end -1.5748 1.1176)
			(stroke
				(width 0.1)
				(type default)
			)
			(layer "F.Fab")
		)
		(fp_line
			(start 1.5748 1.1176)
			(end 1.5748 -1.1176)
			(stroke
				(width 0.1)
				(type default)
			)
			(layer "F.Fab")
		)
		(fp_line
			(start -1.5748 1.1176)
			(end 1.5748 1.1176)
			(stroke
				(width 0.1)
				(type default)
			)
			(layer "F.Fab")
		)
		(fp_poly
			(pts
				(xy -1.9558 -0.649986) (xy -2.7178 -0.268986) (xy -2.7178 -1.030986)
			)
			(stroke
				(width 0)
				(type default)
			)
			(fill yes)
			(layer "F.Fab")
		)
		(pad "1" smd rect
			(at -0.999998 -0.649986)
			(size 0.3556 1.1176)
			(layers "F.Cu" "F.Mask" "F.Paste")
			(net "UART_BIC_DBG_RX_R")
		)
		(pad "2" smd rect
			(at -0.999998 0)
			(size 0.3556 1.1176)
			(layers "F.Cu" "F.Mask" "F.Paste")
			(net "GND")
		)
		(pad "3" smd rect
			(at -0.999998 0.649986)
			(size 0.3556 1.1176)
			(layers "F.Cu" "F.Mask" "F.Paste")
			(net "UART_6_BMC_TXD_R")
		)
		(pad "4" smd rect
			(at 0.999998 0.649986)
			(size 0.3556 1.1176)
			(layers "F.Cu" "F.Mask" "F.Paste")
			(net "UART_BIC_GF_TXD")
		)
		(pad "5" smd rect
			(at 0.999998 0)
			(size 0.3556 1.1176)
			(layers "F.Cu" "F.Mask" "F.Paste")
			(net "P3V3_AUX")
		)
		(pad "6" smd rect
			(at 0.999998 -0.649986)
			(size 0.3556 1.1176)
			(layers "F.Cu" "F.Mask" "F.Paste")
			(net "FM_BIC_DEBUG_SW_N")
		)
	)
	(footprint ""
		(layer "F.Cu")
		(at -6.029198 -137.995152)
		(property "Reference" "DM2"
			(at -0.3937 -0.588518 0)
			(unlocked yes)
			(layer "F.SilkS")
			(effects
				(font
					(size 0.254 0.127)
					(thickness 0.000001)
				)
				(justify left)
			)
		)
		(property "Value" ""
			(at 0 0 0)
			(layer "F.Fab")
			(effects
				(font
					(size 1.27 1.27)
				)
			)
		)
		(duplicate_pad_numbers_are_jumpers no)
		(pad "1" smd circle
			(at 0 0)
			(size 0.762 0.762)
			(layers "F.Cu" "F.Mask" "F.Paste")
			(net "Net_29")
		)
	)
	(footprint ""
		(layer "F.Cu")
		(at 37.68598 -44.1325 -90)
		(property "Reference" "R269"
			(at 0 0 270)
			(layer "F.SilkS")
			(hide yes)
			(effects
				(font
					(size 1.27 1.27)
				)
			)
		)
		(property "Value" ""
			(at 0 0 270)
			(layer "F.Fab")
			(effects
				(font
					(size 1.27 1.27)
				)
			)
		)
		(duplicate_pad_numbers_are_jumpers no)
		(fp_line
			(start -0.7874 0.4064)
			(end -0.7874 -0.4064)
			(stroke
				(width 0.1524)
				(type default)
			)
			(layer "F.SilkS")
		)
		(fp_line
			(start 0.7874 0.4064)
			(end -0.7874 0.4064)
			(stroke
				(width 0.1524)
				(type default)
			)
			(layer "F.SilkS")
		)
		(fp_line
			(start -0.7874 -0.4064)
			(end 0.7874 -0.4064)
			(stroke
				(width 0.1524)
				(type default)
			)
			(layer "F.SilkS")
		)
		(fp_line
			(start 0.7874 -0.4064)
			(end 0.7874 0.4064)
			(stroke
				(width 0.1524)
				(type default)
			)
			(layer "F.SilkS")
		)
		(fp_line
			(start -0.67945 0.3048)
			(end -0.67945 -0.305054)
			(stroke
				(width 0.1)
				(type default)
			)
			(layer "F.Fab")
		)
		(fp_line
			(start -0.12065 0.3048)
			(end -0.67945 0.3048)
			(stroke
				(width 0.1)
				(type default)
			)
			(layer "F.Fab")
		)
		(fp_line
			(start 0.120396 0.3048)
			(end 0.120396 0.2794)
			(stroke
				(width 0.1)
				(type default)
			)
			(layer "F.Fab")
		)
		(fp_line
			(start 0.67945 0.3048)
			(end 0.120396 0.3048)
			(stroke
				(width 0.1)
				(type default)
			)
			(layer "F.Fab")
		)
		(fp_line
			(start -0.12065 0.2794)
			(end -0.12065 0.3048)
			(stroke
				(width 0.1)
				(type default)
			)
			(layer "F.Fab")
		)
		(fp_line
			(start 0.120396 0.2794)
			(end -0.12065 0.2794)
			(stroke
				(width 0.1)
				(type default)
			)
			(layer "F.Fab")
		)
		(fp_line
			(start -0.12065 -0.2794)
			(end 0.12065 -0.2794)
			(stroke
				(width 0.1)
				(type default)
			)
			(layer "F.Fab")
		)
		(fp_line
			(start 0.12065 -0.2794)
			(end 0.12065 -0.3048)
			(stroke
				(width 0.1)
				(type default)
			)
			(layer "F.Fab")
		)
		(fp_line
			(start 0.12065 -0.3048)
			(end 0.67945 -0.3048)
			(stroke
				(width 0.1)
				(type default)
			)
			(layer "F.Fab")
		)
		(fp_line
			(start 0.67945 -0.3048)
			(end 0.67945 0.3048)
			(stroke
				(width 0.1)
				(type default)
			)
			(layer "F.Fab")
		)
		(fp_line
			(start -0.67945 -0.305054)
			(end -0.12065 -0.305054)
			(stroke
				(width 0.1)
				(type default)
			)
			(layer "F.Fab")
		)
		(fp_line
			(start -0.12065 -0.305054)
			(end -0.12065 -0.2794)
			(stroke
				(width 0.1)
				(type default)
			)
			(layer "F.Fab")
		)
		(pad "1" smd circle
			(at -0.40005 0 270)
			(size 0 0)
			(layers "F.Cu" "F.Mask" "F.Paste")
			(net "P3V3_AUX")
		)
		(pad "2" smd circle
			(at 0.40005 0 270)
			(size 0 0)
			(layers "F.Cu" "F.Mask" "F.Paste")
			(net "SMB_BMC_ALERT4_N")
		)
	)
	(footprint ""
		(layer "F.Cu")
		(at 70.358 -11.684 -90)
		(property "Reference" "C336"
			(at 0 0 270)
			(layer "F.SilkS")
			(hide yes)
			(effects
				(font
					(size 1.27 1.27)
				)
			)
		)
		(property "Value" ""
			(at 0 0 270)
			(layer "F.Fab")
			(effects
				(font
					(size 1.27 1.27)
				)
			)
		)
		(duplicate_pad_numbers_are_jumpers no)
		(fp_line
			(start -0.7874 0.4064)
			(end -0.7874 -0.4064)
			(stroke
				(width 0.1524)
				(type default)
			)
			(layer "F.SilkS")
		)
		(fp_line
			(start 0.7874 0.4064)
			(end -0.7874 0.4064)
			(stroke
				(width 0.1524)
				(type default)
			)
			(layer "F.SilkS")
		)
		(fp_line
			(start -0.7874 -0.4064)
			(end 0.7874 -0.4064)
			(stroke
				(width 0.1524)
				(type default)
			)
			(layer "F.SilkS")
		)
		(fp_line
			(start 0.7874 -0.4064)
			(end 0.7874 0.4064)
			(stroke
				(width 0.1524)
				(type default)
			)
			(layer "F.SilkS")
		)
		(fp_line
			(start -0.67945 0.3048)
			(end -0.67945 -0.305054)
			(stroke
				(width 0.1)
				(type default)
			)
			(layer "F.Fab")
		)
		(fp_line
			(start -0.12065 0.3048)
			(end -0.67945 0.3048)
			(stroke
				(width 0.1)
				(type default)
			)
			(layer "F.Fab")
		)
		(fp_line
			(start 0.120396 0.3048)
			(end 0.120396 0.2794)
			(stroke
				(width 0.1)
				(type default)
			)
			(layer "F.Fab")
		)
		(fp_line
			(start 0.67945 0.3048)
			(end 0.120396 0.3048)
			(stroke
				(width 0.1)
				(type default)
			)
			(layer "F.Fab")
		)
		(fp_line
			(start -0.12065 0.2794)
			(end -0.12065 0.3048)
			(stroke
				(width 0.1)
				(type default)
			)
			(layer "F.Fab")
		)
		(fp_line
			(start 0.120396 0.2794)
			(end -0.12065 0.2794)
			(stroke
				(width 0.1)
				(type default)
			)
			(layer "F.Fab")
		)
		(fp_line
			(start -0.12065 -0.2794)
			(end 0.12065 -0.2794)
			(stroke
				(width 0.1)
				(type default)
			)
			(layer "F.Fab")
		)
		(fp_line
			(start 0.12065 -0.2794)
			(end 0.12065 -0.3048)
			(stroke
				(width 0.1)
				(type default)
			)
			(layer "F.Fab")
		)
		(fp_line
			(start 0.12065 -0.3048)
			(end 0.67945 -0.3048)
			(stroke
				(width 0.1)
				(type default)
			)
			(layer "F.Fab")
		)
		(fp_line
			(start 0.67945 -0.3048)
			(end 0.67945 0.3048)
			(stroke
				(width 0.1)
				(type default)
			)
			(layer "F.Fab")
		)
		(fp_line
			(start -0.67945 -0.305054)
			(end -0.12065 -0.305054)
			(stroke
				(width 0.1)
				(type default)
			)
			(layer "F.Fab")
		)
		(fp_line
			(start -0.12065 -0.305054)
			(end -0.12065 -0.2794)
			(stroke
				(width 0.1)
				(type default)
			)
			(layer "F.Fab")
		)
		(pad "1" smd circle
			(at -0.40005 0 270)
			(size 0 0)
			(layers "F.Cu" "F.Mask" "F.Paste")
			(net "P3V3_AUX")
		)
		(pad "2" smd circle
			(at 0.40005 0 270)
			(size 0 0)
			(layers "F.Cu" "F.Mask" "F.Paste")
			(net "GND")
		)
	)
	(footprint ""
		(layer "F.Cu")
		(at 77.281786 -31.307786 90)
		(property "Reference" "D5"
			(at -3.621786 7.580884 90)
			(unlocked yes)
			(layer "F.SilkS")
			(effects
				(font
					(size 0.7874 0.5842)
					(thickness 0.1524)
				)
				(justify left)
			)
		)
		(property "Value" ""
			(at 0 0 90)
			(layer "F.Fab")
			(effects
				(font
					(size 1.27 1.27)
				)
			)
		)
		(duplicate_pad_numbers_are_jumpers no)
		(fp_line
			(start 1.778 -0.5588)
			(end 1.3208 -0.5588)
			(stroke
				(width 0.1524)
				(type default)
			)
			(layer "F.SilkS")
		)
		(fp_line
			(start 1.778 -0.5588)
			(end 1.778 0.5588)
			(stroke
				(width 0.1524)
				(type default)
			)
			(layer "F.SilkS")
		)
		(fp_line
			(start 1.4732 -0.5588)
			(end 1.4732 0.5588)
			(stroke
				(width 0.1524)
				(type default)
			)
			(layer "F.SilkS")
		)
		(fp_line
			(start 1.3208 -0.5588)
			(end 1.3208 0.5588)
			(stroke
				(width 0.1524)
				(type default)
			)
			(layer "F.SilkS")
		)
		(fp_line
			(start -1.3208 -0.5588)
			(end 1.3208 -0.5588)
			(stroke
				(width 0.1524)
				(type default)
			)
			(layer "F.SilkS")
		)
		(fp_line
			(start 1.778 0.5588)
			(end 1.3208 0.5588)
			(stroke
				(width 0.1524)
				(type default)
			)
			(layer "F.SilkS")
		)
		(fp_line
			(start 1.6256 0.5588)
			(end 1.6256 -0.5588)
			(stroke
				(width 0.1524)
				(type default)
			)
			(layer "F.SilkS")
		)
		(fp_line
			(start 1.3208 0.5588)
			(end -1.3208 0.5588)
			(stroke
				(width 0.1524)
				(type default)
			)
			(layer "F.SilkS")
		)
		(fp_line
			(start -1.3208 0.5588)
			(end -1.3208 -0.5588)
			(stroke
				(width 0.1524)
				(type default)
			)
			(layer "F.SilkS")
		)
		(fp_line
			(start 0.8001 -0.40005)
			(end 0.8001 0.40005)
			(stroke
				(width 0.1)
				(type default)
			)
			(layer "F.Fab")
		)
		(fp_line
			(start -0.8001 -0.40005)
			(end 0.8001 -0.40005)
			(stroke
				(width 0.1)
				(type default)
			)
			(layer "F.Fab")
		)
		(fp_line
			(start 0.8001 0.40005)
			(end -0.8001 0.40005)
			(stroke
				(width 0.1)
				(type default)
			)
			(layer "F.Fab")
		)
		(fp_line
			(start -0.8001 0.40005)
			(end -0.8001 -0.40005)
			(stroke
				(width 0.1)
				(type default)
			)
			(layer "F.Fab")
		)
		(fp_text user "-"
			(at 1.661414 -1.024636 90)
			(unlocked yes)
			(layer "F.SilkS")
			(effects
				(font
					(size 1.905 1.4224)
					(thickness 0.1524)
				)
				(justify left)
			)
		)
		(fp_text user "+"
			(at -0.853186 -0.605536 270)
			(unlocked yes)
			(layer "F.SilkS")
			(effects
				(font
					(size 1.905 1.4224)
					(thickness 0.1524)
				)
				(justify left)
			)
		)
		(fp_text user "-"
			(at 1.6256 -0.22225 90)
			(unlocked yes)
			(layer "F.Fab")
			(effects
				(font
					(size 1.905 1.4224)
					(thickness 0.1524)
				)
				(justify left)
			)
		)
		(fp_text user "+"
			(at -2.5654 -0.22225 90)
			(unlocked yes)
			(layer "F.Fab")
			(effects
				(font
					(size 1.905 1.4224)
					(thickness 0.1524)
				)
				(justify left)
			)
		)
		(pad "A" smd rect
			(at -0.750062 0 90)
			(size 0.8128 0.8128)
			(layers "F.Cu" "F.Mask" "F.Paste")
			(net "LED_POSTCODE_5_R")
		)
		(pad "C" smd rect
			(at 0.750062 0 90)
			(size 0.8128 0.8128)
			(layers "F.Cu" "F.Mask" "F.Paste")
			(net "GND")
		)
	)
	(footprint ""
		(layer "F.Cu")
		(at 10.922 -105.5878)
		(property "Reference" "R315"
			(at 0 0 0)
			(layer "F.SilkS")
			(hide yes)
			(effects
				(font
					(size 1.27 1.27)
				)
			)
		)
		(property "Value" ""
			(at 0 0 0)
			(layer "F.Fab")
			(effects
				(font
					(size 1.27 1.27)
				)
			)
		)
		(duplicate_pad_numbers_are_jumpers no)
		(fp_line
			(start -0.7874 -0.4064)
			(end 0.7874 -0.4064)
			(stroke
				(width 0.1524)
				(type default)
			)
			(layer "F.SilkS")
		)
		(fp_line
			(start -0.7874 0.4064)
			(end -0.7874 -0.4064)
			(stroke
				(width 0.1524)
				(type default)
			)
			(layer "F.SilkS")
		)
		(fp_line
			(start 0.7874 -0.4064)
			(end 0.7874 0.4064)
			(stroke
				(width 0.1524)
				(type default)
			)
			(layer "F.SilkS")
		)
		(fp_line
			(start 0.7874 0.4064)
			(end -0.7874 0.4064)
			(stroke
				(width 0.1524)
				(type default)
			)
			(layer "F.SilkS")
		)
		(fp_line
			(start -0.67945 -0.305054)
			(end -0.12065 -0.305054)
			(stroke
				(width 0.1)
				(type default)
			)
			(layer "F.Fab")
		)
		(fp_line
			(start -0.67945 0.3048)
			(end -0.67945 -0.305054)
			(stroke
				(width 0.1)
				(type default)
			)
			(layer "F.Fab")
		)
		(fp_line
			(start -0.12065 -0.305054)
			(end -0.12065 -0.2794)
			(stroke
				(width 0.1)
				(type default)
			)
			(layer "F.Fab")
		)
		(fp_line
			(start -0.12065 -0.2794)
			(end 0.12065 -0.2794)
			(stroke
				(width 0.1)
				(type default)
			)
			(layer "F.Fab")
		)
		(fp_line
			(start -0.12065 0.2794)
			(end -0.12065 0.3048)
			(stroke
				(width 0.1)
				(type default)
			)
			(layer "F.Fab")
		)
		(fp_line
			(start -0.12065 0.3048)
			(end -0.67945 0.3048)
			(stroke
				(width 0.1)
				(type default)
			)
			(layer "F.Fab")
		)
		(fp_line
			(start 0.120396 0.2794)
			(end -0.12065 0.2794)
			(stroke
				(width 0.1)
				(type default)
			)
			(layer "F.Fab")
		)
		(fp_line
			(start 0.120396 0.3048)
			(end 0.120396 0.2794)
			(stroke
				(width 0.1)
				(type default)
			)
			(layer "F.Fab")
		)
		(fp_line
			(start 0.12065 -0.3048)
			(end 0.67945 -0.3048)
			(stroke
				(width 0.1)
				(type default)
			)
			(layer "F.Fab")
		)
		(fp_line
			(start 0.12065 -0.2794)
			(end 0.12065 -0.3048)
			(stroke
				(width 0.1)
				(type default)
			)
			(layer "F.Fab")
		)
		(fp_line
			(start 0.67945 -0.3048)
			(end 0.67945 0.3048)
			(stroke
				(width 0.1)
				(type default)
			)
			(layer "F.Fab")
		)
		(fp_line
			(start 0.67945 0.3048)
			(end 0.120396 0.3048)
			(stroke
				(width 0.1)
				(type default)
			)
			(layer "F.Fab")
		)
		(pad "1" smd circle
			(at -0.40005 0)
			(size 0 0)
			(layers "F.Cu" "F.Mask" "F.Paste")
			(net "RST_BMC_SRST_BUF_R_N")
		)
		(pad "2" smd circle
			(at 0.40005 0)
			(size 0 0)
			(layers "F.Cu" "F.Mask" "F.Paste")
			(net "RST_BMC_SRST_BUF_R1_N")
		)
	)
	(footprint ""
		(layer "F.Cu")
		(at 30.5562 -88.9762)
		(property "Reference" "R809"
			(at 0 0 0)
			(layer "F.SilkS")
			(hide yes)
			(effects
				(font
					(size 1.27 1.27)
				)
			)
		)
		(property "Value" ""
			(at 0 0 0)
			(layer "F.Fab")
			(effects
				(font
					(size 1.27 1.27)
				)
			)
		)
		(duplicate_pad_numbers_are_jumpers no)
		(fp_line
			(start -0.7874 -0.4064)
			(end 0.7874 -0.4064)
			(stroke
				(width 0.1524)
				(type default)
			)
			(layer "F.SilkS")
		)
		(fp_line
			(start -0.7874 0.4064)
			(end -0.7874 -0.4064)
			(stroke
				(width 0.1524)
				(type default)
			)
			(layer "F.SilkS")
		)
		(fp_line
			(start 0.7874 -0.4064)
			(end 0.7874 0.4064)
			(stroke
				(width 0.1524)
				(type default)
			)
			(layer "F.SilkS")
		)
		(fp_line
			(start 0.7874 0.4064)
			(end -0.7874 0.4064)
			(stroke
				(width 0.1524)
				(type default)
			)
			(layer "F.SilkS")
		)
		(fp_line
			(start -0.67945 -0.305054)
			(end -0.12065 -0.305054)
			(stroke
				(width 0.1)
				(type default)
			)
			(layer "F.Fab")
		)
		(fp_line
			(start -0.67945 0.3048)
			(end -0.67945 -0.305054)
			(stroke
				(width 0.1)
				(type default)
			)
			(layer "F.Fab")
		)
		(fp_line
			(start -0.12065 -0.305054)
			(end -0.12065 -0.2794)
			(stroke
				(width 0.1)
				(type default)
			)
			(layer "F.Fab")
		)
		(fp_line
			(start -0.12065 -0.2794)
			(end 0.12065 -0.2794)
			(stroke
				(width 0.1)
				(type default)
			)
			(layer "F.Fab")
		)
		(fp_line
			(start -0.12065 0.2794)
			(end -0.12065 0.3048)
			(stroke
				(width 0.1)
				(type default)
			)
			(layer "F.Fab")
		)
		(fp_line
			(start -0.12065 0.3048)
			(end -0.67945 0.3048)
			(stroke
				(width 0.1)
				(type default)
			)
			(layer "F.Fab")
		)
		(fp_line
			(start 0.120396 0.2794)
			(end -0.12065 0.2794)
			(stroke
				(width 0.1)
				(type default)
			)
			(layer "F.Fab")
		)
		(fp_line
			(start 0.120396 0.3048)
			(end 0.120396 0.2794)
			(stroke
				(width 0.1)
				(type default)
			)
			(layer "F.Fab")
		)
		(fp_line
			(start 0.12065 -0.3048)
			(end 0.67945 -0.3048)
			(stroke
				(width 0.1)
				(type default)
			)
			(layer "F.Fab")
		)
		(fp_line
			(start 0.12065 -0.2794)
			(end 0.12065 -0.3048)
			(stroke
				(width 0.1)
				(type default)
			)
			(layer "F.Fab")
		)
		(fp_line
			(start 0.67945 -0.3048)
			(end 0.67945 0.3048)
			(stroke
				(width 0.1)
				(type default)
			)
			(layer "F.Fab")
		)
		(fp_line
			(start 0.67945 0.3048)
			(end 0.120396 0.3048)
			(stroke
				(width 0.1)
				(type default)
			)
			(layer "F.Fab")
		)
		(pad "1" smd circle
			(at -0.40005 0)
			(size 0 0)
			(layers "F.Cu" "F.Mask" "F.Paste")
			(net "PU_FPGA_NCONFIG")
		)
		(pad "2" smd circle
			(at 0.40005 0)
			(size 0 0)
			(layers "F.Cu" "F.Mask" "F.Paste")
			(net "PVCCIO_AUX_PLD")
		)
	)
	(footprint ""
		(layer "F.Cu")
		(at 42.950638 -22.15642 -90)
		(property "Reference" "R675"
			(at 0 0 270)
			(layer "F.SilkS")
			(hide yes)
			(effects
				(font
					(size 1.27 1.27)
				)
			)
		)
		(property "Value" ""
			(at 0 0 270)
			(layer "F.Fab")
			(effects
				(font
					(size 1.27 1.27)
				)
			)
		)
		(duplicate_pad_numbers_are_jumpers no)
		(fp_line
			(start 0.7874 0.4064)
			(end -0.7874 0.4064)
			(stroke
				(width 0.1524)
				(type default)
			)
			(layer "F.SilkS")
		)
		(fp_line
			(start -0.7874 -0.4064)
			(end 0.7874 -0.4064)
			(stroke
				(width 0.1524)
				(type default)
			)
			(layer "F.SilkS")
		)
		(fp_line
			(start -0.67945 0.3048)
			(end -0.67945 -0.305054)
			(stroke
				(width 0.1)
				(type default)
			)
			(layer "F.Fab")
		)
		(fp_line
			(start -0.12065 0.3048)
			(end -0.67945 0.3048)
			(stroke
				(width 0.1)
				(type default)
			)
			(layer "F.Fab")
		)
		(fp_line
			(start 0.120396 0.3048)
			(end 0.120396 0.2794)
			(stroke
				(width 0.1)
				(type default)
			)
			(layer "F.Fab")
		)
		(fp_line
			(start 0.67945 0.3048)
			(end 0.120396 0.3048)
			(stroke
				(width 0.1)
				(type default)
			)
			(layer "F.Fab")
		)
		(fp_line
			(start -0.12065 0.2794)
			(end -0.12065 0.3048)
			(stroke
				(width 0.1)
				(type default)
			)
			(layer "F.Fab")
		)
		(fp_line
			(start 0.120396 0.2794)
			(end -0.12065 0.2794)
			(stroke
				(width 0.1)
				(type default)
			)
			(layer "F.Fab")
		)
		(fp_line
			(start -0.12065 -0.2794)
			(end 0.12065 -0.2794)
			(stroke
				(width 0.1)
				(type default)
			)
			(layer "F.Fab")
		)
		(fp_line
			(start 0.12065 -0.2794)
			(end 0.12065 -0.3048)
			(stroke
				(width 0.1)
				(type default)
			)
			(layer "F.Fab")
		)
		(fp_line
			(start 0.12065 -0.3048)
			(end 0.67945 -0.3048)
			(stroke
				(width 0.1)
				(type default)
			)
			(layer "F.Fab")
		)
		(fp_line
			(start 0.67945 -0.3048)
			(end 0.67945 0.3048)
			(stroke
				(width 0.1)
				(type default)
			)
			(layer "F.Fab")
		)
		(fp_line
			(start -0.67945 -0.305054)
			(end -0.12065 -0.305054)
			(stroke
				(width 0.1)
				(type default)
			)
			(layer "F.Fab")
		)
		(fp_line
			(start -0.12065 -0.305054)
			(end -0.12065 -0.2794)
			(stroke
				(width 0.1)
				(type default)
			)
			(layer "F.Fab")
		)
		(pad "1" smd circle
			(at -0.40005 0 270)
			(size 0 0)
			(layers "F.Cu" "F.Mask" "F.Paste")
			(net "USB3_01_MUX_FB_RXP")
		)
		(pad "2" smd circle
			(at 0.40005 0 270)
			(size 0 0)
			(layers "F.Cu" "F.Mask" "F.Paste")
			(net "USB3_01_FB_RXP")
		)
	)
	(footprint ""
		(layer "F.Cu")
		(at 30.967172 -83.816952 -90)
		(property "Reference" "R663"
			(at 0 0 270)
			(layer "F.SilkS")
			(hide yes)
			(effects
				(font
					(size 1.27 1.27)
				)
			)
		)
		(property "Value" ""
			(at 0 0 270)
			(layer "F.Fab")
			(effects
				(font
					(size 1.27 1.27)
				)
			)
		)
		(duplicate_pad_numbers_are_jumpers no)
		(fp_line
			(start -0.7874 0.4064)
			(end -0.7874 -0.4064)
			(stroke
				(width 0.1524)
				(type default)
			)
			(layer "F.SilkS")
		)
		(fp_line
			(start 0.7874 0.4064)
			(end -0.7874 0.4064)
			(stroke
				(width 0.1524)
				(type default)
			)
			(layer "F.SilkS")
		)
		(fp_line
			(start -0.7874 -0.4064)
			(end 0.7874 -0.4064)
			(stroke
				(width 0.1524)
				(type default)
			)
			(layer "F.SilkS")
		)
		(fp_line
			(start 0.7874 -0.4064)
			(end 0.7874 0.4064)
			(stroke
				(width 0.1524)
				(type default)
			)
			(layer "F.SilkS")
		)
		(fp_line
			(start -0.67945 0.3048)
			(end -0.67945 -0.305054)
			(stroke
				(width 0.1)
				(type default)
			)
			(layer "F.Fab")
		)
		(fp_line
			(start -0.12065 0.3048)
			(end -0.67945 0.3048)
			(stroke
				(width 0.1)
				(type default)
			)
			(layer "F.Fab")
		)
		(fp_line
			(start 0.120396 0.3048)
			(end 0.120396 0.2794)
			(stroke
				(width 0.1)
				(type default)
			)
			(layer "F.Fab")
		)
		(fp_line
			(start 0.67945 0.3048)
			(end 0.120396 0.3048)
			(stroke
				(width 0.1)
				(type default)
			)
			(layer "F.Fab")
		)
		(fp_line
			(start -0.12065 0.2794)
			(end -0.12065 0.3048)
			(stroke
				(width 0.1)
				(type default)
			)
			(layer "F.Fab")
		)
		(fp_line
			(start 0.120396 0.2794)
			(end -0.12065 0.2794)
			(stroke
				(width 0.1)
				(type default)
			)
			(layer "F.Fab")
		)
		(fp_line
			(start -0.12065 -0.2794)
			(end 0.12065 -0.2794)
			(stroke
				(width 0.1)
				(type default)
			)
			(layer "F.Fab")
		)
		(fp_line
			(start 0.12065 -0.2794)
			(end 0.12065 -0.3048)
			(stroke
				(width 0.1)
				(type default)
			)
			(layer "F.Fab")
		)
		(fp_line
			(start 0.12065 -0.3048)
			(end 0.67945 -0.3048)
			(stroke
				(width 0.1)
				(type default)
			)
			(layer "F.Fab")
		)
		(fp_line
			(start 0.67945 -0.3048)
			(end 0.67945 0.3048)
			(stroke
				(width 0.1)
				(type default)
			)
			(layer "F.Fab")
		)
		(fp_line
			(start -0.67945 -0.305054)
			(end -0.12065 -0.305054)
			(stroke
				(width 0.1)
				(type default)
			)
			(layer "F.Fab")
		)
		(fp_line
			(start -0.12065 -0.305054)
			(end -0.12065 -0.2794)
			(stroke
				(width 0.1)
				(type default)
			)
			(layer "F.Fab")
		)
		(pad "1" smd circle
			(at -0.40005 0 270)
			(size 0 0)
			(layers "F.Cu" "F.Mask" "F.Paste")
			(net "P3V3_AUX")
		)
		(pad "2" smd circle
			(at 0.40005 0 270)
			(size 0 0)
			(layers "F.Cu" "F.Mask" "F.Paste")
			(net "EMMC_CMD_R")
		)
	)
	(footprint ""
		(layer "F.Cu")
		(at 19.3421 -37.868352 180)
		(property "Reference" "PC262"
			(at 0 0 180)
			(layer "F.SilkS")
			(hide yes)
			(effects
				(font
					(size 1.27 1.27)
				)
			)
		)
		(property "Value" ""
			(at 0 0 180)
			(layer "F.Fab")
			(effects
				(font
					(size 1.27 1.27)
				)
			)
		)
		(duplicate_pad_numbers_are_jumpers no)
		(fp_line
			(start 1.651 0.8382)
			(end -1.651 0.8382)
			(stroke
				(width 0.1524)
				(type default)
			)
			(layer "F.SilkS")
		)
		(fp_line
			(start 1.651 -0.8382)
			(end 1.651 0.8382)
			(stroke
				(width 0.1524)
				(type default)
			)
			(layer "F.SilkS")
		)
		(fp_line
			(start 0 0.8382)
			(end 0 -0.8382)
			(stroke
				(width 0.1524)
				(type default)
			)
			(layer "F.SilkS")
		)
		(fp_line
			(start -1.651 0.8382)
			(end -1.651 -0.8382)
			(stroke
				(width 0.1524)
				(type default)
			)
			(layer "F.SilkS")
		)
		(fp_line
			(start -1.651 -0.8382)
			(end 1.651 -0.8382)
			(stroke
				(width 0.1524)
				(type default)
			)
			(layer "F.SilkS")
		)
		(fp_line
			(start 1.55956 0.7366)
			(end 1.55956 -0.7366)
			(stroke
				(width 0.1)
				(type default)
			)
			(layer "F.Fab")
		)
		(fp_line
			(start 1.55956 -0.7366)
			(end 1.524 -0.7366)
			(stroke
				(width 0.1)
				(type default)
			)
			(layer "F.Fab")
		)
		(fp_line
			(start 1.524 0.7366)
			(end 1.55956 0.7366)
			(stroke
				(width 0.1)
				(type default)
			)
			(layer "F.Fab")
		)
		(fp_line
			(start 1.524 -0.7366)
			(end -1.524 -0.7366)
			(stroke
				(width 0.1)
				(type default)
			)
			(layer "F.Fab")
		)
		(fp_line
			(start -1.524 0.7366)
			(end 1.524 0.7366)
			(stroke
				(width 0.1)
				(type default)
			)
			(layer "F.Fab")
		)
		(fp_line
			(start -1.524 -0.7366)
			(end -1.55956 -0.7366)
			(stroke
				(width 0.1)
				(type default)
			)
			(layer "F.Fab")
		)
		(fp_line
			(start -1.55956 0.7366)
			(end -1.524 0.7366)
			(stroke
				(width 0.1)
				(type default)
			)
			(layer "F.Fab")
		)
		(fp_line
			(start -1.55956 -0.7366)
			(end -1.55956 0.7366)
			(stroke
				(width 0.1)
				(type default)
			)
			(layer "F.Fab")
		)
		(pad "1" smd rect
			(at -0.94996 0)
			(size 1.1176 1.3716)
			(layers "F.Cu" "F.Mask" "F.Paste")
			(net "SW_P1V0_AUX_FLT")
		)
		(pad "2" smd rect
			(at 0.94996 0)
			(size 1.1176 1.3716)
			(layers "F.Cu" "F.Mask" "F.Paste")
			(net "GND")
		)
	)
	(footprint ""
		(layer "F.Cu")
		(at 25.781 -65.913 -90)
		(property "Reference" "R39"
			(at 0 0 270)
			(layer "F.SilkS")
			(hide yes)
			(effects
				(font
					(size 1.27 1.27)
				)
			)
		)
		(property "Value" ""
			(at 0 0 270)
			(layer "F.Fab")
			(effects
				(font
					(size 1.27 1.27)
				)
			)
		)
		(duplicate_pad_numbers_are_jumpers no)
		(fp_line
			(start -0.7874 0.4064)
			(end -0.7874 -0.4064)
			(stroke
				(width 0.1524)
				(type default)
			)
			(layer "F.SilkS")
		)
		(fp_line
			(start 0.7874 0.4064)
			(end -0.7874 0.4064)
			(stroke
				(width 0.1524)
				(type default)
			)
			(layer "F.SilkS")
		)
		(fp_line
			(start -0.7874 -0.4064)
			(end 0.7874 -0.4064)
			(stroke
				(width 0.1524)
				(type default)
			)
			(layer "F.SilkS")
		)
		(fp_line
			(start 0.7874 -0.4064)
			(end 0.7874 0.4064)
			(stroke
				(width 0.1524)
				(type default)
			)
			(layer "F.SilkS")
		)
		(fp_line
			(start -0.67945 0.3048)
			(end -0.67945 -0.305054)
			(stroke
				(width 0.1)
				(type default)
			)
			(layer "F.Fab")
		)
		(fp_line
			(start -0.12065 0.3048)
			(end -0.67945 0.3048)
			(stroke
				(width 0.1)
				(type default)
			)
			(layer "F.Fab")
		)
		(fp_line
			(start 0.120396 0.3048)
			(end 0.120396 0.2794)
			(stroke
				(width 0.1)
				(type default)
			)
			(layer "F.Fab")
		)
		(fp_line
			(start 0.67945 0.3048)
			(end 0.120396 0.3048)
			(stroke
				(width 0.1)
				(type default)
			)
			(layer "F.Fab")
		)
		(fp_line
			(start -0.12065 0.2794)
			(end -0.12065 0.3048)
			(stroke
				(width 0.1)
				(type default)
			)
			(layer "F.Fab")
		)
		(fp_line
			(start 0.120396 0.2794)
			(end -0.12065 0.2794)
			(stroke
				(width 0.1)
				(type default)
			)
			(layer "F.Fab")
		)
		(fp_line
			(start -0.12065 -0.2794)
			(end 0.12065 -0.2794)
			(stroke
				(width 0.1)
				(type default)
			)
			(layer "F.Fab")
		)
		(fp_line
			(start 0.12065 -0.2794)
			(end 0.12065 -0.3048)
			(stroke
				(width 0.1)
				(type default)
			)
			(layer "F.Fab")
		)
		(fp_line
			(start 0.12065 -0.3048)
			(end 0.67945 -0.3048)
			(stroke
				(width 0.1)
				(type default)
			)
			(layer "F.Fab")
		)
		(fp_line
			(start 0.67945 -0.3048)
			(end 0.67945 0.3048)
			(stroke
				(width 0.1)
				(type default)
			)
			(layer "F.Fab")
		)
		(fp_line
			(start -0.67945 -0.305054)
			(end -0.12065 -0.305054)
			(stroke
				(width 0.1)
				(type default)
			)
			(layer "F.Fab")
		)
		(fp_line
			(start -0.12065 -0.305054)
			(end -0.12065 -0.2794)
			(stroke
				(width 0.1)
				(type default)
			)
			(layer "F.Fab")
		)
		(pad "1" smd circle
			(at -0.40005 0 270)
			(size 0 0)
			(layers "F.Cu" "F.Mask" "F.Paste")
			(net "SPA_SOUT_SW_BUF_R")
		)
		(pad "2" smd circle
			(at 0.40005 0 270)
			(size 0 0)
			(layers "F.Cu" "F.Mask" "F.Paste")
			(net "SPA_SOUT_SW_BUF")
		)
	)
	(footprint ""
		(layer "F.Cu")
		(at 41.8592 -28.6512 180)
		(property "Reference" "C180"
			(at 0 0 180)
			(layer "F.SilkS")
			(hide yes)
			(effects
				(font
					(size 1.27 1.27)
				)
			)
		)
		(property "Value" ""
			(at 0 0 180)
			(layer "F.Fab")
			(effects
				(font
					(size 1.27 1.27)
				)
			)
		)
		(duplicate_pad_numbers_are_jumpers no)
		(fp_line
			(start 0.7874 0.4064)
			(end -0.7874 0.4064)
			(stroke
				(width 0.1524)
				(type default)
			)
			(layer "F.SilkS")
		)
		(fp_line
			(start 0.7874 -0.4064)
			(end 0.7874 0.4064)
			(stroke
				(width 0.1524)
				(type default)
			)
			(layer "F.SilkS")
		)
		(fp_line
			(start -0.7874 0.4064)
			(end -0.7874 -0.4064)
			(stroke
				(width 0.1524)
				(type default)
			)
			(layer "F.SilkS")
		)
		(fp_line
			(start -0.7874 -0.4064)
			(end 0.7874 -0.4064)
			(stroke
				(width 0.1524)
				(type default)
			)
			(layer "F.SilkS")
		)
		(fp_line
			(start 0.67945 0.3048)
			(end 0.120396 0.3048)
			(stroke
				(width 0.1)
				(type default)
			)
			(layer "F.Fab")
		)
		(fp_line
			(start 0.67945 -0.3048)
			(end 0.67945 0.3048)
			(stroke
				(width 0.1)
				(type default)
			)
			(layer "F.Fab")
		)
		(fp_line
			(start 0.12065 -0.2794)
			(end 0.12065 -0.3048)
			(stroke
				(width 0.1)
				(type default)
			)
			(layer "F.Fab")
		)
		(fp_line
			(start 0.12065 -0.3048)
			(end 0.67945 -0.3048)
			(stroke
				(width 0.1)
				(type default)
			)
			(layer "F.Fab")
		)
		(fp_line
			(start 0.120396 0.3048)
			(end 0.120396 0.2794)
			(stroke
				(width 0.1)
				(type default)
			)
			(layer "F.Fab")
		)
		(fp_line
			(start 0.120396 0.2794)
			(end -0.12065 0.2794)
			(stroke
				(width 0.1)
				(type default)
			)
			(layer "F.Fab")
		)
		(fp_line
			(start -0.12065 0.3048)
			(end -0.67945 0.3048)
			(stroke
				(width 0.1)
				(type default)
			)
			(layer "F.Fab")
		)
		(fp_line
			(start -0.12065 0.2794)
			(end -0.12065 0.3048)
			(stroke
				(width 0.1)
				(type default)
			)
			(layer "F.Fab")
		)
		(fp_line
			(start -0.12065 -0.2794)
			(end 0.12065 -0.2794)
			(stroke
				(width 0.1)
				(type default)
			)
			(layer "F.Fab")
		)
		(fp_line
			(start -0.12065 -0.305054)
			(end -0.12065 -0.2794)
			(stroke
				(width 0.1)
				(type default)
			)
			(layer "F.Fab")
		)
		(fp_line
			(start -0.67945 0.3048)
			(end -0.67945 -0.305054)
			(stroke
				(width 0.1)
				(type default)
			)
			(layer "F.Fab")
		)
		(fp_line
			(start -0.67945 -0.305054)
			(end -0.12065 -0.305054)
			(stroke
				(width 0.1)
				(type default)
			)
			(layer "F.Fab")
		)
		(pad "1" smd circle
			(at -0.40005 0 180)
			(size 0 0)
			(layers "F.Cu" "F.Mask" "F.Paste")
			(net "P3V3_LDO")
		)
		(pad "2" smd circle
			(at 0.40005 0 180)
			(size 0 0)
			(layers "F.Cu" "F.Mask" "F.Paste")
			(net "GND")
		)
	)
	(footprint ""
		(layer "F.Cu")
		(at 41.572942 -22.15642 -90)
		(property "Reference" "R666"
			(at 0 0 270)
			(layer "F.SilkS")
			(hide yes)
			(effects
				(font
					(size 1.27 1.27)
				)
			)
		)
		(property "Value" ""
			(at 0 0 270)
			(layer "F.Fab")
			(effects
				(font
					(size 1.27 1.27)
				)
			)
		)
		(duplicate_pad_numbers_are_jumpers no)
		(fp_line
			(start 0.7874 0.4064)
			(end -0.7874 0.4064)
			(stroke
				(width 0.1524)
				(type default)
			)
			(layer "F.SilkS")
		)
		(fp_line
			(start -0.7874 -0.4064)
			(end 0.7874 -0.4064)
			(stroke
				(width 0.1524)
				(type default)
			)
			(layer "F.SilkS")
		)
		(fp_line
			(start -0.67945 0.3048)
			(end -0.67945 -0.305054)
			(stroke
				(width 0.1)
				(type default)
			)
			(layer "F.Fab")
		)
		(fp_line
			(start -0.12065 0.3048)
			(end -0.67945 0.3048)
			(stroke
				(width 0.1)
				(type default)
			)
			(layer "F.Fab")
		)
		(fp_line
			(start 0.120396 0.3048)
			(end 0.120396 0.2794)
			(stroke
				(width 0.1)
				(type default)
			)
			(layer "F.Fab")
		)
		(fp_line
			(start 0.67945 0.3048)
			(end 0.120396 0.3048)
			(stroke
				(width 0.1)
				(type default)
			)
			(layer "F.Fab")
		)
		(fp_line
			(start -0.12065 0.2794)
			(end -0.12065 0.3048)
			(stroke
				(width 0.1)
				(type default)
			)
			(layer "F.Fab")
		)
		(fp_line
			(start 0.120396 0.2794)
			(end -0.12065 0.2794)
			(stroke
				(width 0.1)
				(type default)
			)
			(layer "F.Fab")
		)
		(fp_line
			(start -0.12065 -0.2794)
			(end 0.12065 -0.2794)
			(stroke
				(width 0.1)
				(type default)
			)
			(layer "F.Fab")
		)
		(fp_line
			(start 0.12065 -0.2794)
			(end 0.12065 -0.3048)
			(stroke
				(width 0.1)
				(type default)
			)
			(layer "F.Fab")
		)
		(fp_line
			(start 0.12065 -0.3048)
			(end 0.67945 -0.3048)
			(stroke
				(width 0.1)
				(type default)
			)
			(layer "F.Fab")
		)
		(fp_line
			(start 0.67945 -0.3048)
			(end 0.67945 0.3048)
			(stroke
				(width 0.1)
				(type default)
			)
			(layer "F.Fab")
		)
		(fp_line
			(start -0.67945 -0.305054)
			(end -0.12065 -0.305054)
			(stroke
				(width 0.1)
				(type default)
			)
			(layer "F.Fab")
		)
		(fp_line
			(start -0.12065 -0.305054)
			(end -0.12065 -0.2794)
			(stroke
				(width 0.1)
				(type default)
			)
			(layer "F.Fab")
		)
		(pad "1" smd circle
			(at -0.40005 0 270)
			(size 0 0)
			(layers "F.Cu" "F.Mask" "F.Paste")
			(net "USB3_01_MUX_FB_TXN")
		)
		(pad "2" smd circle
			(at 0.40005 0 270)
			(size 0 0)
			(layers "F.Cu" "F.Mask" "F.Paste")
			(net "USB3_01_FB_TXN")
		)
	)
	(footprint ""
		(layer "F.Cu")
		(at 39.50462 -30.63748 90)
		(property "Reference" "R213"
			(at 0 0 90)
			(layer "F.SilkS")
			(hide yes)
			(effects
				(font
					(size 1.27 1.27)
				)
			)
		)
		(property "Value" ""
			(at 0 0 90)
			(layer "F.Fab")
			(effects
				(font
					(size 1.27 1.27)
				)
			)
		)
		(duplicate_pad_numbers_are_jumpers no)
		(fp_line
			(start 0.7874 -0.4064)
			(end 0.7874 0.4064)
			(stroke
				(width 0.1524)
				(type default)
			)
			(layer "F.SilkS")
		)
		(fp_line
			(start -0.7874 -0.4064)
			(end 0.7874 -0.4064)
			(stroke
				(width 0.1524)
				(type default)
			)
			(layer "F.SilkS")
		)
		(fp_line
			(start 0.7874 0.4064)
			(end -0.7874 0.4064)
			(stroke
				(width 0.1524)
				(type default)
			)
			(layer "F.SilkS")
		)
		(fp_line
			(start -0.7874 0.4064)
			(end -0.7874 -0.4064)
			(stroke
				(width 0.1524)
				(type default)
			)
			(layer "F.SilkS")
		)
		(fp_line
			(start -0.12065 -0.305054)
			(end -0.12065 -0.2794)
			(stroke
				(width 0.1)
				(type default)
			)
			(layer "F.Fab")
		)
		(fp_line
			(start -0.67945 -0.305054)
			(end -0.12065 -0.305054)
			(stroke
				(width 0.1)
				(type default)
			)
			(layer "F.Fab")
		)
		(fp_line
			(start 0.67945 -0.3048)
			(end 0.67945 0.3048)
			(stroke
				(width 0.1)
				(type default)
			)
			(layer "F.Fab")
		)
		(fp_line
			(start 0.12065 -0.3048)
			(end 0.67945 -0.3048)
			(stroke
				(width 0.1)
				(type default)
			)
			(layer "F.Fab")
		)
		(fp_line
			(start 0.12065 -0.2794)
			(end 0.12065 -0.3048)
			(stroke
				(width 0.1)
				(type default)
			)
			(layer "F.Fab")
		)
		(fp_line
			(start -0.12065 -0.2794)
			(end 0.12065 -0.2794)
			(stroke
				(width 0.1)
				(type default)
			)
			(layer "F.Fab")
		)
		(fp_line
			(start 0.120396 0.2794)
			(end -0.12065 0.2794)
			(stroke
				(width 0.1)
				(type default)
			)
			(layer "F.Fab")
		)
		(fp_line
			(start -0.12065 0.2794)
			(end -0.12065 0.3048)
			(stroke
				(width 0.1)
				(type default)
			)
			(layer "F.Fab")
		)
		(fp_line
			(start 0.67945 0.3048)
			(end 0.120396 0.3048)
			(stroke
				(width 0.1)
				(type default)
			)
			(layer "F.Fab")
		)
		(fp_line
			(start 0.120396 0.3048)
			(end 0.120396 0.2794)
			(stroke
				(width 0.1)
				(type default)
			)
			(layer "F.Fab")
		)
		(fp_line
			(start -0.12065 0.3048)
			(end -0.67945 0.3048)
			(stroke
				(width 0.1)
				(type default)
			)
			(layer "F.Fab")
		)
		(fp_line
			(start -0.67945 0.3048)
			(end -0.67945 -0.305054)
			(stroke
				(width 0.1)
				(type default)
			)
			(layer "F.Fab")
		)
		(pad "1" smd circle
			(at -0.40005 0 90)
			(size 0 0)
			(layers "F.Cu" "F.Mask" "F.Paste")
			(net "P3V3_AUX")
		)
		(pad "2" smd circle
			(at 0.40005 0 90)
			(size 0 0)
			(layers "F.Cu" "F.Mask" "F.Paste")
			(net "P3V3_P1V8_SD2VDD")
		)
	)
	(footprint ""
		(layer "F.Cu")
		(at 77.343 -20.193 180)
		(property "Reference" "R284"
			(at 0 0 180)
			(layer "F.SilkS")
			(hide yes)
			(effects
				(font
					(size 1.27 1.27)
				)
			)
		)
		(property "Value" ""
			(at 0 0 180)
			(layer "F.Fab")
			(effects
				(font
					(size 1.27 1.27)
				)
			)
		)
		(duplicate_pad_numbers_are_jumpers no)
		(fp_line
			(start 0.7874 0.4064)
			(end -0.7874 0.4064)
			(stroke
				(width 0.1524)
				(type default)
			)
			(layer "F.SilkS")
		)
		(fp_line
			(start 0.7874 -0.4064)
			(end 0.7874 0.4064)
			(stroke
				(width 0.1524)
				(type default)
			)
			(layer "F.SilkS")
		)
		(fp_line
			(start -0.7874 0.4064)
			(end -0.7874 -0.4064)
			(stroke
				(width 0.1524)
				(type default)
			)
			(layer "F.SilkS")
		)
		(fp_line
			(start -0.7874 -0.4064)
			(end 0.7874 -0.4064)
			(stroke
				(width 0.1524)
				(type default)
			)
			(layer "F.SilkS")
		)
		(fp_line
			(start 0.67945 0.3048)
			(end 0.120396 0.3048)
			(stroke
				(width 0.1)
				(type default)
			)
			(layer "F.Fab")
		)
		(fp_line
			(start 0.67945 -0.3048)
			(end 0.67945 0.3048)
			(stroke
				(width 0.1)
				(type default)
			)
			(layer "F.Fab")
		)
		(fp_line
			(start 0.12065 -0.2794)
			(end 0.12065 -0.3048)
			(stroke
				(width 0.1)
				(type default)
			)
			(layer "F.Fab")
		)
		(fp_line
			(start 0.12065 -0.3048)
			(end 0.67945 -0.3048)
			(stroke
				(width 0.1)
				(type default)
			)
			(layer "F.Fab")
		)
		(fp_line
			(start 0.120396 0.3048)
			(end 0.120396 0.2794)
			(stroke
				(width 0.1)
				(type default)
			)
			(layer "F.Fab")
		)
		(fp_line
			(start 0.120396 0.2794)
			(end -0.12065 0.2794)
			(stroke
				(width 0.1)
				(type default)
			)
			(layer "F.Fab")
		)
		(fp_line
			(start -0.12065 0.3048)
			(end -0.67945 0.3048)
			(stroke
				(width 0.1)
				(type default)
			)
			(layer "F.Fab")
		)
		(fp_line
			(start -0.12065 0.2794)
			(end -0.12065 0.3048)
			(stroke
				(width 0.1)
				(type default)
			)
			(layer "F.Fab")
		)
		(fp_line
			(start -0.12065 -0.2794)
			(end 0.12065 -0.2794)
			(stroke
				(width 0.1)
				(type default)
			)
			(layer "F.Fab")
		)
		(fp_line
			(start -0.12065 -0.305054)
			(end -0.12065 -0.2794)
			(stroke
				(width 0.1)
				(type default)
			)
			(layer "F.Fab")
		)
		(fp_line
			(start -0.67945 0.3048)
			(end -0.67945 -0.305054)
			(stroke
				(width 0.1)
				(type default)
			)
			(layer "F.Fab")
		)
		(fp_line
			(start -0.67945 -0.305054)
			(end -0.12065 -0.305054)
			(stroke
				(width 0.1)
				(type default)
			)
			(layer "F.Fab")
		)
		(pad "1" smd circle
			(at -0.40005 0 180)
			(size 0 0)
			(layers "F.Cu" "F.Mask" "F.Paste")
			(net "FM_UARTSW_MSB_N")
		)
		(pad "2" smd circle
			(at 0.40005 0 180)
			(size 0 0)
			(layers "F.Cu" "F.Mask" "F.Paste")
			(net "FM_UARTSW_MSB_R1_N")
		)
	)
	(footprint ""
		(layer "F.Cu")
		(at 20.066 -102.743 90)
		(property "Reference" "R323"
			(at 0 0 90)
			(layer "F.SilkS")
			(hide yes)
			(effects
				(font
					(size 1.27 1.27)
				)
			)
		)
		(property "Value" ""
			(at 0 0 90)
			(layer "F.Fab")
			(effects
				(font
					(size 1.27 1.27)
				)
			)
		)
		(duplicate_pad_numbers_are_jumpers no)
		(fp_line
			(start 0.7874 -0.4064)
			(end 0.7874 0.4064)
			(stroke
				(width 0.1524)
				(type default)
			)
			(layer "F.SilkS")
		)
		(fp_line
			(start -0.7874 -0.4064)
			(end 0.7874 -0.4064)
			(stroke
				(width 0.1524)
				(type default)
			)
			(layer "F.SilkS")
		)
		(fp_line
			(start 0.7874 0.4064)
			(end -0.7874 0.4064)
			(stroke
				(width 0.1524)
				(type default)
			)
			(layer "F.SilkS")
		)
		(fp_line
			(start -0.7874 0.4064)
			(end -0.7874 -0.4064)
			(stroke
				(width 0.1524)
				(type default)
			)
			(layer "F.SilkS")
		)
		(fp_line
			(start -0.12065 -0.305054)
			(end -0.12065 -0.2794)
			(stroke
				(width 0.1)
				(type default)
			)
			(layer "F.Fab")
		)
		(fp_line
			(start -0.67945 -0.305054)
			(end -0.12065 -0.305054)
			(stroke
				(width 0.1)
				(type default)
			)
			(layer "F.Fab")
		)
		(fp_line
			(start 0.67945 -0.3048)
			(end 0.67945 0.3048)
			(stroke
				(width 0.1)
				(type default)
			)
			(layer "F.Fab")
		)
		(fp_line
			(start 0.12065 -0.3048)
			(end 0.67945 -0.3048)
			(stroke
				(width 0.1)
				(type default)
			)
			(layer "F.Fab")
		)
		(fp_line
			(start 0.12065 -0.2794)
			(end 0.12065 -0.3048)
			(stroke
				(width 0.1)
				(type default)
			)
			(layer "F.Fab")
		)
		(fp_line
			(start -0.12065 -0.2794)
			(end 0.12065 -0.2794)
			(stroke
				(width 0.1)
				(type default)
			)
			(layer "F.Fab")
		)
		(fp_line
			(start 0.120396 0.2794)
			(end -0.12065 0.2794)
			(stroke
				(width 0.1)
				(type default)
			)
			(layer "F.Fab")
		)
		(fp_line
			(start -0.12065 0.2794)
			(end -0.12065 0.3048)
			(stroke
				(width 0.1)
				(type default)
			)
			(layer "F.Fab")
		)
		(fp_line
			(start 0.67945 0.3048)
			(end 0.120396 0.3048)
			(stroke
				(width 0.1)
				(type default)
			)
			(layer "F.Fab")
		)
		(fp_line
			(start 0.120396 0.3048)
			(end 0.120396 0.2794)
			(stroke
				(width 0.1)
				(type default)
			)
			(layer "F.Fab")
		)
		(fp_line
			(start -0.12065 0.3048)
			(end -0.67945 0.3048)
			(stroke
				(width 0.1)
				(type default)
			)
			(layer "F.Fab")
		)
		(fp_line
			(start -0.67945 0.3048)
			(end -0.67945 -0.305054)
			(stroke
				(width 0.1)
				(type default)
			)
			(layer "F.Fab")
		)
		(pad "1" smd circle
			(at -0.40005 0 90)
			(size 0 0)
			(layers "F.Cu" "F.Mask" "F.Paste")
			(net "PWRGD_P1V2_AUX_R1")
		)
		(pad "2" smd circle
			(at 0.40005 0 90)
			(size 0 0)
			(layers "F.Cu" "F.Mask" "F.Paste")
			(net "PWRGD_P1V2_AUX")
		)
	)
	(footprint ""
		(layer "F.Cu")
		(at 11.761978 -52.008532 90)
		(property "Reference" "PC205"
			(at 0 0 90)
			(layer "F.SilkS")
			(hide yes)
			(effects
				(font
					(size 1.27 1.27)
				)
			)
		)
		(property "Value" ""
			(at 0 0 90)
			(layer "F.Fab")
			(effects
				(font
					(size 1.27 1.27)
				)
			)
		)
		(duplicate_pad_numbers_are_jumpers no)
		(fp_line
			(start 0.7874 -0.4064)
			(end 0.7874 0.4064)
			(stroke
				(width 0.1524)
				(type default)
			)
			(layer "F.SilkS")
		)
		(fp_line
			(start -0.7874 -0.4064)
			(end 0.7874 -0.4064)
			(stroke
				(width 0.1524)
				(type default)
			)
			(layer "F.SilkS")
		)
		(fp_line
			(start 0.7874 0.4064)
			(end -0.7874 0.4064)
			(stroke
				(width 0.1524)
				(type default)
			)
			(layer "F.SilkS")
		)
		(fp_line
			(start -0.7874 0.4064)
			(end -0.7874 -0.4064)
			(stroke
				(width 0.1524)
				(type default)
			)
			(layer "F.SilkS")
		)
		(fp_line
			(start -0.12065 -0.305054)
			(end -0.12065 -0.2794)
			(stroke
				(width 0.1)
				(type default)
			)
			(layer "F.Fab")
		)
		(fp_line
			(start -0.67945 -0.305054)
			(end -0.12065 -0.305054)
			(stroke
				(width 0.1)
				(type default)
			)
			(layer "F.Fab")
		)
		(fp_line
			(start 0.67945 -0.3048)
			(end 0.67945 0.3048)
			(stroke
				(width 0.1)
				(type default)
			)
			(layer "F.Fab")
		)
		(fp_line
			(start 0.12065 -0.3048)
			(end 0.67945 -0.3048)
			(stroke
				(width 0.1)
				(type default)
			)
			(layer "F.Fab")
		)
		(fp_line
			(start 0.12065 -0.2794)
			(end 0.12065 -0.3048)
			(stroke
				(width 0.1)
				(type default)
			)
			(layer "F.Fab")
		)
		(fp_line
			(start -0.12065 -0.2794)
			(end 0.12065 -0.2794)
			(stroke
				(width 0.1)
				(type default)
			)
			(layer "F.Fab")
		)
		(fp_line
			(start 0.120396 0.2794)
			(end -0.12065 0.2794)
			(stroke
				(width 0.1)
				(type default)
			)
			(layer "F.Fab")
		)
		(fp_line
			(start -0.12065 0.2794)
			(end -0.12065 0.3048)
			(stroke
				(width 0.1)
				(type default)
			)
			(layer "F.Fab")
		)
		(fp_line
			(start 0.67945 0.3048)
			(end 0.120396 0.3048)
			(stroke
				(width 0.1)
				(type default)
			)
			(layer "F.Fab")
		)
		(fp_line
			(start 0.120396 0.3048)
			(end 0.120396 0.2794)
			(stroke
				(width 0.1)
				(type default)
			)
			(layer "F.Fab")
		)
		(fp_line
			(start -0.12065 0.3048)
			(end -0.67945 0.3048)
			(stroke
				(width 0.1)
				(type default)
			)
			(layer "F.Fab")
		)
		(fp_line
			(start -0.67945 0.3048)
			(end -0.67945 -0.305054)
			(stroke
				(width 0.1)
				(type default)
			)
			(layer "F.Fab")
		)
		(pad "1" smd circle
			(at -0.40005 0 90)
			(size 0 0)
			(layers "F.Cu" "F.Mask" "F.Paste")
			(net "EN_P5V_AUX")
		)
		(pad "2" smd circle
			(at 0.40005 0 90)
			(size 0 0)
			(layers "F.Cu" "F.Mask" "F.Paste")
			(net "GND")
		)
	)
	(footprint ""
		(layer "F.Cu")
		(at 12.799568 -50.110898 -90)
		(property "Reference" "PC272"
			(at 0 0 270)
			(layer "F.SilkS")
			(hide yes)
			(effects
				(font
					(size 1.27 1.27)
				)
			)
		)
		(property "Value" ""
			(at 0 0 270)
			(layer "F.Fab")
			(effects
				(font
					(size 1.27 1.27)
				)
			)
		)
		(duplicate_pad_numbers_are_jumpers no)
		(fp_line
			(start -0.7874 0.4064)
			(end -0.7874 -0.4064)
			(stroke
				(width 0.1524)
				(type default)
			)
			(layer "F.SilkS")
		)
		(fp_line
			(start 0.7874 0.4064)
			(end -0.7874 0.4064)
			(stroke
				(width 0.1524)
				(type default)
			)
			(layer "F.SilkS")
		)
		(fp_line
			(start -0.7874 -0.4064)
			(end 0.7874 -0.4064)
			(stroke
				(width 0.1524)
				(type default)
			)
			(layer "F.SilkS")
		)
		(fp_line
			(start 0.7874 -0.4064)
			(end 0.7874 0.4064)
			(stroke
				(width 0.1524)
				(type default)
			)
			(layer "F.SilkS")
		)
		(fp_line
			(start -0.67945 0.3048)
			(end -0.67945 -0.305054)
			(stroke
				(width 0.1)
				(type default)
			)
			(layer "F.Fab")
		)
		(fp_line
			(start -0.12065 0.3048)
			(end -0.67945 0.3048)
			(stroke
				(width 0.1)
				(type default)
			)
			(layer "F.Fab")
		)
		(fp_line
			(start 0.120396 0.3048)
			(end 0.120396 0.2794)
			(stroke
				(width 0.1)
				(type default)
			)
			(layer "F.Fab")
		)
		(fp_line
			(start 0.67945 0.3048)
			(end 0.120396 0.3048)
			(stroke
				(width 0.1)
				(type default)
			)
			(layer "F.Fab")
		)
		(fp_line
			(start -0.12065 0.2794)
			(end -0.12065 0.3048)
			(stroke
				(width 0.1)
				(type default)
			)
			(layer "F.Fab")
		)
		(fp_line
			(start 0.120396 0.2794)
			(end -0.12065 0.2794)
			(stroke
				(width 0.1)
				(type default)
			)
			(layer "F.Fab")
		)
		(fp_line
			(start -0.12065 -0.2794)
			(end 0.12065 -0.2794)
			(stroke
				(width 0.1)
				(type default)
			)
			(layer "F.Fab")
		)
		(fp_line
			(start 0.12065 -0.2794)
			(end 0.12065 -0.3048)
			(stroke
				(width 0.1)
				(type default)
			)
			(layer "F.Fab")
		)
		(fp_line
			(start 0.12065 -0.3048)
			(end 0.67945 -0.3048)
			(stroke
				(width 0.1)
				(type default)
			)
			(layer "F.Fab")
		)
		(fp_line
			(start 0.67945 -0.3048)
			(end 0.67945 0.3048)
			(stroke
				(width 0.1)
				(type default)
			)
			(layer "F.Fab")
		)
		(fp_line
			(start -0.67945 -0.305054)
			(end -0.12065 -0.305054)
			(stroke
				(width 0.1)
				(type default)
			)
			(layer "F.Fab")
		)
		(fp_line
			(start -0.12065 -0.305054)
			(end -0.12065 -0.2794)
			(stroke
				(width 0.1)
				(type default)
			)
			(layer "F.Fab")
		)
		(pad "1" smd circle
			(at -0.40005 0 270)
			(size 0 0)
			(layers "F.Cu" "F.Mask" "F.Paste")
			(net "P5V_AUX_FB")
		)
		(pad "2" smd circle
			(at 0.40005 0 270)
			(size 0 0)
			(layers "F.Cu" "F.Mask" "F.Paste")
			(net "P5V_AUX")
		)
	)
	(footprint ""
		(layer "F.Cu")
		(at 39.500302 -97.910142 90)
		(property "Reference" "U17"
			(at 1.861058 9.345168 90)
			(unlocked yes)
			(layer "F.SilkS")
			(effects
				(font
					(size 0.7874 0.5842)
					(thickness 0.1524)
				)
				(justify left)
			)
		)
		(property "Value" ""
			(at 0 0 90)
			(layer "F.Fab")
			(effects
				(font
					(size 1.27 1.27)
				)
			)
		)
		(duplicate_pad_numbers_are_jumpers no)
		(fp_line
			(start 3.800094 -5.249926)
			(end 3.800094 5.249926)
			(stroke
				(width 0.1524)
				(type default)
			)
			(layer "F.SilkS")
		)
		(fp_line
			(start 1.693926 -5.249926)
			(end 3.800094 -5.249926)
			(stroke
				(width 0.1524)
				(type default)
			)
			(layer "F.SilkS")
		)
		(fp_line
			(start -1.693926 -5.249926)
			(end 0 -4.064)
			(stroke
				(width 0.1524)
				(type default)
			)
			(layer "F.SilkS")
		)
		(fp_line
			(start -3.800094 -5.249926)
			(end -1.693926 -5.249926)
			(stroke
				(width 0.1524)
				(type default)
			)
			(layer "F.SilkS")
		)
		(fp_line
			(start 0 -4.064)
			(end 1.693926 -5.249926)
			(stroke
				(width 0.1524)
				(type default)
			)
			(layer "F.SilkS")
		)
		(fp_line
			(start 3.800094 5.249926)
			(end -3.800094 5.249926)
			(stroke
				(width 0.1524)
				(type default)
			)
			(layer "F.SilkS")
		)
		(fp_line
			(start -3.800094 5.249926)
			(end -3.800094 -5.249926)
			(stroke
				(width 0.1524)
				(type default)
			)
			(layer "F.SilkS")
		)
		(fp_poly
			(pts
				(xy -8.128254 -4.953254) (xy -8.128254 -3.937254) (xy -7.112254 -4.445254)
			)
			(stroke
				(width 0)
				(type default)
			)
			(fill yes)
			(layer "F.SilkS")
		)
		(fp_line
			(start 3.800094 -5.249926)
			(end -3.800094 -5.249926)
			(stroke
				(width 0.1)
				(type default)
			)
			(layer "F.Fab")
		)
		(fp_line
			(start -3.800094 -5.249926)
			(end -3.800094 5.249926)
			(stroke
				(width 0.1)
				(type default)
			)
			(layer "F.Fab")
		)
		(fp_line
			(start 3.800094 5.249926)
			(end 3.800094 -5.249926)
			(stroke
				(width 0.1)
				(type default)
			)
			(layer "F.Fab")
		)
		(fp_line
			(start -3.800094 5.249926)
			(end 3.800094 5.249926)
			(stroke
				(width 0.1)
				(type default)
			)
			(layer "F.Fab")
		)
		(fp_poly
			(pts
				(xy -7.2644 -4.953) (xy -7.2644 -3.937) (xy -6.2484 -4.445)
			)
			(stroke
				(width 0)
				(type default)
			)
			(fill yes)
			(layer "F.Fab")
		)
		(pad "1" smd rect
			(at -5.150104 -4.445)
			(size 0.4318 1.7018)
			(layers "F.Cu" "F.Mask" "F.Paste")
			(net "SPI_PCH_IO3_FLASH_R1")
		)
		(pad "2" smd rect
			(at -5.150104 -3.175)
			(size 0.4318 1.7018)
			(layers "F.Cu" "F.Mask" "F.Paste")
			(net "P3V3_AUX")
		)
		(pad "3" smd rect
			(at -5.150104 -1.905)
			(size 0.4318 1.7018)
			(layers "F.Cu" "F.Mask" "F.Paste")
			(net "RST_SPI_PCH_FLASH_R1_N")
		)
		(pad "4" smd rect
			(at -5.150104 -0.635)
			(size 0.4318 1.7018)
			(layers "F.Cu" "F.Mask" "F.Paste")
			(net "TP_J40_4")
		)
		(pad "5" smd rect
			(at -5.150104 0.635)
			(size 0.4318 1.7018)
			(layers "F.Cu" "F.Mask" "F.Paste")
			(net "TP_J40_5")
		)
		(pad "6" smd rect
			(at -5.150104 1.905)
			(size 0.4318 1.7018)
			(layers "F.Cu" "F.Mask" "F.Paste")
			(net "TP_J40_6")
		)
		(pad "7" smd rect
			(at -5.150104 3.175)
			(size 0.4318 1.7018)
			(layers "F.Cu" "F.Mask" "F.Paste")
			(net "SPI_PCH_CS0_FLASH_R1_N")
		)
		(pad "8" smd rect
			(at -5.150104 4.445)
			(size 0.4318 1.7018)
			(layers "F.Cu" "F.Mask" "F.Paste")
			(net "SPI_PCH_IO1_FLASH_R1")
		)
		(pad "9" smd rect
			(at 5.150104 4.445)
			(size 0.4318 1.7018)
			(layers "F.Cu" "F.Mask" "F.Paste")
			(net "SPI_PCH_IO2_FLASH_R1")
		)
		(pad "10" smd rect
			(at 5.150104 3.175)
			(size 0.4318 1.7018)
			(layers "F.Cu" "F.Mask" "F.Paste")
			(net "GND")
		)
		(pad "11" smd rect
			(at 5.150104 1.905)
			(size 0.4318 1.7018)
			(layers "F.Cu" "F.Mask" "F.Paste")
			(net "TP_J40_11")
		)
		(pad "12" smd rect
			(at 5.150104 0.635)
			(size 0.4318 1.7018)
			(layers "F.Cu" "F.Mask" "F.Paste")
			(net "TP_J40_12")
		)
		(pad "13" smd rect
			(at 5.150104 -0.635)
			(size 0.4318 1.7018)
			(layers "F.Cu" "F.Mask" "F.Paste")
			(net "TP_J40_13")
		)
		(pad "14" smd rect
			(at 5.150104 -1.905)
			(size 0.4318 1.7018)
			(layers "F.Cu" "F.Mask" "F.Paste")
			(net "TP_J40_14")
		)
		(pad "15" smd rect
			(at 5.150104 -3.175)
			(size 0.4318 1.7018)
			(layers "F.Cu" "F.Mask" "F.Paste")
			(net "SPI_PCH_IO0_FLASH_R1")
		)
		(pad "16" smd rect
			(at 5.150104 -4.445)
			(size 0.4318 1.7018)
			(layers "F.Cu" "F.Mask" "F.Paste")
			(net "SPI_PCH_CLK_FLASH_R1")
		)
	)
	(footprint ""
		(layer "F.Cu")
		(at 78.907894 -31.764986 -90)
		(property "Reference" "D4"
			(at 4.079748 -7.092442 90)
			(unlocked yes)
			(layer "F.SilkS")
			(effects
				(font
					(size 0.7874 0.5842)
					(thickness 0.1524)
				)
				(justify left)
			)
		)
		(property "Value" ""
			(at 0 0 270)
			(layer "F.Fab")
			(effects
				(font
					(size 1.27 1.27)
				)
			)
		)
		(duplicate_pad_numbers_are_jumpers no)
		(fp_line
			(start -1.3208 0.5588)
			(end -1.3208 -0.5588)
			(stroke
				(width 0.1524)
				(type default)
			)
			(layer "F.SilkS")
		)
		(fp_line
			(start 1.3208 0.5588)
			(end -1.3208 0.5588)
			(stroke
				(width 0.1524)
				(type default)
			)
			(layer "F.SilkS")
		)
		(fp_line
			(start 1.6256 0.5588)
			(end 1.6256 -0.5588)
			(stroke
				(width 0.1524)
				(type default)
			)
			(layer "F.SilkS")
		)
		(fp_line
			(start 1.778 0.5588)
			(end 1.3208 0.5588)
			(stroke
				(width 0.1524)
				(type default)
			)
			(layer "F.SilkS")
		)
		(fp_line
			(start -1.3208 -0.5588)
			(end 1.3208 -0.5588)
			(stroke
				(width 0.1524)
				(type default)
			)
			(layer "F.SilkS")
		)
		(fp_line
			(start 1.3208 -0.5588)
			(end 1.3208 0.5588)
			(stroke
				(width 0.1524)
				(type default)
			)
			(layer "F.SilkS")
		)
		(fp_line
			(start 1.4732 -0.5588)
			(end 1.4732 0.5588)
			(stroke
				(width 0.1524)
				(type default)
			)
			(layer "F.SilkS")
		)
		(fp_line
			(start 1.778 -0.5588)
			(end 1.778 0.5588)
			(stroke
				(width 0.1524)
				(type default)
			)
			(layer "F.SilkS")
		)
		(fp_line
			(start 1.778 -0.5588)
			(end 1.3208 -0.5588)
			(stroke
				(width 0.1524)
				(type default)
			)
			(layer "F.SilkS")
		)
		(fp_line
			(start -0.8001 0.40005)
			(end -0.8001 -0.40005)
			(stroke
				(width 0.1)
				(type default)
			)
			(layer "F.Fab")
		)
		(fp_line
			(start 0.8001 0.40005)
			(end -0.8001 0.40005)
			(stroke
				(width 0.1)
				(type default)
			)
			(layer "F.Fab")
		)
		(fp_line
			(start -0.8001 -0.40005)
			(end 0.8001 -0.40005)
			(stroke
				(width 0.1)
				(type default)
			)
			(layer "F.Fab")
		)
		(fp_line
			(start 0.8001 -0.40005)
			(end 0.8001 0.40005)
			(stroke
				(width 0.1)
				(type default)
			)
			(layer "F.Fab")
		)
		(fp_text user "-"
			(at 0.642874 -1.107948 270)
			(unlocked yes)
			(layer "F.SilkS")
			(effects
				(font
					(size 1.905 1.4224)
					(thickness 0.1524)
				)
				(justify left)
			)
		)
		(fp_text user "+"
			(at -1.606804 -1.380998 270)
			(unlocked yes)
			(layer "F.SilkS")
			(effects
				(font
					(size 1.905 1.4224)
					(thickness 0.1524)
				)
				(justify left)
			)
		)
		(fp_text user "+"
			(at -2.5654 -0.22225 270)
			(unlocked yes)
			(layer "F.Fab")
			(effects
				(font
					(size 1.905 1.4224)
					(thickness 0.1524)
				)
				(justify left)
			)
		)
		(fp_text user "-"
			(at 1.6256 -0.22225 270)
			(unlocked yes)
			(layer "F.Fab")
			(effects
				(font
					(size 1.905 1.4224)
					(thickness 0.1524)
				)
				(justify left)
			)
		)
		(pad "A" smd rect
			(at -0.750062 0 270)
			(size 0.8128 0.8128)
			(layers "F.Cu" "F.Mask" "F.Paste")
			(net "LED_POSTCODE_4_R")
		)
		(pad "C" smd rect
			(at 0.750062 0 270)
			(size 0.8128 0.8128)
			(layers "F.Cu" "F.Mask" "F.Paste")
			(net "GND")
		)
	)
	(footprint ""
		(layer "F.Cu")
		(at -7.6454 -66.929 180)
		(property "Reference" "DB4"
			(at -1.0668 -5.826252 0)
			(unlocked yes)
			(layer "F.SilkS")
			(effects
				(font
					(size 0.7874 0.5842)
					(thickness 0.1524)
				)
				(justify left)
			)
		)
		(property "Value" ""
			(at 0 0 180)
			(layer "F.Fab")
			(effects
				(font
					(size 1.27 1.27)
				)
			)
		)
		(duplicate_pad_numbers_are_jumpers no)
		(fp_line
			(start 3.330702 -4.771136)
			(end 0 4.011168)
			(stroke
				(width 0.1524)
				(type default)
			)
			(layer "F.SilkS")
		)
		(fp_line
			(start 0 4.011168)
			(end -3.330702 -4.771136)
			(stroke
				(width 0.1524)
				(type default)
			)
			(layer "F.SilkS")
		)
		(fp_line
			(start -3.330702 -4.771136)
			(end 3.330702 -4.771136)
			(stroke
				(width 0.1524)
				(type default)
			)
			(layer "F.SilkS")
		)
		(fp_line
			(start 3.330702 -4.771136)
			(end 0 4.011168)
			(stroke
				(width 0.1)
				(type default)
			)
			(layer "F.Fab")
		)
		(fp_line
			(start 0 4.011168)
			(end -3.330702 -4.771136)
			(stroke
				(width 0.1)
				(type default)
			)
			(layer "F.Fab")
		)
		(fp_line
			(start -3.330702 -4.771136)
			(end 3.330702 -4.771136)
			(stroke
				(width 0.1)
				(type default)
			)
			(layer "F.Fab")
		)
		(pad "1" thru_hole circle
			(at 0 0 180)
			(size 2.159 2.159)
			(drill 1.7018)
			(layers "*.Cu" "*.Mask")
			(remove_unused_layers no)
			(net "T_GND")
			(clearance 0.0254)
			(thermal_gap 0.0254)
		)
		(pad "2" thru_hole circle
			(at -1.27 -3.348736 180)
			(size 2.159 2.159)
			(drill 1.7018)
			(layers "*.Cu" "*.Mask")
			(remove_unused_layers no)
			(net "TDR_SE_50_OHM_IN3")
			(clearance 0.0254)
			(thermal_gap 0.0254)
		)
		(pad "3" thru_hole circle
			(at 1.27 -3.348736 180)
			(size 2.159 2.159)
			(drill 1.7018)
			(layers "*.Cu" "*.Mask")
			(remove_unused_layers no)
			(net "TDR_SE_50_OHM_IN3")
			(clearance 0.0254)
			(thermal_gap 0.0254)
		)
	)
	(footprint ""
		(layer "F.Cu")
		(at 53.388006 -30.867604 90)
		(property "Reference" "R261"
			(at 0 0 90)
			(layer "F.SilkS")
			(hide yes)
			(effects
				(font
					(size 1.27 1.27)
				)
			)
		)
		(property "Value" ""
			(at 0 0 90)
			(layer "F.Fab")
			(effects
				(font
					(size 1.27 1.27)
				)
			)
		)
		(duplicate_pad_numbers_are_jumpers no)
		(fp_line
			(start 0.7874 -0.4064)
			(end 0.7874 0.4064)
			(stroke
				(width 0.1524)
				(type default)
			)
			(layer "F.SilkS")
		)
		(fp_line
			(start -0.7874 -0.4064)
			(end 0.7874 -0.4064)
			(stroke
				(width 0.1524)
				(type default)
			)
			(layer "F.SilkS")
		)
		(fp_line
			(start 0.7874 0.4064)
			(end -0.7874 0.4064)
			(stroke
				(width 0.1524)
				(type default)
			)
			(layer "F.SilkS")
		)
		(fp_line
			(start -0.7874 0.4064)
			(end -0.7874 -0.4064)
			(stroke
				(width 0.1524)
				(type default)
			)
			(layer "F.SilkS")
		)
		(fp_line
			(start -0.12065 -0.305054)
			(end -0.12065 -0.2794)
			(stroke
				(width 0.1)
				(type default)
			)
			(layer "F.Fab")
		)
		(fp_line
			(start -0.67945 -0.305054)
			(end -0.12065 -0.305054)
			(stroke
				(width 0.1)
				(type default)
			)
			(layer "F.Fab")
		)
		(fp_line
			(start 0.67945 -0.3048)
			(end 0.67945 0.3048)
			(stroke
				(width 0.1)
				(type default)
			)
			(layer "F.Fab")
		)
		(fp_line
			(start 0.12065 -0.3048)
			(end 0.67945 -0.3048)
			(stroke
				(width 0.1)
				(type default)
			)
			(layer "F.Fab")
		)
		(fp_line
			(start 0.12065 -0.2794)
			(end 0.12065 -0.3048)
			(stroke
				(width 0.1)
				(type default)
			)
			(layer "F.Fab")
		)
		(fp_line
			(start -0.12065 -0.2794)
			(end 0.12065 -0.2794)
			(stroke
				(width 0.1)
				(type default)
			)
			(layer "F.Fab")
		)
		(fp_line
			(start 0.120396 0.2794)
			(end -0.12065 0.2794)
			(stroke
				(width 0.1)
				(type default)
			)
			(layer "F.Fab")
		)
		(fp_line
			(start -0.12065 0.2794)
			(end -0.12065 0.3048)
			(stroke
				(width 0.1)
				(type default)
			)
			(layer "F.Fab")
		)
		(fp_line
			(start 0.67945 0.3048)
			(end 0.120396 0.3048)
			(stroke
				(width 0.1)
				(type default)
			)
			(layer "F.Fab")
		)
		(fp_line
			(start 0.120396 0.3048)
			(end 0.120396 0.2794)
			(stroke
				(width 0.1)
				(type default)
			)
			(layer "F.Fab")
		)
		(fp_line
			(start -0.12065 0.3048)
			(end -0.67945 0.3048)
			(stroke
				(width 0.1)
				(type default)
			)
			(layer "F.Fab")
		)
		(fp_line
			(start -0.67945 0.3048)
			(end -0.67945 -0.305054)
			(stroke
				(width 0.1)
				(type default)
			)
			(layer "F.Fab")
		)
		(pad "1" smd circle
			(at -0.40005 0 90)
			(size 0 0)
			(layers "F.Cu" "F.Mask" "F.Paste")
			(net "P3V3_AUX")
		)
		(pad "2" smd circle
			(at 0.40005 0 90)
			(size 0 0)
			(layers "F.Cu" "F.Mask" "F.Paste")
			(net "SMB_BMC_MM9_SDA")
		)
	)
	(footprint ""
		(layer "F.Cu")
		(at 10.287 -98.298 -90)
		(property "Reference" "R518"
			(at 0 0 270)
			(layer "F.SilkS")
			(hide yes)
			(effects
				(font
					(size 1.27 1.27)
				)
			)
		)
		(property "Value" ""
			(at 0 0 270)
			(layer "F.Fab")
			(effects
				(font
					(size 1.27 1.27)
				)
			)
		)
		(duplicate_pad_numbers_are_jumpers no)
		(fp_line
			(start -0.7874 0.4064)
			(end -0.7874 -0.4064)
			(stroke
				(width 0.1524)
				(type default)
			)
			(layer "F.SilkS")
		)
		(fp_line
			(start 0.7874 0.4064)
			(end -0.7874 0.4064)
			(stroke
				(width 0.1524)
				(type default)
			)
			(layer "F.SilkS")
		)
		(fp_line
			(start -0.7874 -0.4064)
			(end 0.7874 -0.4064)
			(stroke
				(width 0.1524)
				(type default)
			)
			(layer "F.SilkS")
		)
		(fp_line
			(start 0.7874 -0.4064)
			(end 0.7874 0.4064)
			(stroke
				(width 0.1524)
				(type default)
			)
			(layer "F.SilkS")
		)
		(fp_line
			(start -0.67945 0.3048)
			(end -0.67945 -0.305054)
			(stroke
				(width 0.1)
				(type default)
			)
			(layer "F.Fab")
		)
		(fp_line
			(start -0.12065 0.3048)
			(end -0.67945 0.3048)
			(stroke
				(width 0.1)
				(type default)
			)
			(layer "F.Fab")
		)
		(fp_line
			(start 0.120396 0.3048)
			(end 0.120396 0.2794)
			(stroke
				(width 0.1)
				(type default)
			)
			(layer "F.Fab")
		)
		(fp_line
			(start 0.67945 0.3048)
			(end 0.120396 0.3048)
			(stroke
				(width 0.1)
				(type default)
			)
			(layer "F.Fab")
		)
		(fp_line
			(start -0.12065 0.2794)
			(end -0.12065 0.3048)
			(stroke
				(width 0.1)
				(type default)
			)
			(layer "F.Fab")
		)
		(fp_line
			(start 0.120396 0.2794)
			(end -0.12065 0.2794)
			(stroke
				(width 0.1)
				(type default)
			)
			(layer "F.Fab")
		)
		(fp_line
			(start -0.12065 -0.2794)
			(end 0.12065 -0.2794)
			(stroke
				(width 0.1)
				(type default)
			)
			(layer "F.Fab")
		)
		(fp_line
			(start 0.12065 -0.2794)
			(end 0.12065 -0.3048)
			(stroke
				(width 0.1)
				(type default)
			)
			(layer "F.Fab")
		)
		(fp_line
			(start 0.12065 -0.3048)
			(end 0.67945 -0.3048)
			(stroke
				(width 0.1)
				(type default)
			)
			(layer "F.Fab")
		)
		(fp_line
			(start 0.67945 -0.3048)
			(end 0.67945 0.3048)
			(stroke
				(width 0.1)
				(type default)
			)
			(layer "F.Fab")
		)
		(fp_line
			(start -0.67945 -0.305054)
			(end -0.12065 -0.305054)
			(stroke
				(width 0.1)
				(type default)
			)
			(layer "F.Fab")
		)
		(fp_line
			(start -0.12065 -0.305054)
			(end -0.12065 -0.2794)
			(stroke
				(width 0.1)
				(type default)
			)
			(layer "F.Fab")
		)
		(pad "1" smd circle
			(at -0.40005 0 270)
			(size 0 0)
			(layers "F.Cu" "F.Mask" "F.Paste")
			(net "JTAG_SCM_PLD_R1_JTAGEN")
		)
		(pad "2" smd circle
			(at 0.40005 0 270)
			(size 0 0)
			(layers "F.Cu" "F.Mask" "F.Paste")
			(net "JTAG_SCM_PLD_JTAGEN")
		)
	)
	(footprint ""
		(layer "F.Cu")
		(at 14.113002 -106.33837)
		(property "Reference" "U13"
			(at 1.279398 1.81864 0)
			(unlocked yes)
			(layer "F.SilkS")
			(effects
				(font
					(size 0.7874 0.5842)
					(thickness 0.1524)
				)
				(justify left)
			)
		)
		(property "Value" ""
			(at 0 0 0)
			(layer "F.Fab")
			(effects
				(font
					(size 1.27 1.27)
				)
			)
		)
		(duplicate_pad_numbers_are_jumpers no)
		(fp_line
			(start -1.33096 -1.100074)
			(end -0.381 -1.100074)
			(stroke
				(width 0.1524)
				(type default)
			)
			(layer "F.SilkS")
		)
		(fp_line
			(start -1.33096 1.100074)
			(end -1.33096 -1.100074)
			(stroke
				(width 0.1524)
				(type default)
			)
			(layer "F.SilkS")
		)
		(fp_line
			(start -0.381 -1.100074)
			(end 0 -0.649986)
			(stroke
				(width 0.1524)
				(type default)
			)
			(layer "F.SilkS")
		)
		(fp_line
			(start 0 -0.649986)
			(end 0.381 -1.100074)
			(stroke
				(width 0.1524)
				(type default)
			)
			(layer "F.SilkS")
		)
		(fp_line
			(start 0.381 -1.100074)
			(end 1.33096 -1.100074)
			(stroke
				(width 0.1524)
				(type default)
			)
			(layer "F.SilkS")
		)
		(fp_line
			(start 1.33096 -1.100074)
			(end 1.33096 1.100074)
			(stroke
				(width 0.1524)
				(type default)
			)
			(layer "F.SilkS")
		)
		(fp_line
			(start 1.33096 1.100074)
			(end -1.33096 1.100074)
			(stroke
				(width 0.1524)
				(type default)
			)
			(layer "F.SilkS")
		)
		(fp_poly
			(pts
				(xy -2.209292 -0.902462) (xy -2.209292 -0.394462) (xy -1.447292 -0.648462)
			)
			(stroke
				(width 0)
				(type default)
			)
			(fill yes)
			(layer "F.SilkS")
		)
		(fp_line
			(start -0.674878 -1.100074)
			(end 0.674878 -1.100074)
			(stroke
				(width 0.1)
				(type default)
			)
			(layer "F.Fab")
		)
		(fp_line
			(start -0.674878 1.100074)
			(end -0.674878 -1.100074)
			(stroke
				(width 0.1)
				(type default)
			)
			(layer "F.Fab")
		)
		(fp_line
			(start 0.674878 -1.100074)
			(end 0.674878 1.100074)
			(stroke
				(width 0.1)
				(type default)
			)
			(layer "F.Fab")
		)
		(fp_line
			(start 0.674878 1.100074)
			(end -0.674878 1.100074)
			(stroke
				(width 0.1)
				(type default)
			)
			(layer "F.Fab")
		)
		(fp_poly
			(pts
				(xy -2.209292 -0.902462) (xy -2.209292 -0.394462) (xy -1.447292 -0.648462)
			)
			(stroke
				(width 0)
				(type default)
			)
			(fill yes)
			(layer "F.Fab")
		)
		(pad "1" smd rect
			(at -0.94996 -0.649986 90)
			(size 0.4064 0.508)
			(layers "F.Cu" "F.Mask" "F.Paste")
			(net "Net_317")
		)
		(pad "2" smd rect
			(at -0.94996 0 90)
			(size 0.4064 0.508)
			(layers "F.Cu" "F.Mask" "F.Paste")
			(net "RST_BMC_SRST_BUF_R1_N")
		)
		(pad "3" smd rect
			(at -0.94996 0.649986 90)
			(size 0.4064 0.508)
			(layers "F.Cu" "F.Mask" "F.Paste")
			(net "GND")
		)
		(pad "4" smd rect
			(at 0.94996 0.649986 90)
			(size 0.4064 0.508)
			(layers "F.Cu" "F.Mask" "F.Paste")
			(net "RST_BMC_EXTRST_R1_N")
		)
		(pad "5" smd rect
			(at 0.94996 -0.649986 90)
			(size 0.4064 0.508)
			(layers "F.Cu" "F.Mask" "F.Paste")
			(net "P3V3_AUX")
		)
	)
	(footprint ""
		(layer "F.Cu")
		(at 39.095172 -83.816952 -90)
		(property "Reference" "R655"
			(at 0 0 270)
			(layer "F.SilkS")
			(hide yes)
			(effects
				(font
					(size 1.27 1.27)
				)
			)
		)
		(property "Value" ""
			(at 0 0 270)
			(layer "F.Fab")
			(effects
				(font
					(size 1.27 1.27)
				)
			)
		)
		(duplicate_pad_numbers_are_jumpers no)
		(fp_line
			(start -0.7874 0.4064)
			(end -0.7874 -0.4064)
			(stroke
				(width 0.1524)
				(type default)
			)
			(layer "F.SilkS")
		)
		(fp_line
			(start 0.7874 0.4064)
			(end -0.7874 0.4064)
			(stroke
				(width 0.1524)
				(type default)
			)
			(layer "F.SilkS")
		)
		(fp_line
			(start -0.7874 -0.4064)
			(end 0.7874 -0.4064)
			(stroke
				(width 0.1524)
				(type default)
			)
			(layer "F.SilkS")
		)
		(fp_line
			(start 0.7874 -0.4064)
			(end 0.7874 0.4064)
			(stroke
				(width 0.1524)
				(type default)
			)
			(layer "F.SilkS")
		)
		(fp_line
			(start -0.67945 0.3048)
			(end -0.67945 -0.305054)
			(stroke
				(width 0.1)
				(type default)
			)
			(layer "F.Fab")
		)
		(fp_line
			(start -0.12065 0.3048)
			(end -0.67945 0.3048)
			(stroke
				(width 0.1)
				(type default)
			)
			(layer "F.Fab")
		)
		(fp_line
			(start 0.120396 0.3048)
			(end 0.120396 0.2794)
			(stroke
				(width 0.1)
				(type default)
			)
			(layer "F.Fab")
		)
		(fp_line
			(start 0.67945 0.3048)
			(end 0.120396 0.3048)
			(stroke
				(width 0.1)
				(type default)
			)
			(layer "F.Fab")
		)
		(fp_line
			(start -0.12065 0.2794)
			(end -0.12065 0.3048)
			(stroke
				(width 0.1)
				(type default)
			)
			(layer "F.Fab")
		)
		(fp_line
			(start 0.120396 0.2794)
			(end -0.12065 0.2794)
			(stroke
				(width 0.1)
				(type default)
			)
			(layer "F.Fab")
		)
		(fp_line
			(start -0.12065 -0.2794)
			(end 0.12065 -0.2794)
			(stroke
				(width 0.1)
				(type default)
			)
			(layer "F.Fab")
		)
		(fp_line
			(start 0.12065 -0.2794)
			(end 0.12065 -0.3048)
			(stroke
				(width 0.1)
				(type default)
			)
			(layer "F.Fab")
		)
		(fp_line
			(start 0.12065 -0.3048)
			(end 0.67945 -0.3048)
			(stroke
				(width 0.1)
				(type default)
			)
			(layer "F.Fab")
		)
		(fp_line
			(start 0.67945 -0.3048)
			(end 0.67945 0.3048)
			(stroke
				(width 0.1)
				(type default)
			)
			(layer "F.Fab")
		)
		(fp_line
			(start -0.67945 -0.305054)
			(end -0.12065 -0.305054)
			(stroke
				(width 0.1)
				(type default)
			)
			(layer "F.Fab")
		)
		(fp_line
			(start -0.12065 -0.305054)
			(end -0.12065 -0.2794)
			(stroke
				(width 0.1)
				(type default)
			)
			(layer "F.Fab")
		)
		(pad "1" smd circle
			(at -0.40005 0 270)
			(size 0 0)
			(layers "F.Cu" "F.Mask" "F.Paste")
			(net "P3V3_AUX")
		)
		(pad "2" smd circle
			(at 0.40005 0 270)
			(size 0 0)
			(layers "F.Cu" "F.Mask" "F.Paste")
			(net "EMMC_DT0_R")
		)
	)
	(footprint ""
		(layer "F.Cu")
		(at 49.67478 -66.25082)
		(property "Reference" "R234"
			(at 0 0 0)
			(layer "F.SilkS")
			(hide yes)
			(effects
				(font
					(size 1.27 1.27)
				)
			)
		)
		(property "Value" ""
			(at 0 0 0)
			(layer "F.Fab")
			(effects
				(font
					(size 1.27 1.27)
				)
			)
		)
		(duplicate_pad_numbers_are_jumpers no)
		(fp_line
			(start -0.7874 -0.4064)
			(end 0.7874 -0.4064)
			(stroke
				(width 0.1524)
				(type default)
			)
			(layer "F.SilkS")
		)
		(fp_line
			(start -0.7874 0.4064)
			(end -0.7874 -0.4064)
			(stroke
				(width 0.1524)
				(type default)
			)
			(layer "F.SilkS")
		)
		(fp_line
			(start 0.7874 -0.4064)
			(end 0.7874 0.4064)
			(stroke
				(width 0.1524)
				(type default)
			)
			(layer "F.SilkS")
		)
		(fp_line
			(start 0.7874 0.4064)
			(end -0.7874 0.4064)
			(stroke
				(width 0.1524)
				(type default)
			)
			(layer "F.SilkS")
		)
		(fp_line
			(start -0.67945 -0.305054)
			(end -0.12065 -0.305054)
			(stroke
				(width 0.1)
				(type default)
			)
			(layer "F.Fab")
		)
		(fp_line
			(start -0.67945 0.3048)
			(end -0.67945 -0.305054)
			(stroke
				(width 0.1)
				(type default)
			)
			(layer "F.Fab")
		)
		(fp_line
			(start -0.12065 -0.305054)
			(end -0.12065 -0.2794)
			(stroke
				(width 0.1)
				(type default)
			)
			(layer "F.Fab")
		)
		(fp_line
			(start -0.12065 -0.2794)
			(end 0.12065 -0.2794)
			(stroke
				(width 0.1)
				(type default)
			)
			(layer "F.Fab")
		)
		(fp_line
			(start -0.12065 0.2794)
			(end -0.12065 0.3048)
			(stroke
				(width 0.1)
				(type default)
			)
			(layer "F.Fab")
		)
		(fp_line
			(start -0.12065 0.3048)
			(end -0.67945 0.3048)
			(stroke
				(width 0.1)
				(type default)
			)
			(layer "F.Fab")
		)
		(fp_line
			(start 0.120396 0.2794)
			(end -0.12065 0.2794)
			(stroke
				(width 0.1)
				(type default)
			)
			(layer "F.Fab")
		)
		(fp_line
			(start 0.120396 0.3048)
			(end 0.120396 0.2794)
			(stroke
				(width 0.1)
				(type default)
			)
			(layer "F.Fab")
		)
		(fp_line
			(start 0.12065 -0.3048)
			(end 0.67945 -0.3048)
			(stroke
				(width 0.1)
				(type default)
			)
			(layer "F.Fab")
		)
		(fp_line
			(start 0.12065 -0.2794)
			(end 0.12065 -0.3048)
			(stroke
				(width 0.1)
				(type default)
			)
			(layer "F.Fab")
		)
		(fp_line
			(start 0.67945 -0.3048)
			(end 0.67945 0.3048)
			(stroke
				(width 0.1)
				(type default)
			)
			(layer "F.Fab")
		)
		(fp_line
			(start 0.67945 0.3048)
			(end 0.120396 0.3048)
			(stroke
				(width 0.1)
				(type default)
			)
			(layer "F.Fab")
		)
		(pad "1" smd circle
			(at -0.40005 0)
			(size 0 0)
			(layers "F.Cu" "F.Mask" "F.Paste")
			(net "GND")
		)
		(pad "2" smd circle
			(at 0.40005 0)
			(size 0 0)
			(layers "F.Cu" "F.Mask" "F.Paste")
			(net "A_BMC_ADCREXT1")
		)
	)
	(footprint ""
		(layer "F.Cu")
		(at 82.0928 -114.681)
		(property "Reference" ""
			(at 0 0 0)
			(layer "F.SilkS")
			(hide yes)
			(effects
				(font
					(size 1.27 1.27)
				)
			)
		)
		(property "Value" ""
			(at 0 0 0)
			(layer "F.Fab")
			(effects
				(font
					(size 1.27 1.27)
				)
			)
		)
		(duplicate_pad_numbers_are_jumpers no)
		(pad "1" smd circle
			(at 0 0)
			(size 0.9906 0.9906)
			(layers "F.Cu" "F.Mask" "F.Paste")
			(net "Net_597")
		)
	)
	(footprint ""
		(layer "F.Cu")
		(at 49.2125 -92.0115 90)
		(property "Reference" "R290"
			(at 0 0 90)
			(layer "F.SilkS")
			(hide yes)
			(effects
				(font
					(size 1.27 1.27)
				)
			)
		)
		(property "Value" ""
			(at 0 0 90)
			(layer "F.Fab")
			(effects
				(font
					(size 1.27 1.27)
				)
			)
		)
		(duplicate_pad_numbers_are_jumpers no)
		(fp_line
			(start 0.7874 -0.4064)
			(end 0.7874 0.4064)
			(stroke
				(width 0.1524)
				(type default)
			)
			(layer "F.SilkS")
		)
		(fp_line
			(start -0.7874 -0.4064)
			(end 0.7874 -0.4064)
			(stroke
				(width 0.1524)
				(type default)
			)
			(layer "F.SilkS")
		)
		(fp_line
			(start 0.7874 0.4064)
			(end -0.7874 0.4064)
			(stroke
				(width 0.1524)
				(type default)
			)
			(layer "F.SilkS")
		)
		(fp_line
			(start -0.7874 0.4064)
			(end -0.7874 -0.4064)
			(stroke
				(width 0.1524)
				(type default)
			)
			(layer "F.SilkS")
		)
		(fp_line
			(start -0.12065 -0.305054)
			(end -0.12065 -0.2794)
			(stroke
				(width 0.1)
				(type default)
			)
			(layer "F.Fab")
		)
		(fp_line
			(start -0.67945 -0.305054)
			(end -0.12065 -0.305054)
			(stroke
				(width 0.1)
				(type default)
			)
			(layer "F.Fab")
		)
		(fp_line
			(start 0.67945 -0.3048)
			(end 0.67945 0.3048)
			(stroke
				(width 0.1)
				(type default)
			)
			(layer "F.Fab")
		)
		(fp_line
			(start 0.12065 -0.3048)
			(end 0.67945 -0.3048)
			(stroke
				(width 0.1)
				(type default)
			)
			(layer "F.Fab")
		)
		(fp_line
			(start 0.12065 -0.2794)
			(end 0.12065 -0.3048)
			(stroke
				(width 0.1)
				(type default)
			)
			(layer "F.Fab")
		)
		(fp_line
			(start -0.12065 -0.2794)
			(end 0.12065 -0.2794)
			(stroke
				(width 0.1)
				(type default)
			)
			(layer "F.Fab")
		)
		(fp_line
			(start 0.120396 0.2794)
			(end -0.12065 0.2794)
			(stroke
				(width 0.1)
				(type default)
			)
			(layer "F.Fab")
		)
		(fp_line
			(start -0.12065 0.2794)
			(end -0.12065 0.3048)
			(stroke
				(width 0.1)
				(type default)
			)
			(layer "F.Fab")
		)
		(fp_line
			(start 0.67945 0.3048)
			(end 0.120396 0.3048)
			(stroke
				(width 0.1)
				(type default)
			)
			(layer "F.Fab")
		)
		(fp_line
			(start 0.120396 0.3048)
			(end 0.120396 0.2794)
			(stroke
				(width 0.1)
				(type default)
			)
			(layer "F.Fab")
		)
		(fp_line
			(start -0.12065 0.3048)
			(end -0.67945 0.3048)
			(stroke
				(width 0.1)
				(type default)
			)
			(layer "F.Fab")
		)
		(fp_line
			(start -0.67945 0.3048)
			(end -0.67945 -0.305054)
			(stroke
				(width 0.1)
				(type default)
			)
			(layer "F.Fab")
		)
		(pad "1" smd circle
			(at -0.40005 0 90)
			(size 0 0)
			(layers "F.Cu" "F.Mask" "F.Paste")
			(net "BJT_Q3_B")
		)
		(pad "2" smd circle
			(at 0.40005 0 90)
			(size 0 0)
			(layers "F.Cu" "F.Mask" "F.Paste")
			(net "RST_BMC_EXTRST_R1_N")
		)
	)
	(footprint ""
		(layer "F.Cu")
		(at 26.1874 -83.7438 90)
		(property "Reference" "R169"
			(at 0 0 90)
			(layer "F.SilkS")
			(hide yes)
			(effects
				(font
					(size 1.27 1.27)
				)
			)
		)
		(property "Value" ""
			(at 0 0 90)
			(layer "F.Fab")
			(effects
				(font
					(size 1.27 1.27)
				)
			)
		)
		(duplicate_pad_numbers_are_jumpers no)
		(fp_line
			(start 0.7874 -0.4064)
			(end 0.7874 0.4064)
			(stroke
				(width 0.1524)
				(type default)
			)
			(layer "F.SilkS")
		)
		(fp_line
			(start -0.7874 -0.4064)
			(end 0.7874 -0.4064)
			(stroke
				(width 0.1524)
				(type default)
			)
			(layer "F.SilkS")
		)
		(fp_line
			(start 0.7874 0.4064)
			(end -0.7874 0.4064)
			(stroke
				(width 0.1524)
				(type default)
			)
			(layer "F.SilkS")
		)
		(fp_line
			(start -0.7874 0.4064)
			(end -0.7874 -0.4064)
			(stroke
				(width 0.1524)
				(type default)
			)
			(layer "F.SilkS")
		)
		(fp_line
			(start -0.12065 -0.305054)
			(end -0.12065 -0.2794)
			(stroke
				(width 0.1)
				(type default)
			)
			(layer "F.Fab")
		)
		(fp_line
			(start -0.67945 -0.305054)
			(end -0.12065 -0.305054)
			(stroke
				(width 0.1)
				(type default)
			)
			(layer "F.Fab")
		)
		(fp_line
			(start 0.67945 -0.3048)
			(end 0.67945 0.3048)
			(stroke
				(width 0.1)
				(type default)
			)
			(layer "F.Fab")
		)
		(fp_line
			(start 0.12065 -0.3048)
			(end 0.67945 -0.3048)
			(stroke
				(width 0.1)
				(type default)
			)
			(layer "F.Fab")
		)
		(fp_line
			(start 0.12065 -0.2794)
			(end 0.12065 -0.3048)
			(stroke
				(width 0.1)
				(type default)
			)
			(layer "F.Fab")
		)
		(fp_line
			(start -0.12065 -0.2794)
			(end 0.12065 -0.2794)
			(stroke
				(width 0.1)
				(type default)
			)
			(layer "F.Fab")
		)
		(fp_line
			(start 0.120396 0.2794)
			(end -0.12065 0.2794)
			(stroke
				(width 0.1)
				(type default)
			)
			(layer "F.Fab")
		)
		(fp_line
			(start -0.12065 0.2794)
			(end -0.12065 0.3048)
			(stroke
				(width 0.1)
				(type default)
			)
			(layer "F.Fab")
		)
		(fp_line
			(start 0.67945 0.3048)
			(end 0.120396 0.3048)
			(stroke
				(width 0.1)
				(type default)
			)
			(layer "F.Fab")
		)
		(fp_line
			(start 0.120396 0.3048)
			(end 0.120396 0.2794)
			(stroke
				(width 0.1)
				(type default)
			)
			(layer "F.Fab")
		)
		(fp_line
			(start -0.12065 0.3048)
			(end -0.67945 0.3048)
			(stroke
				(width 0.1)
				(type default)
			)
			(layer "F.Fab")
		)
		(fp_line
			(start -0.67945 0.3048)
			(end -0.67945 -0.305054)
			(stroke
				(width 0.1)
				(type default)
			)
			(layer "F.Fab")
		)
		(pad "1" smd circle
			(at -0.40005 0 90)
			(size 0 0)
			(layers "F.Cu" "F.Mask" "F.Paste")
			(net "P3V3_AUX")
		)
		(pad "2" smd circle
			(at 0.40005 0 90)
			(size 0 0)
			(layers "F.Cu" "F.Mask" "F.Paste")
			(net "RST_PCA9548_SENSOR_N")
		)
	)
	(footprint ""
		(layer "F.Cu")
		(at 27.2796 -69.0626 90)
		(property "Reference" "R849"
			(at 0 0 90)
			(layer "F.SilkS")
			(hide yes)
			(effects
				(font
					(size 1.27 1.27)
				)
			)
		)
		(property "Value" ""
			(at 0 0 90)
			(layer "F.Fab")
			(effects
				(font
					(size 1.27 1.27)
				)
			)
		)
		(duplicate_pad_numbers_are_jumpers no)
		(fp_line
			(start 0.7874 -0.4064)
			(end 0.7874 0.4064)
			(stroke
				(width 0.1524)
				(type default)
			)
			(layer "F.SilkS")
		)
		(fp_line
			(start -0.7874 -0.4064)
			(end 0.7874 -0.4064)
			(stroke
				(width 0.1524)
				(type default)
			)
			(layer "F.SilkS")
		)
		(fp_line
			(start 0.7874 0.4064)
			(end -0.7874 0.4064)
			(stroke
				(width 0.1524)
				(type default)
			)
			(layer "F.SilkS")
		)
		(fp_line
			(start -0.7874 0.4064)
			(end -0.7874 -0.4064)
			(stroke
				(width 0.1524)
				(type default)
			)
			(layer "F.SilkS")
		)
		(fp_line
			(start -0.12065 -0.305054)
			(end -0.12065 -0.2794)
			(stroke
				(width 0.1)
				(type default)
			)
			(layer "F.Fab")
		)
		(fp_line
			(start -0.67945 -0.305054)
			(end -0.12065 -0.305054)
			(stroke
				(width 0.1)
				(type default)
			)
			(layer "F.Fab")
		)
		(fp_line
			(start 0.67945 -0.3048)
			(end 0.67945 0.3048)
			(stroke
				(width 0.1)
				(type default)
			)
			(layer "F.Fab")
		)
		(fp_line
			(start 0.12065 -0.3048)
			(end 0.67945 -0.3048)
			(stroke
				(width 0.1)
				(type default)
			)
			(layer "F.Fab")
		)
		(fp_line
			(start 0.12065 -0.2794)
			(end 0.12065 -0.3048)
			(stroke
				(width 0.1)
				(type default)
			)
			(layer "F.Fab")
		)
		(fp_line
			(start -0.12065 -0.2794)
			(end 0.12065 -0.2794)
			(stroke
				(width 0.1)
				(type default)
			)
			(layer "F.Fab")
		)
		(fp_line
			(start 0.120396 0.2794)
			(end -0.12065 0.2794)
			(stroke
				(width 0.1)
				(type default)
			)
			(layer "F.Fab")
		)
		(fp_line
			(start -0.12065 0.2794)
			(end -0.12065 0.3048)
			(stroke
				(width 0.1)
				(type default)
			)
			(layer "F.Fab")
		)
		(fp_line
			(start 0.67945 0.3048)
			(end 0.120396 0.3048)
			(stroke
				(width 0.1)
				(type default)
			)
			(layer "F.Fab")
		)
		(fp_line
			(start 0.120396 0.3048)
			(end 0.120396 0.2794)
			(stroke
				(width 0.1)
				(type default)
			)
			(layer "F.Fab")
		)
		(fp_line
			(start -0.12065 0.3048)
			(end -0.67945 0.3048)
			(stroke
				(width 0.1)
				(type default)
			)
			(layer "F.Fab")
		)
		(fp_line
			(start -0.67945 0.3048)
			(end -0.67945 -0.305054)
			(stroke
				(width 0.1)
				(type default)
			)
			(layer "F.Fab")
		)
		(pad "1" smd circle
			(at -0.40005 0 90)
			(size 0 0)
			(layers "F.Cu" "F.Mask" "F.Paste")
			(net "SMB_BMC_MM16_R5_SCL")
		)
		(pad "2" smd circle
			(at 0.40005 0 90)
			(size 0 0)
			(layers "F.Cu" "F.Mask" "F.Paste")
			(net "SMB_BMC_MM16_R1_SCL")
		)
	)
	(footprint ""
		(layer "F.Cu")
		(at 26.75001 -77.16012 90)
		(property "Reference" "J4"
			(at -3.798062 -11.674348 90)
			(unlocked yes)
			(layer "F.SilkS")
			(effects
				(font
					(size 0.7874 0.5842)
					(thickness 0.1524)
				)
				(justify left)
			)
		)
		(property "Value" ""
			(at 0 0 90)
			(layer "F.Fab")
			(effects
				(font
					(size 1.27 1.27)
				)
			)
		)
		(duplicate_pad_numbers_are_jumpers no)
		(fp_line
			(start 1.448054 -10.925048)
			(end -1.320546 -10.925048)
			(stroke
				(width 0.1524)
				(type default)
			)
			(layer "F.SilkS")
		)
		(fp_line
			(start -1.752346 -10.925048)
			(end -3.57505 -10.925048)
			(stroke
				(width 0.1524)
				(type default)
			)
			(layer "F.SilkS")
		)
		(fp_line
			(start -3.57505 -10.925048)
			(end -3.57505 -9.271)
			(stroke
				(width 0.1524)
				(type default)
			)
			(layer "F.SilkS")
		)
		(fp_line
			(start 3.57505 -9.516618)
			(end 3.57505 -9.600692)
			(stroke
				(width 0.1524)
				(type default)
			)
			(layer "F.SilkS")
		)
		(fp_line
			(start -3.57505 -7.7216)
			(end -3.57505 -5.7785)
			(stroke
				(width 0.1524)
				(type default)
			)
			(layer "F.SilkS")
		)
		(fp_line
			(start 3.57505 -5.5245)
			(end 3.57505 -7.4676)
			(stroke
				(width 0.1524)
				(type default)
			)
			(layer "F.SilkS")
		)
		(fp_line
			(start -3.57505 9.271)
			(end -3.57505 10.925048)
			(stroke
				(width 0.1524)
				(type default)
			)
			(layer "F.SilkS")
		)
		(fp_line
			(start 3.57505 9.59866)
			(end 3.57505 9.525)
			(stroke
				(width 0.1524)
				(type default)
			)
			(layer "F.SilkS")
		)
		(fp_line
			(start -0.761746 10.925048)
			(end 1.448054 10.925048)
			(stroke
				(width 0.1524)
				(type default)
			)
			(layer "F.SilkS")
		)
		(fp_line
			(start -3.57505 10.925048)
			(end -2.260346 10.925048)
			(stroke
				(width 0.1524)
				(type default)
			)
			(layer "F.SilkS")
		)
		(fp_poly
			(pts
				(xy 5.662168 -8.741918) (xy 5.662168 -9.757918) (xy 4.646168 -9.249918)
			)
			(stroke
				(width 0)
				(type default)
			)
			(fill yes)
			(layer "F.SilkS")
		)
		(fp_line
			(start 3.57505 -10.925048)
			(end -3.57505 -10.925048)
			(stroke
				(width 0.1)
				(type default)
			)
			(layer "F.Fab")
		)
		(fp_line
			(start -3.57505 -10.925048)
			(end -3.57505 10.925048)
			(stroke
				(width 0.1)
				(type default)
			)
			(layer "F.Fab")
		)
		(fp_line
			(start 3.57505 10.925048)
			(end 3.57505 -10.925048)
			(stroke
				(width 0.1)
				(type default)
			)
			(layer "F.Fab")
		)
		(fp_line
			(start -3.57505 10.925048)
			(end 3.57505 10.925048)
			(stroke
				(width 0.1)
				(type default)
			)
			(layer "F.Fab")
		)
		(fp_poly
			(pts
				(xy 6.220968 -8.741918) (xy 6.220968 -9.757918) (xy 5.204968 -9.249918)
			)
			(stroke
				(width 0)
				(type default)
			)
			(fill yes)
			(layer "F.Fab")
		)
		(pad "" np_thru_hole circle
			(at -1.525016 -9.99998 90)
			(size 1.2192 1.2192)
			(drill 1.2192)
			(layers "*.Cu" "*.Mask")
			(clearance 0.381)
			(thermal_gap 0.381)
		)
		(pad "" np_thru_hole circle
			(at -1.525016 9.99998 90)
			(size 1.7018 1.7018)
			(drill 1.7018)
			(layers "*.Cu" "*.Mask")
			(clearance 0.381)
			(thermal_gap 0.381)
		)
		(pad "1" smd rect
			(at 3.750056 -9.249918)
			(size 0.2794 1.6002)
			(layers "F.Cu" "F.Mask" "F.Paste")
			(net "GND")
		)
		(pad "2" smd rect
			(at -3.799586 -8.999982)
			(size 0.2794 1.6002)
			(layers "F.Cu" "F.Mask" "F.Paste")
			(net "P3V3_AUX")
		)
		(pad "3" smd rect
			(at 3.750056 -8.750046)
			(size 0.2794 1.6002)
			(layers "F.Cu" "F.Mask" "F.Paste")
			(net "SPI_BMC_BT_WP1_N_R")
		)
		(pad "4" smd rect
			(at -3.799586 -8.50011)
			(size 0.2794 1.6002)
			(layers "F.Cu" "F.Mask" "F.Paste")
			(net "P3V3_AUX")
		)
		(pad "5" smd rect
			(at 3.750056 -8.24992)
			(size 0.2794 1.6002)
			(layers "F.Cu" "F.Mask" "F.Paste")
			(net "SPI_BMC_BT_WP0_N_R")
		)
		(pad "6" smd rect
			(at -3.799586 -7.999984)
			(size 0.2794 1.6002)
			(layers "F.Cu" "F.Mask" "F.Paste")
			(net "Net_1207")
		)
		(pad "7" smd rect
			(at 3.750056 -7.750048)
			(size 0.2794 1.6002)
			(layers "F.Cu" "F.Mask" "F.Paste")
			(net "GND")
		)
		(pad "16" smd rect
			(at -3.799586 -5.500116)
			(size 0.2794 1.6002)
			(layers "F.Cu" "F.Mask" "F.Paste")
			(net "BSM_PRSNT_N")
		)
		(pad "17" smd rect
			(at 3.750056 -5.249926)
			(size 0.2794 1.6002)
			(layers "F.Cu" "F.Mask" "F.Paste")
			(net "Net_1221")
		)
		(pad "18" smd rect
			(at -3.799586 -4.99999)
			(size 0.2794 1.6002)
			(layers "F.Cu" "F.Mask" "F.Paste")
			(net "GND")
		)
		(pad "19" smd rect
			(at 3.750056 -4.750054)
			(size 0.2794 1.6002)
			(layers "F.Cu" "F.Mask" "F.Paste")
			(net "RST_SPI_BMC_FLASH_R2_N")
		)
		(pad "20" smd rect
			(at -3.799586 -4.500118)
			(size 0.2794 1.6002)
			(layers "F.Cu" "F.Mask" "F.Paste")
			(net "Net_1220")
		)
		(pad "21" smd rect
			(at 3.750056 -4.249928)
			(size 0.2794 1.6002)
			(layers "F.Cu" "F.Mask" "F.Paste")
			(net "RST_SPI_BMC_FLASH_R1_N")
		)
		(pad "22" smd rect
			(at -3.799586 -3.999992)
			(size 0.2794 1.6002)
			(layers "F.Cu" "F.Mask" "F.Paste")
			(net "Net_1219")
		)
		(pad "23" smd rect
			(at 3.750056 -3.750056)
			(size 0.2794 1.6002)
			(layers "F.Cu" "F.Mask" "F.Paste")
			(net "GND")
		)
		(pad "24" smd rect
			(at -3.799586 -3.50012)
			(size 0.2794 1.6002)
			(layers "F.Cu" "F.Mask" "F.Paste")
			(net "GND")
		)
		(pad "25" smd rect
			(at 3.750056 -3.24993)
			(size 0.2794 1.6002)
			(layers "F.Cu" "F.Mask" "F.Paste")
			(net "SPI_BMC_IO1_FLASH_R")
		)
		(pad "26" smd rect
			(at -3.799586 -2.999994)
			(size 0.2794 1.6002)
			(layers "F.Cu" "F.Mask" "F.Paste")
			(net "SPI_BMC_HOLD1_N")
		)
		(pad "27" smd rect
			(at 3.750056 -2.750058)
			(size 0.2794 1.6002)
			(layers "F.Cu" "F.Mask" "F.Paste")
			(net "SPI_BMC_IO0_FLASH_R")
		)
		(pad "28" smd rect
			(at -3.799586 -2.500122)
			(size 0.2794 1.6002)
			(layers "F.Cu" "F.Mask" "F.Paste")
			(net "SPI_BMC_HOLD0_N")
		)
		(pad "29" smd rect
			(at 3.750056 -2.249932)
			(size 0.2794 1.6002)
			(layers "F.Cu" "F.Mask" "F.Paste")
			(net "GND")
		)
		(pad "30" smd rect
			(at -3.799586 -1.999996)
			(size 0.2794 1.6002)
			(layers "F.Cu" "F.Mask" "F.Paste")
			(net "GND")
		)
		(pad "31" smd rect
			(at 3.750056 -1.75006)
			(size 0.2794 1.6002)
			(layers "F.Cu" "F.Mask" "F.Paste")
			(net "SPI_BMC_CLK_FLASH_R")
		)
		(pad "32" smd rect
			(at -3.799586 -1.500124)
			(size 0.2794 1.6002)
			(layers "F.Cu" "F.Mask" "F.Paste")
			(net "Net_1218")
		)
		(pad "33" smd rect
			(at 3.750056 -1.249934)
			(size 0.2794 1.6002)
			(layers "F.Cu" "F.Mask" "F.Paste")
			(net "GND")
		)
		(pad "34" smd rect
			(at -3.799586 -0.999998)
			(size 0.2794 1.6002)
			(layers "F.Cu" "F.Mask" "F.Paste")
			(net "Net_1217")
		)
		(pad "35" smd rect
			(at 3.750056 -0.750062)
			(size 0.2794 1.6002)
			(layers "F.Cu" "F.Mask" "F.Paste")
			(net "SPI_BMC_CS1_FLASH_R_N")
		)
		(pad "36" smd rect
			(at -3.799586 -0.499872)
			(size 0.2794 1.6002)
			(layers "F.Cu" "F.Mask" "F.Paste")
			(net "GND")
		)
		(pad "37" smd rect
			(at 3.750056 -0.249936)
			(size 0.2794 1.6002)
			(layers "F.Cu" "F.Mask" "F.Paste")
			(net "SPI_BMC_CS0_FLASH_R_N")
		)
		(pad "38" smd rect
			(at -3.799586 0)
			(size 0.2794 1.6002)
			(layers "F.Cu" "F.Mask" "F.Paste")
			(net "Net_1216")
		)
		(pad "39" smd rect
			(at 3.750056 0.249936)
			(size 0.2794 1.6002)
			(layers "F.Cu" "F.Mask" "F.Paste")
			(net "GND")
		)
		(pad "40" smd rect
			(at -3.799586 0.499872)
			(size 0.2794 1.6002)
			(layers "F.Cu" "F.Mask" "F.Paste")
			(net "SMB_BMC_MM16_R1_SCL")
		)
		(pad "41" smd rect
			(at 3.750056 0.750062)
			(size 0.2794 1.6002)
			(layers "F.Cu" "F.Mask" "F.Paste")
			(net "Net_1215")
		)
		(pad "42" smd rect
			(at -3.799586 0.999998)
			(size 0.2794 1.6002)
			(layers "F.Cu" "F.Mask" "F.Paste")
			(net "SMB_BMC_MM16_R1_SDA")
		)
		(pad "43" smd rect
			(at 3.750056 1.249934)
			(size 0.2794 1.6002)
			(layers "F.Cu" "F.Mask" "F.Paste")
			(net "Net_1214")
		)
		(pad "44" smd rect
			(at -3.799586 1.500124)
			(size 0.2794 1.6002)
			(layers "F.Cu" "F.Mask" "F.Paste")
			(net "Net_1213")
		)
		(pad "45" smd rect
			(at 3.750056 1.75006)
			(size 0.2794 1.6002)
			(layers "F.Cu" "F.Mask" "F.Paste")
			(net "GND")
		)
		(pad "46" smd rect
			(at -3.799586 1.999996)
			(size 0.2794 1.6002)
			(layers "F.Cu" "F.Mask" "F.Paste")
			(net "EMMC_WP")
		)
		(pad "47" smd rect
			(at 3.750056 2.249932)
			(size 0.2794 1.6002)
			(layers "F.Cu" "F.Mask" "F.Paste")
			(net "Net_1212")
		)
		(pad "48" smd rect
			(at -3.799586 2.500122)
			(size 0.2794 1.6002)
			(layers "F.Cu" "F.Mask" "F.Paste")
			(net "Net_1211")
		)
		(pad "49" smd rect
			(at 3.750056 2.750058)
			(size 0.2794 1.6002)
			(layers "F.Cu" "F.Mask" "F.Paste")
			(net "Net_1210")
		)
		(pad "50" smd rect
			(at -3.799586 2.999994)
			(size 0.2794 1.6002)
			(layers "F.Cu" "F.Mask" "F.Paste")
			(net "Net_1209")
		)
		(pad "51" smd rect
			(at 3.750056 3.24993)
			(size 0.2794 1.6002)
			(layers "F.Cu" "F.Mask" "F.Paste")
			(net "GND")
		)
		(pad "52" smd rect
			(at -3.799586 3.50012)
			(size 0.2794 1.6002)
			(layers "F.Cu" "F.Mask" "F.Paste")
			(net "EMMC_DT7_R")
		)
		(pad "53" smd rect
			(at 3.750056 3.750056)
			(size 0.2794 1.6002)
			(layers "F.Cu" "F.Mask" "F.Paste")
			(net "Net_1208")
		)
		(pad "54" smd rect
			(at -3.799586 3.999992)
			(size 0.2794 1.6002)
			(layers "F.Cu" "F.Mask" "F.Paste")
			(net "EMMC_DT6_R")
		)
		(pad "55" smd rect
			(at 3.750056 4.249928)
			(size 0.2794 1.6002)
			(layers "F.Cu" "F.Mask" "F.Paste")
			(net "EMMC_CLK_R")
		)
		(pad "56" smd rect
			(at -3.799586 4.500118)
			(size 0.2794 1.6002)
			(layers "F.Cu" "F.Mask" "F.Paste")
			(net "EMMC_DT5_R")
		)
		(pad "57" smd rect
			(at 3.750056 4.750054)
			(size 0.2794 1.6002)
			(layers "F.Cu" "F.Mask" "F.Paste")
			(net "GND")
		)
		(pad "58" smd rect
			(at -3.799586 4.99999)
			(size 0.2794 1.6002)
			(layers "F.Cu" "F.Mask" "F.Paste")
			(net "EMMC_DT4_R")
		)
		(pad "59" smd rect
			(at 3.750056 5.249926)
			(size 0.2794 1.6002)
			(layers "F.Cu" "F.Mask" "F.Paste")
			(net "EMMC_CMD_R")
		)
		(pad "60" smd rect
			(at -3.799586 5.500116)
			(size 0.2794 1.6002)
			(layers "F.Cu" "F.Mask" "F.Paste")
			(net "Net_1206")
		)
		(pad "61" smd rect
			(at 3.750056 5.750052)
			(size 0.2794 1.6002)
			(layers "F.Cu" "F.Mask" "F.Paste")
			(net "EMMC_DT3_R")
		)
		(pad "62" smd rect
			(at -3.799586 5.999988)
			(size 0.2794 1.6002)
			(layers "F.Cu" "F.Mask" "F.Paste")
			(net "Net_1205")
		)
		(pad "63" smd rect
			(at 3.750056 6.249924)
			(size 0.2794 1.6002)
			(layers "F.Cu" "F.Mask" "F.Paste")
			(net "GND")
		)
		(pad "64" smd rect
			(at -3.799586 6.500114)
			(size 0.2794 1.6002)
			(layers "F.Cu" "F.Mask" "F.Paste")
			(net "Net_1204")
		)
		(pad "65" smd rect
			(at 3.750056 6.75005)
			(size 0.2794 1.6002)
			(layers "F.Cu" "F.Mask" "F.Paste")
			(net "EMMC_DT2_R")
		)
		(pad "66" smd rect
			(at -3.799586 6.999986)
			(size 0.2794 1.6002)
			(layers "F.Cu" "F.Mask" "F.Paste")
			(net "BMC_EMMC_RST_N")
		)
		(pad "67" smd rect
			(at 3.750056 7.249922)
			(size 0.2794 1.6002)
			(layers "F.Cu" "F.Mask" "F.Paste")
			(net "EMMC_DT1_R")
		)
		(pad "68" smd rect
			(at -3.799586 7.500112)
			(size 0.2794 1.6002)
			(layers "F.Cu" "F.Mask" "F.Paste")
			(net "Net_1203")
		)
		(pad "69" smd rect
			(at 3.750056 7.750048)
			(size 0.2794 1.6002)
			(layers "F.Cu" "F.Mask" "F.Paste")
			(net "GND")
		)
		(pad "70" smd rect
			(at -3.799586 7.999984)
			(size 0.2794 1.6002)
			(layers "F.Cu" "F.Mask" "F.Paste")
			(net "Net_1202")
		)
		(pad "71" smd rect
			(at 3.750056 8.24992)
			(size 0.2794 1.6002)
			(layers "F.Cu" "F.Mask" "F.Paste")
			(net "EMMC_DT0_R")
		)
		(pad "72" smd rect
			(at -3.799586 8.50011)
			(size 0.2794 1.6002)
			(layers "F.Cu" "F.Mask" "F.Paste")
			(net "P3V3_AUX")
		)
		(pad "73" smd rect
			(at 3.750056 8.750046)
			(size 0.2794 1.6002)
			(layers "F.Cu" "F.Mask" "F.Paste")
			(net "Net_1201")
		)
		(pad "74" smd rect
			(at -3.799586 8.999982)
			(size 0.2794 1.6002)
			(layers "F.Cu" "F.Mask" "F.Paste")
			(net "P3V3_AUX")
		)
		(pad "75" smd rect
			(at 3.750056 9.249918)
			(size 0.2794 1.6002)
			(layers "F.Cu" "F.Mask" "F.Paste")
			(net "GND")
		)
		(pad "G1" smd rect
			(at 2.975102 -10.349992)
			(size 1.2446 2.794)
			(layers "F.Cu" "F.Mask" "F.Paste")
			(net "GND")
		)
		(pad "G2" smd rect
			(at 2.975102 10.349992)
			(size 1.2446 2.794)
			(layers "F.Cu" "F.Mask" "F.Paste")
			(net "GND")
		)
		(zone
			(layers "F.Cu" "B.Cu" "In1.Cu" "In2.Cu" "In3.Cu" "In4.Cu" "In5.Cu" "In6.Cu"
				"In7.Cu" "In8.Cu" "In9.Cu" "In10.Cu"
			)
			(hatch none 0.5)
			(connect_pads
				(clearance 0)
			)
			(min_thickness 0.25)
			(keepout
				(tracks not_allowed)
				(vias allowed)
				(pads allowed)
				(copperpour not_allowed)
				(footprints allowed)
			)
			(placement
				(enabled no)
				(sheetname "")
			)
			(fill
				(thermal_gap 0.5)
				(thermal_bridge_width 0.5)
				(island_removal_mode 0)
			)
			(polygon
				(pts
					(arc
						(start 17.76603 -75.635104)
						(mid 15.73403 -75.635104)
						(end 17.76603 -75.635104)
					)
				)
			)
		)
		(zone
			(layers "F.Cu" "B.Cu" "In1.Cu" "In2.Cu" "In3.Cu" "In4.Cu" "In5.Cu" "In6.Cu"
				"In7.Cu" "In8.Cu" "In9.Cu" "In10.Cu"
			)
			(hatch none 0.5)
			(connect_pads
				(clearance 0)
			)
			(min_thickness 0.25)
			(keepout
				(tracks not_allowed)
				(vias allowed)
				(pads allowed)
				(copperpour not_allowed)
				(footprints allowed)
			)
			(placement
				(enabled no)
				(sheetname "")
			)
			(fill
				(thermal_gap 0.5)
				(thermal_bridge_width 0.5)
				(island_removal_mode 0)
			)
			(polygon
				(pts
					(arc
						(start 38.00729 -75.635104)
						(mid 35.49269 -75.635104)
						(end 38.00729 -75.635104)
					)
				)
			)
		)
	)
	(footprint ""
		(layer "F.Cu")
		(at 10.287 -96.393 90)
		(property "Reference" "R887"
			(at 0 0 90)
			(layer "F.SilkS")
			(hide yes)
			(effects
				(font
					(size 1.27 1.27)
				)
			)
		)
		(property "Value" ""
			(at 0 0 90)
			(layer "F.Fab")
			(effects
				(font
					(size 1.27 1.27)
				)
			)
		)
		(duplicate_pad_numbers_are_jumpers no)
		(fp_line
			(start 0.7874 -0.4064)
			(end 0.7874 0.4064)
			(stroke
				(width 0.1524)
				(type default)
			)
			(layer "F.SilkS")
		)
		(fp_line
			(start -0.7874 -0.4064)
			(end 0.7874 -0.4064)
			(stroke
				(width 0.1524)
				(type default)
			)
			(layer "F.SilkS")
		)
		(fp_line
			(start 0.7874 0.4064)
			(end -0.7874 0.4064)
			(stroke
				(width 0.1524)
				(type default)
			)
			(layer "F.SilkS")
		)
		(fp_line
			(start -0.7874 0.4064)
			(end -0.7874 -0.4064)
			(stroke
				(width 0.1524)
				(type default)
			)
			(layer "F.SilkS")
		)
		(fp_line
			(start -0.12065 -0.305054)
			(end -0.12065 -0.2794)
			(stroke
				(width 0.1)
				(type default)
			)
			(layer "F.Fab")
		)
		(fp_line
			(start -0.67945 -0.305054)
			(end -0.12065 -0.305054)
			(stroke
				(width 0.1)
				(type default)
			)
			(layer "F.Fab")
		)
		(fp_line
			(start 0.67945 -0.3048)
			(end 0.67945 0.3048)
			(stroke
				(width 0.1)
				(type default)
			)
			(layer "F.Fab")
		)
		(fp_line
			(start 0.12065 -0.3048)
			(end 0.67945 -0.3048)
			(stroke
				(width 0.1)
				(type default)
			)
			(layer "F.Fab")
		)
		(fp_line
			(start 0.12065 -0.2794)
			(end 0.12065 -0.3048)
			(stroke
				(width 0.1)
				(type default)
			)
			(layer "F.Fab")
		)
		(fp_line
			(start -0.12065 -0.2794)
			(end 0.12065 -0.2794)
			(stroke
				(width 0.1)
				(type default)
			)
			(layer "F.Fab")
		)
		(fp_line
			(start 0.120396 0.2794)
			(end -0.12065 0.2794)
			(stroke
				(width 0.1)
				(type default)
			)
			(layer "F.Fab")
		)
		(fp_line
			(start -0.12065 0.2794)
			(end -0.12065 0.3048)
			(stroke
				(width 0.1)
				(type default)
			)
			(layer "F.Fab")
		)
		(fp_line
			(start 0.67945 0.3048)
			(end 0.120396 0.3048)
			(stroke
				(width 0.1)
				(type default)
			)
			(layer "F.Fab")
		)
		(fp_line
			(start 0.120396 0.3048)
			(end 0.120396 0.2794)
			(stroke
				(width 0.1)
				(type default)
			)
			(layer "F.Fab")
		)
		(fp_line
			(start -0.12065 0.3048)
			(end -0.67945 0.3048)
			(stroke
				(width 0.1)
				(type default)
			)
			(layer "F.Fab")
		)
		(fp_line
			(start -0.67945 0.3048)
			(end -0.67945 -0.305054)
			(stroke
				(width 0.1)
				(type default)
			)
			(layer "F.Fab")
		)
		(pad "1" smd circle
			(at -0.40005 0 90)
			(size 0 0)
			(layers "F.Cu" "F.Mask" "F.Paste")
			(net "P3V3_AUX")
		)
		(pad "2" smd circle
			(at 0.40005 0 90)
			(size 0 0)
			(layers "F.Cu" "F.Mask" "F.Paste")
			(net "RST_BMC_HW")
		)
	)
	(footprint ""
		(layer "F.Cu")
		(at 38.718236 -38.53561 90)
		(property "Reference" "C30"
			(at 0 0 90)
			(layer "F.SilkS")
			(hide yes)
			(effects
				(font
					(size 1.27 1.27)
				)
			)
		)
		(property "Value" ""
			(at 0 0 90)
			(layer "F.Fab")
			(effects
				(font
					(size 1.27 1.27)
				)
			)
		)
		(duplicate_pad_numbers_are_jumpers no)
		(fp_line
			(start 0.7874 -0.4064)
			(end 0.7874 0.4064)
			(stroke
				(width 0.1524)
				(type default)
			)
			(layer "F.SilkS")
		)
		(fp_line
			(start -0.7874 -0.4064)
			(end 0.7874 -0.4064)
			(stroke
				(width 0.1524)
				(type default)
			)
			(layer "F.SilkS")
		)
		(fp_line
			(start 0.7874 0.4064)
			(end -0.7874 0.4064)
			(stroke
				(width 0.1524)
				(type default)
			)
			(layer "F.SilkS")
		)
		(fp_line
			(start -0.7874 0.4064)
			(end -0.7874 -0.4064)
			(stroke
				(width 0.1524)
				(type default)
			)
			(layer "F.SilkS")
		)
		(fp_line
			(start -0.12065 -0.305054)
			(end -0.12065 -0.2794)
			(stroke
				(width 0.1)
				(type default)
			)
			(layer "F.Fab")
		)
		(fp_line
			(start -0.67945 -0.305054)
			(end -0.12065 -0.305054)
			(stroke
				(width 0.1)
				(type default)
			)
			(layer "F.Fab")
		)
		(fp_line
			(start 0.67945 -0.3048)
			(end 0.67945 0.3048)
			(stroke
				(width 0.1)
				(type default)
			)
			(layer "F.Fab")
		)
		(fp_line
			(start 0.12065 -0.3048)
			(end 0.67945 -0.3048)
			(stroke
				(width 0.1)
				(type default)
			)
			(layer "F.Fab")
		)
		(fp_line
			(start 0.12065 -0.2794)
			(end 0.12065 -0.3048)
			(stroke
				(width 0.1)
				(type default)
			)
			(layer "F.Fab")
		)
		(fp_line
			(start -0.12065 -0.2794)
			(end 0.12065 -0.2794)
			(stroke
				(width 0.1)
				(type default)
			)
			(layer "F.Fab")
		)
		(fp_line
			(start 0.120396 0.2794)
			(end -0.12065 0.2794)
			(stroke
				(width 0.1)
				(type default)
			)
			(layer "F.Fab")
		)
		(fp_line
			(start -0.12065 0.2794)
			(end -0.12065 0.3048)
			(stroke
				(width 0.1)
				(type default)
			)
			(layer "F.Fab")
		)
		(fp_line
			(start 0.67945 0.3048)
			(end 0.120396 0.3048)
			(stroke
				(width 0.1)
				(type default)
			)
			(layer "F.Fab")
		)
		(fp_line
			(start 0.120396 0.3048)
			(end 0.120396 0.2794)
			(stroke
				(width 0.1)
				(type default)
			)
			(layer "F.Fab")
		)
		(fp_line
			(start -0.12065 0.3048)
			(end -0.67945 0.3048)
			(stroke
				(width 0.1)
				(type default)
			)
			(layer "F.Fab")
		)
		(fp_line
			(start -0.67945 0.3048)
			(end -0.67945 -0.305054)
			(stroke
				(width 0.1)
				(type default)
			)
			(layer "F.Fab")
		)
		(pad "1" smd circle
			(at -0.40005 0 90)
			(size 0 0)
			(layers "F.Cu" "F.Mask" "F.Paste")
			(net "P3V3_P2V5_P1V8_RVDD")
		)
		(pad "2" smd circle
			(at 0.40005 0 90)
			(size 0 0)
			(layers "F.Cu" "F.Mask" "F.Paste")
			(net "GND")
		)
	)
	(footprint ""
		(layer "F.Cu")
		(at 95.926656 -4.605274 -90)
		(property "Reference" "J19"
			(at 1.049274 -2.779014 90)
			(unlocked yes)
			(layer "F.SilkS")
			(effects
				(font
					(size 0.7874 0.5842)
					(thickness 0.1524)
				)
				(justify left)
			)
		)
		(property "Value" ""
			(at 0 0 270)
			(layer "F.Fab")
			(effects
				(font
					(size 1.27 1.27)
				)
			)
		)
		(duplicate_pad_numbers_are_jumpers no)
		(fp_line
			(start -1.2192 2.1082)
			(end -1.2192 -2.1082)
			(stroke
				(width 0.1524)
				(type default)
			)
			(layer "F.SilkS")
		)
		(fp_line
			(start 1.2192 2.1082)
			(end -1.2192 2.1082)
			(stroke
				(width 0.1524)
				(type default)
			)
			(layer "F.SilkS")
		)
		(fp_line
			(start 1.2192 0.810514)
			(end 1.2192 2.1082)
			(stroke
				(width 0.1524)
				(type default)
			)
			(layer "F.SilkS")
		)
		(fp_line
			(start -1.2192 -2.1082)
			(end 1.2192 -2.1082)
			(stroke
				(width 0.1524)
				(type default)
			)
			(layer "F.SilkS")
		)
		(fp_line
			(start 1.2192 -2.1082)
			(end 1.2192 -0.825246)
			(stroke
				(width 0.1524)
				(type default)
			)
			(layer "F.SilkS")
		)
		(pad "" np_thru_hole circle
			(at -2.8829 -1.27 180)
			(size 1.0414 1.0414)
			(drill 1.0414)
			(layers "*.Cu" "*.Mask")
			(clearance 0.381)
			(thermal_gap 0.381)
		)
		(pad "" np_thru_hole circle
			(at -2.8829 1.27 180)
			(size 1.0414 1.0414)
			(drill 1.0414)
			(layers "*.Cu" "*.Mask")
			(clearance 0.381)
			(thermal_gap 0.381)
		)
		(pad "" np_thru_hole circle
			(at 3.4671 -1.27 180)
			(size 1.0414 1.0414)
			(drill 1.0414)
			(layers "*.Cu" "*.Mask")
			(clearance 0.381)
			(thermal_gap 0.381)
		)
		(pad "" np_thru_hole circle
			(at 3.4671 1.27 180)
			(size 1.0414 1.0414)
			(drill 1.0414)
			(layers "*.Cu" "*.Mask")
			(clearance 0.381)
			(thermal_gap 0.381)
		)
		(pad "1" smd rect
			(at 0.8255 -0.249936 180)
			(size 0.3048 0.508)
			(layers "F.Cu" "F.Mask" "F.Paste")
			(net "85_5INCH_IN4_DP")
		)
		(pad "2" smd rect
			(at 0.8255 0.249936 180)
			(size 0.3048 0.508)
			(layers "F.Cu" "F.Mask" "F.Paste")
			(net "85_5INCH_IN4_DN")
		)
		(pad "3" smd circle
			(at 0 0 270)
			(size 0 0)
			(layers "F.Cu" "F.Mask" "F.Paste")
			(net "GND_P1")
		)
		(zone
			(layer "F.Cu")
			(hatch none 0.5)
			(connect_pads
				(clearance 0)
			)
			(min_thickness 0.25)
			(keepout
				(tracks not_allowed)
				(vias allowed)
				(pads allowed)
				(copperpour not_allowed)
				(footprints allowed)
			)
			(placement
				(enabled no)
				(sheetname "")
			)
			(fill
				(thermal_gap 0.5)
				(thermal_bridge_width 0.5)
				(island_removal_mode 0)
			)
			(polygon
				(pts
					(xy 96.475296 -3.487674) (xy 96.379792 -3.487674) (xy 96.379792 -4.084574) (xy 95.973392 -4.084574)
					(xy 95.973392 -3.487674) (xy 95.87992 -3.487674) (xy 95.87992 -4.084574) (xy 95.47352 -4.084574)
					(xy 95.47352 -3.487674) (xy 95.378016 -3.487674) (xy 95.378016 -4.186174) (xy 96.475296 -4.186174)
				)
			)
		)
		(zone
			(layers "F.Cu" "B.Cu" "In1.Cu" "In2.Cu" "In3.Cu" "In4.Cu" "In5.Cu" "In6.Cu"
				"In7.Cu" "In8.Cu" "In9.Cu" "In10.Cu"
			)
			(hatch none 0.5)
			(connect_pads
				(clearance 0)
			)
			(min_thickness 0.25)
			(keepout
				(tracks not_allowed)
				(vias allowed)
				(pads allowed)
				(copperpour not_allowed)
				(footprints allowed)
			)
			(placement
				(enabled no)
				(sheetname "")
			)
			(fill
				(thermal_gap 0.5)
				(thermal_bridge_width 0.5)
				(island_removal_mode 0)
			)
			(polygon
				(pts
					(arc
						(start 95.583756 -7.488174)
						(mid 93.729556 -7.488174)
						(end 95.583756 -7.488174)
					)
				)
			)
		)
		(zone
			(layers "F.Cu" "B.Cu" "In1.Cu" "In2.Cu" "In3.Cu" "In4.Cu" "In5.Cu" "In6.Cu"
				"In7.Cu" "In8.Cu" "In9.Cu" "In10.Cu"
			)
			(hatch none 0.5)
			(connect_pads
				(clearance 0)
			)
			(min_thickness 0.25)
			(keepout
				(tracks not_allowed)
				(vias allowed)
				(pads allowed)
				(copperpour not_allowed)
				(footprints allowed)
			)
			(placement
				(enabled no)
				(sheetname "")
			)
			(fill
				(thermal_gap 0.5)
				(thermal_bridge_width 0.5)
				(island_removal_mode 0)
			)
			(polygon
				(pts
					(arc
						(start 95.583756 -1.138174)
						(mid 93.729556 -1.138174)
						(end 95.583756 -1.138174)
					)
				)
			)
		)
		(zone
			(layers "F.Cu" "B.Cu" "In1.Cu" "In2.Cu" "In3.Cu" "In4.Cu" "In5.Cu" "In6.Cu"
				"In7.Cu" "In8.Cu" "In9.Cu" "In10.Cu"
			)
			(hatch none 0.5)
			(connect_pads
				(clearance 0)
			)
			(min_thickness 0.25)
			(keepout
				(tracks not_allowed)
				(vias allowed)
				(pads allowed)
				(copperpour not_allowed)
				(footprints allowed)
			)
			(placement
				(enabled no)
				(sheetname "")
			)
			(fill
				(thermal_gap 0.5)
				(thermal_bridge_width 0.5)
				(island_removal_mode 0)
			)
			(polygon
				(pts
					(arc
						(start 98.123756 -7.488174)
						(mid 96.269556 -7.488174)
						(end 98.123756 -7.488174)
					)
				)
			)
		)
		(zone
			(layers "F.Cu" "B.Cu" "In1.Cu" "In2.Cu" "In3.Cu" "In4.Cu" "In5.Cu" "In6.Cu"
				"In7.Cu" "In8.Cu" "In9.Cu" "In10.Cu"
			)
			(hatch none 0.5)
			(connect_pads
				(clearance 0)
			)
			(min_thickness 0.25)
			(keepout
				(tracks not_allowed)
				(vias allowed)
				(pads allowed)
				(copperpour not_allowed)
				(footprints allowed)
			)
			(placement
				(enabled no)
				(sheetname "")
			)
			(fill
				(thermal_gap 0.5)
				(thermal_bridge_width 0.5)
				(island_removal_mode 0)
			)
			(polygon
				(pts
					(arc
						(start 98.123756 -1.138174)
						(mid 96.269556 -1.138174)
						(end 98.123756 -1.138174)
					)
				)
			)
		)
	)
	(footprint ""
		(layer "F.Cu")
		(at 50.79619 -34.637726 90)
		(property "Reference" "R148"
			(at 0 0 90)
			(layer "F.SilkS")
			(hide yes)
			(effects
				(font
					(size 1.27 1.27)
				)
			)
		)
		(property "Value" ""
			(at 0 0 90)
			(layer "F.Fab")
			(effects
				(font
					(size 1.27 1.27)
				)
			)
		)
		(duplicate_pad_numbers_are_jumpers no)
		(fp_line
			(start 0.7874 -0.4064)
			(end 0.7874 0.4064)
			(stroke
				(width 0.1524)
				(type default)
			)
			(layer "F.SilkS")
		)
		(fp_line
			(start -0.7874 -0.4064)
			(end 0.7874 -0.4064)
			(stroke
				(width 0.1524)
				(type default)
			)
			(layer "F.SilkS")
		)
		(fp_line
			(start 0.7874 0.4064)
			(end -0.7874 0.4064)
			(stroke
				(width 0.1524)
				(type default)
			)
			(layer "F.SilkS")
		)
		(fp_line
			(start -0.7874 0.4064)
			(end -0.7874 -0.4064)
			(stroke
				(width 0.1524)
				(type default)
			)
			(layer "F.SilkS")
		)
		(fp_line
			(start -0.12065 -0.305054)
			(end -0.12065 -0.2794)
			(stroke
				(width 0.1)
				(type default)
			)
			(layer "F.Fab")
		)
		(fp_line
			(start -0.67945 -0.305054)
			(end -0.12065 -0.305054)
			(stroke
				(width 0.1)
				(type default)
			)
			(layer "F.Fab")
		)
		(fp_line
			(start 0.67945 -0.3048)
			(end 0.67945 0.3048)
			(stroke
				(width 0.1)
				(type default)
			)
			(layer "F.Fab")
		)
		(fp_line
			(start 0.12065 -0.3048)
			(end 0.67945 -0.3048)
			(stroke
				(width 0.1)
				(type default)
			)
			(layer "F.Fab")
		)
		(fp_line
			(start 0.12065 -0.2794)
			(end 0.12065 -0.3048)
			(stroke
				(width 0.1)
				(type default)
			)
			(layer "F.Fab")
		)
		(fp_line
			(start -0.12065 -0.2794)
			(end 0.12065 -0.2794)
			(stroke
				(width 0.1)
				(type default)
			)
			(layer "F.Fab")
		)
		(fp_line
			(start 0.120396 0.2794)
			(end -0.12065 0.2794)
			(stroke
				(width 0.1)
				(type default)
			)
			(layer "F.Fab")
		)
		(fp_line
			(start -0.12065 0.2794)
			(end -0.12065 0.3048)
			(stroke
				(width 0.1)
				(type default)
			)
			(layer "F.Fab")
		)
		(fp_line
			(start 0.67945 0.3048)
			(end 0.120396 0.3048)
			(stroke
				(width 0.1)
				(type default)
			)
			(layer "F.Fab")
		)
		(fp_line
			(start 0.120396 0.3048)
			(end 0.120396 0.2794)
			(stroke
				(width 0.1)
				(type default)
			)
			(layer "F.Fab")
		)
		(fp_line
			(start -0.12065 0.3048)
			(end -0.67945 0.3048)
			(stroke
				(width 0.1)
				(type default)
			)
			(layer "F.Fab")
		)
		(fp_line
			(start -0.67945 0.3048)
			(end -0.67945 -0.305054)
			(stroke
				(width 0.1)
				(type default)
			)
			(layer "F.Fab")
		)
		(pad "1" smd circle
			(at -0.40005 0 90)
			(size 0 0)
			(layers "F.Cu" "F.Mask" "F.Paste")
			(net "SGPIO_CLK_1")
		)
		(pad "2" smd circle
			(at 0.40005 0 90)
			(size 0 0)
			(layers "F.Cu" "F.Mask" "F.Paste")
			(net "SGPIO_BMC_M1_CLK")
		)
	)
	(footprint ""
		(layer "F.Cu")
		(at 82.00009 -2.94005)
		(property "Reference" "SW7"
			(at -5.2705 -5.448554 0)
			(unlocked yes)
			(layer "F.SilkS")
			(effects
				(font
					(size 0.7874 0.5842)
					(thickness 0.1524)
				)
				(justify left)
			)
		)
		(property "Value" ""
			(at 0 0 0)
			(layer "F.Fab")
			(effects
				(font
					(size 1.27 1.27)
				)
			)
		)
		(duplicate_pad_numbers_are_jumpers no)
		(fp_line
			(start -3.700018 -4.549902)
			(end -3.700018 -2.51206)
			(stroke
				(width 0.1524)
				(type default)
			)
			(layer "F.SilkS")
		)
		(fp_line
			(start -3.700018 -0.98806)
			(end -3.700018 -0.88646)
			(stroke
				(width 0.1524)
				(type default)
			)
			(layer "F.SilkS")
		)
		(fp_line
			(start -3.700018 1.39954)
			(end -3.700018 1.549908)
			(stroke
				(width 0.1524)
				(type default)
			)
			(layer "F.SilkS")
		)
		(fp_line
			(start -3.700018 1.549908)
			(end -1.75006 1.549908)
			(stroke
				(width 0.1524)
				(type default)
			)
			(layer "F.SilkS")
		)
		(fp_line
			(start -3.1496 -4.549902)
			(end -3.700018 -4.549902)
			(stroke
				(width 0.1524)
				(type default)
			)
			(layer "F.SilkS")
		)
		(fp_line
			(start -1.75006 1.549908)
			(end -1.75006 4.549902)
			(stroke
				(width 0.1524)
				(type default)
			)
			(layer "F.SilkS")
		)
		(fp_line
			(start -1.75006 4.549902)
			(end 1.75006 4.549902)
			(stroke
				(width 0.1524)
				(type default)
			)
			(layer "F.SilkS")
		)
		(fp_line
			(start 1.3716 -4.549902)
			(end -1.3716 -4.549902)
			(stroke
				(width 0.1524)
				(type default)
			)
			(layer "F.SilkS")
		)
		(fp_line
			(start 1.75006 1.549908)
			(end 3.700018 1.549908)
			(stroke
				(width 0.1524)
				(type default)
			)
			(layer "F.SilkS")
		)
		(fp_line
			(start 1.75006 4.549902)
			(end 1.75006 1.549908)
			(stroke
				(width 0.1524)
				(type default)
			)
			(layer "F.SilkS")
		)
		(fp_line
			(start 3.700018 -4.549902)
			(end 3.1496 -4.549902)
			(stroke
				(width 0.1524)
				(type default)
			)
			(layer "F.SilkS")
		)
		(fp_line
			(start 3.700018 -2.51206)
			(end 3.700018 -4.549902)
			(stroke
				(width 0.1524)
				(type default)
			)
			(layer "F.SilkS")
		)
		(fp_line
			(start 3.700018 -0.88646)
			(end 3.700018 -0.98806)
			(stroke
				(width 0.1524)
				(type default)
			)
			(layer "F.SilkS")
		)
		(fp_line
			(start 3.700018 1.549908)
			(end 3.700018 1.39954)
			(stroke
				(width 0.1524)
				(type default)
			)
			(layer "F.SilkS")
		)
		(fp_poly
			(pts
				(xy -3.883914 -4.043934) (xy -5.310886 -3.330448) (xy -5.310886 -4.75742)
			)
			(stroke
				(width 0)
				(type default)
			)
			(fill yes)
			(layer "F.SilkS")
		)
		(fp_line
			(start -3.700018 -4.549902)
			(end -3.700018 1.549908)
			(stroke
				(width 0.1)
				(type default)
			)
			(layer "F.Fab")
		)
		(fp_line
			(start -3.700018 1.549908)
			(end -1.75006 1.549908)
			(stroke
				(width 0.1)
				(type default)
			)
			(layer "F.Fab")
		)
		(fp_line
			(start -1.75006 1.549908)
			(end -1.75006 4.549902)
			(stroke
				(width 0.1)
				(type default)
			)
			(layer "F.Fab")
		)
		(fp_line
			(start -1.75006 4.549902)
			(end 1.75006 4.549902)
			(stroke
				(width 0.1)
				(type default)
			)
			(layer "F.Fab")
		)
		(fp_line
			(start 1.75006 1.549908)
			(end 3.700018 1.549908)
			(stroke
				(width 0.1)
				(type default)
			)
			(layer "F.Fab")
		)
		(fp_line
			(start 1.75006 4.549902)
			(end 1.75006 1.549908)
			(stroke
				(width 0.1)
				(type default)
			)
			(layer "F.Fab")
		)
		(fp_line
			(start 3.700018 -4.549902)
			(end -3.700018 -4.549902)
			(stroke
				(width 0.1)
				(type default)
			)
			(layer "F.Fab")
		)
		(fp_line
			(start 3.700018 1.549908)
			(end 3.700018 -4.549902)
			(stroke
				(width 0.1)
				(type default)
			)
			(layer "F.Fab")
		)
		(fp_poly
			(pts
				(xy -3.883914 -4.043934) (xy -5.310886 -3.330448) (xy -5.310886 -4.75742)
			)
			(stroke
				(width 0)
				(type default)
			)
			(fill yes)
			(layer "F.Fab")
		)
		(pad "" np_thru_hole circle
			(at -3.50012 -1.75006)
			(size 0.9144 0.9144)
			(drill 0.9144)
			(layers "*.Cu" "*.Mask")
			(clearance 0.381)
			(thermal_gap 0.381)
		)
		(pad "" np_thru_hole circle
			(at 3.50012 -1.75006)
			(size 0.9144 0.9144)
			(drill 0.9144)
			(layers "*.Cu" "*.Mask")
			(clearance 0.381)
			(thermal_gap 0.381)
		)
		(pad "1" smd rect
			(at -2.249932 -4.05003)
			(size 1.4986 2.0066)
			(layers "F.Cu" "F.Mask" "F.Paste")
			(net "GND")
		)
		(pad "2" smd rect
			(at 2.249932 -4.05003)
			(size 1.4986 2.0066)
			(layers "F.Cu" "F.Mask" "F.Paste")
			(net "REAR_ID_RST_BTN_N")
		)
		(pad "3" smd rect
			(at -4.19989 0.249936)
			(size 2.0066 2.0066)
			(layers "F.Cu" "F.Mask" "F.Paste")
			(net "GND")
		)
		(pad "4" smd rect
			(at 4.19989 0.249936)
			(size 2.0066 2.0066)
			(layers "F.Cu" "F.Mask" "F.Paste")
			(net "GND")
		)
		(zone
			(layers "F.Cu" "B.Cu" "In1.Cu" "In2.Cu" "In3.Cu" "In4.Cu" "In5.Cu" "In6.Cu"
				"In7.Cu" "In8.Cu" "In9.Cu" "In10.Cu"
			)
			(hatch none 0.5)
			(connect_pads
				(clearance 0)
			)
			(min_thickness 0.25)
			(keepout
				(tracks not_allowed)
				(vias allowed)
				(pads allowed)
				(copperpour not_allowed)
				(footprints allowed)
			)
			(placement
				(enabled no)
				(sheetname "")
			)
			(fill
				(thermal_gap 0.5)
				(thermal_bridge_width 0.5)
				(island_removal_mode 0)
			)
			(polygon
				(pts
					(arc
						(start 79.363824 -4.69011)
						(mid 77.636116 -4.69011)
						(end 79.363824 -4.69011)
					)
				)
			)
		)
		(zone
			(layers "F.Cu" "B.Cu" "In1.Cu" "In2.Cu" "In3.Cu" "In4.Cu" "In5.Cu" "In6.Cu"
				"In7.Cu" "In8.Cu" "In9.Cu" "In10.Cu"
			)
			(hatch none 0.5)
			(connect_pads
				(clearance 0)
			)
			(min_thickness 0.25)
			(keepout
				(tracks not_allowed)
				(vias allowed)
				(pads allowed)
				(copperpour not_allowed)
				(footprints allowed)
			)
			(placement
				(enabled no)
				(sheetname "")
			)
			(fill
				(thermal_gap 0.5)
				(thermal_bridge_width 0.5)
				(island_removal_mode 0)
			)
			(polygon
				(pts
					(arc
						(start 86.36381 -4.69011)
						(mid 84.63661 -4.69011)
						(end 86.36381 -4.69011)
					)
				)
			)
		)
	)
	(footprint ""
		(layer "F.Cu")
		(at 12.065 -89.789 -90)
		(property "Reference" "R593"
			(at 0 0 270)
			(layer "F.SilkS")
			(hide yes)
			(effects
				(font
					(size 1.27 1.27)
				)
			)
		)
		(property "Value" ""
			(at 0 0 270)
			(layer "F.Fab")
			(effects
				(font
					(size 1.27 1.27)
				)
			)
		)
		(duplicate_pad_numbers_are_jumpers no)
		(fp_line
			(start -0.7874 0.4064)
			(end -0.7874 -0.4064)
			(stroke
				(width 0.1524)
				(type default)
			)
			(layer "F.SilkS")
		)
		(fp_line
			(start 0.7874 0.4064)
			(end -0.7874 0.4064)
			(stroke
				(width 0.1524)
				(type default)
			)
			(layer "F.SilkS")
		)
		(fp_line
			(start -0.7874 -0.4064)
			(end 0.7874 -0.4064)
			(stroke
				(width 0.1524)
				(type default)
			)
			(layer "F.SilkS")
		)
		(fp_line
			(start 0.7874 -0.4064)
			(end 0.7874 0.4064)
			(stroke
				(width 0.1524)
				(type default)
			)
			(layer "F.SilkS")
		)
		(fp_line
			(start -0.67945 0.3048)
			(end -0.67945 -0.305054)
			(stroke
				(width 0.1)
				(type default)
			)
			(layer "F.Fab")
		)
		(fp_line
			(start -0.12065 0.3048)
			(end -0.67945 0.3048)
			(stroke
				(width 0.1)
				(type default)
			)
			(layer "F.Fab")
		)
		(fp_line
			(start 0.120396 0.3048)
			(end 0.120396 0.2794)
			(stroke
				(width 0.1)
				(type default)
			)
			(layer "F.Fab")
		)
		(fp_line
			(start 0.67945 0.3048)
			(end 0.120396 0.3048)
			(stroke
				(width 0.1)
				(type default)
			)
			(layer "F.Fab")
		)
		(fp_line
			(start -0.12065 0.2794)
			(end -0.12065 0.3048)
			(stroke
				(width 0.1)
				(type default)
			)
			(layer "F.Fab")
		)
		(fp_line
			(start 0.120396 0.2794)
			(end -0.12065 0.2794)
			(stroke
				(width 0.1)
				(type default)
			)
			(layer "F.Fab")
		)
		(fp_line
			(start -0.12065 -0.2794)
			(end 0.12065 -0.2794)
			(stroke
				(width 0.1)
				(type default)
			)
			(layer "F.Fab")
		)
		(fp_line
			(start 0.12065 -0.2794)
			(end 0.12065 -0.3048)
			(stroke
				(width 0.1)
				(type default)
			)
			(layer "F.Fab")
		)
		(fp_line
			(start 0.12065 -0.3048)
			(end 0.67945 -0.3048)
			(stroke
				(width 0.1)
				(type default)
			)
			(layer "F.Fab")
		)
		(fp_line
			(start 0.67945 -0.3048)
			(end 0.67945 0.3048)
			(stroke
				(width 0.1)
				(type default)
			)
			(layer "F.Fab")
		)
		(fp_line
			(start -0.67945 -0.305054)
			(end -0.12065 -0.305054)
			(stroke
				(width 0.1)
				(type default)
			)
			(layer "F.Fab")
		)
		(fp_line
			(start -0.12065 -0.305054)
			(end -0.12065 -0.2794)
			(stroke
				(width 0.1)
				(type default)
			)
			(layer "F.Fab")
		)
		(pad "1" smd circle
			(at -0.40005 0 270)
			(size 0 0)
			(layers "F.Cu" "F.Mask" "F.Paste")
			(net "P3V3_AUX")
		)
		(pad "2" smd circle
			(at 0.40005 0 270)
			(size 0 0)
			(layers "F.Cu" "F.Mask" "F.Paste")
			(net "BMC_CPLD_GPIO_7")
		)
	)
	(footprint ""
		(layer "F.Cu")
		(at 75.946 -79.121 180)
		(property "Reference" "R631"
			(at 0 0 180)
			(layer "F.SilkS")
			(hide yes)
			(effects
				(font
					(size 1.27 1.27)
				)
			)
		)
		(property "Value" ""
			(at 0 0 180)
			(layer "F.Fab")
			(effects
				(font
					(size 1.27 1.27)
				)
			)
		)
		(duplicate_pad_numbers_are_jumpers no)
		(fp_line
			(start 0.7874 0.4064)
			(end -0.7874 0.4064)
			(stroke
				(width 0.1524)
				(type default)
			)
			(layer "F.SilkS")
		)
		(fp_line
			(start 0.7874 -0.4064)
			(end 0.7874 0.4064)
			(stroke
				(width 0.1524)
				(type default)
			)
			(layer "F.SilkS")
		)
		(fp_line
			(start -0.7874 0.4064)
			(end -0.7874 -0.4064)
			(stroke
				(width 0.1524)
				(type default)
			)
			(layer "F.SilkS")
		)
		(fp_line
			(start -0.7874 -0.4064)
			(end 0.7874 -0.4064)
			(stroke
				(width 0.1524)
				(type default)
			)
			(layer "F.SilkS")
		)
		(fp_line
			(start 0.67945 0.3048)
			(end 0.120396 0.3048)
			(stroke
				(width 0.1)
				(type default)
			)
			(layer "F.Fab")
		)
		(fp_line
			(start 0.67945 -0.3048)
			(end 0.67945 0.3048)
			(stroke
				(width 0.1)
				(type default)
			)
			(layer "F.Fab")
		)
		(fp_line
			(start 0.12065 -0.2794)
			(end 0.12065 -0.3048)
			(stroke
				(width 0.1)
				(type default)
			)
			(layer "F.Fab")
		)
		(fp_line
			(start 0.12065 -0.3048)
			(end 0.67945 -0.3048)
			(stroke
				(width 0.1)
				(type default)
			)
			(layer "F.Fab")
		)
		(fp_line
			(start 0.120396 0.3048)
			(end 0.120396 0.2794)
			(stroke
				(width 0.1)
				(type default)
			)
			(layer "F.Fab")
		)
		(fp_line
			(start 0.120396 0.2794)
			(end -0.12065 0.2794)
			(stroke
				(width 0.1)
				(type default)
			)
			(layer "F.Fab")
		)
		(fp_line
			(start -0.12065 0.3048)
			(end -0.67945 0.3048)
			(stroke
				(width 0.1)
				(type default)
			)
			(layer "F.Fab")
		)
		(fp_line
			(start -0.12065 0.2794)
			(end -0.12065 0.3048)
			(stroke
				(width 0.1)
				(type default)
			)
			(layer "F.Fab")
		)
		(fp_line
			(start -0.12065 -0.2794)
			(end 0.12065 -0.2794)
			(stroke
				(width 0.1)
				(type default)
			)
			(layer "F.Fab")
		)
		(fp_line
			(start -0.12065 -0.305054)
			(end -0.12065 -0.2794)
			(stroke
				(width 0.1)
				(type default)
			)
			(layer "F.Fab")
		)
		(fp_line
			(start -0.67945 0.3048)
			(end -0.67945 -0.305054)
			(stroke
				(width 0.1)
				(type default)
			)
			(layer "F.Fab")
		)
		(fp_line
			(start -0.67945 -0.305054)
			(end -0.12065 -0.305054)
			(stroke
				(width 0.1)
				(type default)
			)
			(layer "F.Fab")
		)
		(pad "1" smd circle
			(at -0.40005 0 180)
			(size 0 0)
			(layers "F.Cu" "F.Mask" "F.Paste")
			(net "P3V3_LDO")
		)
		(pad "2" smd circle
			(at 0.40005 0 180)
			(size 0 0)
			(layers "F.Cu" "F.Mask" "F.Paste")
			(net "U56_ADJ_1")
		)
	)
	(footprint ""
		(layer "F.Cu")
		(at 73.66 -94.6658)
		(property "Reference" "R113"
			(at 0 0 0)
			(layer "F.SilkS")
			(hide yes)
			(effects
				(font
					(size 1.27 1.27)
				)
			)
		)
		(property "Value" ""
			(at 0 0 0)
			(layer "F.Fab")
			(effects
				(font
					(size 1.27 1.27)
				)
			)
		)
		(duplicate_pad_numbers_are_jumpers no)
		(fp_line
			(start -0.7874 -0.4064)
			(end 0.7874 -0.4064)
			(stroke
				(width 0.1524)
				(type default)
			)
			(layer "F.SilkS")
		)
		(fp_line
			(start -0.7874 0.4064)
			(end -0.7874 -0.4064)
			(stroke
				(width 0.1524)
				(type default)
			)
			(layer "F.SilkS")
		)
		(fp_line
			(start 0.7874 -0.4064)
			(end 0.7874 0.4064)
			(stroke
				(width 0.1524)
				(type default)
			)
			(layer "F.SilkS")
		)
		(fp_line
			(start 0.7874 0.4064)
			(end -0.7874 0.4064)
			(stroke
				(width 0.1524)
				(type default)
			)
			(layer "F.SilkS")
		)
		(fp_line
			(start -0.67945 -0.305054)
			(end -0.12065 -0.305054)
			(stroke
				(width 0.1)
				(type default)
			)
			(layer "F.Fab")
		)
		(fp_line
			(start -0.67945 0.3048)
			(end -0.67945 -0.305054)
			(stroke
				(width 0.1)
				(type default)
			)
			(layer "F.Fab")
		)
		(fp_line
			(start -0.12065 -0.305054)
			(end -0.12065 -0.2794)
			(stroke
				(width 0.1)
				(type default)
			)
			(layer "F.Fab")
		)
		(fp_line
			(start -0.12065 -0.2794)
			(end 0.12065 -0.2794)
			(stroke
				(width 0.1)
				(type default)
			)
			(layer "F.Fab")
		)
		(fp_line
			(start -0.12065 0.2794)
			(end -0.12065 0.3048)
			(stroke
				(width 0.1)
				(type default)
			)
			(layer "F.Fab")
		)
		(fp_line
			(start -0.12065 0.3048)
			(end -0.67945 0.3048)
			(stroke
				(width 0.1)
				(type default)
			)
			(layer "F.Fab")
		)
		(fp_line
			(start 0.120396 0.2794)
			(end -0.12065 0.2794)
			(stroke
				(width 0.1)
				(type default)
			)
			(layer "F.Fab")
		)
		(fp_line
			(start 0.120396 0.3048)
			(end 0.120396 0.2794)
			(stroke
				(width 0.1)
				(type default)
			)
			(layer "F.Fab")
		)
		(fp_line
			(start 0.12065 -0.3048)
			(end 0.67945 -0.3048)
			(stroke
				(width 0.1)
				(type default)
			)
			(layer "F.Fab")
		)
		(fp_line
			(start 0.12065 -0.2794)
			(end 0.12065 -0.3048)
			(stroke
				(width 0.1)
				(type default)
			)
			(layer "F.Fab")
		)
		(fp_line
			(start 0.67945 -0.3048)
			(end 0.67945 0.3048)
			(stroke
				(width 0.1)
				(type default)
			)
			(layer "F.Fab")
		)
		(fp_line
			(start 0.67945 0.3048)
			(end 0.120396 0.3048)
			(stroke
				(width 0.1)
				(type default)
			)
			(layer "F.Fab")
		)
		(pad "1" smd circle
			(at -0.40005 0)
			(size 0 0)
			(layers "F.Cu" "F.Mask" "F.Paste")
			(net "IRQ_TPM_SPI_N")
		)
		(pad "2" smd circle
			(at 0.40005 0)
			(size 0 0)
			(layers "F.Cu" "F.Mask" "F.Paste")
			(net "IRQ_BMC_TPM_SPI_R_N")
		)
	)
	(footprint ""
		(layer "F.Cu")
		(at 6.4516 -107.3404)
		(property "Reference" "D20"
			(at -4.8641 -1.58623 0)
			(unlocked yes)
			(layer "F.SilkS")
			(effects
				(font
					(size 0.7874 0.5842)
					(thickness 0.1524)
				)
				(justify left)
			)
		)
		(property "Value" ""
			(at 0 0 0)
			(layer "F.Fab")
			(effects
				(font
					(size 1.27 1.27)
				)
			)
		)
		(duplicate_pad_numbers_are_jumpers no)
		(fp_line
			(start -2.4638 -1.0414)
			(end 2.7178 -1.0414)
			(stroke
				(width 0.1524)
				(type default)
			)
			(layer "F.SilkS")
		)
		(fp_line
			(start -2.4638 1.0414)
			(end -2.4638 -1.0414)
			(stroke
				(width 0.1524)
				(type default)
			)
			(layer "F.SilkS")
		)
		(fp_line
			(start -0.508 -0.508)
			(end -0.508 0.5334)
			(stroke
				(width 0.1524)
				(type default)
			)
			(layer "F.SilkS")
		)
		(fp_line
			(start -0.508 0.5334)
			(end 0.1778 -0.0254)
			(stroke
				(width 0.1524)
				(type default)
			)
			(layer "F.SilkS")
		)
		(fp_line
			(start 0.1778 -0.0254)
			(end -0.4826 -0.4826)
			(stroke
				(width 0.1524)
				(type default)
			)
			(layer "F.SilkS")
		)
		(fp_line
			(start 0.254 -0.508)
			(end 0.254 0.5334)
			(stroke
				(width 0.1524)
				(type default)
			)
			(layer "F.SilkS")
		)
		(fp_line
			(start 2.4638 -1.0414)
			(end 2.4638 1.0414)
			(stroke
				(width 0.1524)
				(type default)
			)
			(layer "F.SilkS")
		)
		(fp_line
			(start 2.5908 -1.0414)
			(end 2.5908 1.0414)
			(stroke
				(width 0.1524)
				(type default)
			)
			(layer "F.SilkS")
		)
		(fp_line
			(start 2.7178 -1.0414)
			(end 2.7178 1.0414)
			(stroke
				(width 0.1524)
				(type default)
			)
			(layer "F.SilkS")
		)
		(fp_line
			(start 2.7178 1.0414)
			(end -2.4638 1.0414)
			(stroke
				(width 0.1524)
				(type default)
			)
			(layer "F.SilkS")
		)
		(fp_line
			(start -2.4638 -1.0414)
			(end 2.7178 -1.0414)
			(stroke
				(width 0.1)
				(type default)
			)
			(layer "F.Fab")
		)
		(fp_line
			(start -2.4638 1.0414)
			(end -2.4638 -1.0414)
			(stroke
				(width 0.1)
				(type default)
			)
			(layer "F.Fab")
		)
		(fp_line
			(start 2.7178 -1.0414)
			(end 2.7178 1.0414)
			(stroke
				(width 0.1)
				(type default)
			)
			(layer "F.Fab")
		)
		(fp_line
			(start 2.7178 1.0414)
			(end -2.4638 1.0414)
			(stroke
				(width 0.1)
				(type default)
			)
			(layer "F.Fab")
		)
		(fp_text user "+"
			(at -3.9624 -0.17145 0)
			(unlocked yes)
			(layer "F.SilkS")
			(effects
				(font
					(size 1.905 1.4224)
					(thickness 0.1524)
				)
				(justify left)
			)
		)
		(fp_text user "-"
			(at 2.4892 -0.26035 0)
			(unlocked yes)
			(layer "F.SilkS")
			(effects
				(font
					(size 1.905 1.4224)
					(thickness 0.1524)
				)
				(justify left)
			)
		)
		(fp_text user "+"
			(at -3.9624 -0.17145 0)
			(unlocked yes)
			(layer "F.Fab")
			(effects
				(font
					(size 1.905 1.4224)
					(thickness 0.1524)
				)
				(justify left)
			)
		)
		(fp_text user "-"
			(at 2.9845 -0.366268 0)
			(unlocked yes)
			(layer "F.Fab")
			(effects
				(font
					(size 1.905 1.4224)
					(thickness 0.1524)
				)
				(justify left)
			)
		)
		(pad "1" smd rect
			(at -1.724914 0)
			(size 1.1684 1.7526)
			(layers "F.Cu" "F.Mask" "F.Paste")
			(net "P3V3_AUX")
		)
		(pad "2" smd rect
			(at 1.724914 0)
			(size 1.1684 1.7526)
			(layers "F.Cu" "F.Mask" "F.Paste")
			(net "J7_P1")
		)
	)
	(footprint ""
		(layer "F.Cu")
		(at 72.46493 -28.546044 90)
		(property "Reference" "R602"
			(at 0 0 90)
			(layer "F.SilkS")
			(hide yes)
			(effects
				(font
					(size 1.27 1.27)
				)
			)
		)
		(property "Value" ""
			(at 0 0 90)
			(layer "F.Fab")
			(effects
				(font
					(size 1.27 1.27)
				)
			)
		)
		(duplicate_pad_numbers_are_jumpers no)
		(fp_line
			(start 0.7874 -0.4064)
			(end 0.7874 0.4064)
			(stroke
				(width 0.1524)
				(type default)
			)
			(layer "F.SilkS")
		)
		(fp_line
			(start -0.7874 -0.4064)
			(end 0.7874 -0.4064)
			(stroke
				(width 0.1524)
				(type default)
			)
			(layer "F.SilkS")
		)
		(fp_line
			(start 0.7874 0.4064)
			(end -0.7874 0.4064)
			(stroke
				(width 0.1524)
				(type default)
			)
			(layer "F.SilkS")
		)
		(fp_line
			(start -0.7874 0.4064)
			(end -0.7874 -0.4064)
			(stroke
				(width 0.1524)
				(type default)
			)
			(layer "F.SilkS")
		)
		(fp_line
			(start -0.12065 -0.305054)
			(end -0.12065 -0.2794)
			(stroke
				(width 0.1)
				(type default)
			)
			(layer "F.Fab")
		)
		(fp_line
			(start -0.67945 -0.305054)
			(end -0.12065 -0.305054)
			(stroke
				(width 0.1)
				(type default)
			)
			(layer "F.Fab")
		)
		(fp_line
			(start 0.67945 -0.3048)
			(end 0.67945 0.3048)
			(stroke
				(width 0.1)
				(type default)
			)
			(layer "F.Fab")
		)
		(fp_line
			(start 0.12065 -0.3048)
			(end 0.67945 -0.3048)
			(stroke
				(width 0.1)
				(type default)
			)
			(layer "F.Fab")
		)
		(fp_line
			(start 0.12065 -0.2794)
			(end 0.12065 -0.3048)
			(stroke
				(width 0.1)
				(type default)
			)
			(layer "F.Fab")
		)
		(fp_line
			(start -0.12065 -0.2794)
			(end 0.12065 -0.2794)
			(stroke
				(width 0.1)
				(type default)
			)
			(layer "F.Fab")
		)
		(fp_line
			(start 0.120396 0.2794)
			(end -0.12065 0.2794)
			(stroke
				(width 0.1)
				(type default)
			)
			(layer "F.Fab")
		)
		(fp_line
			(start -0.12065 0.2794)
			(end -0.12065 0.3048)
			(stroke
				(width 0.1)
				(type default)
			)
			(layer "F.Fab")
		)
		(fp_line
			(start 0.67945 0.3048)
			(end 0.120396 0.3048)
			(stroke
				(width 0.1)
				(type default)
			)
			(layer "F.Fab")
		)
		(fp_line
			(start 0.120396 0.3048)
			(end 0.120396 0.2794)
			(stroke
				(width 0.1)
				(type default)
			)
			(layer "F.Fab")
		)
		(fp_line
			(start -0.12065 0.3048)
			(end -0.67945 0.3048)
			(stroke
				(width 0.1)
				(type default)
			)
			(layer "F.Fab")
		)
		(fp_line
			(start -0.67945 0.3048)
			(end -0.67945 -0.305054)
			(stroke
				(width 0.1)
				(type default)
			)
			(layer "F.Fab")
		)
		(pad "1" smd circle
			(at -0.40005 0 90)
			(size 0 0)
			(layers "F.Cu" "F.Mask" "F.Paste")
			(net "LED_POSTCODE_2")
		)
		(pad "2" smd circle
			(at 0.40005 0 90)
			(size 0 0)
			(layers "F.Cu" "F.Mask" "F.Paste")
			(net "LED_POSTCODE_2_R")
		)
	)
	(footprint ""
		(layer "F.Cu")
		(at 29.591 -10.287 -90)
		(property "Reference" "R815"
			(at 0 0 270)
			(layer "F.SilkS")
			(hide yes)
			(effects
				(font
					(size 1.27 1.27)
				)
			)
		)
		(property "Value" ""
			(at 0 0 270)
			(layer "F.Fab")
			(effects
				(font
					(size 1.27 1.27)
				)
			)
		)
		(duplicate_pad_numbers_are_jumpers no)
		(fp_line
			(start -0.7874 0.4064)
			(end -0.7874 -0.4064)
			(stroke
				(width 0.1524)
				(type default)
			)
			(layer "F.SilkS")
		)
		(fp_line
			(start 0.7874 0.4064)
			(end -0.7874 0.4064)
			(stroke
				(width 0.1524)
				(type default)
			)
			(layer "F.SilkS")
		)
		(fp_line
			(start -0.7874 -0.4064)
			(end 0.7874 -0.4064)
			(stroke
				(width 0.1524)
				(type default)
			)
			(layer "F.SilkS")
		)
		(fp_line
			(start 0.7874 -0.4064)
			(end 0.7874 0.4064)
			(stroke
				(width 0.1524)
				(type default)
			)
			(layer "F.SilkS")
		)
		(fp_line
			(start -0.67945 0.3048)
			(end -0.67945 -0.305054)
			(stroke
				(width 0.1)
				(type default)
			)
			(layer "F.Fab")
		)
		(fp_line
			(start -0.12065 0.3048)
			(end -0.67945 0.3048)
			(stroke
				(width 0.1)
				(type default)
			)
			(layer "F.Fab")
		)
		(fp_line
			(start 0.120396 0.3048)
			(end 0.120396 0.2794)
			(stroke
				(width 0.1)
				(type default)
			)
			(layer "F.Fab")
		)
		(fp_line
			(start 0.67945 0.3048)
			(end 0.120396 0.3048)
			(stroke
				(width 0.1)
				(type default)
			)
			(layer "F.Fab")
		)
		(fp_line
			(start -0.12065 0.2794)
			(end -0.12065 0.3048)
			(stroke
				(width 0.1)
				(type default)
			)
			(layer "F.Fab")
		)
		(fp_line
			(start 0.120396 0.2794)
			(end -0.12065 0.2794)
			(stroke
				(width 0.1)
				(type default)
			)
			(layer "F.Fab")
		)
		(fp_line
			(start -0.12065 -0.2794)
			(end 0.12065 -0.2794)
			(stroke
				(width 0.1)
				(type default)
			)
			(layer "F.Fab")
		)
		(fp_line
			(start 0.12065 -0.2794)
			(end 0.12065 -0.3048)
			(stroke
				(width 0.1)
				(type default)
			)
			(layer "F.Fab")
		)
		(fp_line
			(start 0.12065 -0.3048)
			(end 0.67945 -0.3048)
			(stroke
				(width 0.1)
				(type default)
			)
			(layer "F.Fab")
		)
		(fp_line
			(start 0.67945 -0.3048)
			(end 0.67945 0.3048)
			(stroke
				(width 0.1)
				(type default)
			)
			(layer "F.Fab")
		)
		(fp_line
			(start -0.67945 -0.305054)
			(end -0.12065 -0.305054)
			(stroke
				(width 0.1)
				(type default)
			)
			(layer "F.Fab")
		)
		(fp_line
			(start -0.12065 -0.305054)
			(end -0.12065 -0.2794)
			(stroke
				(width 0.1)
				(type default)
			)
			(layer "F.Fab")
		)
		(pad "1" smd circle
			(at -0.40005 0 270)
			(size 0 0)
			(layers "F.Cu" "F.Mask" "F.Paste")
			(net "P5V_AUX")
		)
		(pad "2" smd circle
			(at 0.40005 0 270)
			(size 0 0)
			(layers "F.Cu" "F.Mask" "F.Paste")
			(net "HDD_LED_BUF_R")
		)
	)
	(footprint ""
		(layer "F.Cu")
		(at 25.527 -102.743 -90)
		(property "Reference" "R445"
			(at 0 0 270)
			(layer "F.SilkS")
			(hide yes)
			(effects
				(font
					(size 1.27 1.27)
				)
			)
		)
		(property "Value" ""
			(at 0 0 270)
			(layer "F.Fab")
			(effects
				(font
					(size 1.27 1.27)
				)
			)
		)
		(duplicate_pad_numbers_are_jumpers no)
		(fp_line
			(start -0.7874 0.4064)
			(end -0.7874 -0.4064)
			(stroke
				(width 0.1524)
				(type default)
			)
			(layer "F.SilkS")
		)
		(fp_line
			(start 0.7874 0.4064)
			(end -0.7874 0.4064)
			(stroke
				(width 0.1524)
				(type default)
			)
			(layer "F.SilkS")
		)
		(fp_line
			(start -0.7874 -0.4064)
			(end 0.7874 -0.4064)
			(stroke
				(width 0.1524)
				(type default)
			)
			(layer "F.SilkS")
		)
		(fp_line
			(start 0.7874 -0.4064)
			(end 0.7874 0.4064)
			(stroke
				(width 0.1524)
				(type default)
			)
			(layer "F.SilkS")
		)
		(fp_line
			(start -0.67945 0.3048)
			(end -0.67945 -0.305054)
			(stroke
				(width 0.1)
				(type default)
			)
			(layer "F.Fab")
		)
		(fp_line
			(start -0.12065 0.3048)
			(end -0.67945 0.3048)
			(stroke
				(width 0.1)
				(type default)
			)
			(layer "F.Fab")
		)
		(fp_line
			(start 0.120396 0.3048)
			(end 0.120396 0.2794)
			(stroke
				(width 0.1)
				(type default)
			)
			(layer "F.Fab")
		)
		(fp_line
			(start 0.67945 0.3048)
			(end 0.120396 0.3048)
			(stroke
				(width 0.1)
				(type default)
			)
			(layer "F.Fab")
		)
		(fp_line
			(start -0.12065 0.2794)
			(end -0.12065 0.3048)
			(stroke
				(width 0.1)
				(type default)
			)
			(layer "F.Fab")
		)
		(fp_line
			(start 0.120396 0.2794)
			(end -0.12065 0.2794)
			(stroke
				(width 0.1)
				(type default)
			)
			(layer "F.Fab")
		)
		(fp_line
			(start -0.12065 -0.2794)
			(end 0.12065 -0.2794)
			(stroke
				(width 0.1)
				(type default)
			)
			(layer "F.Fab")
		)
		(fp_line
			(start 0.12065 -0.2794)
			(end 0.12065 -0.3048)
			(stroke
				(width 0.1)
				(type default)
			)
			(layer "F.Fab")
		)
		(fp_line
			(start 0.12065 -0.3048)
			(end 0.67945 -0.3048)
			(stroke
				(width 0.1)
				(type default)
			)
			(layer "F.Fab")
		)
		(fp_line
			(start 0.67945 -0.3048)
			(end 0.67945 0.3048)
			(stroke
				(width 0.1)
				(type default)
			)
			(layer "F.Fab")
		)
		(fp_line
			(start -0.67945 -0.305054)
			(end -0.12065 -0.305054)
			(stroke
				(width 0.1)
				(type default)
			)
			(layer "F.Fab")
		)
		(fp_line
			(start -0.12065 -0.305054)
			(end -0.12065 -0.2794)
			(stroke
				(width 0.1)
				(type default)
			)
			(layer "F.Fab")
		)
		(pad "1" smd circle
			(at -0.40005 0 270)
			(size 0 0)
			(layers "F.Cu" "F.Mask" "F.Paste")
			(net "FM_BMC_SUSACK_N")
		)
		(pad "2" smd circle
			(at 0.40005 0 270)
			(size 0 0)
			(layers "F.Cu" "F.Mask" "F.Paste")
			(net "FM_BMC_SUSACK_R2_N")
		)
	)
	(footprint ""
		(layer "F.Cu")
		(at 58.266584 -34.637726 -90)
		(property "Reference" "R71"
			(at 0 0 270)
			(layer "F.SilkS")
			(hide yes)
			(effects
				(font
					(size 1.27 1.27)
				)
			)
		)
		(property "Value" ""
			(at 0 0 270)
			(layer "F.Fab")
			(effects
				(font
					(size 1.27 1.27)
				)
			)
		)
		(duplicate_pad_numbers_are_jumpers no)
		(fp_line
			(start -0.7874 0.4064)
			(end -0.7874 -0.4064)
			(stroke
				(width 0.1524)
				(type default)
			)
			(layer "F.SilkS")
		)
		(fp_line
			(start 0.7874 0.4064)
			(end -0.7874 0.4064)
			(stroke
				(width 0.1524)
				(type default)
			)
			(layer "F.SilkS")
		)
		(fp_line
			(start -0.7874 -0.4064)
			(end 0.7874 -0.4064)
			(stroke
				(width 0.1524)
				(type default)
			)
			(layer "F.SilkS")
		)
		(fp_line
			(start 0.7874 -0.4064)
			(end 0.7874 0.4064)
			(stroke
				(width 0.1524)
				(type default)
			)
			(layer "F.SilkS")
		)
		(fp_line
			(start -0.67945 0.3048)
			(end -0.67945 -0.305054)
			(stroke
				(width 0.1)
				(type default)
			)
			(layer "F.Fab")
		)
		(fp_line
			(start -0.12065 0.3048)
			(end -0.67945 0.3048)
			(stroke
				(width 0.1)
				(type default)
			)
			(layer "F.Fab")
		)
		(fp_line
			(start 0.120396 0.3048)
			(end 0.120396 0.2794)
			(stroke
				(width 0.1)
				(type default)
			)
			(layer "F.Fab")
		)
		(fp_line
			(start 0.67945 0.3048)
			(end 0.120396 0.3048)
			(stroke
				(width 0.1)
				(type default)
			)
			(layer "F.Fab")
		)
		(fp_line
			(start -0.12065 0.2794)
			(end -0.12065 0.3048)
			(stroke
				(width 0.1)
				(type default)
			)
			(layer "F.Fab")
		)
		(fp_line
			(start 0.120396 0.2794)
			(end -0.12065 0.2794)
			(stroke
				(width 0.1)
				(type default)
			)
			(layer "F.Fab")
		)
		(fp_line
			(start -0.12065 -0.2794)
			(end 0.12065 -0.2794)
			(stroke
				(width 0.1)
				(type default)
			)
			(layer "F.Fab")
		)
		(fp_line
			(start 0.12065 -0.2794)
			(end 0.12065 -0.3048)
			(stroke
				(width 0.1)
				(type default)
			)
			(layer "F.Fab")
		)
		(fp_line
			(start 0.12065 -0.3048)
			(end 0.67945 -0.3048)
			(stroke
				(width 0.1)
				(type default)
			)
			(layer "F.Fab")
		)
		(fp_line
			(start 0.67945 -0.3048)
			(end 0.67945 0.3048)
			(stroke
				(width 0.1)
				(type default)
			)
			(layer "F.Fab")
		)
		(fp_line
			(start -0.67945 -0.305054)
			(end -0.12065 -0.305054)
			(stroke
				(width 0.1)
				(type default)
			)
			(layer "F.Fab")
		)
		(fp_line
			(start -0.12065 -0.305054)
			(end -0.12065 -0.2794)
			(stroke
				(width 0.1)
				(type default)
			)
			(layer "F.Fab")
		)
		(pad "1" smd circle
			(at -0.40005 0 270)
			(size 0 0)
			(layers "F.Cu" "F.Mask" "F.Paste")
			(net "SMB_BMC_MM5_R_SCL")
		)
		(pad "2" smd circle
			(at 0.40005 0 270)
			(size 0 0)
			(layers "F.Cu" "F.Mask" "F.Paste")
			(net "SMB_BMC_MM5_SCL")
		)
	)
	(footprint ""
		(layer "F.Cu")
		(at 31.623 -66.7258 90)
		(property "Reference" "R757"
			(at 0 0 90)
			(layer "F.SilkS")
			(hide yes)
			(effects
				(font
					(size 1.27 1.27)
				)
			)
		)
		(property "Value" ""
			(at 0 0 90)
			(layer "F.Fab")
			(effects
				(font
					(size 1.27 1.27)
				)
			)
		)
		(duplicate_pad_numbers_are_jumpers no)
		(fp_line
			(start 0.7874 -0.4064)
			(end 0.7874 0.4064)
			(stroke
				(width 0.1524)
				(type default)
			)
			(layer "F.SilkS")
		)
		(fp_line
			(start -0.7874 -0.4064)
			(end 0.7874 -0.4064)
			(stroke
				(width 0.1524)
				(type default)
			)
			(layer "F.SilkS")
		)
		(fp_line
			(start 0.7874 0.4064)
			(end -0.7874 0.4064)
			(stroke
				(width 0.1524)
				(type default)
			)
			(layer "F.SilkS")
		)
		(fp_line
			(start -0.7874 0.4064)
			(end -0.7874 -0.4064)
			(stroke
				(width 0.1524)
				(type default)
			)
			(layer "F.SilkS")
		)
		(fp_line
			(start -0.12065 -0.305054)
			(end -0.12065 -0.2794)
			(stroke
				(width 0.1)
				(type default)
			)
			(layer "F.Fab")
		)
		(fp_line
			(start -0.67945 -0.305054)
			(end -0.12065 -0.305054)
			(stroke
				(width 0.1)
				(type default)
			)
			(layer "F.Fab")
		)
		(fp_line
			(start 0.67945 -0.3048)
			(end 0.67945 0.3048)
			(stroke
				(width 0.1)
				(type default)
			)
			(layer "F.Fab")
		)
		(fp_line
			(start 0.12065 -0.3048)
			(end 0.67945 -0.3048)
			(stroke
				(width 0.1)
				(type default)
			)
			(layer "F.Fab")
		)
		(fp_line
			(start 0.12065 -0.2794)
			(end 0.12065 -0.3048)
			(stroke
				(width 0.1)
				(type default)
			)
			(layer "F.Fab")
		)
		(fp_line
			(start -0.12065 -0.2794)
			(end 0.12065 -0.2794)
			(stroke
				(width 0.1)
				(type default)
			)
			(layer "F.Fab")
		)
		(fp_line
			(start 0.120396 0.2794)
			(end -0.12065 0.2794)
			(stroke
				(width 0.1)
				(type default)
			)
			(layer "F.Fab")
		)
		(fp_line
			(start -0.12065 0.2794)
			(end -0.12065 0.3048)
			(stroke
				(width 0.1)
				(type default)
			)
			(layer "F.Fab")
		)
		(fp_line
			(start 0.67945 0.3048)
			(end 0.120396 0.3048)
			(stroke
				(width 0.1)
				(type default)
			)
			(layer "F.Fab")
		)
		(fp_line
			(start 0.120396 0.3048)
			(end 0.120396 0.2794)
			(stroke
				(width 0.1)
				(type default)
			)
			(layer "F.Fab")
		)
		(fp_line
			(start -0.12065 0.3048)
			(end -0.67945 0.3048)
			(stroke
				(width 0.1)
				(type default)
			)
			(layer "F.Fab")
		)
		(fp_line
			(start -0.67945 0.3048)
			(end -0.67945 -0.305054)
			(stroke
				(width 0.1)
				(type default)
			)
			(layer "F.Fab")
		)
		(pad "1" smd circle
			(at -0.40005 0 90)
			(size 0 0)
			(layers "F.Cu" "F.Mask" "F.Paste")
			(net "UART_BMC_5_RXD_BUF1_R")
		)
		(pad "2" smd circle
			(at 0.40005 0 90)
			(size 0 0)
			(layers "F.Cu" "F.Mask" "F.Paste")
			(net "UART_BMC_5_RXD_R")
		)
	)
	(footprint ""
		(layer "F.Cu")
		(at 73.66 -16.256 -90)
		(property "Reference" "R391"
			(at 0 0 270)
			(layer "F.SilkS")
			(hide yes)
			(effects
				(font
					(size 1.27 1.27)
				)
			)
		)
		(property "Value" ""
			(at 0 0 270)
			(layer "F.Fab")
			(effects
				(font
					(size 1.27 1.27)
				)
			)
		)
		(duplicate_pad_numbers_are_jumpers no)
		(fp_line
			(start -0.7874 0.4064)
			(end -0.7874 -0.4064)
			(stroke
				(width 0.1524)
				(type default)
			)
			(layer "F.SilkS")
		)
		(fp_line
			(start 0.7874 0.4064)
			(end -0.7874 0.4064)
			(stroke
				(width 0.1524)
				(type default)
			)
			(layer "F.SilkS")
		)
		(fp_line
			(start -0.7874 -0.4064)
			(end 0.7874 -0.4064)
			(stroke
				(width 0.1524)
				(type default)
			)
			(layer "F.SilkS")
		)
		(fp_line
			(start 0.7874 -0.4064)
			(end 0.7874 0.4064)
			(stroke
				(width 0.1524)
				(type default)
			)
			(layer "F.SilkS")
		)
		(fp_line
			(start -0.67945 0.3048)
			(end -0.67945 -0.305054)
			(stroke
				(width 0.1)
				(type default)
			)
			(layer "F.Fab")
		)
		(fp_line
			(start -0.12065 0.3048)
			(end -0.67945 0.3048)
			(stroke
				(width 0.1)
				(type default)
			)
			(layer "F.Fab")
		)
		(fp_line
			(start 0.120396 0.3048)
			(end 0.120396 0.2794)
			(stroke
				(width 0.1)
				(type default)
			)
			(layer "F.Fab")
		)
		(fp_line
			(start 0.67945 0.3048)
			(end 0.120396 0.3048)
			(stroke
				(width 0.1)
				(type default)
			)
			(layer "F.Fab")
		)
		(fp_line
			(start -0.12065 0.2794)
			(end -0.12065 0.3048)
			(stroke
				(width 0.1)
				(type default)
			)
			(layer "F.Fab")
		)
		(fp_line
			(start 0.120396 0.2794)
			(end -0.12065 0.2794)
			(stroke
				(width 0.1)
				(type default)
			)
			(layer "F.Fab")
		)
		(fp_line
			(start -0.12065 -0.2794)
			(end 0.12065 -0.2794)
			(stroke
				(width 0.1)
				(type default)
			)
			(layer "F.Fab")
		)
		(fp_line
			(start 0.12065 -0.2794)
			(end 0.12065 -0.3048)
			(stroke
				(width 0.1)
				(type default)
			)
			(layer "F.Fab")
		)
		(fp_line
			(start 0.12065 -0.3048)
			(end 0.67945 -0.3048)
			(stroke
				(width 0.1)
				(type default)
			)
			(layer "F.Fab")
		)
		(fp_line
			(start 0.67945 -0.3048)
			(end 0.67945 0.3048)
			(stroke
				(width 0.1)
				(type default)
			)
			(layer "F.Fab")
		)
		(fp_line
			(start -0.67945 -0.305054)
			(end -0.12065 -0.305054)
			(stroke
				(width 0.1)
				(type default)
			)
			(layer "F.Fab")
		)
		(fp_line
			(start -0.12065 -0.305054)
			(end -0.12065 -0.2794)
			(stroke
				(width 0.1)
				(type default)
			)
			(layer "F.Fab")
		)
		(pad "1" smd circle
			(at -0.40005 0 270)
			(size 0 0)
			(layers "F.Cu" "F.Mask" "F.Paste")
			(net "P3V3_AUX")
		)
		(pad "2" smd circle
			(at 0.40005 0 270)
			(size 0 0)
			(layers "F.Cu" "F.Mask" "F.Paste")
			(net "REAR_AC_PWR_BTN_N")
		)
	)
	(footprint ""
		(layer "F.Cu")
		(at 77.947774 -72.413368)
		(property "Reference" "R764"
			(at 0 0 0)
			(layer "F.SilkS")
			(hide yes)
			(effects
				(font
					(size 1.27 1.27)
				)
			)
		)
		(property "Value" ""
			(at 0 0 0)
			(layer "F.Fab")
			(effects
				(font
					(size 1.27 1.27)
				)
			)
		)
		(duplicate_pad_numbers_are_jumpers no)
		(fp_line
			(start -0.7874 -0.4064)
			(end 0.7874 -0.4064)
			(stroke
				(width 0.1524)
				(type default)
			)
			(layer "F.SilkS")
		)
		(fp_line
			(start -0.7874 0.4064)
			(end -0.7874 -0.4064)
			(stroke
				(width 0.1524)
				(type default)
			)
			(layer "F.SilkS")
		)
		(fp_line
			(start 0.7874 -0.4064)
			(end 0.7874 0.4064)
			(stroke
				(width 0.1524)
				(type default)
			)
			(layer "F.SilkS")
		)
		(fp_line
			(start 0.7874 0.4064)
			(end -0.7874 0.4064)
			(stroke
				(width 0.1524)
				(type default)
			)
			(layer "F.SilkS")
		)
		(fp_line
			(start -0.67945 -0.305054)
			(end -0.12065 -0.305054)
			(stroke
				(width 0.1)
				(type default)
			)
			(layer "F.Fab")
		)
		(fp_line
			(start -0.67945 0.3048)
			(end -0.67945 -0.305054)
			(stroke
				(width 0.1)
				(type default)
			)
			(layer "F.Fab")
		)
		(fp_line
			(start -0.12065 -0.305054)
			(end -0.12065 -0.2794)
			(stroke
				(width 0.1)
				(type default)
			)
			(layer "F.Fab")
		)
		(fp_line
			(start -0.12065 -0.2794)
			(end 0.12065 -0.2794)
			(stroke
				(width 0.1)
				(type default)
			)
			(layer "F.Fab")
		)
		(fp_line
			(start -0.12065 0.2794)
			(end -0.12065 0.3048)
			(stroke
				(width 0.1)
				(type default)
			)
			(layer "F.Fab")
		)
		(fp_line
			(start -0.12065 0.3048)
			(end -0.67945 0.3048)
			(stroke
				(width 0.1)
				(type default)
			)
			(layer "F.Fab")
		)
		(fp_line
			(start 0.120396 0.2794)
			(end -0.12065 0.2794)
			(stroke
				(width 0.1)
				(type default)
			)
			(layer "F.Fab")
		)
		(fp_line
			(start 0.120396 0.3048)
			(end 0.120396 0.2794)
			(stroke
				(width 0.1)
				(type default)
			)
			(layer "F.Fab")
		)
		(fp_line
			(start 0.12065 -0.3048)
			(end 0.67945 -0.3048)
			(stroke
				(width 0.1)
				(type default)
			)
			(layer "F.Fab")
		)
		(fp_line
			(start 0.12065 -0.2794)
			(end 0.12065 -0.3048)
			(stroke
				(width 0.1)
				(type default)
			)
			(layer "F.Fab")
		)
		(fp_line
			(start 0.67945 -0.3048)
			(end 0.67945 0.3048)
			(stroke
				(width 0.1)
				(type default)
			)
			(layer "F.Fab")
		)
		(fp_line
			(start 0.67945 0.3048)
			(end 0.120396 0.3048)
			(stroke
				(width 0.1)
				(type default)
			)
			(layer "F.Fab")
		)
		(pad "1" smd circle
			(at -0.40005 0)
			(size 0 0)
			(layers "F.Cu" "F.Mask" "F.Paste")
			(net "PWRGD_P1V8_AUX")
		)
		(pad "2" smd circle
			(at 0.40005 0)
			(size 0 0)
			(layers "F.Cu" "F.Mask" "F.Paste")
			(net "EN_P1V2_AUX_R")
		)
	)
	(footprint ""
		(layer "F.Cu")
		(at 77.947774 -71.396352)
		(property "Reference" "R708"
			(at 0 0 0)
			(layer "F.SilkS")
			(hide yes)
			(effects
				(font
					(size 1.27 1.27)
				)
			)
		)
		(property "Value" ""
			(at 0 0 0)
			(layer "F.Fab")
			(effects
				(font
					(size 1.27 1.27)
				)
			)
		)
		(duplicate_pad_numbers_are_jumpers no)
		(fp_line
			(start -0.7874 -0.4064)
			(end 0.7874 -0.4064)
			(stroke
				(width 0.1524)
				(type default)
			)
			(layer "F.SilkS")
		)
		(fp_line
			(start -0.7874 0.4064)
			(end -0.7874 -0.4064)
			(stroke
				(width 0.1524)
				(type default)
			)
			(layer "F.SilkS")
		)
		(fp_line
			(start 0.7874 -0.4064)
			(end 0.7874 0.4064)
			(stroke
				(width 0.1524)
				(type default)
			)
			(layer "F.SilkS")
		)
		(fp_line
			(start 0.7874 0.4064)
			(end -0.7874 0.4064)
			(stroke
				(width 0.1524)
				(type default)
			)
			(layer "F.SilkS")
		)
		(fp_line
			(start -0.67945 -0.305054)
			(end -0.12065 -0.305054)
			(stroke
				(width 0.1)
				(type default)
			)
			(layer "F.Fab")
		)
		(fp_line
			(start -0.67945 0.3048)
			(end -0.67945 -0.305054)
			(stroke
				(width 0.1)
				(type default)
			)
			(layer "F.Fab")
		)
		(fp_line
			(start -0.12065 -0.305054)
			(end -0.12065 -0.2794)
			(stroke
				(width 0.1)
				(type default)
			)
			(layer "F.Fab")
		)
		(fp_line
			(start -0.12065 -0.2794)
			(end 0.12065 -0.2794)
			(stroke
				(width 0.1)
				(type default)
			)
			(layer "F.Fab")
		)
		(fp_line
			(start -0.12065 0.2794)
			(end -0.12065 0.3048)
			(stroke
				(width 0.1)
				(type default)
			)
			(layer "F.Fab")
		)
		(fp_line
			(start -0.12065 0.3048)
			(end -0.67945 0.3048)
			(stroke
				(width 0.1)
				(type default)
			)
			(layer "F.Fab")
		)
		(fp_line
			(start 0.120396 0.2794)
			(end -0.12065 0.2794)
			(stroke
				(width 0.1)
				(type default)
			)
			(layer "F.Fab")
		)
		(fp_line
			(start 0.120396 0.3048)
			(end 0.120396 0.2794)
			(stroke
				(width 0.1)
				(type default)
			)
			(layer "F.Fab")
		)
		(fp_line
			(start 0.12065 -0.3048)
			(end 0.67945 -0.3048)
			(stroke
				(width 0.1)
				(type default)
			)
			(layer "F.Fab")
		)
		(fp_line
			(start 0.12065 -0.2794)
			(end 0.12065 -0.3048)
			(stroke
				(width 0.1)
				(type default)
			)
			(layer "F.Fab")
		)
		(fp_line
			(start 0.67945 -0.3048)
			(end 0.67945 0.3048)
			(stroke
				(width 0.1)
				(type default)
			)
			(layer "F.Fab")
		)
		(fp_line
			(start 0.67945 0.3048)
			(end 0.120396 0.3048)
			(stroke
				(width 0.1)
				(type default)
			)
			(layer "F.Fab")
		)
		(pad "1" smd circle
			(at -0.40005 0)
			(size 0 0)
			(layers "F.Cu" "F.Mask" "F.Paste")
			(net "EN_P1V2_AUX")
		)
		(pad "2" smd circle
			(at 0.40005 0)
			(size 0 0)
			(layers "F.Cu" "F.Mask" "F.Paste")
			(net "EN_P1V2_AUX_R")
		)
	)
	(footprint ""
		(layer "F.Cu")
		(at 19.1516 -58.7756 90)
		(property "Reference" "R766"
			(at 0 0 90)
			(layer "F.SilkS")
			(hide yes)
			(effects
				(font
					(size 1.27 1.27)
				)
			)
		)
		(property "Value" ""
			(at 0 0 90)
			(layer "F.Fab")
			(effects
				(font
					(size 1.27 1.27)
				)
			)
		)
		(duplicate_pad_numbers_are_jumpers no)
		(fp_line
			(start 0.7874 -0.4064)
			(end 0.7874 0.4064)
			(stroke
				(width 0.1524)
				(type default)
			)
			(layer "F.SilkS")
		)
		(fp_line
			(start -0.7874 -0.4064)
			(end 0.7874 -0.4064)
			(stroke
				(width 0.1524)
				(type default)
			)
			(layer "F.SilkS")
		)
		(fp_line
			(start 0.7874 0.4064)
			(end -0.7874 0.4064)
			(stroke
				(width 0.1524)
				(type default)
			)
			(layer "F.SilkS")
		)
		(fp_line
			(start -0.7874 0.4064)
			(end -0.7874 -0.4064)
			(stroke
				(width 0.1524)
				(type default)
			)
			(layer "F.SilkS")
		)
		(fp_line
			(start -0.12065 -0.305054)
			(end -0.12065 -0.2794)
			(stroke
				(width 0.1)
				(type default)
			)
			(layer "F.Fab")
		)
		(fp_line
			(start -0.67945 -0.305054)
			(end -0.12065 -0.305054)
			(stroke
				(width 0.1)
				(type default)
			)
			(layer "F.Fab")
		)
		(fp_line
			(start 0.67945 -0.3048)
			(end 0.67945 0.3048)
			(stroke
				(width 0.1)
				(type default)
			)
			(layer "F.Fab")
		)
		(fp_line
			(start 0.12065 -0.3048)
			(end 0.67945 -0.3048)
			(stroke
				(width 0.1)
				(type default)
			)
			(layer "F.Fab")
		)
		(fp_line
			(start 0.12065 -0.2794)
			(end 0.12065 -0.3048)
			(stroke
				(width 0.1)
				(type default)
			)
			(layer "F.Fab")
		)
		(fp_line
			(start -0.12065 -0.2794)
			(end 0.12065 -0.2794)
			(stroke
				(width 0.1)
				(type default)
			)
			(layer "F.Fab")
		)
		(fp_line
			(start 0.120396 0.2794)
			(end -0.12065 0.2794)
			(stroke
				(width 0.1)
				(type default)
			)
			(layer "F.Fab")
		)
		(fp_line
			(start -0.12065 0.2794)
			(end -0.12065 0.3048)
			(stroke
				(width 0.1)
				(type default)
			)
			(layer "F.Fab")
		)
		(fp_line
			(start 0.67945 0.3048)
			(end 0.120396 0.3048)
			(stroke
				(width 0.1)
				(type default)
			)
			(layer "F.Fab")
		)
		(fp_line
			(start 0.120396 0.3048)
			(end 0.120396 0.2794)
			(stroke
				(width 0.1)
				(type default)
			)
			(layer "F.Fab")
		)
		(fp_line
			(start -0.12065 0.3048)
			(end -0.67945 0.3048)
			(stroke
				(width 0.1)
				(type default)
			)
			(layer "F.Fab")
		)
		(fp_line
			(start -0.67945 0.3048)
			(end -0.67945 -0.305054)
			(stroke
				(width 0.1)
				(type default)
			)
			(layer "F.Fab")
		)
		(pad "1" smd circle
			(at -0.40005 0 90)
			(size 0 0)
			(layers "F.Cu" "F.Mask" "F.Paste")
			(net "UART_BMC_5_RXD_BUF1")
		)
		(pad "2" smd circle
			(at 0.40005 0 90)
			(size 0 0)
			(layers "F.Cu" "F.Mask" "F.Paste")
			(net "UART_BMC_5_RXD_BUF1_SW")
		)
	)
	(footprint ""
		(layer "F.Cu")
		(at 7.059676 -49.979834 180)
		(property "Reference" "PU38"
			(at 3.122168 -3.362452 0)
			(unlocked yes)
			(layer "F.SilkS")
			(effects
				(font
					(size 0.7874 0.5842)
					(thickness 0.1524)
				)
				(justify left)
			)
		)
		(property "Value" ""
			(at 0 0 180)
			(layer "F.Fab")
			(effects
				(font
					(size 1.27 1.27)
				)
			)
		)
		(duplicate_pad_numbers_are_jumpers no)
		(fp_line
			(start 1.549908 2.050034)
			(end 1.549908 1.9304)
			(stroke
				(width 0.1524)
				(type default)
			)
			(layer "F.SilkS")
		)
		(fp_line
			(start 1.549908 -1.9812)
			(end 1.549908 -2.050034)
			(stroke
				(width 0.1524)
				(type default)
			)
			(layer "F.SilkS")
		)
		(fp_line
			(start 1.549908 -2.050034)
			(end 0.5842 -2.050034)
			(stroke
				(width 0.1524)
				(type default)
			)
			(layer "F.SilkS")
		)
		(fp_line
			(start 0 2.050034)
			(end 1.549908 2.050034)
			(stroke
				(width 0.1524)
				(type default)
			)
			(layer "F.SilkS")
		)
		(fp_line
			(start -0.5842 -2.050034)
			(end -1.549908 -2.050034)
			(stroke
				(width 0.1524)
				(type default)
			)
			(layer "F.SilkS")
		)
		(fp_line
			(start -1.549908 2.050034)
			(end -0.5842 2.050034)
			(stroke
				(width 0.1524)
				(type default)
			)
			(layer "F.SilkS")
		)
		(fp_line
			(start -1.549908 1.9812)
			(end -1.549908 2.050034)
			(stroke
				(width 0.1524)
				(type default)
			)
			(layer "F.SilkS")
		)
		(fp_line
			(start -1.549908 -2.050034)
			(end -1.549908 -1.9812)
			(stroke
				(width 0.1524)
				(type default)
			)
			(layer "F.SilkS")
		)
		(fp_poly
			(pts
				(xy -2.9464 -2.208022) (xy -2.9464 -1.192022) (xy -1.9304 -1.700022)
			)
			(stroke
				(width 0)
				(type default)
			)
			(fill yes)
			(layer "F.SilkS")
		)
		(fp_line
			(start 1.549908 2.050034)
			(end 1.549908 -2.050034)
			(stroke
				(width 0.1)
				(type default)
			)
			(layer "F.Fab")
		)
		(fp_line
			(start 1.549908 -2.050034)
			(end -1.549908 -2.050034)
			(stroke
				(width 0.1)
				(type default)
			)
			(layer "F.Fab")
		)
		(fp_line
			(start -1.549908 2.050034)
			(end 1.549908 2.050034)
			(stroke
				(width 0.1)
				(type default)
			)
			(layer "F.Fab")
		)
		(fp_line
			(start -1.549908 -2.050034)
			(end -1.549908 2.050034)
			(stroke
				(width 0.1)
				(type default)
			)
			(layer "F.Fab")
		)
		(fp_poly
			(pts
				(xy -2.9464 -2.208022) (xy -2.9464 -1.192022) (xy -1.9304 -1.700022)
			)
			(stroke
				(width 0)
				(type default)
			)
			(fill yes)
			(layer "F.Fab")
		)
		(pad "1" smd circle
			(at -1.35001 -1.700022 180)
			(size 0 0)
			(layers "F.Cu" "F.Mask" "F.Paste")
			(net "SW_P5V_AUX_BST")
		)
		(pad "2" smd rect
			(at -1.400048 -1.199896 270)
			(size 0.1778 0.8128)
			(layers "F.Cu" "F.Mask" "F.Paste")
			(net "GND")
		)
		(pad "3" smd rect
			(at -1.400048 -0.8001 270)
			(size 0.1778 0.8128)
			(layers "F.Cu" "F.Mask" "F.Paste")
			(net "P5V_AUX_CS")
		)
		(pad "4" smd rect
			(at -1.400048 -0.40005 270)
			(size 0.1778 0.8128)
			(layers "F.Cu" "F.Mask" "F.Paste")
			(net "GND")
		)
		(pad "5" smd rect
			(at -1.400048 0 270)
			(size 0.1778 0.8128)
			(layers "F.Cu" "F.Mask" "F.Paste")
			(net "P5V_AUX_REF")
		)
		(pad "6" smd rect
			(at -1.400048 0.40005 270)
			(size 0.1778 0.8128)
			(layers "F.Cu" "F.Mask" "F.Paste")
			(net "GND")
		)
		(pad "7" smd rect
			(at -1.400048 0.8001 270)
			(size 0.1778 0.8128)
			(layers "F.Cu" "F.Mask" "F.Paste")
			(net "P5V_AUX_FB")
		)
		(pad "8" smd rect
			(at -1.400048 1.199896 270)
			(size 0.1778 0.8128)
			(layers "F.Cu" "F.Mask" "F.Paste")
			(net "EN_P5V_AUX")
		)
		(pad "9" smd rect
			(at -1.400048 1.700022 270)
			(size 0.3048 0.8128)
			(layers "F.Cu" "F.Mask" "F.Paste")
			(net "PWRGD_P5V_AUX_R")
		)
		(pad "10" smd rect
			(at -0.299974 1.299972 180)
			(size 0.3048 2.0066)
			(layers "F.Cu" "F.Mask" "F.Paste")
			(net "SW_P5V_AUX_FLT")
		)
		(pad "11_18" smd circle
			(at 1.175004 0.275082 180)
			(size 0 0)
			(layers "F.Cu" "F.Mask" "F.Paste")
			(net "GND")
		)
		(pad "19" smd rect
			(at 1.400048 -1.700022 90)
			(size 0.3048 0.8128)
			(layers "F.Cu" "F.Mask" "F.Paste")
			(net "P5V_AUX_VCC")
		)
		(pad "20" smd rect
			(at 0.299974 -1.299972 180)
			(size 0.3048 2.0066)
			(layers "F.Cu" "F.Mask" "F.Paste")
			(net "SW_P5V_AUX_SW")
		)
		(pad "21" smd rect
			(at -0.299974 -1.299972 180)
			(size 0.3048 2.0066)
			(layers "F.Cu" "F.Mask" "F.Paste")
			(net "SW_P5V_AUX_FLT")
		)
	)
	(footprint ""
		(layer "F.Cu")
		(at 112.014 -24.384 90)
		(property "Reference" "X12"
			(at 0.3175 5.37337 90)
			(unlocked yes)
			(layer "F.SilkS")
			(effects
				(font
					(size 0.7874 0.5842)
					(thickness 0.1524)
				)
				(justify left)
			)
		)
		(property "Value" ""
			(at 0 0 90)
			(layer "F.Fab")
			(effects
				(font
					(size 1.27 1.27)
				)
			)
		)
		(property "Device Type" "TP_TDR_4P_FTS_TH-TP_TDR_4P_DIPA"
			(at 1.30175 1.27 180)
			(unlocked yes)
			(layer "F.Fab")
			(hide yes)
			(effects
				(font
					(size 0.635 0.4064)
					(thickness 0.1524)
				)
			)
		)
		(property "User Part Number" "N_A"
			(at 1.30175 1.27 180)
			(unlocked yes)
			(layer "Cmts.User")
			(hide yes)
			(effects
				(font
					(size 0.635 0.4064)
					(thickness 0.1524)
				)
			)
		)
		(duplicate_pad_numbers_are_jumpers no)
		(fp_line
			(start 2.54 -1.27)
			(end 0 -1.27)
			(stroke
				(width 0.1524)
				(type default)
			)
			(layer "F.SilkS")
		)
		(fp_line
			(start 0 -1.27)
			(end 0 -0.635)
			(stroke
				(width 0.1524)
				(type default)
			)
			(layer "F.SilkS")
		)
		(fp_line
			(start 2.54 -1.1303)
			(end 2.54 -1.27)
			(stroke
				(width 0.1524)
				(type default)
			)
			(layer "F.SilkS")
		)
		(fp_line
			(start 0 0.635)
			(end 0 1.905)
			(stroke
				(width 0.1524)
				(type default)
			)
			(layer "F.SilkS")
		)
		(fp_line
			(start 2.54 1.4097)
			(end 2.54 1.1303)
			(stroke
				(width 0.1524)
				(type default)
			)
			(layer "F.SilkS")
		)
		(fp_line
			(start 0 3.175)
			(end 0 3.81)
			(stroke
				(width 0.1524)
				(type default)
			)
			(layer "F.SilkS")
		)
		(fp_line
			(start 2.54 3.81)
			(end 2.54 3.6703)
			(stroke
				(width 0.1524)
				(type default)
			)
			(layer "F.SilkS")
		)
		(fp_line
			(start 0 3.81)
			(end 2.54 3.81)
			(stroke
				(width 0.1524)
				(type default)
			)
			(layer "F.SilkS")
		)
		(fp_poly
			(pts
				(xy -0.761746 0) (xy -2.285746 -0.762) (xy -2.285746 0.762)
			)
			(stroke
				(width 0)
				(type default)
			)
			(fill yes)
			(layer "F.SilkS")
		)
		(fp_line
			(start 2.54 -1.27)
			(end 0 -1.27)
			(stroke
				(width 0.1)
				(type default)
			)
			(layer "F.Fab")
		)
		(fp_line
			(start 0 -1.27)
			(end 0 3.81)
			(stroke
				(width 0.1)
				(type default)
			)
			(layer "F.Fab")
		)
		(fp_line
			(start 2.54 3.81)
			(end 2.54 -1.27)
			(stroke
				(width 0.1)
				(type default)
			)
			(layer "F.Fab")
		)
		(fp_line
			(start 0 3.81)
			(end 2.54 3.81)
			(stroke
				(width 0.1)
				(type default)
			)
			(layer "F.Fab")
		)
		(fp_poly
			(pts
				(xy -0.761746 0) (xy -2.285746 -0.762) (xy -2.285746 0.762)
			)
			(stroke
				(width 0)
				(type default)
			)
			(fill yes)
			(layer "F.Fab")
		)
		(pad "1" thru_hole circle
			(at 0 0 90)
			(size 1.0033 1.0033)
			(drill 0.249936)
			(layers "*.Cu" "*.Mask")
			(remove_unused_layers no)
			(net "TDR_DIFF_85_BOT_DN")
			(clearance 0.10795)
			(thermal_gap 0.10795)
			(padstack
				(mode front_inner_back)
				(layer "Inner"
					(shape circle)
					(size 0.8001 0.8001)
					(clearance 0.1524)
				)
				(layer "B.Cu"
					(shape circle)
					(size 1.0033 1.0033)
					(clearance 0.10795)
				)
			)
		)
		(pad "2" thru_hole circle
			(at 2.54 0 90)
			(size 1.9939 1.9939)
			(drill 0.249936)
			(layers "*.Cu" "*.Mask")
			(remove_unused_layers no)
			(net "GND_P1")
			(clearance 0.10795)
			(thermal_gap 0.10795)
			(padstack
				(mode front_inner_back)
				(layer "Inner"
					(shape circle)
					(size 0.8001 0.8001)
					(clearance 0.1524)
				)
				(layer "B.Cu"
					(shape circle)
					(size 1.9939 1.9939)
					(clearance 0.10795)
				)
			)
		)
		(pad "3" thru_hole circle
			(at 2.54 2.54 90)
			(size 1.9939 1.9939)
			(drill 0.249936)
			(layers "*.Cu" "*.Mask")
			(remove_unused_layers no)
			(net "GND_P1")
			(clearance 0.10795)
			(thermal_gap 0.10795)
			(padstack
				(mode front_inner_back)
				(layer "Inner"
					(shape circle)
					(size 0.8001 0.8001)
					(clearance 0.1524)
				)
				(layer "B.Cu"
					(shape circle)
					(size 1.9939 1.9939)
					(clearance 0.10795)
				)
			)
		)
		(pad "4" thru_hole circle
			(at 0 2.54 90)
			(size 1.0033 1.0033)
			(drill 0.249936)
			(layers "*.Cu" "*.Mask")
			(remove_unused_layers no)
			(net "TDR_DIFF_85_BOT_DP")
			(clearance 0.10795)
			(thermal_gap 0.10795)
			(padstack
				(mode front_inner_back)
				(layer "Inner"
					(shape circle)
					(size 0.8001 0.8001)
					(clearance 0.1524)
				)
				(layer "B.Cu"
					(shape circle)
					(size 1.0033 1.0033)
					(clearance 0.10795)
				)
			)
		)
	)
	(footprint ""
		(layer "F.Cu")
		(at 40.10787 -38.881558 180)
		(property "Reference" "R173"
			(at 0 0 180)
			(layer "F.SilkS")
			(hide yes)
			(effects
				(font
					(size 1.27 1.27)
				)
			)
		)
		(property "Value" ""
			(at 0 0 180)
			(layer "F.Fab")
			(effects
				(font
					(size 1.27 1.27)
				)
			)
		)
		(duplicate_pad_numbers_are_jumpers no)
		(fp_line
			(start 0.7874 0.4064)
			(end -0.7874 0.4064)
			(stroke
				(width 0.1524)
				(type default)
			)
			(layer "F.SilkS")
		)
		(fp_line
			(start 0.7874 -0.4064)
			(end 0.7874 0.4064)
			(stroke
				(width 0.1524)
				(type default)
			)
			(layer "F.SilkS")
		)
		(fp_line
			(start -0.7874 0.4064)
			(end -0.7874 -0.4064)
			(stroke
				(width 0.1524)
				(type default)
			)
			(layer "F.SilkS")
		)
		(fp_line
			(start -0.7874 -0.4064)
			(end 0.7874 -0.4064)
			(stroke
				(width 0.1524)
				(type default)
			)
			(layer "F.SilkS")
		)
		(fp_line
			(start 0.67945 0.3048)
			(end 0.120396 0.3048)
			(stroke
				(width 0.1)
				(type default)
			)
			(layer "F.Fab")
		)
		(fp_line
			(start 0.67945 -0.3048)
			(end 0.67945 0.3048)
			(stroke
				(width 0.1)
				(type default)
			)
			(layer "F.Fab")
		)
		(fp_line
			(start 0.12065 -0.2794)
			(end 0.12065 -0.3048)
			(stroke
				(width 0.1)
				(type default)
			)
			(layer "F.Fab")
		)
		(fp_line
			(start 0.12065 -0.3048)
			(end 0.67945 -0.3048)
			(stroke
				(width 0.1)
				(type default)
			)
			(layer "F.Fab")
		)
		(fp_line
			(start 0.120396 0.3048)
			(end 0.120396 0.2794)
			(stroke
				(width 0.1)
				(type default)
			)
			(layer "F.Fab")
		)
		(fp_line
			(start 0.120396 0.2794)
			(end -0.12065 0.2794)
			(stroke
				(width 0.1)
				(type default)
			)
			(layer "F.Fab")
		)
		(fp_line
			(start -0.12065 0.3048)
			(end -0.67945 0.3048)
			(stroke
				(width 0.1)
				(type default)
			)
			(layer "F.Fab")
		)
		(fp_line
			(start -0.12065 0.2794)
			(end -0.12065 0.3048)
			(stroke
				(width 0.1)
				(type default)
			)
			(layer "F.Fab")
		)
		(fp_line
			(start -0.12065 -0.2794)
			(end 0.12065 -0.2794)
			(stroke
				(width 0.1)
				(type default)
			)
			(layer "F.Fab")
		)
		(fp_line
			(start -0.12065 -0.305054)
			(end -0.12065 -0.2794)
			(stroke
				(width 0.1)
				(type default)
			)
			(layer "F.Fab")
		)
		(fp_line
			(start -0.67945 0.3048)
			(end -0.67945 -0.305054)
			(stroke
				(width 0.1)
				(type default)
			)
			(layer "F.Fab")
		)
		(fp_line
			(start -0.67945 -0.305054)
			(end -0.12065 -0.305054)
			(stroke
				(width 0.1)
				(type default)
			)
			(layer "F.Fab")
		)
		(pad "1" smd circle
			(at -0.40005 0 180)
			(size 0 0)
			(layers "F.Cu" "F.Mask" "F.Paste")
			(net "RMII_TXD1_R")
		)
		(pad "2" smd circle
			(at 0.40005 0 180)
			(size 0 0)
			(layers "F.Cu" "F.Mask" "F.Paste")
			(net "RMII_TXD1")
		)
	)
	(footprint ""
		(layer "F.Cu")
		(at 71.374 -19.685 90)
		(property "Reference" "R856"
			(at 0 0 90)
			(layer "F.SilkS")
			(hide yes)
			(effects
				(font
					(size 1.27 1.27)
				)
			)
		)
		(property "Value" ""
			(at 0 0 90)
			(layer "F.Fab")
			(effects
				(font
					(size 1.27 1.27)
				)
			)
		)
		(duplicate_pad_numbers_are_jumpers no)
		(fp_line
			(start 0.7874 -0.4064)
			(end 0.7874 0.4064)
			(stroke
				(width 0.1524)
				(type default)
			)
			(layer "F.SilkS")
		)
		(fp_line
			(start -0.7874 -0.4064)
			(end 0.7874 -0.4064)
			(stroke
				(width 0.1524)
				(type default)
			)
			(layer "F.SilkS")
		)
		(fp_line
			(start 0.7874 0.4064)
			(end -0.7874 0.4064)
			(stroke
				(width 0.1524)
				(type default)
			)
			(layer "F.SilkS")
		)
		(fp_line
			(start -0.7874 0.4064)
			(end -0.7874 -0.4064)
			(stroke
				(width 0.1524)
				(type default)
			)
			(layer "F.SilkS")
		)
		(fp_line
			(start -0.12065 -0.305054)
			(end -0.12065 -0.2794)
			(stroke
				(width 0.1)
				(type default)
			)
			(layer "F.Fab")
		)
		(fp_line
			(start -0.67945 -0.305054)
			(end -0.12065 -0.305054)
			(stroke
				(width 0.1)
				(type default)
			)
			(layer "F.Fab")
		)
		(fp_line
			(start 0.67945 -0.3048)
			(end 0.67945 0.3048)
			(stroke
				(width 0.1)
				(type default)
			)
			(layer "F.Fab")
		)
		(fp_line
			(start 0.12065 -0.3048)
			(end 0.67945 -0.3048)
			(stroke
				(width 0.1)
				(type default)
			)
			(layer "F.Fab")
		)
		(fp_line
			(start 0.12065 -0.2794)
			(end 0.12065 -0.3048)
			(stroke
				(width 0.1)
				(type default)
			)
			(layer "F.Fab")
		)
		(fp_line
			(start -0.12065 -0.2794)
			(end 0.12065 -0.2794)
			(stroke
				(width 0.1)
				(type default)
			)
			(layer "F.Fab")
		)
		(fp_line
			(start 0.120396 0.2794)
			(end -0.12065 0.2794)
			(stroke
				(width 0.1)
				(type default)
			)
			(layer "F.Fab")
		)
		(fp_line
			(start -0.12065 0.2794)
			(end -0.12065 0.3048)
			(stroke
				(width 0.1)
				(type default)
			)
			(layer "F.Fab")
		)
		(fp_line
			(start 0.67945 0.3048)
			(end 0.120396 0.3048)
			(stroke
				(width 0.1)
				(type default)
			)
			(layer "F.Fab")
		)
		(fp_line
			(start 0.120396 0.3048)
			(end 0.120396 0.2794)
			(stroke
				(width 0.1)
				(type default)
			)
			(layer "F.Fab")
		)
		(fp_line
			(start -0.12065 0.3048)
			(end -0.67945 0.3048)
			(stroke
				(width 0.1)
				(type default)
			)
			(layer "F.Fab")
		)
		(fp_line
			(start -0.67945 0.3048)
			(end -0.67945 -0.305054)
			(stroke
				(width 0.1)
				(type default)
			)
			(layer "F.Fab")
		)
		(pad "1" smd circle
			(at -0.40005 0 90)
			(size 0 0)
			(layers "F.Cu" "F.Mask" "F.Paste")
			(net "P1V8_AUX")
		)
		(pad "2" smd circle
			(at 0.40005 0 90)
			(size 0 0)
			(layers "F.Cu" "F.Mask" "F.Paste")
			(net "FM_BOARD_BMC_REV_ID1")
		)
	)
	(footprint ""
		(layer "F.Cu")
		(at 79.202026 -94.856046 180)
		(property "Reference" "J10"
			(at 4.589526 -5.741416 0)
			(unlocked yes)
			(layer "F.SilkS")
			(effects
				(font
					(size 0.7874 0.5842)
					(thickness 0.1524)
				)
				(justify left)
			)
		)
		(property "Value" ""
			(at 0 0 180)
			(layer "F.Fab")
			(effects
				(font
					(size 1.27 1.27)
				)
			)
		)
		(duplicate_pad_numbers_are_jumpers no)
		(fp_line
			(start 2.500122 5.150104)
			(end -2.500122 5.150104)
			(stroke
				(width 0.1524)
				(type default)
			)
			(layer "F.SilkS")
		)
		(fp_line
			(start 2.500122 5.08)
			(end 2.500122 5.150104)
			(stroke
				(width 0.1524)
				(type default)
			)
			(layer "F.SilkS")
		)
		(fp_line
			(start 2.500122 2.4384)
			(end 2.500122 3.3782)
			(stroke
				(width 0.1524)
				(type default)
			)
			(layer "F.SilkS")
		)
		(fp_line
			(start 2.500122 -3.3782)
			(end 2.500122 -2.4384)
			(stroke
				(width 0.1524)
				(type default)
			)
			(layer "F.SilkS")
		)
		(fp_line
			(start 2.500122 -5.150104)
			(end 2.500122 -5.08)
			(stroke
				(width 0.1524)
				(type default)
			)
			(layer "F.SilkS")
		)
		(fp_line
			(start -2.500122 5.150104)
			(end -2.500122 5.08)
			(stroke
				(width 0.1524)
				(type default)
			)
			(layer "F.SilkS")
		)
		(fp_line
			(start -2.500122 3.3782)
			(end -2.500122 2.9464)
			(stroke
				(width 0.1524)
				(type default)
			)
			(layer "F.SilkS")
		)
		(fp_line
			(start -2.500122 -2.9464)
			(end -2.500122 -3.3782)
			(stroke
				(width 0.1524)
				(type default)
			)
			(layer "F.SilkS")
		)
		(fp_line
			(start -2.500122 -5.08)
			(end -2.500122 -5.150104)
			(stroke
				(width 0.1524)
				(type default)
			)
			(layer "F.SilkS")
		)
		(fp_line
			(start -2.500122 -5.150104)
			(end 2.500122 -5.150104)
			(stroke
				(width 0.1524)
				(type default)
			)
			(layer "F.SilkS")
		)
		(fp_poly
			(pts
				(xy -4.0386 -2.068322) (xy -4.0386 -3.084322) (xy -3.0226 -2.576322)
			)
			(stroke
				(width 0)
				(type default)
			)
			(fill yes)
			(layer "F.SilkS")
		)
		(fp_line
			(start 2.500122 5.150104)
			(end 2.500122 -5.150104)
			(stroke
				(width 0.1)
				(type default)
			)
			(layer "F.Fab")
		)
		(fp_line
			(start 2.500122 -5.150104)
			(end -2.500122 -5.150104)
			(stroke
				(width 0.1)
				(type default)
			)
			(layer "F.Fab")
		)
		(fp_line
			(start -2.500122 5.150104)
			(end 2.500122 5.150104)
			(stroke
				(width 0.1)
				(type default)
			)
			(layer "F.Fab")
		)
		(fp_line
			(start -2.500122 -5.150104)
			(end -2.500122 5.150104)
			(stroke
				(width 0.1)
				(type default)
			)
			(layer "F.Fab")
		)
		(fp_poly
			(pts
				(xy -4.0894 -1.992122) (xy -4.0894 -3.008122) (xy -3.0734 -2.500122)
			)
			(stroke
				(width 0)
				(type default)
			)
			(fill yes)
			(layer "F.Fab")
		)
		(fp_text user "11"
			(at 3.814826 2.259584 0)
			(unlocked yes)
			(layer "F.SilkS")
			(effects
				(font
					(size 0.7874 0.5842)
					(thickness 0.1524)
				)
			)
		)
		(fp_text user "7"
			(at 3.535426 -2.566416 0)
			(unlocked yes)
			(layer "F.SilkS")
			(effects
				(font
					(size 0.7874 0.5842)
					(thickness 0.1524)
				)
			)
		)
		(fp_text user "6"
			(at -3.779774 3.341624 180)
			(unlocked yes)
			(layer "F.SilkS")
			(effects
				(font
					(size 0.7874 0.5842)
					(thickness 0.1524)
				)
			)
		)
		(fp_text user "7"
			(at 3.520948 -2.048002 90)
			(unlocked yes)
			(layer "F.Fab")
			(effects
				(font
					(size 0.7874 0.5842)
					(thickness 0.1524)
				)
			)
		)
		(fp_text user "11"
			(at 3.495548 2.028444 90)
			(unlocked yes)
			(layer "F.Fab")
			(effects
				(font
					(size 0.7874 0.5842)
					(thickness 0.1524)
				)
			)
		)
		(fp_text user "6"
			(at -3.591052 2.574798 90)
			(unlocked yes)
			(layer "F.Fab")
			(effects
				(font
					(size 0.7874 0.5842)
					(thickness 0.1524)
				)
			)
		)
		(pad "1" smd rect
			(at -2.109978 -2.500122 270)
			(size 0.6096 1.651)
			(layers "F.Cu" "F.Mask" "F.Paste")
			(net "SPI_BMC_TPM_CLK_R")
		)
		(pad "2" smd rect
			(at -2.109978 -1.500124 270)
			(size 0.6096 1.651)
			(layers "F.Cu" "F.Mask" "F.Paste")
			(net "RST_BMC_EXTRST_R3_N")
		)
		(pad "3" smd rect
			(at -2.109978 -0.499872 270)
			(size 0.6096 1.651)
			(layers "F.Cu" "F.Mask" "F.Paste")
			(net "SPI_BMC_TPM_MOSI_R")
		)
		(pad "4" smd rect
			(at -2.109978 0.499872 270)
			(size 0.6096 1.651)
			(layers "F.Cu" "F.Mask" "F.Paste")
			(net "SPI_BMC_TPM_MISO_R")
		)
		(pad "5" smd rect
			(at -2.109978 1.500124 270)
			(size 0.6096 1.651)
			(layers "F.Cu" "F.Mask" "F.Paste")
			(net "SPI_BMC_TPM_CS2_N_R")
		)
		(pad "6" smd rect
			(at -2.109978 2.500122 270)
			(size 0.6096 1.651)
			(layers "F.Cu" "F.Mask" "F.Paste")
			(net "SMB_BMC_TPM_MM16_SDA")
		)
		(pad "7" smd rect
			(at 2.109978 -1.999996 90)
			(size 0.6096 1.651)
			(layers "F.Cu" "F.Mask" "F.Paste")
			(net "P3V3_AUX")
		)
		(pad "8" smd rect
			(at 2.109978 -0.999998 90)
			(size 0.6096 1.651)
			(layers "F.Cu" "F.Mask" "F.Paste")
			(net "FM_TPM_PRSNT_1_N")
		)
		(pad "9" smd rect
			(at 2.109978 0 90)
			(size 0.6096 1.651)
			(layers "F.Cu" "F.Mask" "F.Paste")
			(net "IRQ_BMC_TPM_SPI_R_N")
		)
		(pad "10" smd rect
			(at 2.109978 0.999998 90)
			(size 0.6096 1.651)
			(layers "F.Cu" "F.Mask" "F.Paste")
			(net "SMB_BMC_TPM_MM16_SCL")
		)
		(pad "11" smd rect
			(at 2.109978 1.999996 90)
			(size 0.6096 1.651)
			(layers "F.Cu" "F.Mask" "F.Paste")
			(net "GND")
		)
		(pad "G1" smd rect
			(at 0 -4.219956 270)
			(size 1.4224 5.8674)
			(layers "F.Cu" "F.Mask" "F.Paste")
			(net "GND")
		)
		(pad "G2" smd rect
			(at 0 4.219956 90)
			(size 1.4224 5.8674)
			(layers "F.Cu" "F.Mask" "F.Paste")
			(net "GND")
		)
	)
	(footprint ""
		(layer "F.Cu")
		(at 37.592 -53.086 180)
		(property "Reference" "C142"
			(at 0 0 180)
			(layer "F.SilkS")
			(hide yes)
			(effects
				(font
					(size 1.27 1.27)
				)
			)
		)
		(property "Value" ""
			(at 0 0 180)
			(layer "F.Fab")
			(effects
				(font
					(size 1.27 1.27)
				)
			)
		)
		(duplicate_pad_numbers_are_jumpers no)
		(fp_line
			(start 1.651 0.8382)
			(end -1.651 0.8382)
			(stroke
				(width 0.1524)
				(type default)
			)
			(layer "F.SilkS")
		)
		(fp_line
			(start 1.651 -0.8382)
			(end 1.651 0.8382)
			(stroke
				(width 0.1524)
				(type default)
			)
			(layer "F.SilkS")
		)
		(fp_line
			(start 0 0.8382)
			(end 0 -0.8382)
			(stroke
				(width 0.1524)
				(type default)
			)
			(layer "F.SilkS")
		)
		(fp_line
			(start -1.651 0.8382)
			(end -1.651 -0.8382)
			(stroke
				(width 0.1524)
				(type default)
			)
			(layer "F.SilkS")
		)
		(fp_line
			(start -1.651 -0.8382)
			(end 1.651 -0.8382)
			(stroke
				(width 0.1524)
				(type default)
			)
			(layer "F.SilkS")
		)
		(fp_line
			(start 1.55956 0.7366)
			(end 1.55956 -0.7366)
			(stroke
				(width 0.1)
				(type default)
			)
			(layer "F.Fab")
		)
		(fp_line
			(start 1.55956 -0.7366)
			(end 1.524 -0.7366)
			(stroke
				(width 0.1)
				(type default)
			)
			(layer "F.Fab")
		)
		(fp_line
			(start 1.524 0.7366)
			(end 1.55956 0.7366)
			(stroke
				(width 0.1)
				(type default)
			)
			(layer "F.Fab")
		)
		(fp_line
			(start 1.524 -0.7366)
			(end -1.524 -0.7366)
			(stroke
				(width 0.1)
				(type default)
			)
			(layer "F.Fab")
		)
		(fp_line
			(start -1.524 0.7366)
			(end 1.524 0.7366)
			(stroke
				(width 0.1)
				(type default)
			)
			(layer "F.Fab")
		)
		(fp_line
			(start -1.524 -0.7366)
			(end -1.55956 -0.7366)
			(stroke
				(width 0.1)
				(type default)
			)
			(layer "F.Fab")
		)
		(fp_line
			(start -1.55956 0.7366)
			(end -1.524 0.7366)
			(stroke
				(width 0.1)
				(type default)
			)
			(layer "F.Fab")
		)
		(fp_line
			(start -1.55956 -0.7366)
			(end -1.55956 0.7366)
			(stroke
				(width 0.1)
				(type default)
			)
			(layer "F.Fab")
		)
		(pad "1" smd rect
			(at -0.94996 0)
			(size 1.1176 1.3716)
			(layers "F.Cu" "F.Mask" "F.Paste")
			(net "P1V8_AUX")
		)
		(pad "2" smd rect
			(at 0.94996 0)
			(size 1.1176 1.3716)
			(layers "F.Cu" "F.Mask" "F.Paste")
			(net "GND")
		)
	)
	(footprint ""
		(layer "F.Cu")
		(at 9.271 -31.837122 -90)
		(property "Reference" "PC214"
			(at 0 0 270)
			(layer "F.SilkS")
			(hide yes)
			(effects
				(font
					(size 1.27 1.27)
				)
			)
		)
		(property "Value" ""
			(at 0 0 270)
			(layer "F.Fab")
			(effects
				(font
					(size 1.27 1.27)
				)
			)
		)
		(duplicate_pad_numbers_are_jumpers no)
		(fp_line
			(start -1.651 0.8382)
			(end -1.651 -0.8382)
			(stroke
				(width 0.1524)
				(type default)
			)
			(layer "F.SilkS")
		)
		(fp_line
			(start 0 0.8382)
			(end 0 -0.8382)
			(stroke
				(width 0.1524)
				(type default)
			)
			(layer "F.SilkS")
		)
		(fp_line
			(start 1.651 0.8382)
			(end -1.651 0.8382)
			(stroke
				(width 0.1524)
				(type default)
			)
			(layer "F.SilkS")
		)
		(fp_line
			(start -1.651 -0.8382)
			(end 1.651 -0.8382)
			(stroke
				(width 0.1524)
				(type default)
			)
			(layer "F.SilkS")
		)
		(fp_line
			(start 1.651 -0.8382)
			(end 1.651 0.8382)
			(stroke
				(width 0.1524)
				(type default)
			)
			(layer "F.SilkS")
		)
		(fp_line
			(start -1.55956 0.7366)
			(end -1.524 0.7366)
			(stroke
				(width 0.1)
				(type default)
			)
			(layer "F.Fab")
		)
		(fp_line
			(start -1.524 0.7366)
			(end 1.524 0.7366)
			(stroke
				(width 0.1)
				(type default)
			)
			(layer "F.Fab")
		)
		(fp_line
			(start 1.524 0.7366)
			(end 1.55956 0.7366)
			(stroke
				(width 0.1)
				(type default)
			)
			(layer "F.Fab")
		)
		(fp_line
			(start 1.55956 0.7366)
			(end 1.55956 -0.7366)
			(stroke
				(width 0.1)
				(type default)
			)
			(layer "F.Fab")
		)
		(fp_line
			(start -1.55956 -0.7366)
			(end -1.55956 0.7366)
			(stroke
				(width 0.1)
				(type default)
			)
			(layer "F.Fab")
		)
		(fp_line
			(start -1.524 -0.7366)
			(end -1.55956 -0.7366)
			(stroke
				(width 0.1)
				(type default)
			)
			(layer "F.Fab")
		)
		(fp_line
			(start 1.524 -0.7366)
			(end -1.524 -0.7366)
			(stroke
				(width 0.1)
				(type default)
			)
			(layer "F.Fab")
		)
		(fp_line
			(start 1.55956 -0.7366)
			(end 1.524 -0.7366)
			(stroke
				(width 0.1)
				(type default)
			)
			(layer "F.Fab")
		)
		(pad "1" smd rect
			(at -0.94996 0 90)
			(size 1.1176 1.3716)
			(layers "F.Cu" "F.Mask" "F.Paste")
			(net "P5V_AUX")
		)
		(pad "2" smd rect
			(at 0.94996 0 90)
			(size 1.1176 1.3716)
			(layers "F.Cu" "F.Mask" "F.Paste")
			(net "GND")
		)
	)
	(footprint ""
		(layer "F.Cu")
		(at 63.246 -81.788)
		(property "Reference" "R507"
			(at 0 0 0)
			(layer "F.SilkS")
			(hide yes)
			(effects
				(font
					(size 1.27 1.27)
				)
			)
		)
		(property "Value" ""
			(at 0 0 0)
			(layer "F.Fab")
			(effects
				(font
					(size 1.27 1.27)
				)
			)
		)
		(duplicate_pad_numbers_are_jumpers no)
		(fp_line
			(start -0.7874 -0.4064)
			(end 0.7874 -0.4064)
			(stroke
				(width 0.1524)
				(type default)
			)
			(layer "F.SilkS")
		)
		(fp_line
			(start -0.7874 0.4064)
			(end -0.7874 -0.4064)
			(stroke
				(width 0.1524)
				(type default)
			)
			(layer "F.SilkS")
		)
		(fp_line
			(start 0.7874 -0.4064)
			(end 0.7874 0.4064)
			(stroke
				(width 0.1524)
				(type default)
			)
			(layer "F.SilkS")
		)
		(fp_line
			(start 0.7874 0.4064)
			(end -0.7874 0.4064)
			(stroke
				(width 0.1524)
				(type default)
			)
			(layer "F.SilkS")
		)
		(fp_line
			(start -0.67945 -0.305054)
			(end -0.12065 -0.305054)
			(stroke
				(width 0.1)
				(type default)
			)
			(layer "F.Fab")
		)
		(fp_line
			(start -0.67945 0.3048)
			(end -0.67945 -0.305054)
			(stroke
				(width 0.1)
				(type default)
			)
			(layer "F.Fab")
		)
		(fp_line
			(start -0.12065 -0.305054)
			(end -0.12065 -0.2794)
			(stroke
				(width 0.1)
				(type default)
			)
			(layer "F.Fab")
		)
		(fp_line
			(start -0.12065 -0.2794)
			(end 0.12065 -0.2794)
			(stroke
				(width 0.1)
				(type default)
			)
			(layer "F.Fab")
		)
		(fp_line
			(start -0.12065 0.2794)
			(end -0.12065 0.3048)
			(stroke
				(width 0.1)
				(type default)
			)
			(layer "F.Fab")
		)
		(fp_line
			(start -0.12065 0.3048)
			(end -0.67945 0.3048)
			(stroke
				(width 0.1)
				(type default)
			)
			(layer "F.Fab")
		)
		(fp_line
			(start 0.120396 0.2794)
			(end -0.12065 0.2794)
			(stroke
				(width 0.1)
				(type default)
			)
			(layer "F.Fab")
		)
		(fp_line
			(start 0.120396 0.3048)
			(end 0.120396 0.2794)
			(stroke
				(width 0.1)
				(type default)
			)
			(layer "F.Fab")
		)
		(fp_line
			(start 0.12065 -0.3048)
			(end 0.67945 -0.3048)
			(stroke
				(width 0.1)
				(type default)
			)
			(layer "F.Fab")
		)
		(fp_line
			(start 0.12065 -0.2794)
			(end 0.12065 -0.3048)
			(stroke
				(width 0.1)
				(type default)
			)
			(layer "F.Fab")
		)
		(fp_line
			(start 0.67945 -0.3048)
			(end 0.67945 0.3048)
			(stroke
				(width 0.1)
				(type default)
			)
			(layer "F.Fab")
		)
		(fp_line
			(start 0.67945 0.3048)
			(end 0.120396 0.3048)
			(stroke
				(width 0.1)
				(type default)
			)
			(layer "F.Fab")
		)
		(pad "1" smd circle
			(at -0.40005 0)
			(size 0 0)
			(layers "F.Cu" "F.Mask" "F.Paste")
			(net "MB_JTAG_PLD_R_JTAGEN")
		)
		(pad "2" smd circle
			(at 0.40005 0)
			(size 0 0)
			(layers "F.Cu" "F.Mask" "F.Paste")
			(net "GND")
		)
	)
	(footprint ""
		(layer "F.Cu")
		(at 74.09815 -92.204032 180)
		(property "Reference" "C144"
			(at 0 0 180)
			(layer "F.SilkS")
			(hide yes)
			(effects
				(font
					(size 1.27 1.27)
				)
			)
		)
		(property "Value" ""
			(at 0 0 180)
			(layer "F.Fab")
			(effects
				(font
					(size 1.27 1.27)
				)
			)
		)
		(duplicate_pad_numbers_are_jumpers no)
		(fp_line
			(start 0.7874 0.4064)
			(end -0.7874 0.4064)
			(stroke
				(width 0.1524)
				(type default)
			)
			(layer "F.SilkS")
		)
		(fp_line
			(start 0.7874 -0.4064)
			(end 0.7874 0.4064)
			(stroke
				(width 0.1524)
				(type default)
			)
			(layer "F.SilkS")
		)
		(fp_line
			(start -0.7874 0.4064)
			(end -0.7874 -0.4064)
			(stroke
				(width 0.1524)
				(type default)
			)
			(layer "F.SilkS")
		)
		(fp_line
			(start -0.7874 -0.4064)
			(end 0.7874 -0.4064)
			(stroke
				(width 0.1524)
				(type default)
			)
			(layer "F.SilkS")
		)
		(fp_line
			(start 0.67945 0.3048)
			(end 0.120396 0.3048)
			(stroke
				(width 0.1)
				(type default)
			)
			(layer "F.Fab")
		)
		(fp_line
			(start 0.67945 -0.3048)
			(end 0.67945 0.3048)
			(stroke
				(width 0.1)
				(type default)
			)
			(layer "F.Fab")
		)
		(fp_line
			(start 0.12065 -0.2794)
			(end 0.12065 -0.3048)
			(stroke
				(width 0.1)
				(type default)
			)
			(layer "F.Fab")
		)
		(fp_line
			(start 0.12065 -0.3048)
			(end 0.67945 -0.3048)
			(stroke
				(width 0.1)
				(type default)
			)
			(layer "F.Fab")
		)
		(fp_line
			(start 0.120396 0.3048)
			(end 0.120396 0.2794)
			(stroke
				(width 0.1)
				(type default)
			)
			(layer "F.Fab")
		)
		(fp_line
			(start 0.120396 0.2794)
			(end -0.12065 0.2794)
			(stroke
				(width 0.1)
				(type default)
			)
			(layer "F.Fab")
		)
		(fp_line
			(start -0.12065 0.3048)
			(end -0.67945 0.3048)
			(stroke
				(width 0.1)
				(type default)
			)
			(layer "F.Fab")
		)
		(fp_line
			(start -0.12065 0.2794)
			(end -0.12065 0.3048)
			(stroke
				(width 0.1)
				(type default)
			)
			(layer "F.Fab")
		)
		(fp_line
			(start -0.12065 -0.2794)
			(end 0.12065 -0.2794)
			(stroke
				(width 0.1)
				(type default)
			)
			(layer "F.Fab")
		)
		(fp_line
			(start -0.12065 -0.305054)
			(end -0.12065 -0.2794)
			(stroke
				(width 0.1)
				(type default)
			)
			(layer "F.Fab")
		)
		(fp_line
			(start -0.67945 0.3048)
			(end -0.67945 -0.305054)
			(stroke
				(width 0.1)
				(type default)
			)
			(layer "F.Fab")
		)
		(fp_line
			(start -0.67945 -0.305054)
			(end -0.12065 -0.305054)
			(stroke
				(width 0.1)
				(type default)
			)
			(layer "F.Fab")
		)
		(pad "1" smd circle
			(at -0.40005 0 180)
			(size 0 0)
			(layers "F.Cu" "F.Mask" "F.Paste")
			(net "P3V3_AUX")
		)
		(pad "2" smd circle
			(at 0.40005 0 180)
			(size 0 0)
			(layers "F.Cu" "F.Mask" "F.Paste")
			(net "GND")
		)
	)
	(footprint ""
		(layer "F.Cu")
		(at 59.182 -10.922 90)
		(property "Reference" "C27"
			(at 0 0 90)
			(layer "F.SilkS")
			(hide yes)
			(effects
				(font
					(size 1.27 1.27)
				)
			)
		)
		(property "Value" ""
			(at 0 0 90)
			(layer "F.Fab")
			(effects
				(font
					(size 1.27 1.27)
				)
			)
		)
		(duplicate_pad_numbers_are_jumpers no)
		(fp_line
			(start -0.492506 -0.4064)
			(end 0.421894 -0.4064)
			(stroke
				(width 0.1524)
				(type default)
			)
			(layer "F.SilkS")
		)
		(fp_line
			(start 0.7874 -0.077216)
			(end 0.7874 0.4064)
			(stroke
				(width 0.1524)
				(type default)
			)
			(layer "F.SilkS")
		)
		(fp_line
			(start 0.7874 0.4064)
			(end -0.7874 0.4064)
			(stroke
				(width 0.1524)
				(type default)
			)
			(layer "F.SilkS")
		)
		(fp_line
			(start -0.7874 0.4064)
			(end -0.7874 -0.039116)
			(stroke
				(width 0.1524)
				(type default)
			)
			(layer "F.SilkS")
		)
		(fp_line
			(start -0.12065 -0.305054)
			(end -0.12065 -0.2794)
			(stroke
				(width 0.1)
				(type default)
			)
			(layer "F.Fab")
		)
		(fp_line
			(start -0.67945 -0.305054)
			(end -0.12065 -0.305054)
			(stroke
				(width 0.1)
				(type default)
			)
			(layer "F.Fab")
		)
		(fp_line
			(start 0.67945 -0.3048)
			(end 0.67945 0.3048)
			(stroke
				(width 0.1)
				(type default)
			)
			(layer "F.Fab")
		)
		(fp_line
			(start 0.12065 -0.3048)
			(end 0.67945 -0.3048)
			(stroke
				(width 0.1)
				(type default)
			)
			(layer "F.Fab")
		)
		(fp_line
			(start 0.12065 -0.2794)
			(end 0.12065 -0.3048)
			(stroke
				(width 0.1)
				(type default)
			)
			(layer "F.Fab")
		)
		(fp_line
			(start -0.12065 -0.2794)
			(end 0.12065 -0.2794)
			(stroke
				(width 0.1)
				(type default)
			)
			(layer "F.Fab")
		)
		(fp_line
			(start 0.120396 0.2794)
			(end -0.12065 0.2794)
			(stroke
				(width 0.1)
				(type default)
			)
			(layer "F.Fab")
		)
		(fp_line
			(start -0.12065 0.2794)
			(end -0.12065 0.3048)
			(stroke
				(width 0.1)
				(type default)
			)
			(layer "F.Fab")
		)
		(fp_line
			(start 0.67945 0.3048)
			(end 0.120396 0.3048)
			(stroke
				(width 0.1)
				(type default)
			)
			(layer "F.Fab")
		)
		(fp_line
			(start 0.120396 0.3048)
			(end 0.120396 0.2794)
			(stroke
				(width 0.1)
				(type default)
			)
			(layer "F.Fab")
		)
		(fp_line
			(start -0.12065 0.3048)
			(end -0.67945 0.3048)
			(stroke
				(width 0.1)
				(type default)
			)
			(layer "F.Fab")
		)
		(fp_line
			(start -0.67945 0.3048)
			(end -0.67945 -0.305054)
			(stroke
				(width 0.1)
				(type default)
			)
			(layer "F.Fab")
		)
		(pad "1" smd circle
			(at -0.40005 0 90)
			(size 0 0)
			(layers "F.Cu" "F.Mask" "F.Paste")
			(net "LED_D22_R")
		)
		(pad "2" smd circle
			(at 0.40005 0 90)
			(size 0 0)
			(layers "F.Cu" "F.Mask" "F.Paste")
			(net "GND")
		)
	)
	(footprint ""
		(layer "F.Cu")
		(at 43.9166 -69.2912 180)
		(property "Reference" "R167"
			(at 0 0 180)
			(layer "F.SilkS")
			(hide yes)
			(effects
				(font
					(size 1.27 1.27)
				)
			)
		)
		(property "Value" ""
			(at 0 0 180)
			(layer "F.Fab")
			(effects
				(font
					(size 1.27 1.27)
				)
			)
		)
		(duplicate_pad_numbers_are_jumpers no)
		(fp_line
			(start 0.7874 0.4064)
			(end -0.7874 0.4064)
			(stroke
				(width 0.1524)
				(type default)
			)
			(layer "F.SilkS")
		)
		(fp_line
			(start 0.7874 -0.4064)
			(end 0.7874 0.4064)
			(stroke
				(width 0.1524)
				(type default)
			)
			(layer "F.SilkS")
		)
		(fp_line
			(start -0.7874 0.4064)
			(end -0.7874 -0.4064)
			(stroke
				(width 0.1524)
				(type default)
			)
			(layer "F.SilkS")
		)
		(fp_line
			(start -0.7874 -0.4064)
			(end 0.7874 -0.4064)
			(stroke
				(width 0.1524)
				(type default)
			)
			(layer "F.SilkS")
		)
		(fp_line
			(start 0.67945 0.3048)
			(end 0.120396 0.3048)
			(stroke
				(width 0.1)
				(type default)
			)
			(layer "F.Fab")
		)
		(fp_line
			(start 0.67945 -0.3048)
			(end 0.67945 0.3048)
			(stroke
				(width 0.1)
				(type default)
			)
			(layer "F.Fab")
		)
		(fp_line
			(start 0.12065 -0.2794)
			(end 0.12065 -0.3048)
			(stroke
				(width 0.1)
				(type default)
			)
			(layer "F.Fab")
		)
		(fp_line
			(start 0.12065 -0.3048)
			(end 0.67945 -0.3048)
			(stroke
				(width 0.1)
				(type default)
			)
			(layer "F.Fab")
		)
		(fp_line
			(start 0.120396 0.3048)
			(end 0.120396 0.2794)
			(stroke
				(width 0.1)
				(type default)
			)
			(layer "F.Fab")
		)
		(fp_line
			(start 0.120396 0.2794)
			(end -0.12065 0.2794)
			(stroke
				(width 0.1)
				(type default)
			)
			(layer "F.Fab")
		)
		(fp_line
			(start -0.12065 0.3048)
			(end -0.67945 0.3048)
			(stroke
				(width 0.1)
				(type default)
			)
			(layer "F.Fab")
		)
		(fp_line
			(start -0.12065 0.2794)
			(end -0.12065 0.3048)
			(stroke
				(width 0.1)
				(type default)
			)
			(layer "F.Fab")
		)
		(fp_line
			(start -0.12065 -0.2794)
			(end 0.12065 -0.2794)
			(stroke
				(width 0.1)
				(type default)
			)
			(layer "F.Fab")
		)
		(fp_line
			(start -0.12065 -0.305054)
			(end -0.12065 -0.2794)
			(stroke
				(width 0.1)
				(type default)
			)
			(layer "F.Fab")
		)
		(fp_line
			(start -0.67945 0.3048)
			(end -0.67945 -0.305054)
			(stroke
				(width 0.1)
				(type default)
			)
			(layer "F.Fab")
		)
		(fp_line
			(start -0.67945 -0.305054)
			(end -0.12065 -0.305054)
			(stroke
				(width 0.1)
				(type default)
			)
			(layer "F.Fab")
		)
		(pad "1" smd circle
			(at -0.40005 0 180)
			(size 0 0)
			(layers "F.Cu" "F.Mask" "F.Paste")
			(net "P3V3_AUX")
		)
		(pad "2" smd circle
			(at 0.40005 0 180)
			(size 0 0)
			(layers "F.Cu" "F.Mask" "F.Paste")
			(net "BMC_HEARTBEAT_R_N")
		)
	)
	(footprint ""
		(layer "F.Cu")
		(at 75.946 -77.978)
		(property "Reference" "R677"
			(at 0 0 0)
			(layer "F.SilkS")
			(hide yes)
			(effects
				(font
					(size 1.27 1.27)
				)
			)
		)
		(property "Value" ""
			(at 0 0 0)
			(layer "F.Fab")
			(effects
				(font
					(size 1.27 1.27)
				)
			)
		)
		(duplicate_pad_numbers_are_jumpers no)
		(fp_line
			(start -0.7874 -0.4064)
			(end 0.7874 -0.4064)
			(stroke
				(width 0.1524)
				(type default)
			)
			(layer "F.SilkS")
		)
		(fp_line
			(start -0.7874 0.4064)
			(end -0.7874 -0.4064)
			(stroke
				(width 0.1524)
				(type default)
			)
			(layer "F.SilkS")
		)
		(fp_line
			(start 0.7874 -0.4064)
			(end 0.7874 0.4064)
			(stroke
				(width 0.1524)
				(type default)
			)
			(layer "F.SilkS")
		)
		(fp_line
			(start 0.7874 0.4064)
			(end -0.7874 0.4064)
			(stroke
				(width 0.1524)
				(type default)
			)
			(layer "F.SilkS")
		)
		(fp_line
			(start -0.67945 -0.305054)
			(end -0.12065 -0.305054)
			(stroke
				(width 0.1)
				(type default)
			)
			(layer "F.Fab")
		)
		(fp_line
			(start -0.67945 0.3048)
			(end -0.67945 -0.305054)
			(stroke
				(width 0.1)
				(type default)
			)
			(layer "F.Fab")
		)
		(fp_line
			(start -0.12065 -0.305054)
			(end -0.12065 -0.2794)
			(stroke
				(width 0.1)
				(type default)
			)
			(layer "F.Fab")
		)
		(fp_line
			(start -0.12065 -0.2794)
			(end 0.12065 -0.2794)
			(stroke
				(width 0.1)
				(type default)
			)
			(layer "F.Fab")
		)
		(fp_line
			(start -0.12065 0.2794)
			(end -0.12065 0.3048)
			(stroke
				(width 0.1)
				(type default)
			)
			(layer "F.Fab")
		)
		(fp_line
			(start -0.12065 0.3048)
			(end -0.67945 0.3048)
			(stroke
				(width 0.1)
				(type default)
			)
			(layer "F.Fab")
		)
		(fp_line
			(start 0.120396 0.2794)
			(end -0.12065 0.2794)
			(stroke
				(width 0.1)
				(type default)
			)
			(layer "F.Fab")
		)
		(fp_line
			(start 0.120396 0.3048)
			(end 0.120396 0.2794)
			(stroke
				(width 0.1)
				(type default)
			)
			(layer "F.Fab")
		)
		(fp_line
			(start 0.12065 -0.3048)
			(end 0.67945 -0.3048)
			(stroke
				(width 0.1)
				(type default)
			)
			(layer "F.Fab")
		)
		(fp_line
			(start 0.12065 -0.2794)
			(end 0.12065 -0.3048)
			(stroke
				(width 0.1)
				(type default)
			)
			(layer "F.Fab")
		)
		(fp_line
			(start 0.67945 -0.3048)
			(end 0.67945 0.3048)
			(stroke
				(width 0.1)
				(type default)
			)
			(layer "F.Fab")
		)
		(fp_line
			(start 0.67945 0.3048)
			(end 0.120396 0.3048)
			(stroke
				(width 0.1)
				(type default)
			)
			(layer "F.Fab")
		)
		(pad "1" smd circle
			(at -0.40005 0)
			(size 0 0)
			(layers "F.Cu" "F.Mask" "F.Paste")
			(net "U56_ADJ_1")
		)
		(pad "2" smd circle
			(at 0.40005 0)
			(size 0 0)
			(layers "F.Cu" "F.Mask" "F.Paste")
			(net "GND")
		)
	)
	(footprint ""
		(layer "F.Cu")
		(at 75.646534 -28.196032 -90)
		(property "Reference" "D2"
			(at 2.282952 -8.41883 90)
			(unlocked yes)
			(layer "F.SilkS")
			(effects
				(font
					(size 0.7874 0.5842)
					(thickness 0.1524)
				)
				(justify left)
			)
		)
		(property "Value" ""
			(at 0 0 270)
			(layer "F.Fab")
			(effects
				(font
					(size 1.27 1.27)
				)
			)
		)
		(duplicate_pad_numbers_are_jumpers no)
		(fp_line
			(start -1.3208 0.5588)
			(end -1.3208 -0.5588)
			(stroke
				(width 0.1524)
				(type default)
			)
			(layer "F.SilkS")
		)
		(fp_line
			(start 1.3208 0.5588)
			(end -1.3208 0.5588)
			(stroke
				(width 0.1524)
				(type default)
			)
			(layer "F.SilkS")
		)
		(fp_line
			(start 1.6256 0.5588)
			(end 1.6256 -0.5588)
			(stroke
				(width 0.1524)
				(type default)
			)
			(layer "F.SilkS")
		)
		(fp_line
			(start 1.778 0.5588)
			(end 1.3208 0.5588)
			(stroke
				(width 0.1524)
				(type default)
			)
			(layer "F.SilkS")
		)
		(fp_line
			(start -1.3208 -0.5588)
			(end 1.3208 -0.5588)
			(stroke
				(width 0.1524)
				(type default)
			)
			(layer "F.SilkS")
		)
		(fp_line
			(start 1.3208 -0.5588)
			(end 1.3208 0.5588)
			(stroke
				(width 0.1524)
				(type default)
			)
			(layer "F.SilkS")
		)
		(fp_line
			(start 1.4732 -0.5588)
			(end 1.4732 0.5588)
			(stroke
				(width 0.1524)
				(type default)
			)
			(layer "F.SilkS")
		)
		(fp_line
			(start 1.778 -0.5588)
			(end 1.778 0.5588)
			(stroke
				(width 0.1524)
				(type default)
			)
			(layer "F.SilkS")
		)
		(fp_line
			(start 1.778 -0.5588)
			(end 1.3208 -0.5588)
			(stroke
				(width 0.1524)
				(type default)
			)
			(layer "F.SilkS")
		)
		(fp_line
			(start -1.235964 0.508)
			(end -1.1684 0.508)
			(stroke
				(width 0.1)
				(type default)
			)
			(layer "F.Fab")
		)
		(fp_line
			(start -1.1684 0.508)
			(end 1.1684 0.508)
			(stroke
				(width 0.1)
				(type default)
			)
			(layer "F.Fab")
		)
		(fp_line
			(start 1.1684 0.508)
			(end 1.236726 0.508)
			(stroke
				(width 0.1)
				(type default)
			)
			(layer "F.Fab")
		)
		(fp_line
			(start 1.236726 0.508)
			(end 1.236726 -0.508)
			(stroke
				(width 0.1)
				(type default)
			)
			(layer "F.Fab")
		)
		(fp_line
			(start -1.235964 -0.508)
			(end -1.235964 0.508)
			(stroke
				(width 0.1)
				(type default)
			)
			(layer "F.Fab")
		)
		(fp_line
			(start -1.1684 -0.508)
			(end -1.235964 -0.508)
			(stroke
				(width 0.1)
				(type default)
			)
			(layer "F.Fab")
		)
		(fp_line
			(start 1.1684 -0.508)
			(end -1.1684 -0.508)
			(stroke
				(width 0.1)
				(type default)
			)
			(layer "F.Fab")
		)
		(fp_line
			(start 1.236726 -0.508)
			(end 1.1684 -0.508)
			(stroke
				(width 0.1)
				(type default)
			)
			(layer "F.Fab")
		)
		(fp_text user "+"
			(at -0.861568 1.014984 90)
			(unlocked yes)
			(layer "F.SilkS")
			(effects
				(font
					(size 1.905 1.4224)
					(thickness 0.1524)
				)
				(justify left)
			)
		)
		(fp_text user "-"
			(at 1.678432 -1.055116 270)
			(unlocked yes)
			(layer "F.SilkS")
			(effects
				(font
					(size 1.905 1.4224)
					(thickness 0.1524)
				)
				(justify left)
			)
		)
		(fp_text user "+"
			(at -2.5654 -0.24765 270)
			(unlocked yes)
			(layer "F.Fab")
			(effects
				(font
					(size 1.905 1.4224)
					(thickness 0.1524)
				)
				(justify left)
			)
		)
		(fp_text user "-"
			(at 1.524 -0.24765 270)
			(unlocked yes)
			(layer "F.Fab")
			(effects
				(font
					(size 1.905 1.4224)
					(thickness 0.1524)
				)
				(justify left)
			)
		)
		(pad "A" smd rect
			(at -0.750062 0 270)
			(size 0.8128 0.8128)
			(layers "F.Cu" "F.Mask" "F.Paste")
			(net "LED_POSTCODE_2_R")
		)
		(pad "C" smd rect
			(at 0.750062 0 270)
			(size 0.8128 0.8128)
			(layers "F.Cu" "F.Mask" "F.Paste")
			(net "GND")
		)
	)
	(footprint ""
		(layer "F.Cu")
		(at 25.06472 -108.4453 90)
		(property "Reference" "R313"
			(at 0 0 90)
			(layer "F.SilkS")
			(hide yes)
			(effects
				(font
					(size 1.27 1.27)
				)
			)
		)
		(property "Value" ""
			(at 0 0 90)
			(layer "F.Fab")
			(effects
				(font
					(size 1.27 1.27)
				)
			)
		)
		(duplicate_pad_numbers_are_jumpers no)
		(fp_line
			(start 0.7874 -0.4064)
			(end 0.7874 0.4064)
			(stroke
				(width 0.1524)
				(type default)
			)
			(layer "F.SilkS")
		)
		(fp_line
			(start -0.7874 -0.4064)
			(end 0.7874 -0.4064)
			(stroke
				(width 0.1524)
				(type default)
			)
			(layer "F.SilkS")
		)
		(fp_line
			(start 0.7874 0.4064)
			(end -0.7874 0.4064)
			(stroke
				(width 0.1524)
				(type default)
			)
			(layer "F.SilkS")
		)
		(fp_line
			(start -0.7874 0.4064)
			(end -0.7874 -0.4064)
			(stroke
				(width 0.1524)
				(type default)
			)
			(layer "F.SilkS")
		)
		(fp_line
			(start -0.12065 -0.305054)
			(end -0.12065 -0.2794)
			(stroke
				(width 0.1)
				(type default)
			)
			(layer "F.Fab")
		)
		(fp_line
			(start -0.67945 -0.305054)
			(end -0.12065 -0.305054)
			(stroke
				(width 0.1)
				(type default)
			)
			(layer "F.Fab")
		)
		(fp_line
			(start 0.67945 -0.3048)
			(end 0.67945 0.3048)
			(stroke
				(width 0.1)
				(type default)
			)
			(layer "F.Fab")
		)
		(fp_line
			(start 0.12065 -0.3048)
			(end 0.67945 -0.3048)
			(stroke
				(width 0.1)
				(type default)
			)
			(layer "F.Fab")
		)
		(fp_line
			(start 0.12065 -0.2794)
			(end 0.12065 -0.3048)
			(stroke
				(width 0.1)
				(type default)
			)
			(layer "F.Fab")
		)
		(fp_line
			(start -0.12065 -0.2794)
			(end 0.12065 -0.2794)
			(stroke
				(width 0.1)
				(type default)
			)
			(layer "F.Fab")
		)
		(fp_line
			(start 0.120396 0.2794)
			(end -0.12065 0.2794)
			(stroke
				(width 0.1)
				(type default)
			)
			(layer "F.Fab")
		)
		(fp_line
			(start -0.12065 0.2794)
			(end -0.12065 0.3048)
			(stroke
				(width 0.1)
				(type default)
			)
			(layer "F.Fab")
		)
		(fp_line
			(start 0.67945 0.3048)
			(end 0.120396 0.3048)
			(stroke
				(width 0.1)
				(type default)
			)
			(layer "F.Fab")
		)
		(fp_line
			(start 0.120396 0.3048)
			(end 0.120396 0.2794)
			(stroke
				(width 0.1)
				(type default)
			)
			(layer "F.Fab")
		)
		(fp_line
			(start -0.12065 0.3048)
			(end -0.67945 0.3048)
			(stroke
				(width 0.1)
				(type default)
			)
			(layer "F.Fab")
		)
		(fp_line
			(start -0.67945 0.3048)
			(end -0.67945 -0.305054)
			(stroke
				(width 0.1)
				(type default)
			)
			(layer "F.Fab")
		)
		(pad "1" smd circle
			(at -0.40005 0 90)
			(size 0 0)
			(layers "F.Cu" "F.Mask" "F.Paste")
			(net "RST_BMC_SELF_HW_D")
		)
		(pad "2" smd circle
			(at 0.40005 0 90)
			(size 0 0)
			(layers "F.Cu" "F.Mask" "F.Paste")
			(net "GND")
		)
	)
	(footprint ""
		(layer "F.Cu")
		(at 56.3372 -63.6524 90)
		(property "Reference" "R494"
			(at 0 0 90)
			(layer "F.SilkS")
			(hide yes)
			(effects
				(font
					(size 1.27 1.27)
				)
			)
		)
		(property "Value" ""
			(at 0 0 90)
			(layer "F.Fab")
			(effects
				(font
					(size 1.27 1.27)
				)
			)
		)
		(duplicate_pad_numbers_are_jumpers no)
		(fp_line
			(start 0.7874 -0.4064)
			(end 0.7874 0.4064)
			(stroke
				(width 0.1524)
				(type default)
			)
			(layer "F.SilkS")
		)
		(fp_line
			(start -0.7874 -0.4064)
			(end 0.7874 -0.4064)
			(stroke
				(width 0.1524)
				(type default)
			)
			(layer "F.SilkS")
		)
		(fp_line
			(start 0.7874 0.4064)
			(end -0.7874 0.4064)
			(stroke
				(width 0.1524)
				(type default)
			)
			(layer "F.SilkS")
		)
		(fp_line
			(start -0.7874 0.4064)
			(end -0.7874 -0.4064)
			(stroke
				(width 0.1524)
				(type default)
			)
			(layer "F.SilkS")
		)
		(fp_line
			(start -0.12065 -0.305054)
			(end -0.12065 -0.2794)
			(stroke
				(width 0.1)
				(type default)
			)
			(layer "F.Fab")
		)
		(fp_line
			(start -0.67945 -0.305054)
			(end -0.12065 -0.305054)
			(stroke
				(width 0.1)
				(type default)
			)
			(layer "F.Fab")
		)
		(fp_line
			(start 0.67945 -0.3048)
			(end 0.67945 0.3048)
			(stroke
				(width 0.1)
				(type default)
			)
			(layer "F.Fab")
		)
		(fp_line
			(start 0.12065 -0.3048)
			(end 0.67945 -0.3048)
			(stroke
				(width 0.1)
				(type default)
			)
			(layer "F.Fab")
		)
		(fp_line
			(start 0.12065 -0.2794)
			(end 0.12065 -0.3048)
			(stroke
				(width 0.1)
				(type default)
			)
			(layer "F.Fab")
		)
		(fp_line
			(start -0.12065 -0.2794)
			(end 0.12065 -0.2794)
			(stroke
				(width 0.1)
				(type default)
			)
			(layer "F.Fab")
		)
		(fp_line
			(start 0.120396 0.2794)
			(end -0.12065 0.2794)
			(stroke
				(width 0.1)
				(type default)
			)
			(layer "F.Fab")
		)
		(fp_line
			(start -0.12065 0.2794)
			(end -0.12065 0.3048)
			(stroke
				(width 0.1)
				(type default)
			)
			(layer "F.Fab")
		)
		(fp_line
			(start 0.67945 0.3048)
			(end 0.120396 0.3048)
			(stroke
				(width 0.1)
				(type default)
			)
			(layer "F.Fab")
		)
		(fp_line
			(start 0.120396 0.3048)
			(end 0.120396 0.2794)
			(stroke
				(width 0.1)
				(type default)
			)
			(layer "F.Fab")
		)
		(fp_line
			(start -0.12065 0.3048)
			(end -0.67945 0.3048)
			(stroke
				(width 0.1)
				(type default)
			)
			(layer "F.Fab")
		)
		(fp_line
			(start -0.67945 0.3048)
			(end -0.67945 -0.305054)
			(stroke
				(width 0.1)
				(type default)
			)
			(layer "F.Fab")
		)
		(pad "1" smd circle
			(at -0.40005 0 90)
			(size 0 0)
			(layers "F.Cu" "F.Mask" "F.Paste")
			(net "RST_BMC_SELF_HW_R1")
		)
		(pad "2" smd circle
			(at 0.40005 0 90)
			(size 0 0)
			(layers "F.Cu" "F.Mask" "F.Paste")
			(net "RST_BMC_SELF_HW")
		)
	)
	(footprint ""
		(layer "F.Cu")
		(at 56.7182 -30.861 90)
		(property "Reference" "R840"
			(at 0 0 90)
			(layer "F.SilkS")
			(hide yes)
			(effects
				(font
					(size 1.27 1.27)
				)
			)
		)
		(property "Value" ""
			(at 0 0 90)
			(layer "F.Fab")
			(effects
				(font
					(size 1.27 1.27)
				)
			)
		)
		(duplicate_pad_numbers_are_jumpers no)
		(fp_line
			(start 0.7874 -0.4064)
			(end 0.7874 0.4064)
			(stroke
				(width 0.1524)
				(type default)
			)
			(layer "F.SilkS")
		)
		(fp_line
			(start -0.7874 -0.4064)
			(end 0.7874 -0.4064)
			(stroke
				(width 0.1524)
				(type default)
			)
			(layer "F.SilkS")
		)
		(fp_line
			(start 0.7874 0.4064)
			(end -0.7874 0.4064)
			(stroke
				(width 0.1524)
				(type default)
			)
			(layer "F.SilkS")
		)
		(fp_line
			(start -0.7874 0.4064)
			(end -0.7874 -0.4064)
			(stroke
				(width 0.1524)
				(type default)
			)
			(layer "F.SilkS")
		)
		(fp_line
			(start -0.12065 -0.305054)
			(end -0.12065 -0.2794)
			(stroke
				(width 0.1)
				(type default)
			)
			(layer "F.Fab")
		)
		(fp_line
			(start -0.67945 -0.305054)
			(end -0.12065 -0.305054)
			(stroke
				(width 0.1)
				(type default)
			)
			(layer "F.Fab")
		)
		(fp_line
			(start 0.67945 -0.3048)
			(end 0.67945 0.3048)
			(stroke
				(width 0.1)
				(type default)
			)
			(layer "F.Fab")
		)
		(fp_line
			(start 0.12065 -0.3048)
			(end 0.67945 -0.3048)
			(stroke
				(width 0.1)
				(type default)
			)
			(layer "F.Fab")
		)
		(fp_line
			(start 0.12065 -0.2794)
			(end 0.12065 -0.3048)
			(stroke
				(width 0.1)
				(type default)
			)
			(layer "F.Fab")
		)
		(fp_line
			(start -0.12065 -0.2794)
			(end 0.12065 -0.2794)
			(stroke
				(width 0.1)
				(type default)
			)
			(layer "F.Fab")
		)
		(fp_line
			(start 0.120396 0.2794)
			(end -0.12065 0.2794)
			(stroke
				(width 0.1)
				(type default)
			)
			(layer "F.Fab")
		)
		(fp_line
			(start -0.12065 0.2794)
			(end -0.12065 0.3048)
			(stroke
				(width 0.1)
				(type default)
			)
			(layer "F.Fab")
		)
		(fp_line
			(start 0.67945 0.3048)
			(end 0.120396 0.3048)
			(stroke
				(width 0.1)
				(type default)
			)
			(layer "F.Fab")
		)
		(fp_line
			(start 0.120396 0.3048)
			(end 0.120396 0.2794)
			(stroke
				(width 0.1)
				(type default)
			)
			(layer "F.Fab")
		)
		(fp_line
			(start -0.12065 0.3048)
			(end -0.67945 0.3048)
			(stroke
				(width 0.1)
				(type default)
			)
			(layer "F.Fab")
		)
		(fp_line
			(start -0.67945 0.3048)
			(end -0.67945 -0.305054)
			(stroke
				(width 0.1)
				(type default)
			)
			(layer "F.Fab")
		)
		(pad "1" smd circle
			(at -0.40005 0 90)
			(size 0 0)
			(layers "F.Cu" "F.Mask" "F.Paste")
			(net "PWRGD_SYS_PWROK")
		)
		(pad "2" smd circle
			(at 0.40005 0 90)
			(size 0 0)
			(layers "F.Cu" "F.Mask" "F.Paste")
			(net "PWRGD_SYS_PWROK_BMC")
		)
	)
	(footprint ""
		(layer "F.Cu")
		(at 39.751 -34.036 -90)
		(property "Reference" "R214"
			(at 0 0 270)
			(layer "F.SilkS")
			(hide yes)
			(effects
				(font
					(size 1.27 1.27)
				)
			)
		)
		(property "Value" ""
			(at 0 0 270)
			(layer "F.Fab")
			(effects
				(font
					(size 1.27 1.27)
				)
			)
		)
		(duplicate_pad_numbers_are_jumpers no)
		(fp_line
			(start -0.7874 0.4064)
			(end -0.7874 -0.4064)
			(stroke
				(width 0.1524)
				(type default)
			)
			(layer "F.SilkS")
		)
		(fp_line
			(start 0.7874 0.4064)
			(end -0.7874 0.4064)
			(stroke
				(width 0.1524)
				(type default)
			)
			(layer "F.SilkS")
		)
		(fp_line
			(start -0.7874 -0.4064)
			(end 0.7874 -0.4064)
			(stroke
				(width 0.1524)
				(type default)
			)
			(layer "F.SilkS")
		)
		(fp_line
			(start 0.7874 -0.4064)
			(end 0.7874 0.4064)
			(stroke
				(width 0.1524)
				(type default)
			)
			(layer "F.SilkS")
		)
		(fp_line
			(start -0.67945 0.3048)
			(end -0.67945 -0.305054)
			(stroke
				(width 0.1)
				(type default)
			)
			(layer "F.Fab")
		)
		(fp_line
			(start -0.12065 0.3048)
			(end -0.67945 0.3048)
			(stroke
				(width 0.1)
				(type default)
			)
			(layer "F.Fab")
		)
		(fp_line
			(start 0.120396 0.3048)
			(end 0.120396 0.2794)
			(stroke
				(width 0.1)
				(type default)
			)
			(layer "F.Fab")
		)
		(fp_line
			(start 0.67945 0.3048)
			(end 0.120396 0.3048)
			(stroke
				(width 0.1)
				(type default)
			)
			(layer "F.Fab")
		)
		(fp_line
			(start -0.12065 0.2794)
			(end -0.12065 0.3048)
			(stroke
				(width 0.1)
				(type default)
			)
			(layer "F.Fab")
		)
		(fp_line
			(start 0.120396 0.2794)
			(end -0.12065 0.2794)
			(stroke
				(width 0.1)
				(type default)
			)
			(layer "F.Fab")
		)
		(fp_line
			(start -0.12065 -0.2794)
			(end 0.12065 -0.2794)
			(stroke
				(width 0.1)
				(type default)
			)
			(layer "F.Fab")
		)
		(fp_line
			(start 0.12065 -0.2794)
			(end 0.12065 -0.3048)
			(stroke
				(width 0.1)
				(type default)
			)
			(layer "F.Fab")
		)
		(fp_line
			(start 0.12065 -0.3048)
			(end 0.67945 -0.3048)
			(stroke
				(width 0.1)
				(type default)
			)
			(layer "F.Fab")
		)
		(fp_line
			(start 0.67945 -0.3048)
			(end 0.67945 0.3048)
			(stroke
				(width 0.1)
				(type default)
			)
			(layer "F.Fab")
		)
		(fp_line
			(start -0.67945 -0.305054)
			(end -0.12065 -0.305054)
			(stroke
				(width 0.1)
				(type default)
			)
			(layer "F.Fab")
		)
		(fp_line
			(start -0.12065 -0.305054)
			(end -0.12065 -0.2794)
			(stroke
				(width 0.1)
				(type default)
			)
			(layer "F.Fab")
		)
		(pad "1" smd circle
			(at -0.40005 0 270)
			(size 0 0)
			(layers "F.Cu" "F.Mask" "F.Paste")
			(net "P1V8_AUX")
		)
		(pad "2" smd circle
			(at 0.40005 0 270)
			(size 0 0)
			(layers "F.Cu" "F.Mask" "F.Paste")
			(net "P3V3_P1V8_SD2VDD")
		)
	)
	(footprint ""
		(layer "F.Cu")
		(at 53.12156 -62.2046 180)
		(property "Reference" "R678"
			(at 0 0 180)
			(layer "F.SilkS")
			(hide yes)
			(effects
				(font
					(size 1.27 1.27)
				)
			)
		)
		(property "Value" ""
			(at 0 0 180)
			(layer "F.Fab")
			(effects
				(font
					(size 1.27 1.27)
				)
			)
		)
		(duplicate_pad_numbers_are_jumpers no)
		(fp_line
			(start 0.7874 0.4064)
			(end -0.7874 0.4064)
			(stroke
				(width 0.1524)
				(type default)
			)
			(layer "F.SilkS")
		)
		(fp_line
			(start 0.7874 -0.4064)
			(end 0.7874 0.4064)
			(stroke
				(width 0.1524)
				(type default)
			)
			(layer "F.SilkS")
		)
		(fp_line
			(start -0.7874 0.4064)
			(end -0.7874 -0.4064)
			(stroke
				(width 0.1524)
				(type default)
			)
			(layer "F.SilkS")
		)
		(fp_line
			(start -0.7874 -0.4064)
			(end 0.7874 -0.4064)
			(stroke
				(width 0.1524)
				(type default)
			)
			(layer "F.SilkS")
		)
		(fp_line
			(start 0.67945 0.3048)
			(end 0.120396 0.3048)
			(stroke
				(width 0.1)
				(type default)
			)
			(layer "F.Fab")
		)
		(fp_line
			(start 0.67945 -0.3048)
			(end 0.67945 0.3048)
			(stroke
				(width 0.1)
				(type default)
			)
			(layer "F.Fab")
		)
		(fp_line
			(start 0.12065 -0.2794)
			(end 0.12065 -0.3048)
			(stroke
				(width 0.1)
				(type default)
			)
			(layer "F.Fab")
		)
		(fp_line
			(start 0.12065 -0.3048)
			(end 0.67945 -0.3048)
			(stroke
				(width 0.1)
				(type default)
			)
			(layer "F.Fab")
		)
		(fp_line
			(start 0.120396 0.3048)
			(end 0.120396 0.2794)
			(stroke
				(width 0.1)
				(type default)
			)
			(layer "F.Fab")
		)
		(fp_line
			(start 0.120396 0.2794)
			(end -0.12065 0.2794)
			(stroke
				(width 0.1)
				(type default)
			)
			(layer "F.Fab")
		)
		(fp_line
			(start -0.12065 0.3048)
			(end -0.67945 0.3048)
			(stroke
				(width 0.1)
				(type default)
			)
			(layer "F.Fab")
		)
		(fp_line
			(start -0.12065 0.2794)
			(end -0.12065 0.3048)
			(stroke
				(width 0.1)
				(type default)
			)
			(layer "F.Fab")
		)
		(fp_line
			(start -0.12065 -0.2794)
			(end 0.12065 -0.2794)
			(stroke
				(width 0.1)
				(type default)
			)
			(layer "F.Fab")
		)
		(fp_line
			(start -0.12065 -0.305054)
			(end -0.12065 -0.2794)
			(stroke
				(width 0.1)
				(type default)
			)
			(layer "F.Fab")
		)
		(fp_line
			(start -0.67945 0.3048)
			(end -0.67945 -0.305054)
			(stroke
				(width 0.1)
				(type default)
			)
			(layer "F.Fab")
		)
		(fp_line
			(start -0.67945 -0.305054)
			(end -0.12065 -0.305054)
			(stroke
				(width 0.1)
				(type default)
			)
			(layer "F.Fab")
		)
		(pad "1" smd circle
			(at -0.40005 0 180)
			(size 0 0)
			(layers "F.Cu" "F.Mask" "F.Paste")
			(net "SPI_BMC_CLK_R")
		)
		(pad "2" smd circle
			(at 0.40005 0 180)
			(size 0 0)
			(layers "F.Cu" "F.Mask" "F.Paste")
			(net "QSPI_2_PLD_CLK")
		)
	)
	(footprint ""
		(layer "F.Cu")
		(at 85.2932 -18.796)
		(property "Reference" "C199"
			(at 0 0 0)
			(layer "F.SilkS")
			(hide yes)
			(effects
				(font
					(size 1.27 1.27)
				)
			)
		)
		(property "Value" ""
			(at 0 0 0)
			(layer "F.Fab")
			(effects
				(font
					(size 1.27 1.27)
				)
			)
		)
		(duplicate_pad_numbers_are_jumpers no)
		(fp_line
			(start -0.7874 -0.4064)
			(end 0.7874 -0.4064)
			(stroke
				(width 0.1524)
				(type default)
			)
			(layer "F.SilkS")
		)
		(fp_line
			(start -0.7874 0.4064)
			(end -0.7874 -0.4064)
			(stroke
				(width 0.1524)
				(type default)
			)
			(layer "F.SilkS")
		)
		(fp_line
			(start 0.7874 -0.4064)
			(end 0.7874 0.4064)
			(stroke
				(width 0.1524)
				(type default)
			)
			(layer "F.SilkS")
		)
		(fp_line
			(start 0.7874 0.4064)
			(end -0.7874 0.4064)
			(stroke
				(width 0.1524)
				(type default)
			)
			(layer "F.SilkS")
		)
		(fp_line
			(start -0.67945 -0.305054)
			(end -0.12065 -0.305054)
			(stroke
				(width 0.1)
				(type default)
			)
			(layer "F.Fab")
		)
		(fp_line
			(start -0.67945 0.3048)
			(end -0.67945 -0.305054)
			(stroke
				(width 0.1)
				(type default)
			)
			(layer "F.Fab")
		)
		(fp_line
			(start -0.12065 -0.305054)
			(end -0.12065 -0.2794)
			(stroke
				(width 0.1)
				(type default)
			)
			(layer "F.Fab")
		)
		(fp_line
			(start -0.12065 -0.2794)
			(end 0.12065 -0.2794)
			(stroke
				(width 0.1)
				(type default)
			)
			(layer "F.Fab")
		)
		(fp_line
			(start -0.12065 0.2794)
			(end -0.12065 0.3048)
			(stroke
				(width 0.1)
				(type default)
			)
			(layer "F.Fab")
		)
		(fp_line
			(start -0.12065 0.3048)
			(end -0.67945 0.3048)
			(stroke
				(width 0.1)
				(type default)
			)
			(layer "F.Fab")
		)
		(fp_line
			(start 0.120396 0.2794)
			(end -0.12065 0.2794)
			(stroke
				(width 0.1)
				(type default)
			)
			(layer "F.Fab")
		)
		(fp_line
			(start 0.120396 0.3048)
			(end 0.120396 0.2794)
			(stroke
				(width 0.1)
				(type default)
			)
			(layer "F.Fab")
		)
		(fp_line
			(start 0.12065 -0.3048)
			(end 0.67945 -0.3048)
			(stroke
				(width 0.1)
				(type default)
			)
			(layer "F.Fab")
		)
		(fp_line
			(start 0.12065 -0.2794)
			(end 0.12065 -0.3048)
			(stroke
				(width 0.1)
				(type default)
			)
			(layer "F.Fab")
		)
		(fp_line
			(start 0.67945 -0.3048)
			(end 0.67945 0.3048)
			(stroke
				(width 0.1)
				(type default)
			)
			(layer "F.Fab")
		)
		(fp_line
			(start 0.67945 0.3048)
			(end 0.120396 0.3048)
			(stroke
				(width 0.1)
				(type default)
			)
			(layer "F.Fab")
		)
		(pad "1" smd circle
			(at -0.40005 0)
			(size 0 0)
			(layers "F.Cu" "F.Mask" "F.Paste")
			(net "REAR_ID_RST_BTN_N")
		)
		(pad "2" smd circle
			(at 0.40005 0)
			(size 0 0)
			(layers "F.Cu" "F.Mask" "F.Paste")
			(net "GND")
		)
	)
	(footprint ""
		(layer "F.Cu")
		(at 55.184548 -34.637726 -90)
		(property "Reference" "R582"
			(at 0 0 270)
			(layer "F.SilkS")
			(hide yes)
			(effects
				(font
					(size 1.27 1.27)
				)
			)
		)
		(property "Value" ""
			(at 0 0 270)
			(layer "F.Fab")
			(effects
				(font
					(size 1.27 1.27)
				)
			)
		)
		(duplicate_pad_numbers_are_jumpers no)
		(fp_line
			(start -0.7874 0.4064)
			(end -0.7874 -0.4064)
			(stroke
				(width 0.1524)
				(type default)
			)
			(layer "F.SilkS")
		)
		(fp_line
			(start 0.7874 0.4064)
			(end -0.7874 0.4064)
			(stroke
				(width 0.1524)
				(type default)
			)
			(layer "F.SilkS")
		)
		(fp_line
			(start -0.7874 -0.4064)
			(end 0.7874 -0.4064)
			(stroke
				(width 0.1524)
				(type default)
			)
			(layer "F.SilkS")
		)
		(fp_line
			(start 0.7874 -0.4064)
			(end 0.7874 0.4064)
			(stroke
				(width 0.1524)
				(type default)
			)
			(layer "F.SilkS")
		)
		(fp_line
			(start -0.67945 0.3048)
			(end -0.67945 -0.305054)
			(stroke
				(width 0.1)
				(type default)
			)
			(layer "F.Fab")
		)
		(fp_line
			(start -0.12065 0.3048)
			(end -0.67945 0.3048)
			(stroke
				(width 0.1)
				(type default)
			)
			(layer "F.Fab")
		)
		(fp_line
			(start 0.120396 0.3048)
			(end 0.120396 0.2794)
			(stroke
				(width 0.1)
				(type default)
			)
			(layer "F.Fab")
		)
		(fp_line
			(start 0.67945 0.3048)
			(end 0.120396 0.3048)
			(stroke
				(width 0.1)
				(type default)
			)
			(layer "F.Fab")
		)
		(fp_line
			(start -0.12065 0.2794)
			(end -0.12065 0.3048)
			(stroke
				(width 0.1)
				(type default)
			)
			(layer "F.Fab")
		)
		(fp_line
			(start 0.120396 0.2794)
			(end -0.12065 0.2794)
			(stroke
				(width 0.1)
				(type default)
			)
			(layer "F.Fab")
		)
		(fp_line
			(start -0.12065 -0.2794)
			(end 0.12065 -0.2794)
			(stroke
				(width 0.1)
				(type default)
			)
			(layer "F.Fab")
		)
		(fp_line
			(start 0.12065 -0.2794)
			(end 0.12065 -0.3048)
			(stroke
				(width 0.1)
				(type default)
			)
			(layer "F.Fab")
		)
		(fp_line
			(start 0.12065 -0.3048)
			(end 0.67945 -0.3048)
			(stroke
				(width 0.1)
				(type default)
			)
			(layer "F.Fab")
		)
		(fp_line
			(start 0.67945 -0.3048)
			(end 0.67945 0.3048)
			(stroke
				(width 0.1)
				(type default)
			)
			(layer "F.Fab")
		)
		(fp_line
			(start -0.67945 -0.305054)
			(end -0.12065 -0.305054)
			(stroke
				(width 0.1)
				(type default)
			)
			(layer "F.Fab")
		)
		(fp_line
			(start -0.12065 -0.305054)
			(end -0.12065 -0.2794)
			(stroke
				(width 0.1)
				(type default)
			)
			(layer "F.Fab")
		)
		(pad "1" smd circle
			(at -0.40005 0 270)
			(size 0 0)
			(layers "F.Cu" "F.Mask" "F.Paste")
			(net "SMB_BMC_MM9_R_SDA")
		)
		(pad "2" smd circle
			(at 0.40005 0 270)
			(size 0 0)
			(layers "F.Cu" "F.Mask" "F.Paste")
			(net "SMB_BMC_MM9_SDA")
		)
	)
	(footprint ""
		(layer "F.Cu")
		(at 61.51753 -34.637726 90)
		(property "Reference" "R118"
			(at 0 0 90)
			(layer "F.SilkS")
			(hide yes)
			(effects
				(font
					(size 1.27 1.27)
				)
			)
		)
		(property "Value" ""
			(at 0 0 90)
			(layer "F.Fab")
			(effects
				(font
					(size 1.27 1.27)
				)
			)
		)
		(duplicate_pad_numbers_are_jumpers no)
		(fp_line
			(start 0.7874 -0.4064)
			(end 0.7874 0.4064)
			(stroke
				(width 0.1524)
				(type default)
			)
			(layer "F.SilkS")
		)
		(fp_line
			(start -0.7874 -0.4064)
			(end 0.7874 -0.4064)
			(stroke
				(width 0.1524)
				(type default)
			)
			(layer "F.SilkS")
		)
		(fp_line
			(start 0.7874 0.4064)
			(end -0.7874 0.4064)
			(stroke
				(width 0.1524)
				(type default)
			)
			(layer "F.SilkS")
		)
		(fp_line
			(start -0.7874 0.4064)
			(end -0.7874 -0.4064)
			(stroke
				(width 0.1524)
				(type default)
			)
			(layer "F.SilkS")
		)
		(fp_line
			(start -0.12065 -0.305054)
			(end -0.12065 -0.2794)
			(stroke
				(width 0.1)
				(type default)
			)
			(layer "F.Fab")
		)
		(fp_line
			(start -0.67945 -0.305054)
			(end -0.12065 -0.305054)
			(stroke
				(width 0.1)
				(type default)
			)
			(layer "F.Fab")
		)
		(fp_line
			(start 0.67945 -0.3048)
			(end 0.67945 0.3048)
			(stroke
				(width 0.1)
				(type default)
			)
			(layer "F.Fab")
		)
		(fp_line
			(start 0.12065 -0.3048)
			(end 0.67945 -0.3048)
			(stroke
				(width 0.1)
				(type default)
			)
			(layer "F.Fab")
		)
		(fp_line
			(start 0.12065 -0.2794)
			(end 0.12065 -0.3048)
			(stroke
				(width 0.1)
				(type default)
			)
			(layer "F.Fab")
		)
		(fp_line
			(start -0.12065 -0.2794)
			(end 0.12065 -0.2794)
			(stroke
				(width 0.1)
				(type default)
			)
			(layer "F.Fab")
		)
		(fp_line
			(start 0.120396 0.2794)
			(end -0.12065 0.2794)
			(stroke
				(width 0.1)
				(type default)
			)
			(layer "F.Fab")
		)
		(fp_line
			(start -0.12065 0.2794)
			(end -0.12065 0.3048)
			(stroke
				(width 0.1)
				(type default)
			)
			(layer "F.Fab")
		)
		(fp_line
			(start 0.67945 0.3048)
			(end 0.120396 0.3048)
			(stroke
				(width 0.1)
				(type default)
			)
			(layer "F.Fab")
		)
		(fp_line
			(start 0.120396 0.3048)
			(end 0.120396 0.2794)
			(stroke
				(width 0.1)
				(type default)
			)
			(layer "F.Fab")
		)
		(fp_line
			(start -0.12065 0.3048)
			(end -0.67945 0.3048)
			(stroke
				(width 0.1)
				(type default)
			)
			(layer "F.Fab")
		)
		(fp_line
			(start -0.67945 0.3048)
			(end -0.67945 -0.305054)
			(stroke
				(width 0.1)
				(type default)
			)
			(layer "F.Fab")
		)
		(pad "1" smd circle
			(at -0.40005 0 90)
			(size 0 0)
			(layers "F.Cu" "F.Mask" "F.Paste")
			(net "GND")
		)
		(pad "2" smd circle
			(at 0.40005 0 90)
			(size 0 0)
			(layers "F.Cu" "F.Mask" "F.Paste")
			(net "RST_PLTRST_N")
		)
	)
	(footprint ""
		(layer "F.Cu")
		(at 95.911416 -15.895574 90)
		(property "Reference" "J23"
			(at -1.163574 2.794254 90)
			(unlocked yes)
			(layer "F.SilkS")
			(effects
				(font
					(size 0.7874 0.5842)
					(thickness 0.1524)
				)
				(justify left)
			)
		)
		(property "Value" ""
			(at 0 0 90)
			(layer "F.Fab")
			(effects
				(font
					(size 1.27 1.27)
				)
			)
		)
		(duplicate_pad_numbers_are_jumpers no)
		(fp_line
			(start 1.2192 -2.1082)
			(end 1.2192 -0.804672)
			(stroke
				(width 0.1524)
				(type default)
			)
			(layer "F.SilkS")
		)
		(fp_line
			(start -1.2192 -2.1082)
			(end 1.2192 -2.1082)
			(stroke
				(width 0.1524)
				(type default)
			)
			(layer "F.SilkS")
		)
		(fp_line
			(start 1.2192 0.821944)
			(end 1.2192 2.1082)
			(stroke
				(width 0.1524)
				(type default)
			)
			(layer "F.SilkS")
		)
		(fp_line
			(start 1.2192 2.1082)
			(end -1.2192 2.1082)
			(stroke
				(width 0.1524)
				(type default)
			)
			(layer "F.SilkS")
		)
		(fp_line
			(start -1.2192 2.1082)
			(end -1.2192 -2.1082)
			(stroke
				(width 0.1524)
				(type default)
			)
			(layer "F.SilkS")
		)
		(pad "" np_thru_hole circle
			(at -2.8829 -1.27)
			(size 1.0414 1.0414)
			(drill 1.0414)
			(layers "*.Cu" "*.Mask")
			(clearance 0.381)
			(thermal_gap 0.381)
		)
		(pad "" np_thru_hole circle
			(at -2.8829 1.27)
			(size 1.0414 1.0414)
			(drill 1.0414)
			(layers "*.Cu" "*.Mask")
			(clearance 0.381)
			(thermal_gap 0.381)
		)
		(pad "" np_thru_hole circle
			(at 3.4671 -1.27)
			(size 1.0414 1.0414)
			(drill 1.0414)
			(layers "*.Cu" "*.Mask")
			(clearance 0.381)
			(thermal_gap 0.381)
		)
		(pad "" np_thru_hole circle
			(at 3.4671 1.27)
			(size 1.0414 1.0414)
			(drill 1.0414)
			(layers "*.Cu" "*.Mask")
			(clearance 0.381)
			(thermal_gap 0.381)
		)
		(pad "1" smd rect
			(at 0.8255 -0.249936)
			(size 0.3048 0.508)
			(layers "F.Cu" "F.Mask" "F.Paste")
			(net "85_10INCH_IN4_DP")
		)
		(pad "2" smd rect
			(at 0.8255 0.249936)
			(size 0.3048 0.508)
			(layers "F.Cu" "F.Mask" "F.Paste")
			(net "85_10INCH_IN4_DN")
		)
		(pad "3" smd circle
			(at 0 0 90)
			(size 0 0)
			(layers "F.Cu" "F.Mask" "F.Paste")
			(net "GND_P1")
		)
		(zone
			(layer "F.Cu")
			(hatch none 0.5)
			(connect_pads
				(clearance 0)
			)
			(min_thickness 0.25)
			(keepout
				(tracks not_allowed)
				(vias allowed)
				(pads allowed)
				(copperpour not_allowed)
				(footprints allowed)
			)
			(placement
				(enabled no)
				(sheetname "")
			)
			(fill
				(thermal_gap 0.5)
				(thermal_bridge_width 0.5)
				(island_removal_mode 0)
			)
			(polygon
				(pts
					(xy 95.362776 -17.013174) (xy 95.45828 -17.013174) (xy 95.45828 -16.416274) (xy 95.86468 -16.416274)
					(xy 95.86468 -17.013174) (xy 95.958152 -17.013174) (xy 95.958152 -16.416274) (xy 96.364552 -16.416274)
					(xy 96.364552 -17.013174) (xy 96.460056 -17.013174) (xy 96.460056 -16.314674) (xy 95.362776 -16.314674)
				)
			)
		)
		(zone
			(layers "F.Cu" "B.Cu" "In1.Cu" "In2.Cu" "In3.Cu" "In4.Cu" "In5.Cu" "In6.Cu"
				"In7.Cu" "In8.Cu" "In9.Cu" "In10.Cu"
			)
			(hatch none 0.5)
			(connect_pads
				(clearance 0)
			)
			(min_thickness 0.25)
			(keepout
				(tracks not_allowed)
				(vias allowed)
				(pads allowed)
				(copperpour not_allowed)
				(footprints allowed)
			)
			(placement
				(enabled no)
				(sheetname "")
			)
			(fill
				(thermal_gap 0.5)
				(thermal_bridge_width 0.5)
				(island_removal_mode 0)
			)
			(polygon
				(pts
					(arc
						(start 95.568516 -19.362674)
						(mid 93.714316 -19.362674)
						(end 95.568516 -19.362674)
					)
				)
			)
		)
		(zone
			(layers "F.Cu" "B.Cu" "In1.Cu" "In2.Cu" "In3.Cu" "In4.Cu" "In5.Cu" "In6.Cu"
				"In7.Cu" "In8.Cu" "In9.Cu" "In10.Cu"
			)
			(hatch none 0.5)
			(connect_pads
				(clearance 0)
			)
			(min_thickness 0.25)
			(keepout
				(tracks not_allowed)
				(vias allowed)
				(pads allowed)
				(copperpour not_allowed)
				(footprints allowed)
			)
			(placement
				(enabled no)
				(sheetname "")
			)
			(fill
				(thermal_gap 0.5)
				(thermal_bridge_width 0.5)
				(island_removal_mode 0)
			)
			(polygon
				(pts
					(arc
						(start 95.568516 -13.012674)
						(mid 93.714316 -13.012674)
						(end 95.568516 -13.012674)
					)
				)
			)
		)
		(zone
			(layers "F.Cu" "B.Cu" "In1.Cu" "In2.Cu" "In3.Cu" "In4.Cu" "In5.Cu" "In6.Cu"
				"In7.Cu" "In8.Cu" "In9.Cu" "In10.Cu"
			)
			(hatch none 0.5)
			(connect_pads
				(clearance 0)
			)
			(min_thickness 0.25)
			(keepout
				(tracks not_allowed)
				(vias allowed)
				(pads allowed)
				(copperpour not_allowed)
				(footprints allowed)
			)
			(placement
				(enabled no)
				(sheetname "")
			)
			(fill
				(thermal_gap 0.5)
				(thermal_bridge_width 0.5)
				(island_removal_mode 0)
			)
			(polygon
				(pts
					(arc
						(start 98.108516 -19.362674)
						(mid 96.254316 -19.362674)
						(end 98.108516 -19.362674)
					)
				)
			)
		)
		(zone
			(layers "F.Cu" "B.Cu" "In1.Cu" "In2.Cu" "In3.Cu" "In4.Cu" "In5.Cu" "In6.Cu"
				"In7.Cu" "In8.Cu" "In9.Cu" "In10.Cu"
			)
			(hatch none 0.5)
			(connect_pads
				(clearance 0)
			)
			(min_thickness 0.25)
			(keepout
				(tracks not_allowed)
				(vias allowed)
				(pads allowed)
				(copperpour not_allowed)
				(footprints allowed)
			)
			(placement
				(enabled no)
				(sheetname "")
			)
			(fill
				(thermal_gap 0.5)
				(thermal_bridge_width 0.5)
				(island_removal_mode 0)
			)
			(polygon
				(pts
					(arc
						(start 98.108516 -13.012674)
						(mid 96.254316 -13.012674)
						(end 98.108516 -13.012674)
					)
				)
			)
		)
	)
	(footprint ""
		(layer "F.Cu")
		(at 68.072 -11.43)
		(property "Reference" "U57"
			(at -0.463042 -1.674876 0)
			(unlocked yes)
			(layer "F.SilkS")
			(effects
				(font
					(size 0.7874 0.5842)
					(thickness 0.1524)
				)
				(justify left)
			)
		)
		(property "Value" ""
			(at 0 0 0)
			(layer "F.Fab")
			(effects
				(font
					(size 1.27 1.27)
				)
			)
		)
		(duplicate_pad_numbers_are_jumpers no)
		(fp_line
			(start -1.4986 -1.100074)
			(end 1.4986 -1.100074)
			(stroke
				(width 0.1524)
				(type default)
			)
			(layer "F.SilkS")
		)
		(fp_line
			(start -1.4986 1.100074)
			(end -1.4986 -1.100074)
			(stroke
				(width 0.1524)
				(type default)
			)
			(layer "F.SilkS")
		)
		(fp_line
			(start 1.4986 -1.100074)
			(end 1.4986 1.100074)
			(stroke
				(width 0.1524)
				(type default)
			)
			(layer "F.SilkS")
		)
		(fp_line
			(start 1.4986 1.100074)
			(end -1.4986 1.100074)
			(stroke
				(width 0.1524)
				(type default)
			)
			(layer "F.SilkS")
		)
		(fp_poly
			(pts
				(xy -2.20472 -0.338328) (xy -2.20472 -0.963168) (xy -1.651 -0.635)
			)
			(stroke
				(width 0)
				(type default)
			)
			(fill yes)
			(layer "F.SilkS")
		)
		(fp_line
			(start -0.67437 -1.100074)
			(end 0.67437 -1.100074)
			(stroke
				(width 0.1)
				(type default)
			)
			(layer "F.Fab")
		)
		(fp_line
			(start -0.67437 1.100074)
			(end -0.67437 -1.100074)
			(stroke
				(width 0.1)
				(type default)
			)
			(layer "F.Fab")
		)
		(fp_line
			(start 0.67437 -1.100074)
			(end 0.67437 1.100074)
			(stroke
				(width 0.1)
				(type default)
			)
			(layer "F.Fab")
		)
		(fp_line
			(start 0.67437 1.100074)
			(end -0.67437 1.100074)
			(stroke
				(width 0.1)
				(type default)
			)
			(layer "F.Fab")
		)
		(fp_poly
			(pts
				(xy -2.20472 -0.338328) (xy -2.20472 -0.963168) (xy -1.651 -0.635)
			)
			(stroke
				(width 0)
				(type default)
			)
			(fill yes)
			(layer "F.Fab")
		)
		(pad "1" smd rect
			(at -0.889 -0.649986)
			(size 1.016 0.381)
			(layers "F.Cu" "F.Mask" "F.Paste")
			(net "NC_U57_P1")
		)
		(pad "2" smd rect
			(at -0.889 0)
			(size 1.016 0.381)
			(layers "F.Cu" "F.Mask" "F.Paste")
			(net "REAR_AC_PWR_BMC_BTN_N")
		)
		(pad "3" smd rect
			(at -0.889 0.649986)
			(size 1.016 0.381)
			(layers "F.Cu" "F.Mask" "F.Paste")
			(net "GND")
		)
		(pad "4" smd rect
			(at 0.889 0.649986)
			(size 1.016 0.381)
			(layers "F.Cu" "F.Mask" "F.Paste")
			(net "AC_PWR_BMC_BTN_N")
		)
		(pad "5" smd rect
			(at 0.889 -0.649986)
			(size 1.016 0.381)
			(layers "F.Cu" "F.Mask" "F.Paste")
			(net "P3V3_AUX")
		)
	)
	(footprint ""
		(layer "F.Cu")
		(at 72.39 -19.685 90)
		(property "Reference" "R854"
			(at 0 0 90)
			(layer "F.SilkS")
			(hide yes)
			(effects
				(font
					(size 1.27 1.27)
				)
			)
		)
		(property "Value" ""
			(at 0 0 90)
			(layer "F.Fab")
			(effects
				(font
					(size 1.27 1.27)
				)
			)
		)
		(duplicate_pad_numbers_are_jumpers no)
		(fp_line
			(start 0.7874 -0.4064)
			(end 0.7874 0.4064)
			(stroke
				(width 0.1524)
				(type default)
			)
			(layer "F.SilkS")
		)
		(fp_line
			(start -0.7874 -0.4064)
			(end 0.7874 -0.4064)
			(stroke
				(width 0.1524)
				(type default)
			)
			(layer "F.SilkS")
		)
		(fp_line
			(start 0.7874 0.4064)
			(end -0.7874 0.4064)
			(stroke
				(width 0.1524)
				(type default)
			)
			(layer "F.SilkS")
		)
		(fp_line
			(start -0.7874 0.4064)
			(end -0.7874 -0.4064)
			(stroke
				(width 0.1524)
				(type default)
			)
			(layer "F.SilkS")
		)
		(fp_line
			(start -0.12065 -0.305054)
			(end -0.12065 -0.2794)
			(stroke
				(width 0.1)
				(type default)
			)
			(layer "F.Fab")
		)
		(fp_line
			(start -0.67945 -0.305054)
			(end -0.12065 -0.305054)
			(stroke
				(width 0.1)
				(type default)
			)
			(layer "F.Fab")
		)
		(fp_line
			(start 0.67945 -0.3048)
			(end 0.67945 0.3048)
			(stroke
				(width 0.1)
				(type default)
			)
			(layer "F.Fab")
		)
		(fp_line
			(start 0.12065 -0.3048)
			(end 0.67945 -0.3048)
			(stroke
				(width 0.1)
				(type default)
			)
			(layer "F.Fab")
		)
		(fp_line
			(start 0.12065 -0.2794)
			(end 0.12065 -0.3048)
			(stroke
				(width 0.1)
				(type default)
			)
			(layer "F.Fab")
		)
		(fp_line
			(start -0.12065 -0.2794)
			(end 0.12065 -0.2794)
			(stroke
				(width 0.1)
				(type default)
			)
			(layer "F.Fab")
		)
		(fp_line
			(start 0.120396 0.2794)
			(end -0.12065 0.2794)
			(stroke
				(width 0.1)
				(type default)
			)
			(layer "F.Fab")
		)
		(fp_line
			(start -0.12065 0.2794)
			(end -0.12065 0.3048)
			(stroke
				(width 0.1)
				(type default)
			)
			(layer "F.Fab")
		)
		(fp_line
			(start 0.67945 0.3048)
			(end 0.120396 0.3048)
			(stroke
				(width 0.1)
				(type default)
			)
			(layer "F.Fab")
		)
		(fp_line
			(start 0.120396 0.3048)
			(end 0.120396 0.2794)
			(stroke
				(width 0.1)
				(type default)
			)
			(layer "F.Fab")
		)
		(fp_line
			(start -0.12065 0.3048)
			(end -0.67945 0.3048)
			(stroke
				(width 0.1)
				(type default)
			)
			(layer "F.Fab")
		)
		(fp_line
			(start -0.67945 0.3048)
			(end -0.67945 -0.305054)
			(stroke
				(width 0.1)
				(type default)
			)
			(layer "F.Fab")
		)
		(pad "1" smd circle
			(at -0.40005 0 90)
			(size 0 0)
			(layers "F.Cu" "F.Mask" "F.Paste")
			(net "P1V8_AUX")
		)
		(pad "2" smd circle
			(at 0.40005 0 90)
			(size 0 0)
			(layers "F.Cu" "F.Mask" "F.Paste")
			(net "FM_BOARD_BMC_REV_ID2")
		)
	)
	(footprint ""
		(layer "F.Cu")
		(at 39.9415 -47.587916 180)
		(property "Reference" "R137"
			(at 0 0 180)
			(layer "F.SilkS")
			(hide yes)
			(effects
				(font
					(size 1.27 1.27)
				)
			)
		)
		(property "Value" ""
			(at 0 0 180)
			(layer "F.Fab")
			(effects
				(font
					(size 1.27 1.27)
				)
			)
		)
		(duplicate_pad_numbers_are_jumpers no)
		(fp_line
			(start 0.7874 0.4064)
			(end -0.7874 0.4064)
			(stroke
				(width 0.1524)
				(type default)
			)
			(layer "F.SilkS")
		)
		(fp_line
			(start 0.7874 -0.4064)
			(end 0.7874 0.4064)
			(stroke
				(width 0.1524)
				(type default)
			)
			(layer "F.SilkS")
		)
		(fp_line
			(start -0.7874 0.4064)
			(end -0.7874 -0.4064)
			(stroke
				(width 0.1524)
				(type default)
			)
			(layer "F.SilkS")
		)
		(fp_line
			(start -0.7874 -0.4064)
			(end 0.7874 -0.4064)
			(stroke
				(width 0.1524)
				(type default)
			)
			(layer "F.SilkS")
		)
		(fp_line
			(start 0.67945 0.3048)
			(end 0.120396 0.3048)
			(stroke
				(width 0.1)
				(type default)
			)
			(layer "F.Fab")
		)
		(fp_line
			(start 0.67945 -0.3048)
			(end 0.67945 0.3048)
			(stroke
				(width 0.1)
				(type default)
			)
			(layer "F.Fab")
		)
		(fp_line
			(start 0.12065 -0.2794)
			(end 0.12065 -0.3048)
			(stroke
				(width 0.1)
				(type default)
			)
			(layer "F.Fab")
		)
		(fp_line
			(start 0.12065 -0.3048)
			(end 0.67945 -0.3048)
			(stroke
				(width 0.1)
				(type default)
			)
			(layer "F.Fab")
		)
		(fp_line
			(start 0.120396 0.3048)
			(end 0.120396 0.2794)
			(stroke
				(width 0.1)
				(type default)
			)
			(layer "F.Fab")
		)
		(fp_line
			(start 0.120396 0.2794)
			(end -0.12065 0.2794)
			(stroke
				(width 0.1)
				(type default)
			)
			(layer "F.Fab")
		)
		(fp_line
			(start -0.12065 0.3048)
			(end -0.67945 0.3048)
			(stroke
				(width 0.1)
				(type default)
			)
			(layer "F.Fab")
		)
		(fp_line
			(start -0.12065 0.2794)
			(end -0.12065 0.3048)
			(stroke
				(width 0.1)
				(type default)
			)
			(layer "F.Fab")
		)
		(fp_line
			(start -0.12065 -0.2794)
			(end 0.12065 -0.2794)
			(stroke
				(width 0.1)
				(type default)
			)
			(layer "F.Fab")
		)
		(fp_line
			(start -0.12065 -0.305054)
			(end -0.12065 -0.2794)
			(stroke
				(width 0.1)
				(type default)
			)
			(layer "F.Fab")
		)
		(fp_line
			(start -0.67945 0.3048)
			(end -0.67945 -0.305054)
			(stroke
				(width 0.1)
				(type default)
			)
			(layer "F.Fab")
		)
		(fp_line
			(start -0.67945 -0.305054)
			(end -0.12065 -0.305054)
			(stroke
				(width 0.1)
				(type default)
			)
			(layer "F.Fab")
		)
		(pad "1" smd circle
			(at -0.40005 0 180)
			(size 0 0)
			(layers "F.Cu" "F.Mask" "F.Paste")
			(net "SMB_BMC_MM12_R_SCL")
		)
		(pad "2" smd circle
			(at 0.40005 0 180)
			(size 0 0)
			(layers "F.Cu" "F.Mask" "F.Paste")
			(net "SMB_BMC_MM12_SCL")
		)
	)
	(footprint ""
		(layer "F.Cu")
		(at 39.9288 -44.3992 180)
		(property "Reference" "R426"
			(at 0 0 180)
			(layer "F.SilkS")
			(hide yes)
			(effects
				(font
					(size 1.27 1.27)
				)
			)
		)
		(property "Value" ""
			(at 0 0 180)
			(layer "F.Fab")
			(effects
				(font
					(size 1.27 1.27)
				)
			)
		)
		(duplicate_pad_numbers_are_jumpers no)
		(fp_line
			(start 0.7874 0.4064)
			(end -0.7874 0.4064)
			(stroke
				(width 0.1524)
				(type default)
			)
			(layer "F.SilkS")
		)
		(fp_line
			(start 0.7874 -0.4064)
			(end 0.7874 0.4064)
			(stroke
				(width 0.1524)
				(type default)
			)
			(layer "F.SilkS")
		)
		(fp_line
			(start -0.7874 0.4064)
			(end -0.7874 -0.4064)
			(stroke
				(width 0.1524)
				(type default)
			)
			(layer "F.SilkS")
		)
		(fp_line
			(start -0.7874 -0.4064)
			(end 0.7874 -0.4064)
			(stroke
				(width 0.1524)
				(type default)
			)
			(layer "F.SilkS")
		)
		(fp_line
			(start 0.67945 0.3048)
			(end 0.120396 0.3048)
			(stroke
				(width 0.1)
				(type default)
			)
			(layer "F.Fab")
		)
		(fp_line
			(start 0.67945 -0.3048)
			(end 0.67945 0.3048)
			(stroke
				(width 0.1)
				(type default)
			)
			(layer "F.Fab")
		)
		(fp_line
			(start 0.12065 -0.2794)
			(end 0.12065 -0.3048)
			(stroke
				(width 0.1)
				(type default)
			)
			(layer "F.Fab")
		)
		(fp_line
			(start 0.12065 -0.3048)
			(end 0.67945 -0.3048)
			(stroke
				(width 0.1)
				(type default)
			)
			(layer "F.Fab")
		)
		(fp_line
			(start 0.120396 0.3048)
			(end 0.120396 0.2794)
			(stroke
				(width 0.1)
				(type default)
			)
			(layer "F.Fab")
		)
		(fp_line
			(start 0.120396 0.2794)
			(end -0.12065 0.2794)
			(stroke
				(width 0.1)
				(type default)
			)
			(layer "F.Fab")
		)
		(fp_line
			(start -0.12065 0.3048)
			(end -0.67945 0.3048)
			(stroke
				(width 0.1)
				(type default)
			)
			(layer "F.Fab")
		)
		(fp_line
			(start -0.12065 0.2794)
			(end -0.12065 0.3048)
			(stroke
				(width 0.1)
				(type default)
			)
			(layer "F.Fab")
		)
		(fp_line
			(start -0.12065 -0.2794)
			(end 0.12065 -0.2794)
			(stroke
				(width 0.1)
				(type default)
			)
			(layer "F.Fab")
		)
		(fp_line
			(start -0.12065 -0.305054)
			(end -0.12065 -0.2794)
			(stroke
				(width 0.1)
				(type default)
			)
			(layer "F.Fab")
		)
		(fp_line
			(start -0.67945 0.3048)
			(end -0.67945 -0.305054)
			(stroke
				(width 0.1)
				(type default)
			)
			(layer "F.Fab")
		)
		(fp_line
			(start -0.67945 -0.305054)
			(end -0.12065 -0.305054)
			(stroke
				(width 0.1)
				(type default)
			)
			(layer "F.Fab")
		)
		(pad "1" smd circle
			(at -0.40005 0 180)
			(size 0 0)
			(layers "F.Cu" "F.Mask" "F.Paste")
			(net "SMB_BMC_MM14_R_SDA")
		)
		(pad "2" smd circle
			(at 0.40005 0 180)
			(size 0 0)
			(layers "F.Cu" "F.Mask" "F.Paste")
			(net "SMB_BMC_MM14_SDA")
		)
	)
	(footprint ""
		(layer "F.Cu")
		(at 6.7818 -80.4926 180)
		(property "Reference" "C34"
			(at 0 0 180)
			(layer "F.SilkS")
			(hide yes)
			(effects
				(font
					(size 1.27 1.27)
				)
			)
		)
		(property "Value" ""
			(at 0 0 180)
			(layer "F.Fab")
			(effects
				(font
					(size 1.27 1.27)
				)
			)
		)
		(duplicate_pad_numbers_are_jumpers no)
		(fp_line
			(start 0.7874 0.4064)
			(end -0.7874 0.4064)
			(stroke
				(width 0.1524)
				(type default)
			)
			(layer "F.SilkS")
		)
		(fp_line
			(start 0.7874 -0.4064)
			(end 0.7874 0.4064)
			(stroke
				(width 0.1524)
				(type default)
			)
			(layer "F.SilkS")
		)
		(fp_line
			(start -0.7874 0.4064)
			(end -0.7874 -0.4064)
			(stroke
				(width 0.1524)
				(type default)
			)
			(layer "F.SilkS")
		)
		(fp_line
			(start -0.7874 -0.4064)
			(end 0.7874 -0.4064)
			(stroke
				(width 0.1524)
				(type default)
			)
			(layer "F.SilkS")
		)
		(fp_line
			(start 0.67945 0.3048)
			(end 0.120396 0.3048)
			(stroke
				(width 0.1)
				(type default)
			)
			(layer "F.Fab")
		)
		(fp_line
			(start 0.67945 -0.3048)
			(end 0.67945 0.3048)
			(stroke
				(width 0.1)
				(type default)
			)
			(layer "F.Fab")
		)
		(fp_line
			(start 0.12065 -0.2794)
			(end 0.12065 -0.3048)
			(stroke
				(width 0.1)
				(type default)
			)
			(layer "F.Fab")
		)
		(fp_line
			(start 0.12065 -0.3048)
			(end 0.67945 -0.3048)
			(stroke
				(width 0.1)
				(type default)
			)
			(layer "F.Fab")
		)
		(fp_line
			(start 0.120396 0.3048)
			(end 0.120396 0.2794)
			(stroke
				(width 0.1)
				(type default)
			)
			(layer "F.Fab")
		)
		(fp_line
			(start 0.120396 0.2794)
			(end -0.12065 0.2794)
			(stroke
				(width 0.1)
				(type default)
			)
			(layer "F.Fab")
		)
		(fp_line
			(start -0.12065 0.3048)
			(end -0.67945 0.3048)
			(stroke
				(width 0.1)
				(type default)
			)
			(layer "F.Fab")
		)
		(fp_line
			(start -0.12065 0.2794)
			(end -0.12065 0.3048)
			(stroke
				(width 0.1)
				(type default)
			)
			(layer "F.Fab")
		)
		(fp_line
			(start -0.12065 -0.2794)
			(end 0.12065 -0.2794)
			(stroke
				(width 0.1)
				(type default)
			)
			(layer "F.Fab")
		)
		(fp_line
			(start -0.12065 -0.305054)
			(end -0.12065 -0.2794)
			(stroke
				(width 0.1)
				(type default)
			)
			(layer "F.Fab")
		)
		(fp_line
			(start -0.67945 0.3048)
			(end -0.67945 -0.305054)
			(stroke
				(width 0.1)
				(type default)
			)
			(layer "F.Fab")
		)
		(fp_line
			(start -0.67945 -0.305054)
			(end -0.12065 -0.305054)
			(stroke
				(width 0.1)
				(type default)
			)
			(layer "F.Fab")
		)
		(pad "1" smd circle
			(at -0.40005 0 180)
			(size 0 0)
			(layers "F.Cu" "F.Mask" "F.Paste")
			(net "P3V3_AUX")
		)
		(pad "2" smd circle
			(at 0.40005 0 180)
			(size 0 0)
			(layers "F.Cu" "F.Mask" "F.Paste")
			(net "GND")
		)
	)
	(footprint ""
		(layer "F.Cu")
		(at 28.27401 -16.50365 90)
		(property "Reference" "L23"
			(at 0 0 90)
			(layer "F.SilkS")
			(hide yes)
			(effects
				(font
					(size 1.27 1.27)
				)
			)
		)
		(property "Value" ""
			(at 0 0 90)
			(layer "F.Fab")
			(effects
				(font
					(size 1.27 1.27)
				)
			)
		)
		(duplicate_pad_numbers_are_jumpers no)
		(fp_line
			(start 0.8636 -1.524)
			(end 0.8636 1.524)
			(stroke
				(width 0.1524)
				(type default)
			)
			(layer "F.SilkS")
		)
		(fp_line
			(start 0.38481 -1.524)
			(end 0.8636 -1.524)
			(stroke
				(width 0.1524)
				(type default)
			)
			(layer "F.SilkS")
		)
		(fp_line
			(start -0.8636 -1.524)
			(end -0.40767 -1.524)
			(stroke
				(width 0.1524)
				(type default)
			)
			(layer "F.SilkS")
		)
		(fp_line
			(start 0.8636 1.524)
			(end 0.49403 1.524)
			(stroke
				(width 0.1524)
				(type default)
			)
			(layer "F.SilkS")
		)
		(fp_line
			(start -0.45593 1.524)
			(end -0.8636 1.524)
			(stroke
				(width 0.1524)
				(type default)
			)
			(layer "F.SilkS")
		)
		(fp_line
			(start -0.8636 1.524)
			(end -0.8636 -1.524)
			(stroke
				(width 0.1524)
				(type default)
			)
			(layer "F.SilkS")
		)
		(fp_poly
			(pts
				(xy -1.1049 -1.06426) (xy -1.6129 -0.810514) (xy -1.6129 -1.31826)
			)
			(stroke
				(width 0)
				(type default)
			)
			(fill yes)
			(layer "F.SilkS")
		)
		(fp_line
			(start 0.700024 -1.100074)
			(end 0.700024 1.100074)
			(stroke
				(width 0.1)
				(type default)
			)
			(layer "F.Fab")
		)
		(fp_line
			(start -0.700024 -1.100074)
			(end 0.700024 -1.100074)
			(stroke
				(width 0.1)
				(type default)
			)
			(layer "F.Fab")
		)
		(fp_line
			(start 0.700024 1.100074)
			(end -0.700024 1.100074)
			(stroke
				(width 0.1)
				(type default)
			)
			(layer "F.Fab")
		)
		(fp_line
			(start -0.700024 1.100074)
			(end -0.700024 -1.100074)
			(stroke
				(width 0.1)
				(type default)
			)
			(layer "F.Fab")
		)
		(fp_poly
			(pts
				(xy -0.4572 -1.6256) (xy -0.7112 -2.1336) (xy -0.2032 -2.1336)
			)
			(stroke
				(width 0)
				(type default)
			)
			(fill yes)
			(layer "F.Fab")
		)
		(pad "1" smd rect
			(at -0.424942 -0.849884 90)
			(size 0.3556 0.9144)
			(layers "F.Cu" "F.Mask" "F.Paste")
			(net "USB_FPNL_DP")
		)
		(pad "2" smd rect
			(at -0.424942 0.849884 90)
			(size 0.3556 0.9144)
			(layers "F.Cu" "F.Mask" "F.Paste")
			(net "USB2_01_F_DP")
		)
		(pad "3" smd rect
			(at 0.424942 0.849884 90)
			(size 0.3556 0.9144)
			(layers "F.Cu" "F.Mask" "F.Paste")
			(net "USB2_01_F_DN")
		)
		(pad "4" smd rect
			(at 0.424942 -0.849884 90)
			(size 0.3556 0.9144)
			(layers "F.Cu" "F.Mask" "F.Paste")
			(net "USB_FPNL_DN")
		)
	)
	(footprint ""
		(layer "F.Cu")
		(at 44.704 -109.8804)
		(property "Reference" "R82"
			(at 0 0 0)
			(layer "F.SilkS")
			(hide yes)
			(effects
				(font
					(size 1.27 1.27)
				)
			)
		)
		(property "Value" ""
			(at 0 0 0)
			(layer "F.Fab")
			(effects
				(font
					(size 1.27 1.27)
				)
			)
		)
		(duplicate_pad_numbers_are_jumpers no)
		(fp_line
			(start -0.7874 -0.4064)
			(end 0.7874 -0.4064)
			(stroke
				(width 0.1524)
				(type default)
			)
			(layer "F.SilkS")
		)
		(fp_line
			(start -0.7874 0.4064)
			(end -0.7874 -0.4064)
			(stroke
				(width 0.1524)
				(type default)
			)
			(layer "F.SilkS")
		)
		(fp_line
			(start 0.7874 -0.4064)
			(end 0.7874 0.4064)
			(stroke
				(width 0.1524)
				(type default)
			)
			(layer "F.SilkS")
		)
		(fp_line
			(start 0.7874 0.4064)
			(end -0.7874 0.4064)
			(stroke
				(width 0.1524)
				(type default)
			)
			(layer "F.SilkS")
		)
		(fp_line
			(start -0.67945 -0.305054)
			(end -0.12065 -0.305054)
			(stroke
				(width 0.1)
				(type default)
			)
			(layer "F.Fab")
		)
		(fp_line
			(start -0.67945 0.3048)
			(end -0.67945 -0.305054)
			(stroke
				(width 0.1)
				(type default)
			)
			(layer "F.Fab")
		)
		(fp_line
			(start -0.12065 -0.305054)
			(end -0.12065 -0.2794)
			(stroke
				(width 0.1)
				(type default)
			)
			(layer "F.Fab")
		)
		(fp_line
			(start -0.12065 -0.2794)
			(end 0.12065 -0.2794)
			(stroke
				(width 0.1)
				(type default)
			)
			(layer "F.Fab")
		)
		(fp_line
			(start -0.12065 0.2794)
			(end -0.12065 0.3048)
			(stroke
				(width 0.1)
				(type default)
			)
			(layer "F.Fab")
		)
		(fp_line
			(start -0.12065 0.3048)
			(end -0.67945 0.3048)
			(stroke
				(width 0.1)
				(type default)
			)
			(layer "F.Fab")
		)
		(fp_line
			(start 0.120396 0.2794)
			(end -0.12065 0.2794)
			(stroke
				(width 0.1)
				(type default)
			)
			(layer "F.Fab")
		)
		(fp_line
			(start 0.120396 0.3048)
			(end 0.120396 0.2794)
			(stroke
				(width 0.1)
				(type default)
			)
			(layer "F.Fab")
		)
		(fp_line
			(start 0.12065 -0.3048)
			(end 0.67945 -0.3048)
			(stroke
				(width 0.1)
				(type default)
			)
			(layer "F.Fab")
		)
		(fp_line
			(start 0.12065 -0.2794)
			(end 0.12065 -0.3048)
			(stroke
				(width 0.1)
				(type default)
			)
			(layer "F.Fab")
		)
		(fp_line
			(start 0.67945 -0.3048)
			(end 0.67945 0.3048)
			(stroke
				(width 0.1)
				(type default)
			)
			(layer "F.Fab")
		)
		(fp_line
			(start 0.67945 0.3048)
			(end 0.120396 0.3048)
			(stroke
				(width 0.1)
				(type default)
			)
			(layer "F.Fab")
		)
		(pad "1" smd circle
			(at -0.40005 0)
			(size 0 0)
			(layers "F.Cu" "F.Mask" "F.Paste")
			(net "P3V3_AUX")
		)
		(pad "2" smd circle
			(at 0.40005 0)
			(size 0 0)
			(layers "F.Cu" "F.Mask" "F.Paste")
			(net "SGPIO_CLK_0")
		)
	)
	(footprint ""
		(layer "F.Cu")
		(at 101.2825 -65.6336 90)
		(property "Reference" "J9"
			(at -5.1816 -1.56083 90)
			(unlocked yes)
			(layer "F.SilkS")
			(effects
				(font
					(size 0.7874 0.5842)
					(thickness 0.1524)
				)
				(justify left)
			)
		)
		(property "Value" ""
			(at 0 0 90)
			(layer "F.Fab")
			(effects
				(font
					(size 1.27 1.27)
				)
			)
		)
		(duplicate_pad_numbers_are_jumpers no)
		(fp_line
			(start 1.2192 -2.1082)
			(end 1.2192 -0.462026)
			(stroke
				(width 0.1524)
				(type default)
			)
			(layer "F.SilkS")
		)
		(fp_line
			(start -1.2192 -2.1082)
			(end 1.2192 -2.1082)
			(stroke
				(width 0.1524)
				(type default)
			)
			(layer "F.SilkS")
		)
		(fp_line
			(start 1.2192 0.454406)
			(end 1.2192 2.1082)
			(stroke
				(width 0.1524)
				(type default)
			)
			(layer "F.SilkS")
		)
		(fp_line
			(start 1.2192 2.1082)
			(end -1.2192 2.1082)
			(stroke
				(width 0.1524)
				(type default)
			)
			(layer "F.SilkS")
		)
		(fp_line
			(start -1.2192 2.1082)
			(end -1.2192 -2.1082)
			(stroke
				(width 0.1524)
				(type default)
			)
			(layer "F.SilkS")
		)
		(pad "" np_thru_hole circle
			(at -2.8829 -1.27)
			(size 1.0414 1.0414)
			(drill 1.0414)
			(layers "*.Cu" "*.Mask")
			(clearance 0.381)
			(thermal_gap 0.381)
		)
		(pad "" np_thru_hole circle
			(at -2.8829 1.27)
			(size 1.0414 1.0414)
			(drill 1.0414)
			(layers "*.Cu" "*.Mask")
			(clearance 0.381)
			(thermal_gap 0.381)
		)
		(pad "" np_thru_hole circle
			(at 3.4671 -1.27)
			(size 1.0414 1.0414)
			(drill 1.0414)
			(layers "*.Cu" "*.Mask")
			(clearance 0.381)
			(thermal_gap 0.381)
		)
		(pad "" np_thru_hole circle
			(at 3.4671 1.27)
			(size 1.0414 1.0414)
			(drill 1.0414)
			(layers "*.Cu" "*.Mask")
			(clearance 0.381)
			(thermal_gap 0.381)
		)
		(pad "1" smd rect
			(at 0.8255 -0.249936)
			(size 0.3048 0.508)
			(layers "F.Cu" "F.Mask" "F.Paste")
			(net "85_5INCH_TOP_DN")
		)
		(pad "2" smd rect
			(at 0.8255 0.249936)
			(size 0.3048 0.508)
			(layers "F.Cu" "F.Mask" "F.Paste")
			(net "85_5INCH_TOP_DP")
		)
		(pad "3" smd circle
			(at 0 0 90)
			(size 0 0)
			(layers "F.Cu" "F.Mask" "F.Paste")
			(net "GND_P1")
		)
		(zone
			(layer "F.Cu")
			(hatch none 0.5)
			(connect_pads
				(clearance 0)
			)
			(min_thickness 0.25)
			(keepout
				(tracks not_allowed)
				(vias allowed)
				(pads allowed)
				(copperpour not_allowed)
				(footprints allowed)
			)
			(placement
				(enabled no)
				(sheetname "")
			)
			(fill
				(thermal_gap 0.5)
				(thermal_bridge_width 0.5)
				(island_removal_mode 0)
			)
			(polygon
				(pts
					(xy 100.73386 -66.7512) (xy 100.829364 -66.7512) (xy 100.829364 -66.1543) (xy 101.235764 -66.1543)
					(xy 101.235764 -66.7512) (xy 101.329236 -66.7512) (xy 101.329236 -66.1543) (xy 101.735636 -66.1543)
					(xy 101.735636 -66.7512) (xy 101.83114 -66.7512) (xy 101.83114 -66.0527) (xy 100.73386 -66.0527)
				)
			)
		)
		(zone
			(layers "F.Cu" "B.Cu" "In1.Cu" "In2.Cu" "In3.Cu" "In4.Cu" "In5.Cu" "In6.Cu"
				"In7.Cu" "In8.Cu" "In9.Cu" "In10.Cu"
			)
			(hatch none 0.5)
			(connect_pads
				(clearance 0)
			)
			(min_thickness 0.25)
			(keepout
				(tracks not_allowed)
				(vias allowed)
				(pads allowed)
				(copperpour not_allowed)
				(footprints allowed)
			)
			(placement
				(enabled no)
				(sheetname "")
			)
			(fill
				(thermal_gap 0.5)
				(thermal_bridge_width 0.5)
				(island_removal_mode 0)
			)
			(polygon
				(pts
					(arc
						(start 100.9396 -69.1007)
						(mid 99.0854 -69.1007)
						(end 100.9396 -69.1007)
					)
				)
			)
		)
		(zone
			(layers "F.Cu" "B.Cu" "In1.Cu" "In2.Cu" "In3.Cu" "In4.Cu" "In5.Cu" "In6.Cu"
				"In7.Cu" "In8.Cu" "In9.Cu" "In10.Cu"
			)
			(hatch none 0.5)
			(connect_pads
				(clearance 0)
			)
			(min_thickness 0.25)
			(keepout
				(tracks not_allowed)
				(vias allowed)
				(pads allowed)
				(copperpour not_allowed)
				(footprints allowed)
			)
			(placement
				(enabled no)
				(sheetname "")
			)
			(fill
				(thermal_gap 0.5)
				(thermal_bridge_width 0.5)
				(island_removal_mode 0)
			)
			(polygon
				(pts
					(arc
						(start 100.9396 -62.7507)
						(mid 99.0854 -62.7507)
						(end 100.9396 -62.7507)
					)
				)
			)
		)
		(zone
			(layers "F.Cu" "B.Cu" "In1.Cu" "In2.Cu" "In3.Cu" "In4.Cu" "In5.Cu" "In6.Cu"
				"In7.Cu" "In8.Cu" "In9.Cu" "In10.Cu"
			)
			(hatch none 0.5)
			(connect_pads
				(clearance 0)
			)
			(min_thickness 0.25)
			(keepout
				(tracks not_allowed)
				(vias allowed)
				(pads allowed)
				(copperpour not_allowed)
				(footprints allowed)
			)
			(placement
				(enabled no)
				(sheetname "")
			)
			(fill
				(thermal_gap 0.5)
				(thermal_bridge_width 0.5)
				(island_removal_mode 0)
			)
			(polygon
				(pts
					(arc
						(start 103.4796 -69.1007)
						(mid 101.6254 -69.1007)
						(end 103.4796 -69.1007)
					)
				)
			)
		)
		(zone
			(layers "F.Cu" "B.Cu" "In1.Cu" "In2.Cu" "In3.Cu" "In4.Cu" "In5.Cu" "In6.Cu"
				"In7.Cu" "In8.Cu" "In9.Cu" "In10.Cu"
			)
			(hatch none 0.5)
			(connect_pads
				(clearance 0)
			)
			(min_thickness 0.25)
			(keepout
				(tracks not_allowed)
				(vias allowed)
				(pads allowed)
				(copperpour not_allowed)
				(footprints allowed)
			)
			(placement
				(enabled no)
				(sheetname "")
			)
			(fill
				(thermal_gap 0.5)
				(thermal_bridge_width 0.5)
				(island_removal_mode 0)
			)
			(polygon
				(pts
					(arc
						(start 103.4796 -62.7507)
						(mid 101.6254 -62.7507)
						(end 103.4796 -62.7507)
					)
				)
			)
		)
	)
	(footprint ""
		(layer "F.Cu")
		(at 77.851 -79.121)
		(property "Reference" "C227"
			(at 0 0 0)
			(layer "F.SilkS")
			(hide yes)
			(effects
				(font
					(size 1.27 1.27)
				)
			)
		)
		(property "Value" ""
			(at 0 0 0)
			(layer "F.Fab")
			(effects
				(font
					(size 1.27 1.27)
				)
			)
		)
		(duplicate_pad_numbers_are_jumpers no)
		(fp_line
			(start -0.7874 -0.4064)
			(end 0.7874 -0.4064)
			(stroke
				(width 0.1524)
				(type default)
			)
			(layer "F.SilkS")
		)
		(fp_line
			(start -0.7874 0.4064)
			(end -0.7874 -0.4064)
			(stroke
				(width 0.1524)
				(type default)
			)
			(layer "F.SilkS")
		)
		(fp_line
			(start 0.7874 -0.4064)
			(end 0.7874 0.4064)
			(stroke
				(width 0.1524)
				(type default)
			)
			(layer "F.SilkS")
		)
		(fp_line
			(start 0.7874 0.4064)
			(end -0.7874 0.4064)
			(stroke
				(width 0.1524)
				(type default)
			)
			(layer "F.SilkS")
		)
		(fp_line
			(start -0.67945 -0.305054)
			(end -0.12065 -0.305054)
			(stroke
				(width 0.1)
				(type default)
			)
			(layer "F.Fab")
		)
		(fp_line
			(start -0.67945 0.3048)
			(end -0.67945 -0.305054)
			(stroke
				(width 0.1)
				(type default)
			)
			(layer "F.Fab")
		)
		(fp_line
			(start -0.12065 -0.305054)
			(end -0.12065 -0.2794)
			(stroke
				(width 0.1)
				(type default)
			)
			(layer "F.Fab")
		)
		(fp_line
			(start -0.12065 -0.2794)
			(end 0.12065 -0.2794)
			(stroke
				(width 0.1)
				(type default)
			)
			(layer "F.Fab")
		)
		(fp_line
			(start -0.12065 0.2794)
			(end -0.12065 0.3048)
			(stroke
				(width 0.1)
				(type default)
			)
			(layer "F.Fab")
		)
		(fp_line
			(start -0.12065 0.3048)
			(end -0.67945 0.3048)
			(stroke
				(width 0.1)
				(type default)
			)
			(layer "F.Fab")
		)
		(fp_line
			(start 0.120396 0.2794)
			(end -0.12065 0.2794)
			(stroke
				(width 0.1)
				(type default)
			)
			(layer "F.Fab")
		)
		(fp_line
			(start 0.120396 0.3048)
			(end 0.120396 0.2794)
			(stroke
				(width 0.1)
				(type default)
			)
			(layer "F.Fab")
		)
		(fp_line
			(start 0.12065 -0.3048)
			(end 0.67945 -0.3048)
			(stroke
				(width 0.1)
				(type default)
			)
			(layer "F.Fab")
		)
		(fp_line
			(start 0.12065 -0.2794)
			(end 0.12065 -0.3048)
			(stroke
				(width 0.1)
				(type default)
			)
			(layer "F.Fab")
		)
		(fp_line
			(start 0.67945 -0.3048)
			(end 0.67945 0.3048)
			(stroke
				(width 0.1)
				(type default)
			)
			(layer "F.Fab")
		)
		(fp_line
			(start 0.67945 0.3048)
			(end 0.120396 0.3048)
			(stroke
				(width 0.1)
				(type default)
			)
			(layer "F.Fab")
		)
		(pad "1" smd circle
			(at -0.40005 0)
			(size 0 0)
			(layers "F.Cu" "F.Mask" "F.Paste")
			(net "P3V3_LDO")
		)
		(pad "2" smd circle
			(at 0.40005 0)
			(size 0 0)
			(layers "F.Cu" "F.Mask" "F.Paste")
			(net "GND")
		)
	)
	(footprint ""
		(layer "F.Cu")
		(at 11.783568 -50.110898 -90)
		(property "Reference" "PR527"
			(at 0 0 270)
			(layer "F.SilkS")
			(hide yes)
			(effects
				(font
					(size 1.27 1.27)
				)
			)
		)
		(property "Value" ""
			(at 0 0 270)
			(layer "F.Fab")
			(effects
				(font
					(size 1.27 1.27)
				)
			)
		)
		(duplicate_pad_numbers_are_jumpers no)
		(fp_line
			(start -0.7874 0.4064)
			(end -0.7874 -0.4064)
			(stroke
				(width 0.1524)
				(type default)
			)
			(layer "F.SilkS")
		)
		(fp_line
			(start 0.7874 0.4064)
			(end -0.7874 0.4064)
			(stroke
				(width 0.1524)
				(type default)
			)
			(layer "F.SilkS")
		)
		(fp_line
			(start -0.7874 -0.4064)
			(end 0.7874 -0.4064)
			(stroke
				(width 0.1524)
				(type default)
			)
			(layer "F.SilkS")
		)
		(fp_line
			(start 0.7874 -0.4064)
			(end 0.7874 0.4064)
			(stroke
				(width 0.1524)
				(type default)
			)
			(layer "F.SilkS")
		)
		(fp_line
			(start -0.67945 0.3048)
			(end -0.67945 -0.305054)
			(stroke
				(width 0.1)
				(type default)
			)
			(layer "F.Fab")
		)
		(fp_line
			(start -0.12065 0.3048)
			(end -0.67945 0.3048)
			(stroke
				(width 0.1)
				(type default)
			)
			(layer "F.Fab")
		)
		(fp_line
			(start 0.120396 0.3048)
			(end 0.120396 0.2794)
			(stroke
				(width 0.1)
				(type default)
			)
			(layer "F.Fab")
		)
		(fp_line
			(start 0.67945 0.3048)
			(end 0.120396 0.3048)
			(stroke
				(width 0.1)
				(type default)
			)
			(layer "F.Fab")
		)
		(fp_line
			(start -0.12065 0.2794)
			(end -0.12065 0.3048)
			(stroke
				(width 0.1)
				(type default)
			)
			(layer "F.Fab")
		)
		(fp_line
			(start 0.120396 0.2794)
			(end -0.12065 0.2794)
			(stroke
				(width 0.1)
				(type default)
			)
			(layer "F.Fab")
		)
		(fp_line
			(start -0.12065 -0.2794)
			(end 0.12065 -0.2794)
			(stroke
				(width 0.1)
				(type default)
			)
			(layer "F.Fab")
		)
		(fp_line
			(start 0.12065 -0.2794)
			(end 0.12065 -0.3048)
			(stroke
				(width 0.1)
				(type default)
			)
			(layer "F.Fab")
		)
		(fp_line
			(start 0.12065 -0.3048)
			(end 0.67945 -0.3048)
			(stroke
				(width 0.1)
				(type default)
			)
			(layer "F.Fab")
		)
		(fp_line
			(start 0.67945 -0.3048)
			(end 0.67945 0.3048)
			(stroke
				(width 0.1)
				(type default)
			)
			(layer "F.Fab")
		)
		(fp_line
			(start -0.67945 -0.305054)
			(end -0.12065 -0.305054)
			(stroke
				(width 0.1)
				(type default)
			)
			(layer "F.Fab")
		)
		(fp_line
			(start -0.12065 -0.305054)
			(end -0.12065 -0.2794)
			(stroke
				(width 0.1)
				(type default)
			)
			(layer "F.Fab")
		)
		(pad "1" smd circle
			(at -0.40005 0 270)
			(size 0 0)
			(layers "F.Cu" "F.Mask" "F.Paste")
			(net "P5V_AUX_FB")
		)
		(pad "2" smd circle
			(at 0.40005 0 270)
			(size 0 0)
			(layers "F.Cu" "F.Mask" "F.Paste")
			(net "P5V_AUX")
		)
	)
	(footprint ""
		(layer "F.Cu")
		(at 83.77555 -70.458838 -90)
		(property "Reference" "PR274"
			(at 0 0 270)
			(layer "F.SilkS")
			(hide yes)
			(effects
				(font
					(size 1.27 1.27)
				)
			)
		)
		(property "Value" ""
			(at 0 0 270)
			(layer "F.Fab")
			(effects
				(font
					(size 1.27 1.27)
				)
			)
		)
		(duplicate_pad_numbers_are_jumpers no)
		(fp_line
			(start -0.7874 0.4064)
			(end -0.7874 -0.4064)
			(stroke
				(width 0.1524)
				(type default)
			)
			(layer "F.SilkS")
		)
		(fp_line
			(start 0.7874 0.4064)
			(end -0.7874 0.4064)
			(stroke
				(width 0.1524)
				(type default)
			)
			(layer "F.SilkS")
		)
		(fp_line
			(start -0.7874 -0.4064)
			(end 0.7874 -0.4064)
			(stroke
				(width 0.1524)
				(type default)
			)
			(layer "F.SilkS")
		)
		(fp_line
			(start 0.7874 -0.4064)
			(end 0.7874 0.4064)
			(stroke
				(width 0.1524)
				(type default)
			)
			(layer "F.SilkS")
		)
		(fp_line
			(start -0.67945 0.3048)
			(end -0.67945 -0.305054)
			(stroke
				(width 0.1)
				(type default)
			)
			(layer "F.Fab")
		)
		(fp_line
			(start -0.12065 0.3048)
			(end -0.67945 0.3048)
			(stroke
				(width 0.1)
				(type default)
			)
			(layer "F.Fab")
		)
		(fp_line
			(start 0.120396 0.3048)
			(end 0.120396 0.2794)
			(stroke
				(width 0.1)
				(type default)
			)
			(layer "F.Fab")
		)
		(fp_line
			(start 0.67945 0.3048)
			(end 0.120396 0.3048)
			(stroke
				(width 0.1)
				(type default)
			)
			(layer "F.Fab")
		)
		(fp_line
			(start -0.12065 0.2794)
			(end -0.12065 0.3048)
			(stroke
				(width 0.1)
				(type default)
			)
			(layer "F.Fab")
		)
		(fp_line
			(start 0.120396 0.2794)
			(end -0.12065 0.2794)
			(stroke
				(width 0.1)
				(type default)
			)
			(layer "F.Fab")
		)
		(fp_line
			(start -0.12065 -0.2794)
			(end 0.12065 -0.2794)
			(stroke
				(width 0.1)
				(type default)
			)
			(layer "F.Fab")
		)
		(fp_line
			(start 0.12065 -0.2794)
			(end 0.12065 -0.3048)
			(stroke
				(width 0.1)
				(type default)
			)
			(layer "F.Fab")
		)
		(fp_line
			(start 0.12065 -0.3048)
			(end 0.67945 -0.3048)
			(stroke
				(width 0.1)
				(type default)
			)
			(layer "F.Fab")
		)
		(fp_line
			(start 0.67945 -0.3048)
			(end 0.67945 0.3048)
			(stroke
				(width 0.1)
				(type default)
			)
			(layer "F.Fab")
		)
		(fp_line
			(start -0.67945 -0.305054)
			(end -0.12065 -0.305054)
			(stroke
				(width 0.1)
				(type default)
			)
			(layer "F.Fab")
		)
		(fp_line
			(start -0.12065 -0.305054)
			(end -0.12065 -0.2794)
			(stroke
				(width 0.1)
				(type default)
			)
			(layer "F.Fab")
		)
		(pad "1" smd circle
			(at -0.40005 0 270)
			(size 0 0)
			(layers "F.Cu" "F.Mask" "F.Paste")
			(net "P3V3_AUX")
		)
		(pad "2" smd circle
			(at 0.40005 0 270)
			(size 0 0)
			(layers "F.Cu" "F.Mask" "F.Paste")
			(net "PVCC1_AUX")
		)
	)
	(footprint ""
		(layer "F.Cu")
		(at 10.287 -91.059 -90)
		(property "Reference" "R514"
			(at 0 0 270)
			(layer "F.SilkS")
			(hide yes)
			(effects
				(font
					(size 1.27 1.27)
				)
			)
		)
		(property "Value" ""
			(at 0 0 270)
			(layer "F.Fab")
			(effects
				(font
					(size 1.27 1.27)
				)
			)
		)
		(duplicate_pad_numbers_are_jumpers no)
		(fp_line
			(start -0.7874 0.4064)
			(end -0.7874 -0.4064)
			(stroke
				(width 0.1524)
				(type default)
			)
			(layer "F.SilkS")
		)
		(fp_line
			(start 0.7874 0.4064)
			(end -0.7874 0.4064)
			(stroke
				(width 0.1524)
				(type default)
			)
			(layer "F.SilkS")
		)
		(fp_line
			(start -0.7874 -0.4064)
			(end 0.7874 -0.4064)
			(stroke
				(width 0.1524)
				(type default)
			)
			(layer "F.SilkS")
		)
		(fp_line
			(start 0.7874 -0.4064)
			(end 0.7874 0.4064)
			(stroke
				(width 0.1524)
				(type default)
			)
			(layer "F.SilkS")
		)
		(fp_line
			(start -0.67945 0.3048)
			(end -0.67945 -0.305054)
			(stroke
				(width 0.1)
				(type default)
			)
			(layer "F.Fab")
		)
		(fp_line
			(start -0.12065 0.3048)
			(end -0.67945 0.3048)
			(stroke
				(width 0.1)
				(type default)
			)
			(layer "F.Fab")
		)
		(fp_line
			(start 0.120396 0.3048)
			(end 0.120396 0.2794)
			(stroke
				(width 0.1)
				(type default)
			)
			(layer "F.Fab")
		)
		(fp_line
			(start 0.67945 0.3048)
			(end 0.120396 0.3048)
			(stroke
				(width 0.1)
				(type default)
			)
			(layer "F.Fab")
		)
		(fp_line
			(start -0.12065 0.2794)
			(end -0.12065 0.3048)
			(stroke
				(width 0.1)
				(type default)
			)
			(layer "F.Fab")
		)
		(fp_line
			(start 0.120396 0.2794)
			(end -0.12065 0.2794)
			(stroke
				(width 0.1)
				(type default)
			)
			(layer "F.Fab")
		)
		(fp_line
			(start -0.12065 -0.2794)
			(end 0.12065 -0.2794)
			(stroke
				(width 0.1)
				(type default)
			)
			(layer "F.Fab")
		)
		(fp_line
			(start 0.12065 -0.2794)
			(end 0.12065 -0.3048)
			(stroke
				(width 0.1)
				(type default)
			)
			(layer "F.Fab")
		)
		(fp_line
			(start 0.12065 -0.3048)
			(end 0.67945 -0.3048)
			(stroke
				(width 0.1)
				(type default)
			)
			(layer "F.Fab")
		)
		(fp_line
			(start 0.67945 -0.3048)
			(end 0.67945 0.3048)
			(stroke
				(width 0.1)
				(type default)
			)
			(layer "F.Fab")
		)
		(fp_line
			(start -0.67945 -0.305054)
			(end -0.12065 -0.305054)
			(stroke
				(width 0.1)
				(type default)
			)
			(layer "F.Fab")
		)
		(fp_line
			(start -0.12065 -0.305054)
			(end -0.12065 -0.2794)
			(stroke
				(width 0.1)
				(type default)
			)
			(layer "F.Fab")
		)
		(pad "1" smd circle
			(at -0.40005 0 270)
			(size 0 0)
			(layers "F.Cu" "F.Mask" "F.Paste")
			(net "JTAG_SCM_PLD_TCK")
		)
		(pad "2" smd circle
			(at 0.40005 0 270)
			(size 0 0)
			(layers "F.Cu" "F.Mask" "F.Paste")
			(net "JTAG_SCM_CONN_TCK")
		)
	)
	(footprint ""
		(layer "F.Cu")
		(at 43.848528 -30.867604 90)
		(property "Reference" "R62"
			(at 0 0 90)
			(layer "F.SilkS")
			(hide yes)
			(effects
				(font
					(size 1.27 1.27)
				)
			)
		)
		(property "Value" ""
			(at 0 0 90)
			(layer "F.Fab")
			(effects
				(font
					(size 1.27 1.27)
				)
			)
		)
		(duplicate_pad_numbers_are_jumpers no)
		(fp_line
			(start 0.7874 -0.4064)
			(end 0.7874 0.4064)
			(stroke
				(width 0.1524)
				(type default)
			)
			(layer "F.SilkS")
		)
		(fp_line
			(start -0.7874 -0.4064)
			(end 0.7874 -0.4064)
			(stroke
				(width 0.1524)
				(type default)
			)
			(layer "F.SilkS")
		)
		(fp_line
			(start 0.7874 0.4064)
			(end -0.7874 0.4064)
			(stroke
				(width 0.1524)
				(type default)
			)
			(layer "F.SilkS")
		)
		(fp_line
			(start -0.7874 0.4064)
			(end -0.7874 -0.4064)
			(stroke
				(width 0.1524)
				(type default)
			)
			(layer "F.SilkS")
		)
		(fp_line
			(start -0.12065 -0.305054)
			(end -0.12065 -0.2794)
			(stroke
				(width 0.1)
				(type default)
			)
			(layer "F.Fab")
		)
		(fp_line
			(start -0.67945 -0.305054)
			(end -0.12065 -0.305054)
			(stroke
				(width 0.1)
				(type default)
			)
			(layer "F.Fab")
		)
		(fp_line
			(start 0.67945 -0.3048)
			(end 0.67945 0.3048)
			(stroke
				(width 0.1)
				(type default)
			)
			(layer "F.Fab")
		)
		(fp_line
			(start 0.12065 -0.3048)
			(end 0.67945 -0.3048)
			(stroke
				(width 0.1)
				(type default)
			)
			(layer "F.Fab")
		)
		(fp_line
			(start 0.12065 -0.2794)
			(end 0.12065 -0.3048)
			(stroke
				(width 0.1)
				(type default)
			)
			(layer "F.Fab")
		)
		(fp_line
			(start -0.12065 -0.2794)
			(end 0.12065 -0.2794)
			(stroke
				(width 0.1)
				(type default)
			)
			(layer "F.Fab")
		)
		(fp_line
			(start 0.120396 0.2794)
			(end -0.12065 0.2794)
			(stroke
				(width 0.1)
				(type default)
			)
			(layer "F.Fab")
		)
		(fp_line
			(start -0.12065 0.2794)
			(end -0.12065 0.3048)
			(stroke
				(width 0.1)
				(type default)
			)
			(layer "F.Fab")
		)
		(fp_line
			(start 0.67945 0.3048)
			(end 0.120396 0.3048)
			(stroke
				(width 0.1)
				(type default)
			)
			(layer "F.Fab")
		)
		(fp_line
			(start 0.120396 0.3048)
			(end 0.120396 0.2794)
			(stroke
				(width 0.1)
				(type default)
			)
			(layer "F.Fab")
		)
		(fp_line
			(start -0.12065 0.3048)
			(end -0.67945 0.3048)
			(stroke
				(width 0.1)
				(type default)
			)
			(layer "F.Fab")
		)
		(fp_line
			(start -0.67945 0.3048)
			(end -0.67945 -0.305054)
			(stroke
				(width 0.1)
				(type default)
			)
			(layer "F.Fab")
		)
		(pad "1" smd circle
			(at -0.40005 0 90)
			(size 0 0)
			(layers "F.Cu" "F.Mask" "F.Paste")
			(net "P3V3_AUX")
		)
		(pad "2" smd circle
			(at 0.40005 0 90)
			(size 0 0)
			(layers "F.Cu" "F.Mask" "F.Paste")
			(net "FM_PCH_BMC_THERMTRIP_N")
		)
	)
	(footprint ""
		(layer "F.Cu")
		(at 46.863 -22.352 180)
		(property "Reference" "R378"
			(at 0 0 180)
			(layer "F.SilkS")
			(hide yes)
			(effects
				(font
					(size 1.27 1.27)
				)
			)
		)
		(property "Value" ""
			(at 0 0 180)
			(layer "F.Fab")
			(effects
				(font
					(size 1.27 1.27)
				)
			)
		)
		(duplicate_pad_numbers_are_jumpers no)
		(fp_line
			(start 0.7874 0.4064)
			(end -0.7874 0.4064)
			(stroke
				(width 0.1524)
				(type default)
			)
			(layer "F.SilkS")
		)
		(fp_line
			(start 0.7874 -0.4064)
			(end 0.7874 0.4064)
			(stroke
				(width 0.1524)
				(type default)
			)
			(layer "F.SilkS")
		)
		(fp_line
			(start -0.7874 0.4064)
			(end -0.7874 -0.4064)
			(stroke
				(width 0.1524)
				(type default)
			)
			(layer "F.SilkS")
		)
		(fp_line
			(start -0.7874 -0.4064)
			(end 0.7874 -0.4064)
			(stroke
				(width 0.1524)
				(type default)
			)
			(layer "F.SilkS")
		)
		(fp_line
			(start 0.67945 0.3048)
			(end 0.120396 0.3048)
			(stroke
				(width 0.1)
				(type default)
			)
			(layer "F.Fab")
		)
		(fp_line
			(start 0.67945 -0.3048)
			(end 0.67945 0.3048)
			(stroke
				(width 0.1)
				(type default)
			)
			(layer "F.Fab")
		)
		(fp_line
			(start 0.12065 -0.2794)
			(end 0.12065 -0.3048)
			(stroke
				(width 0.1)
				(type default)
			)
			(layer "F.Fab")
		)
		(fp_line
			(start 0.12065 -0.3048)
			(end 0.67945 -0.3048)
			(stroke
				(width 0.1)
				(type default)
			)
			(layer "F.Fab")
		)
		(fp_line
			(start 0.120396 0.3048)
			(end 0.120396 0.2794)
			(stroke
				(width 0.1)
				(type default)
			)
			(layer "F.Fab")
		)
		(fp_line
			(start 0.120396 0.2794)
			(end -0.12065 0.2794)
			(stroke
				(width 0.1)
				(type default)
			)
			(layer "F.Fab")
		)
		(fp_line
			(start -0.12065 0.3048)
			(end -0.67945 0.3048)
			(stroke
				(width 0.1)
				(type default)
			)
			(layer "F.Fab")
		)
		(fp_line
			(start -0.12065 0.2794)
			(end -0.12065 0.3048)
			(stroke
				(width 0.1)
				(type default)
			)
			(layer "F.Fab")
		)
		(fp_line
			(start -0.12065 -0.2794)
			(end 0.12065 -0.2794)
			(stroke
				(width 0.1)
				(type default)
			)
			(layer "F.Fab")
		)
		(fp_line
			(start -0.12065 -0.305054)
			(end -0.12065 -0.2794)
			(stroke
				(width 0.1)
				(type default)
			)
			(layer "F.Fab")
		)
		(fp_line
			(start -0.67945 0.3048)
			(end -0.67945 -0.305054)
			(stroke
				(width 0.1)
				(type default)
			)
			(layer "F.Fab")
		)
		(fp_line
			(start -0.67945 -0.305054)
			(end -0.12065 -0.305054)
			(stroke
				(width 0.1)
				(type default)
			)
			(layer "F.Fab")
		)
		(pad "1" smd circle
			(at -0.40005 0 180)
			(size 0 0)
			(layers "F.Cu" "F.Mask" "F.Paste")
			(net "USB_OC0_ILIM")
		)
		(pad "2" smd circle
			(at 0.40005 0 180)
			(size 0 0)
			(layers "F.Cu" "F.Mask" "F.Paste")
			(net "GND")
		)
	)
	(footprint ""
		(layer "F.Cu")
		(at 12.319 -92.456 180)
		(property "Reference" "R595"
			(at 0 0 180)
			(layer "F.SilkS")
			(hide yes)
			(effects
				(font
					(size 1.27 1.27)
				)
			)
		)
		(property "Value" ""
			(at 0 0 180)
			(layer "F.Fab")
			(effects
				(font
					(size 1.27 1.27)
				)
			)
		)
		(duplicate_pad_numbers_are_jumpers no)
		(fp_line
			(start 0.7874 0.4064)
			(end -0.7874 0.4064)
			(stroke
				(width 0.1524)
				(type default)
			)
			(layer "F.SilkS")
		)
		(fp_line
			(start 0.7874 -0.4064)
			(end 0.7874 0.4064)
			(stroke
				(width 0.1524)
				(type default)
			)
			(layer "F.SilkS")
		)
		(fp_line
			(start -0.7874 0.4064)
			(end -0.7874 -0.4064)
			(stroke
				(width 0.1524)
				(type default)
			)
			(layer "F.SilkS")
		)
		(fp_line
			(start -0.7874 -0.4064)
			(end 0.7874 -0.4064)
			(stroke
				(width 0.1524)
				(type default)
			)
			(layer "F.SilkS")
		)
		(fp_line
			(start 0.67945 0.3048)
			(end 0.120396 0.3048)
			(stroke
				(width 0.1)
				(type default)
			)
			(layer "F.Fab")
		)
		(fp_line
			(start 0.67945 -0.3048)
			(end 0.67945 0.3048)
			(stroke
				(width 0.1)
				(type default)
			)
			(layer "F.Fab")
		)
		(fp_line
			(start 0.12065 -0.2794)
			(end 0.12065 -0.3048)
			(stroke
				(width 0.1)
				(type default)
			)
			(layer "F.Fab")
		)
		(fp_line
			(start 0.12065 -0.3048)
			(end 0.67945 -0.3048)
			(stroke
				(width 0.1)
				(type default)
			)
			(layer "F.Fab")
		)
		(fp_line
			(start 0.120396 0.3048)
			(end 0.120396 0.2794)
			(stroke
				(width 0.1)
				(type default)
			)
			(layer "F.Fab")
		)
		(fp_line
			(start 0.120396 0.2794)
			(end -0.12065 0.2794)
			(stroke
				(width 0.1)
				(type default)
			)
			(layer "F.Fab")
		)
		(fp_line
			(start -0.12065 0.3048)
			(end -0.67945 0.3048)
			(stroke
				(width 0.1)
				(type default)
			)
			(layer "F.Fab")
		)
		(fp_line
			(start -0.12065 0.2794)
			(end -0.12065 0.3048)
			(stroke
				(width 0.1)
				(type default)
			)
			(layer "F.Fab")
		)
		(fp_line
			(start -0.12065 -0.2794)
			(end 0.12065 -0.2794)
			(stroke
				(width 0.1)
				(type default)
			)
			(layer "F.Fab")
		)
		(fp_line
			(start -0.12065 -0.305054)
			(end -0.12065 -0.2794)
			(stroke
				(width 0.1)
				(type default)
			)
			(layer "F.Fab")
		)
		(fp_line
			(start -0.67945 0.3048)
			(end -0.67945 -0.305054)
			(stroke
				(width 0.1)
				(type default)
			)
			(layer "F.Fab")
		)
		(fp_line
			(start -0.67945 -0.305054)
			(end -0.12065 -0.305054)
			(stroke
				(width 0.1)
				(type default)
			)
			(layer "F.Fab")
		)
		(pad "1" smd circle
			(at -0.40005 0 180)
			(size 0 0)
			(layers "F.Cu" "F.Mask" "F.Paste")
			(net "P3V3_AUX")
		)
		(pad "2" smd circle
			(at 0.40005 0 180)
			(size 0 0)
			(layers "F.Cu" "F.Mask" "F.Paste")
			(net "BMC_CPLD_GPIO_8")
		)
	)
	(footprint ""
		(layer "F.Cu")
		(at 72.25665 -94.871032 -90)
		(property "Reference" "R59"
			(at 0 0 270)
			(layer "F.SilkS")
			(hide yes)
			(effects
				(font
					(size 1.27 1.27)
				)
			)
		)
		(property "Value" ""
			(at 0 0 270)
			(layer "F.Fab")
			(effects
				(font
					(size 1.27 1.27)
				)
			)
		)
		(duplicate_pad_numbers_are_jumpers no)
		(fp_line
			(start -0.7874 0.4064)
			(end -0.7874 -0.4064)
			(stroke
				(width 0.1524)
				(type default)
			)
			(layer "F.SilkS")
		)
		(fp_line
			(start 0.7874 0.4064)
			(end -0.7874 0.4064)
			(stroke
				(width 0.1524)
				(type default)
			)
			(layer "F.SilkS")
		)
		(fp_line
			(start -0.7874 -0.4064)
			(end 0.7874 -0.4064)
			(stroke
				(width 0.1524)
				(type default)
			)
			(layer "F.SilkS")
		)
		(fp_line
			(start 0.7874 -0.4064)
			(end 0.7874 0.4064)
			(stroke
				(width 0.1524)
				(type default)
			)
			(layer "F.SilkS")
		)
		(fp_line
			(start -0.67945 0.3048)
			(end -0.67945 -0.305054)
			(stroke
				(width 0.1)
				(type default)
			)
			(layer "F.Fab")
		)
		(fp_line
			(start -0.12065 0.3048)
			(end -0.67945 0.3048)
			(stroke
				(width 0.1)
				(type default)
			)
			(layer "F.Fab")
		)
		(fp_line
			(start 0.120396 0.3048)
			(end 0.120396 0.2794)
			(stroke
				(width 0.1)
				(type default)
			)
			(layer "F.Fab")
		)
		(fp_line
			(start 0.67945 0.3048)
			(end 0.120396 0.3048)
			(stroke
				(width 0.1)
				(type default)
			)
			(layer "F.Fab")
		)
		(fp_line
			(start -0.12065 0.2794)
			(end -0.12065 0.3048)
			(stroke
				(width 0.1)
				(type default)
			)
			(layer "F.Fab")
		)
		(fp_line
			(start 0.120396 0.2794)
			(end -0.12065 0.2794)
			(stroke
				(width 0.1)
				(type default)
			)
			(layer "F.Fab")
		)
		(fp_line
			(start -0.12065 -0.2794)
			(end 0.12065 -0.2794)
			(stroke
				(width 0.1)
				(type default)
			)
			(layer "F.Fab")
		)
		(fp_line
			(start 0.12065 -0.2794)
			(end 0.12065 -0.3048)
			(stroke
				(width 0.1)
				(type default)
			)
			(layer "F.Fab")
		)
		(fp_line
			(start 0.12065 -0.3048)
			(end 0.67945 -0.3048)
			(stroke
				(width 0.1)
				(type default)
			)
			(layer "F.Fab")
		)
		(fp_line
			(start 0.67945 -0.3048)
			(end 0.67945 0.3048)
			(stroke
				(width 0.1)
				(type default)
			)
			(layer "F.Fab")
		)
		(fp_line
			(start -0.67945 -0.305054)
			(end -0.12065 -0.305054)
			(stroke
				(width 0.1)
				(type default)
			)
			(layer "F.Fab")
		)
		(fp_line
			(start -0.12065 -0.305054)
			(end -0.12065 -0.2794)
			(stroke
				(width 0.1)
				(type default)
			)
			(layer "F.Fab")
		)
		(pad "1" smd circle
			(at -0.40005 0 270)
			(size 0 0)
			(layers "F.Cu" "F.Mask" "F.Paste")
			(net "P3V3_AUX")
		)
		(pad "2" smd circle
			(at 0.40005 0 270)
			(size 0 0)
			(layers "F.Cu" "F.Mask" "F.Paste")
			(net "IRQ_TPM_SPI_N")
		)
	)
	(footprint ""
		(layer "F.Cu")
		(at 33.629092 -57.452768 -90)
		(property "Reference" "R393"
			(at 0 0 270)
			(layer "F.SilkS")
			(hide yes)
			(effects
				(font
					(size 1.27 1.27)
				)
			)
		)
		(property "Value" ""
			(at 0 0 270)
			(layer "F.Fab")
			(effects
				(font
					(size 1.27 1.27)
				)
			)
		)
		(duplicate_pad_numbers_are_jumpers no)
		(fp_line
			(start -0.7874 0.4064)
			(end -0.7874 -0.4064)
			(stroke
				(width 0.1524)
				(type default)
			)
			(layer "F.SilkS")
		)
		(fp_line
			(start 0.7874 0.4064)
			(end -0.7874 0.4064)
			(stroke
				(width 0.1524)
				(type default)
			)
			(layer "F.SilkS")
		)
		(fp_line
			(start -0.7874 -0.4064)
			(end 0.7874 -0.4064)
			(stroke
				(width 0.1524)
				(type default)
			)
			(layer "F.SilkS")
		)
		(fp_line
			(start 0.7874 -0.4064)
			(end 0.7874 0.4064)
			(stroke
				(width 0.1524)
				(type default)
			)
			(layer "F.SilkS")
		)
		(fp_line
			(start -0.67945 0.3048)
			(end -0.67945 -0.305054)
			(stroke
				(width 0.1)
				(type default)
			)
			(layer "F.Fab")
		)
		(fp_line
			(start -0.12065 0.3048)
			(end -0.67945 0.3048)
			(stroke
				(width 0.1)
				(type default)
			)
			(layer "F.Fab")
		)
		(fp_line
			(start 0.120396 0.3048)
			(end 0.120396 0.2794)
			(stroke
				(width 0.1)
				(type default)
			)
			(layer "F.Fab")
		)
		(fp_line
			(start 0.67945 0.3048)
			(end 0.120396 0.3048)
			(stroke
				(width 0.1)
				(type default)
			)
			(layer "F.Fab")
		)
		(fp_line
			(start -0.12065 0.2794)
			(end -0.12065 0.3048)
			(stroke
				(width 0.1)
				(type default)
			)
			(layer "F.Fab")
		)
		(fp_line
			(start 0.120396 0.2794)
			(end -0.12065 0.2794)
			(stroke
				(width 0.1)
				(type default)
			)
			(layer "F.Fab")
		)
		(fp_line
			(start -0.12065 -0.2794)
			(end 0.12065 -0.2794)
			(stroke
				(width 0.1)
				(type default)
			)
			(layer "F.Fab")
		)
		(fp_line
			(start 0.12065 -0.2794)
			(end 0.12065 -0.3048)
			(stroke
				(width 0.1)
				(type default)
			)
			(layer "F.Fab")
		)
		(fp_line
			(start 0.12065 -0.3048)
			(end 0.67945 -0.3048)
			(stroke
				(width 0.1)
				(type default)
			)
			(layer "F.Fab")
		)
		(fp_line
			(start 0.67945 -0.3048)
			(end 0.67945 0.3048)
			(stroke
				(width 0.1)
				(type default)
			)
			(layer "F.Fab")
		)
		(fp_line
			(start -0.67945 -0.305054)
			(end -0.12065 -0.305054)
			(stroke
				(width 0.1)
				(type default)
			)
			(layer "F.Fab")
		)
		(fp_line
			(start -0.12065 -0.305054)
			(end -0.12065 -0.2794)
			(stroke
				(width 0.1)
				(type default)
			)
			(layer "F.Fab")
		)
		(pad "1" smd circle
			(at -0.40005 0 270)
			(size 0 0)
			(layers "F.Cu" "F.Mask" "F.Paste")
			(net "EN_P1V8")
		)
		(pad "2" smd circle
			(at 0.40005 0 270)
			(size 0 0)
			(layers "F.Cu" "F.Mask" "F.Paste")
			(net "EN_P1V8_R")
		)
	)
	(footprint ""
		(layer "F.Cu")
		(at 12.7762 -66.2432 180)
		(property "Reference" "PR242"
			(at 0 0 180)
			(layer "F.SilkS")
			(hide yes)
			(effects
				(font
					(size 1.27 1.27)
				)
			)
		)
		(property "Value" ""
			(at 0 0 180)
			(layer "F.Fab")
			(effects
				(font
					(size 1.27 1.27)
				)
			)
		)
		(duplicate_pad_numbers_are_jumpers no)
		(fp_line
			(start 0.7874 0.4064)
			(end -0.7874 0.4064)
			(stroke
				(width 0.1524)
				(type default)
			)
			(layer "F.SilkS")
		)
		(fp_line
			(start 0.7874 -0.4064)
			(end 0.7874 0.4064)
			(stroke
				(width 0.1524)
				(type default)
			)
			(layer "F.SilkS")
		)
		(fp_line
			(start -0.7874 0.4064)
			(end -0.7874 -0.4064)
			(stroke
				(width 0.1524)
				(type default)
			)
			(layer "F.SilkS")
		)
		(fp_line
			(start -0.7874 -0.4064)
			(end 0.7874 -0.4064)
			(stroke
				(width 0.1524)
				(type default)
			)
			(layer "F.SilkS")
		)
		(fp_line
			(start 0.67945 0.3048)
			(end 0.120396 0.3048)
			(stroke
				(width 0.1)
				(type default)
			)
			(layer "F.Fab")
		)
		(fp_line
			(start 0.67945 -0.3048)
			(end 0.67945 0.3048)
			(stroke
				(width 0.1)
				(type default)
			)
			(layer "F.Fab")
		)
		(fp_line
			(start 0.12065 -0.2794)
			(end 0.12065 -0.3048)
			(stroke
				(width 0.1)
				(type default)
			)
			(layer "F.Fab")
		)
		(fp_line
			(start 0.12065 -0.3048)
			(end 0.67945 -0.3048)
			(stroke
				(width 0.1)
				(type default)
			)
			(layer "F.Fab")
		)
		(fp_line
			(start 0.120396 0.3048)
			(end 0.120396 0.2794)
			(stroke
				(width 0.1)
				(type default)
			)
			(layer "F.Fab")
		)
		(fp_line
			(start 0.120396 0.2794)
			(end -0.12065 0.2794)
			(stroke
				(width 0.1)
				(type default)
			)
			(layer "F.Fab")
		)
		(fp_line
			(start -0.12065 0.3048)
			(end -0.67945 0.3048)
			(stroke
				(width 0.1)
				(type default)
			)
			(layer "F.Fab")
		)
		(fp_line
			(start -0.12065 0.2794)
			(end -0.12065 0.3048)
			(stroke
				(width 0.1)
				(type default)
			)
			(layer "F.Fab")
		)
		(fp_line
			(start -0.12065 -0.2794)
			(end 0.12065 -0.2794)
			(stroke
				(width 0.1)
				(type default)
			)
			(layer "F.Fab")
		)
		(fp_line
			(start -0.12065 -0.305054)
			(end -0.12065 -0.2794)
			(stroke
				(width 0.1)
				(type default)
			)
			(layer "F.Fab")
		)
		(fp_line
			(start -0.67945 0.3048)
			(end -0.67945 -0.305054)
			(stroke
				(width 0.1)
				(type default)
			)
			(layer "F.Fab")
		)
		(fp_line
			(start -0.67945 -0.305054)
			(end -0.12065 -0.305054)
			(stroke
				(width 0.1)
				(type default)
			)
			(layer "F.Fab")
		)
		(pad "1" smd circle
			(at -0.40005 0 180)
			(size 0 0)
			(layers "F.Cu" "F.Mask" "F.Paste")
			(net "P3V3_AUX")
		)
		(pad "2" smd circle
			(at 0.40005 0 180)
			(size 0 0)
			(layers "F.Cu" "F.Mask" "F.Paste")
			(net "PWRGD_P3V3_AUX_R")
		)
	)
	(footprint ""
		(layer "F.Cu")
		(at 18.923 -69.977 -90)
		(property "Reference" "C235"
			(at 0 0 270)
			(layer "F.SilkS")
			(hide yes)
			(effects
				(font
					(size 1.27 1.27)
				)
			)
		)
		(property "Value" ""
			(at 0 0 270)
			(layer "F.Fab")
			(effects
				(font
					(size 1.27 1.27)
				)
			)
		)
		(duplicate_pad_numbers_are_jumpers no)
		(fp_line
			(start -0.7874 0.4064)
			(end -0.7874 -0.4064)
			(stroke
				(width 0.1524)
				(type default)
			)
			(layer "F.SilkS")
		)
		(fp_line
			(start 0.7874 0.4064)
			(end -0.7874 0.4064)
			(stroke
				(width 0.1524)
				(type default)
			)
			(layer "F.SilkS")
		)
		(fp_line
			(start -0.7874 -0.4064)
			(end 0.7874 -0.4064)
			(stroke
				(width 0.1524)
				(type default)
			)
			(layer "F.SilkS")
		)
		(fp_line
			(start 0.7874 -0.4064)
			(end 0.7874 0.4064)
			(stroke
				(width 0.1524)
				(type default)
			)
			(layer "F.SilkS")
		)
		(fp_line
			(start -0.67945 0.3048)
			(end -0.67945 -0.305054)
			(stroke
				(width 0.1)
				(type default)
			)
			(layer "F.Fab")
		)
		(fp_line
			(start -0.12065 0.3048)
			(end -0.67945 0.3048)
			(stroke
				(width 0.1)
				(type default)
			)
			(layer "F.Fab")
		)
		(fp_line
			(start 0.120396 0.3048)
			(end 0.120396 0.2794)
			(stroke
				(width 0.1)
				(type default)
			)
			(layer "F.Fab")
		)
		(fp_line
			(start 0.67945 0.3048)
			(end 0.120396 0.3048)
			(stroke
				(width 0.1)
				(type default)
			)
			(layer "F.Fab")
		)
		(fp_line
			(start -0.12065 0.2794)
			(end -0.12065 0.3048)
			(stroke
				(width 0.1)
				(type default)
			)
			(layer "F.Fab")
		)
		(fp_line
			(start 0.120396 0.2794)
			(end -0.12065 0.2794)
			(stroke
				(width 0.1)
				(type default)
			)
			(layer "F.Fab")
		)
		(fp_line
			(start -0.12065 -0.2794)
			(end 0.12065 -0.2794)
			(stroke
				(width 0.1)
				(type default)
			)
			(layer "F.Fab")
		)
		(fp_line
			(start 0.12065 -0.2794)
			(end 0.12065 -0.3048)
			(stroke
				(width 0.1)
				(type default)
			)
			(layer "F.Fab")
		)
		(fp_line
			(start 0.12065 -0.3048)
			(end 0.67945 -0.3048)
			(stroke
				(width 0.1)
				(type default)
			)
			(layer "F.Fab")
		)
		(fp_line
			(start 0.67945 -0.3048)
			(end 0.67945 0.3048)
			(stroke
				(width 0.1)
				(type default)
			)
			(layer "F.Fab")
		)
		(fp_line
			(start -0.67945 -0.305054)
			(end -0.12065 -0.305054)
			(stroke
				(width 0.1)
				(type default)
			)
			(layer "F.Fab")
		)
		(fp_line
			(start -0.12065 -0.305054)
			(end -0.12065 -0.2794)
			(stroke
				(width 0.1)
				(type default)
			)
			(layer "F.Fab")
		)
		(pad "1" smd circle
			(at -0.40005 0 270)
			(size 0 0)
			(layers "F.Cu" "F.Mask" "F.Paste")
			(net "P3V3_AUX")
		)
		(pad "2" smd circle
			(at 0.40005 0 270)
			(size 0 0)
			(layers "F.Cu" "F.Mask" "F.Paste")
			(net "GND")
		)
	)
	(footprint ""
		(layer "F.Cu")
		(at 41.0083 -109.474 -90)
		(property "Reference" "R78"
			(at 0 0 270)
			(layer "F.SilkS")
			(hide yes)
			(effects
				(font
					(size 1.27 1.27)
				)
			)
		)
		(property "Value" ""
			(at 0 0 270)
			(layer "F.Fab")
			(effects
				(font
					(size 1.27 1.27)
				)
			)
		)
		(duplicate_pad_numbers_are_jumpers no)
		(fp_line
			(start -0.7874 0.4064)
			(end -0.7874 -0.4064)
			(stroke
				(width 0.1524)
				(type default)
			)
			(layer "F.SilkS")
		)
		(fp_line
			(start 0.7874 0.4064)
			(end -0.7874 0.4064)
			(stroke
				(width 0.1524)
				(type default)
			)
			(layer "F.SilkS")
		)
		(fp_line
			(start -0.7874 -0.4064)
			(end 0.7874 -0.4064)
			(stroke
				(width 0.1524)
				(type default)
			)
			(layer "F.SilkS")
		)
		(fp_line
			(start 0.7874 -0.4064)
			(end 0.7874 0.4064)
			(stroke
				(width 0.1524)
				(type default)
			)
			(layer "F.SilkS")
		)
		(fp_line
			(start -0.67945 0.3048)
			(end -0.67945 -0.305054)
			(stroke
				(width 0.1)
				(type default)
			)
			(layer "F.Fab")
		)
		(fp_line
			(start -0.12065 0.3048)
			(end -0.67945 0.3048)
			(stroke
				(width 0.1)
				(type default)
			)
			(layer "F.Fab")
		)
		(fp_line
			(start 0.120396 0.3048)
			(end 0.120396 0.2794)
			(stroke
				(width 0.1)
				(type default)
			)
			(layer "F.Fab")
		)
		(fp_line
			(start 0.67945 0.3048)
			(end 0.120396 0.3048)
			(stroke
				(width 0.1)
				(type default)
			)
			(layer "F.Fab")
		)
		(fp_line
			(start -0.12065 0.2794)
			(end -0.12065 0.3048)
			(stroke
				(width 0.1)
				(type default)
			)
			(layer "F.Fab")
		)
		(fp_line
			(start 0.120396 0.2794)
			(end -0.12065 0.2794)
			(stroke
				(width 0.1)
				(type default)
			)
			(layer "F.Fab")
		)
		(fp_line
			(start -0.12065 -0.2794)
			(end 0.12065 -0.2794)
			(stroke
				(width 0.1)
				(type default)
			)
			(layer "F.Fab")
		)
		(fp_line
			(start 0.12065 -0.2794)
			(end 0.12065 -0.3048)
			(stroke
				(width 0.1)
				(type default)
			)
			(layer "F.Fab")
		)
		(fp_line
			(start 0.12065 -0.3048)
			(end 0.67945 -0.3048)
			(stroke
				(width 0.1)
				(type default)
			)
			(layer "F.Fab")
		)
		(fp_line
			(start 0.67945 -0.3048)
			(end 0.67945 0.3048)
			(stroke
				(width 0.1)
				(type default)
			)
			(layer "F.Fab")
		)
		(fp_line
			(start -0.67945 -0.305054)
			(end -0.12065 -0.305054)
			(stroke
				(width 0.1)
				(type default)
			)
			(layer "F.Fab")
		)
		(fp_line
			(start -0.12065 -0.305054)
			(end -0.12065 -0.2794)
			(stroke
				(width 0.1)
				(type default)
			)
			(layer "F.Fab")
		)
		(pad "1" smd circle
			(at -0.40005 0 270)
			(size 0 0)
			(layers "F.Cu" "F.Mask" "F.Paste")
			(net "P3V3_AUX")
		)
		(pad "2" smd circle
			(at 0.40005 0 270)
			(size 0 0)
			(layers "F.Cu" "F.Mask" "F.Paste")
			(net "SGPIO_DI_0")
		)
	)
	(footprint ""
		(layer "F.Cu")
		(at 23.1775 -105.918)
		(property "Reference" "R314"
			(at 0 0 0)
			(layer "F.SilkS")
			(hide yes)
			(effects
				(font
					(size 1.27 1.27)
				)
			)
		)
		(property "Value" ""
			(at 0 0 0)
			(layer "F.Fab")
			(effects
				(font
					(size 1.27 1.27)
				)
			)
		)
		(duplicate_pad_numbers_are_jumpers no)
		(fp_line
			(start -0.7874 -0.4064)
			(end 0.7874 -0.4064)
			(stroke
				(width 0.1524)
				(type default)
			)
			(layer "F.SilkS")
		)
		(fp_line
			(start -0.7874 0.4064)
			(end -0.7874 -0.4064)
			(stroke
				(width 0.1524)
				(type default)
			)
			(layer "F.SilkS")
		)
		(fp_line
			(start 0.7874 -0.4064)
			(end 0.7874 0.4064)
			(stroke
				(width 0.1524)
				(type default)
			)
			(layer "F.SilkS")
		)
		(fp_line
			(start 0.7874 0.4064)
			(end -0.7874 0.4064)
			(stroke
				(width 0.1524)
				(type default)
			)
			(layer "F.SilkS")
		)
		(fp_line
			(start -0.67945 -0.305054)
			(end -0.12065 -0.305054)
			(stroke
				(width 0.1)
				(type default)
			)
			(layer "F.Fab")
		)
		(fp_line
			(start -0.67945 0.3048)
			(end -0.67945 -0.305054)
			(stroke
				(width 0.1)
				(type default)
			)
			(layer "F.Fab")
		)
		(fp_line
			(start -0.12065 -0.305054)
			(end -0.12065 -0.2794)
			(stroke
				(width 0.1)
				(type default)
			)
			(layer "F.Fab")
		)
		(fp_line
			(start -0.12065 -0.2794)
			(end 0.12065 -0.2794)
			(stroke
				(width 0.1)
				(type default)
			)
			(layer "F.Fab")
		)
		(fp_line
			(start -0.12065 0.2794)
			(end -0.12065 0.3048)
			(stroke
				(width 0.1)
				(type default)
			)
			(layer "F.Fab")
		)
		(fp_line
			(start -0.12065 0.3048)
			(end -0.67945 0.3048)
			(stroke
				(width 0.1)
				(type default)
			)
			(layer "F.Fab")
		)
		(fp_line
			(start 0.120396 0.2794)
			(end -0.12065 0.2794)
			(stroke
				(width 0.1)
				(type default)
			)
			(layer "F.Fab")
		)
		(fp_line
			(start 0.120396 0.3048)
			(end 0.120396 0.2794)
			(stroke
				(width 0.1)
				(type default)
			)
			(layer "F.Fab")
		)
		(fp_line
			(start 0.12065 -0.3048)
			(end 0.67945 -0.3048)
			(stroke
				(width 0.1)
				(type default)
			)
			(layer "F.Fab")
		)
		(fp_line
			(start 0.12065 -0.2794)
			(end 0.12065 -0.3048)
			(stroke
				(width 0.1)
				(type default)
			)
			(layer "F.Fab")
		)
		(fp_line
			(start 0.67945 -0.3048)
			(end 0.67945 0.3048)
			(stroke
				(width 0.1)
				(type default)
			)
			(layer "F.Fab")
		)
		(fp_line
			(start 0.67945 0.3048)
			(end 0.120396 0.3048)
			(stroke
				(width 0.1)
				(type default)
			)
			(layer "F.Fab")
		)
		(pad "1" smd circle
			(at -0.40005 0)
			(size 0 0)
			(layers "F.Cu" "F.Mask" "F.Paste")
			(net "RST_BMC_SELF_HW_D_C")
		)
		(pad "2" smd circle
			(at 0.40005 0)
			(size 0 0)
			(layers "F.Cu" "F.Mask" "F.Paste")
			(net "GND")
		)
	)
	(footprint ""
		(layer "F.Cu")
		(at 42.3418 -26.2636)
		(property "Reference" "U28"
			(at 0.573278 -2.323846 0)
			(unlocked yes)
			(layer "F.SilkS")
			(effects
				(font
					(size 0.7874 0.5842)
					(thickness 0.1524)
				)
				(justify left)
			)
		)
		(property "Value" ""
			(at 0 0 0)
			(layer "F.Fab")
			(effects
				(font
					(size 1.27 1.27)
				)
			)
		)
		(duplicate_pad_numbers_are_jumpers no)
		(fp_line
			(start -2.032 -1.549908)
			(end 2.032 -1.549908)
			(stroke
				(width 0.1524)
				(type default)
			)
			(layer "F.SilkS")
		)
		(fp_line
			(start -2.032 1.549908)
			(end -2.032 -1.549908)
			(stroke
				(width 0.1524)
				(type default)
			)
			(layer "F.SilkS")
		)
		(fp_line
			(start 2.032 -1.549908)
			(end 2.032 1.549908)
			(stroke
				(width 0.1524)
				(type default)
			)
			(layer "F.SilkS")
		)
		(fp_line
			(start 2.032 1.549908)
			(end -2.032 1.549908)
			(stroke
				(width 0.1524)
				(type default)
			)
			(layer "F.SilkS")
		)
		(fp_poly
			(pts
				(xy -2.9464 -1.2192) (xy -2.9464 -0.7112) (xy -2.1844 -0.9652)
			)
			(stroke
				(width 0)
				(type default)
			)
			(fill yes)
			(layer "F.SilkS")
		)
		(fp_line
			(start -0.849884 -1.549908)
			(end -0.849884 1.549908)
			(stroke
				(width 0.1)
				(type default)
			)
			(layer "F.Fab")
		)
		(fp_line
			(start -0.849884 1.549908)
			(end 0.849884 1.549908)
			(stroke
				(width 0.1)
				(type default)
			)
			(layer "F.Fab")
		)
		(fp_line
			(start 0.849884 -1.549908)
			(end -0.849884 -1.549908)
			(stroke
				(width 0.1)
				(type default)
			)
			(layer "F.Fab")
		)
		(fp_line
			(start 0.849884 1.549908)
			(end 0.849884 -1.549908)
			(stroke
				(width 0.1)
				(type default)
			)
			(layer "F.Fab")
		)
		(fp_poly
			(pts
				(xy -2.9464 -1.2192) (xy -2.9464 -0.7112) (xy -2.1844 -0.9652)
			)
			(stroke
				(width 0)
				(type default)
			)
			(fill yes)
			(layer "F.Fab")
		)
		(pad "1" smd rect
			(at -1.225042 -0.94996 270)
			(size 0.4572 1.3208)
			(layers "F.Cu" "F.Mask" "F.Paste")
			(net "RMII_OCP_RCLKI")
		)
		(pad "2" smd rect
			(at -1.225042 0 270)
			(size 0.4572 1.3208)
			(layers "F.Cu" "F.Mask" "F.Paste")
			(net "RMII_OCP_RCLKI_ISO")
		)
		(pad "3" smd rect
			(at -1.225042 0.94996 270)
			(size 0.4572 1.3208)
			(layers "F.Cu" "F.Mask" "F.Paste")
			(net "GND")
		)
		(pad "4" smd rect
			(at 1.225042 0.94996 270)
			(size 0.4572 1.3208)
			(layers "F.Cu" "F.Mask" "F.Paste")
			(net "PWRGD_P1V0_AUX_DELAY_R")
		)
		(pad "5" smd rect
			(at 1.225042 -0.94996 270)
			(size 0.4572 1.3208)
			(layers "F.Cu" "F.Mask" "F.Paste")
			(net "P3V3_LDO")
		)
	)
	(footprint ""
		(layer "F.Cu")
		(at 40.887142 -63.756794 -90)
		(property "Reference" "R185"
			(at 0 0 270)
			(layer "F.SilkS")
			(hide yes)
			(effects
				(font
					(size 1.27 1.27)
				)
			)
		)
		(property "Value" ""
			(at 0 0 270)
			(layer "F.Fab")
			(effects
				(font
					(size 1.27 1.27)
				)
			)
		)
		(duplicate_pad_numbers_are_jumpers no)
		(fp_line
			(start -0.7874 0.4064)
			(end -0.7874 -0.4064)
			(stroke
				(width 0.1524)
				(type default)
			)
			(layer "F.SilkS")
		)
		(fp_line
			(start 0.7874 0.4064)
			(end -0.7874 0.4064)
			(stroke
				(width 0.1524)
				(type default)
			)
			(layer "F.SilkS")
		)
		(fp_line
			(start -0.7874 -0.4064)
			(end 0.7874 -0.4064)
			(stroke
				(width 0.1524)
				(type default)
			)
			(layer "F.SilkS")
		)
		(fp_line
			(start 0.7874 -0.4064)
			(end 0.7874 0.4064)
			(stroke
				(width 0.1524)
				(type default)
			)
			(layer "F.SilkS")
		)
		(fp_line
			(start -0.67945 0.3048)
			(end -0.67945 -0.305054)
			(stroke
				(width 0.1)
				(type default)
			)
			(layer "F.Fab")
		)
		(fp_line
			(start -0.12065 0.3048)
			(end -0.67945 0.3048)
			(stroke
				(width 0.1)
				(type default)
			)
			(layer "F.Fab")
		)
		(fp_line
			(start 0.120396 0.3048)
			(end 0.120396 0.2794)
			(stroke
				(width 0.1)
				(type default)
			)
			(layer "F.Fab")
		)
		(fp_line
			(start 0.67945 0.3048)
			(end 0.120396 0.3048)
			(stroke
				(width 0.1)
				(type default)
			)
			(layer "F.Fab")
		)
		(fp_line
			(start -0.12065 0.2794)
			(end -0.12065 0.3048)
			(stroke
				(width 0.1)
				(type default)
			)
			(layer "F.Fab")
		)
		(fp_line
			(start 0.120396 0.2794)
			(end -0.12065 0.2794)
			(stroke
				(width 0.1)
				(type default)
			)
			(layer "F.Fab")
		)
		(fp_line
			(start -0.12065 -0.2794)
			(end 0.12065 -0.2794)
			(stroke
				(width 0.1)
				(type default)
			)
			(layer "F.Fab")
		)
		(fp_line
			(start 0.12065 -0.2794)
			(end 0.12065 -0.3048)
			(stroke
				(width 0.1)
				(type default)
			)
			(layer "F.Fab")
		)
		(fp_line
			(start 0.12065 -0.3048)
			(end 0.67945 -0.3048)
			(stroke
				(width 0.1)
				(type default)
			)
			(layer "F.Fab")
		)
		(fp_line
			(start 0.67945 -0.3048)
			(end 0.67945 0.3048)
			(stroke
				(width 0.1)
				(type default)
			)
			(layer "F.Fab")
		)
		(fp_line
			(start -0.67945 -0.305054)
			(end -0.12065 -0.305054)
			(stroke
				(width 0.1)
				(type default)
			)
			(layer "F.Fab")
		)
		(fp_line
			(start -0.12065 -0.305054)
			(end -0.12065 -0.2794)
			(stroke
				(width 0.1)
				(type default)
			)
			(layer "F.Fab")
		)
		(pad "1" smd circle
			(at -0.40005 0 270)
			(size 0 0)
			(layers "F.Cu" "F.Mask" "F.Paste")
			(net "I3C1_SPD_SDA")
		)
		(pad "2" smd circle
			(at 0.40005 0 270)
			(size 0 0)
			(layers "F.Cu" "F.Mask" "F.Paste")
			(net "I3C1_SDA_R")
		)
	)
	(footprint ""
		(layer "F.Cu")
		(at 13.335 -16.383 90)
		(property "Reference" "R619"
			(at 0 0 90)
			(layer "F.SilkS")
			(hide yes)
			(effects
				(font
					(size 1.27 1.27)
				)
			)
		)
		(property "Value" ""
			(at 0 0 90)
			(layer "F.Fab")
			(effects
				(font
					(size 1.27 1.27)
				)
			)
		)
		(duplicate_pad_numbers_are_jumpers no)
		(fp_line
			(start 0.7874 -0.4064)
			(end 0.7874 0.4064)
			(stroke
				(width 0.1524)
				(type default)
			)
			(layer "F.SilkS")
		)
		(fp_line
			(start -0.7874 -0.4064)
			(end 0.7874 -0.4064)
			(stroke
				(width 0.1524)
				(type default)
			)
			(layer "F.SilkS")
		)
		(fp_line
			(start 0.7874 0.4064)
			(end -0.7874 0.4064)
			(stroke
				(width 0.1524)
				(type default)
			)
			(layer "F.SilkS")
		)
		(fp_line
			(start -0.7874 0.4064)
			(end -0.7874 -0.4064)
			(stroke
				(width 0.1524)
				(type default)
			)
			(layer "F.SilkS")
		)
		(fp_line
			(start -0.12065 -0.305054)
			(end -0.12065 -0.2794)
			(stroke
				(width 0.1)
				(type default)
			)
			(layer "F.Fab")
		)
		(fp_line
			(start -0.67945 -0.305054)
			(end -0.12065 -0.305054)
			(stroke
				(width 0.1)
				(type default)
			)
			(layer "F.Fab")
		)
		(fp_line
			(start 0.67945 -0.3048)
			(end 0.67945 0.3048)
			(stroke
				(width 0.1)
				(type default)
			)
			(layer "F.Fab")
		)
		(fp_line
			(start 0.12065 -0.3048)
			(end 0.67945 -0.3048)
			(stroke
				(width 0.1)
				(type default)
			)
			(layer "F.Fab")
		)
		(fp_line
			(start 0.12065 -0.2794)
			(end 0.12065 -0.3048)
			(stroke
				(width 0.1)
				(type default)
			)
			(layer "F.Fab")
		)
		(fp_line
			(start -0.12065 -0.2794)
			(end 0.12065 -0.2794)
			(stroke
				(width 0.1)
				(type default)
			)
			(layer "F.Fab")
		)
		(fp_line
			(start 0.120396 0.2794)
			(end -0.12065 0.2794)
			(stroke
				(width 0.1)
				(type default)
			)
			(layer "F.Fab")
		)
		(fp_line
			(start -0.12065 0.2794)
			(end -0.12065 0.3048)
			(stroke
				(width 0.1)
				(type default)
			)
			(layer "F.Fab")
		)
		(fp_line
			(start 0.67945 0.3048)
			(end 0.120396 0.3048)
			(stroke
				(width 0.1)
				(type default)
			)
			(layer "F.Fab")
		)
		(fp_line
			(start 0.120396 0.3048)
			(end 0.120396 0.2794)
			(stroke
				(width 0.1)
				(type default)
			)
			(layer "F.Fab")
		)
		(fp_line
			(start -0.12065 0.3048)
			(end -0.67945 0.3048)
			(stroke
				(width 0.1)
				(type default)
			)
			(layer "F.Fab")
		)
		(fp_line
			(start -0.67945 0.3048)
			(end -0.67945 -0.305054)
			(stroke
				(width 0.1)
				(type default)
			)
			(layer "F.Fab")
		)
		(pad "1" smd circle
			(at -0.40005 0 90)
			(size 0 0)
			(layers "F.Cu" "F.Mask" "F.Paste")
			(net "HDD_LED_N")
		)
		(pad "2" smd circle
			(at 0.40005 0 90)
			(size 0 0)
			(layers "F.Cu" "F.Mask" "F.Paste")
			(net "GND")
		)
	)
	(footprint ""
		(layer "F.Cu")
		(at 43.45559 -22.159976)
		(property "Reference" "L22"
			(at 0 0 0)
			(layer "F.SilkS")
			(hide yes)
			(effects
				(font
					(size 1.27 1.27)
				)
			)
		)
		(property "Value" ""
			(at 0 0 0)
			(layer "F.Fab")
			(effects
				(font
					(size 1.27 1.27)
				)
			)
		)
		(duplicate_pad_numbers_are_jumpers no)
		(fp_line
			(start -0.8636 -1.524)
			(end -0.379984 -1.524)
			(stroke
				(width 0.1524)
				(type default)
			)
			(layer "F.SilkS")
		)
		(fp_line
			(start -0.8636 1.524)
			(end -0.8636 -1.524)
			(stroke
				(width 0.1524)
				(type default)
			)
			(layer "F.SilkS")
		)
		(fp_line
			(start -0.425704 1.524)
			(end -0.8636 1.524)
			(stroke
				(width 0.1524)
				(type default)
			)
			(layer "F.SilkS")
		)
		(fp_line
			(start 0.425196 -1.524)
			(end 0.8636 -1.524)
			(stroke
				(width 0.1524)
				(type default)
			)
			(layer "F.SilkS")
		)
		(fp_line
			(start 0.8636 -1.524)
			(end 0.8636 1.524)
			(stroke
				(width 0.1524)
				(type default)
			)
			(layer "F.SilkS")
		)
		(fp_line
			(start 0.8636 1.524)
			(end 0.511556 1.524)
			(stroke
				(width 0.1524)
				(type default)
			)
			(layer "F.SilkS")
		)
		(fp_poly
			(pts
				(xy -0.922528 -1.650746) (xy -1.461262 -1.830324) (xy -1.102106 -2.18948)
			)
			(stroke
				(width 0)
				(type default)
			)
			(fill yes)
			(layer "F.SilkS")
		)
		(fp_line
			(start -0.700024 -1.100074)
			(end 0.700024 -1.100074)
			(stroke
				(width 0.1)
				(type default)
			)
			(layer "F.Fab")
		)
		(fp_line
			(start -0.700024 1.100074)
			(end -0.700024 -1.100074)
			(stroke
				(width 0.1)
				(type default)
			)
			(layer "F.Fab")
		)
		(fp_line
			(start 0.700024 -1.100074)
			(end 0.700024 1.100074)
			(stroke
				(width 0.1)
				(type default)
			)
			(layer "F.Fab")
		)
		(fp_line
			(start 0.700024 1.100074)
			(end -0.700024 1.100074)
			(stroke
				(width 0.1)
				(type default)
			)
			(layer "F.Fab")
		)
		(fp_poly
			(pts
				(xy -0.4572 -1.6256) (xy -0.7112 -2.1336) (xy -0.2032 -2.1336)
			)
			(stroke
				(width 0)
				(type default)
			)
			(fill yes)
			(layer "F.Fab")
		)
		(pad "1" smd rect
			(at -0.424942 -0.849884)
			(size 0.3556 0.9144)
			(layers "F.Cu" "F.Mask" "F.Paste")
			(net "USB3_01_MUX_FB_RXP")
		)
		(pad "2" smd rect
			(at -0.424942 0.849884)
			(size 0.3556 0.9144)
			(layers "F.Cu" "F.Mask" "F.Paste")
			(net "USB3_01_FB_RXP")
		)
		(pad "3" smd rect
			(at 0.424942 0.849884)
			(size 0.3556 0.9144)
			(layers "F.Cu" "F.Mask" "F.Paste")
			(net "USB3_01_FB_RXN")
		)
		(pad "4" smd rect
			(at 0.424942 -0.849884)
			(size 0.3556 0.9144)
			(layers "F.Cu" "F.Mask" "F.Paste")
			(net "USB3_01_MUX_FB_RXN")
		)
	)
	(footprint ""
		(layer "F.Cu")
		(at 61.595 -86.868 -90)
		(property "Reference" "R94"
			(at 0 0 270)
			(layer "F.SilkS")
			(hide yes)
			(effects
				(font
					(size 1.27 1.27)
				)
			)
		)
		(property "Value" ""
			(at 0 0 270)
			(layer "F.Fab")
			(effects
				(font
					(size 1.27 1.27)
				)
			)
		)
		(duplicate_pad_numbers_are_jumpers no)
		(fp_line
			(start -0.7874 0.4064)
			(end -0.7874 -0.4064)
			(stroke
				(width 0.1524)
				(type default)
			)
			(layer "F.SilkS")
		)
		(fp_line
			(start 0.7874 0.4064)
			(end -0.7874 0.4064)
			(stroke
				(width 0.1524)
				(type default)
			)
			(layer "F.SilkS")
		)
		(fp_line
			(start -0.7874 -0.4064)
			(end 0.7874 -0.4064)
			(stroke
				(width 0.1524)
				(type default)
			)
			(layer "F.SilkS")
		)
		(fp_line
			(start 0.7874 -0.4064)
			(end 0.7874 0.4064)
			(stroke
				(width 0.1524)
				(type default)
			)
			(layer "F.SilkS")
		)
		(fp_line
			(start -0.67945 0.3048)
			(end -0.67945 -0.305054)
			(stroke
				(width 0.1)
				(type default)
			)
			(layer "F.Fab")
		)
		(fp_line
			(start -0.12065 0.3048)
			(end -0.67945 0.3048)
			(stroke
				(width 0.1)
				(type default)
			)
			(layer "F.Fab")
		)
		(fp_line
			(start 0.120396 0.3048)
			(end 0.120396 0.2794)
			(stroke
				(width 0.1)
				(type default)
			)
			(layer "F.Fab")
		)
		(fp_line
			(start 0.67945 0.3048)
			(end 0.120396 0.3048)
			(stroke
				(width 0.1)
				(type default)
			)
			(layer "F.Fab")
		)
		(fp_line
			(start -0.12065 0.2794)
			(end -0.12065 0.3048)
			(stroke
				(width 0.1)
				(type default)
			)
			(layer "F.Fab")
		)
		(fp_line
			(start 0.120396 0.2794)
			(end -0.12065 0.2794)
			(stroke
				(width 0.1)
				(type default)
			)
			(layer "F.Fab")
		)
		(fp_line
			(start -0.12065 -0.2794)
			(end 0.12065 -0.2794)
			(stroke
				(width 0.1)
				(type default)
			)
			(layer "F.Fab")
		)
		(fp_line
			(start 0.12065 -0.2794)
			(end 0.12065 -0.3048)
			(stroke
				(width 0.1)
				(type default)
			)
			(layer "F.Fab")
		)
		(fp_line
			(start 0.12065 -0.3048)
			(end 0.67945 -0.3048)
			(stroke
				(width 0.1)
				(type default)
			)
			(layer "F.Fab")
		)
		(fp_line
			(start 0.67945 -0.3048)
			(end 0.67945 0.3048)
			(stroke
				(width 0.1)
				(type default)
			)
			(layer "F.Fab")
		)
		(fp_line
			(start -0.67945 -0.305054)
			(end -0.12065 -0.305054)
			(stroke
				(width 0.1)
				(type default)
			)
			(layer "F.Fab")
		)
		(fp_line
			(start -0.12065 -0.305054)
			(end -0.12065 -0.2794)
			(stroke
				(width 0.1)
				(type default)
			)
			(layer "F.Fab")
		)
		(pad "1" smd circle
			(at -0.40005 0 270)
			(size 0 0)
			(layers "F.Cu" "F.Mask" "F.Paste")
			(net "SPI_BMC_BOOT_MOSI")
		)
		(pad "2" smd circle
			(at 0.40005 0 270)
			(size 0 0)
			(layers "F.Cu" "F.Mask" "F.Paste")
			(net "GND")
		)
	)
	(footprint ""
		(layer "F.Cu")
		(at 76.708 -14.478)
		(property "Reference" "C29"
			(at 0 0 0)
			(layer "F.SilkS")
			(hide yes)
			(effects
				(font
					(size 1.27 1.27)
				)
			)
		)
		(property "Value" ""
			(at 0 0 0)
			(layer "F.Fab")
			(effects
				(font
					(size 1.27 1.27)
				)
			)
		)
		(duplicate_pad_numbers_are_jumpers no)
		(fp_line
			(start -0.7874 -0.4064)
			(end 0.7874 -0.4064)
			(stroke
				(width 0.1524)
				(type default)
			)
			(layer "F.SilkS")
		)
		(fp_line
			(start -0.7874 0.4064)
			(end -0.7874 -0.4064)
			(stroke
				(width 0.1524)
				(type default)
			)
			(layer "F.SilkS")
		)
		(fp_line
			(start 0.7874 -0.4064)
			(end 0.7874 0.4064)
			(stroke
				(width 0.1524)
				(type default)
			)
			(layer "F.SilkS")
		)
		(fp_line
			(start 0.7874 0.4064)
			(end -0.7874 0.4064)
			(stroke
				(width 0.1524)
				(type default)
			)
			(layer "F.SilkS")
		)
		(fp_line
			(start -0.67945 -0.305054)
			(end -0.12065 -0.305054)
			(stroke
				(width 0.1)
				(type default)
			)
			(layer "F.Fab")
		)
		(fp_line
			(start -0.67945 0.3048)
			(end -0.67945 -0.305054)
			(stroke
				(width 0.1)
				(type default)
			)
			(layer "F.Fab")
		)
		(fp_line
			(start -0.12065 -0.305054)
			(end -0.12065 -0.2794)
			(stroke
				(width 0.1)
				(type default)
			)
			(layer "F.Fab")
		)
		(fp_line
			(start -0.12065 -0.2794)
			(end 0.12065 -0.2794)
			(stroke
				(width 0.1)
				(type default)
			)
			(layer "F.Fab")
		)
		(fp_line
			(start -0.12065 0.2794)
			(end -0.12065 0.3048)
			(stroke
				(width 0.1)
				(type default)
			)
			(layer "F.Fab")
		)
		(fp_line
			(start -0.12065 0.3048)
			(end -0.67945 0.3048)
			(stroke
				(width 0.1)
				(type default)
			)
			(layer "F.Fab")
		)
		(fp_line
			(start 0.120396 0.2794)
			(end -0.12065 0.2794)
			(stroke
				(width 0.1)
				(type default)
			)
			(layer "F.Fab")
		)
		(fp_line
			(start 0.120396 0.3048)
			(end 0.120396 0.2794)
			(stroke
				(width 0.1)
				(type default)
			)
			(layer "F.Fab")
		)
		(fp_line
			(start 0.12065 -0.3048)
			(end 0.67945 -0.3048)
			(stroke
				(width 0.1)
				(type default)
			)
			(layer "F.Fab")
		)
		(fp_line
			(start 0.12065 -0.2794)
			(end 0.12065 -0.3048)
			(stroke
				(width 0.1)
				(type default)
			)
			(layer "F.Fab")
		)
		(fp_line
			(start 0.67945 -0.3048)
			(end 0.67945 0.3048)
			(stroke
				(width 0.1)
				(type default)
			)
			(layer "F.Fab")
		)
		(fp_line
			(start 0.67945 0.3048)
			(end 0.120396 0.3048)
			(stroke
				(width 0.1)
				(type default)
			)
			(layer "F.Fab")
		)
		(pad "1" smd circle
			(at -0.40005 0)
			(size 0 0)
			(layers "F.Cu" "F.Mask" "F.Paste")
			(net "P3V3_AUX")
		)
		(pad "2" smd circle
			(at 0.40005 0)
			(size 0 0)
			(layers "F.Cu" "F.Mask" "F.Paste")
			(net "GND")
		)
	)
	(footprint ""
		(layer "F.Cu")
		(at 77.47 -21.336 180)
		(property "Reference" "D19"
			(at 1.143 1.11633 0)
			(unlocked yes)
			(layer "F.SilkS")
			(effects
				(font
					(size 0.7874 0.5842)
					(thickness 0.1524)
				)
				(justify left)
			)
		)
		(property "Value" ""
			(at 0 0 180)
			(layer "F.Fab")
			(effects
				(font
					(size 1.27 1.27)
				)
			)
		)
		(duplicate_pad_numbers_are_jumpers no)
		(fp_line
			(start 1.16078 0.4826)
			(end -0.64008 0.4826)
			(stroke
				(width 0.1524)
				(type default)
			)
			(layer "F.SilkS")
		)
		(fp_line
			(start 1.16078 -0.4826)
			(end 1.16078 0.4826)
			(stroke
				(width 0.1524)
				(type default)
			)
			(layer "F.SilkS")
		)
		(fp_line
			(start 1.03378 0.4826)
			(end -0.79248 0.4826)
			(stroke
				(width 0.1524)
				(type default)
			)
			(layer "F.SilkS")
		)
		(fp_line
			(start 1.03378 -0.4826)
			(end 1.03378 0.4826)
			(stroke
				(width 0.1524)
				(type default)
			)
			(layer "F.SilkS")
		)
		(fp_line
			(start 0.90678 0.4826)
			(end -0.90678 0.4826)
			(stroke
				(width 0.1524)
				(type default)
			)
			(layer "F.SilkS")
		)
		(fp_line
			(start 0.90678 -0.4826)
			(end 0.90678 0.4826)
			(stroke
				(width 0.1524)
				(type default)
			)
			(layer "F.SilkS")
		)
		(fp_line
			(start -0.64008 -0.4826)
			(end 1.16078 -0.4826)
			(stroke
				(width 0.1524)
				(type default)
			)
			(layer "F.SilkS")
		)
		(fp_line
			(start -0.79248 -0.4826)
			(end 1.03378 -0.4826)
			(stroke
				(width 0.1524)
				(type default)
			)
			(layer "F.SilkS")
		)
		(fp_line
			(start -0.89408 -0.4826)
			(end 0.90678 -0.4826)
			(stroke
				(width 0.1524)
				(type default)
			)
			(layer "F.SilkS")
		)
		(fp_line
			(start -0.90678 0.4826)
			(end -0.90678 -0.4699)
			(stroke
				(width 0.1524)
				(type default)
			)
			(layer "F.SilkS")
		)
		(fp_line
			(start 0.499872 0.249936)
			(end -0.499872 0.249936)
			(stroke
				(width 0.1)
				(type default)
			)
			(layer "F.Fab")
		)
		(fp_line
			(start 0.499872 -0.249936)
			(end 0.499872 0.249936)
			(stroke
				(width 0.1)
				(type default)
			)
			(layer "F.Fab")
		)
		(fp_line
			(start -0.499872 0.249936)
			(end -0.499872 -0.249936)
			(stroke
				(width 0.1)
				(type default)
			)
			(layer "F.Fab")
		)
		(fp_line
			(start -0.499872 -0.249936)
			(end 0.499872 -0.249936)
			(stroke
				(width 0.1)
				(type default)
			)
			(layer "F.Fab")
		)
		(pad "A" smd rect
			(at -0.47498 0 180)
			(size 0.6096 0.7112)
			(layers "F.Cu" "F.Mask" "F.Paste")
			(net "P3V3_AUX")
		)
		(pad "C" smd rect
			(at 0.47498 0 180)
			(size 0.6096 0.7112)
			(layers "F.Cu" "F.Mask" "F.Paste")
			(net "FM_UARTSW_MSB_R1_N")
		)
	)
	(footprint ""
		(layer "F.Cu")
		(at 52.991258 -34.637726 -90)
		(property "Reference" "R639"
			(at 0 0 270)
			(layer "F.SilkS")
			(hide yes)
			(effects
				(font
					(size 1.27 1.27)
				)
			)
		)
		(property "Value" ""
			(at 0 0 270)
			(layer "F.Fab")
			(effects
				(font
					(size 1.27 1.27)
				)
			)
		)
		(duplicate_pad_numbers_are_jumpers no)
		(fp_line
			(start -0.7874 0.4064)
			(end -0.7874 -0.4064)
			(stroke
				(width 0.1524)
				(type default)
			)
			(layer "F.SilkS")
		)
		(fp_line
			(start 0.7874 0.4064)
			(end -0.7874 0.4064)
			(stroke
				(width 0.1524)
				(type default)
			)
			(layer "F.SilkS")
		)
		(fp_line
			(start -0.7874 -0.4064)
			(end 0.7874 -0.4064)
			(stroke
				(width 0.1524)
				(type default)
			)
			(layer "F.SilkS")
		)
		(fp_line
			(start 0.7874 -0.4064)
			(end 0.7874 0.4064)
			(stroke
				(width 0.1524)
				(type default)
			)
			(layer "F.SilkS")
		)
		(fp_line
			(start -0.67945 0.3048)
			(end -0.67945 -0.305054)
			(stroke
				(width 0.1)
				(type default)
			)
			(layer "F.Fab")
		)
		(fp_line
			(start -0.12065 0.3048)
			(end -0.67945 0.3048)
			(stroke
				(width 0.1)
				(type default)
			)
			(layer "F.Fab")
		)
		(fp_line
			(start 0.120396 0.3048)
			(end 0.120396 0.2794)
			(stroke
				(width 0.1)
				(type default)
			)
			(layer "F.Fab")
		)
		(fp_line
			(start 0.67945 0.3048)
			(end 0.120396 0.3048)
			(stroke
				(width 0.1)
				(type default)
			)
			(layer "F.Fab")
		)
		(fp_line
			(start -0.12065 0.2794)
			(end -0.12065 0.3048)
			(stroke
				(width 0.1)
				(type default)
			)
			(layer "F.Fab")
		)
		(fp_line
			(start 0.120396 0.2794)
			(end -0.12065 0.2794)
			(stroke
				(width 0.1)
				(type default)
			)
			(layer "F.Fab")
		)
		(fp_line
			(start -0.12065 -0.2794)
			(end 0.12065 -0.2794)
			(stroke
				(width 0.1)
				(type default)
			)
			(layer "F.Fab")
		)
		(fp_line
			(start 0.12065 -0.2794)
			(end 0.12065 -0.3048)
			(stroke
				(width 0.1)
				(type default)
			)
			(layer "F.Fab")
		)
		(fp_line
			(start 0.12065 -0.3048)
			(end 0.67945 -0.3048)
			(stroke
				(width 0.1)
				(type default)
			)
			(layer "F.Fab")
		)
		(fp_line
			(start 0.67945 -0.3048)
			(end 0.67945 0.3048)
			(stroke
				(width 0.1)
				(type default)
			)
			(layer "F.Fab")
		)
		(fp_line
			(start -0.67945 -0.305054)
			(end -0.12065 -0.305054)
			(stroke
				(width 0.1)
				(type default)
			)
			(layer "F.Fab")
		)
		(fp_line
			(start -0.12065 -0.305054)
			(end -0.12065 -0.2794)
			(stroke
				(width 0.1)
				(type default)
			)
			(layer "F.Fab")
		)
		(pad "1" smd circle
			(at -0.40005 0 270)
			(size 0 0)
			(layers "F.Cu" "F.Mask" "F.Paste")
			(net "JTAG_1_BMC_TDI_R")
		)
		(pad "2" smd circle
			(at 0.40005 0 270)
			(size 0 0)
			(layers "F.Cu" "F.Mask" "F.Paste")
			(net "JTAG_MB_TDI")
		)
	)
	(footprint ""
		(layer "F.Cu")
		(at 61.70676 -66.031364 -90)
		(property "Reference" "R799"
			(at 0 0 270)
			(layer "F.SilkS")
			(hide yes)
			(effects
				(font
					(size 1.27 1.27)
				)
			)
		)
		(property "Value" ""
			(at 0 0 270)
			(layer "F.Fab")
			(effects
				(font
					(size 1.27 1.27)
				)
			)
		)
		(duplicate_pad_numbers_are_jumpers no)
		(fp_line
			(start -0.7874 0.4064)
			(end -0.7874 -0.4064)
			(stroke
				(width 0.1524)
				(type default)
			)
			(layer "F.SilkS")
		)
		(fp_line
			(start 0.7874 0.4064)
			(end -0.7874 0.4064)
			(stroke
				(width 0.1524)
				(type default)
			)
			(layer "F.SilkS")
		)
		(fp_line
			(start -0.7874 -0.4064)
			(end 0.7874 -0.4064)
			(stroke
				(width 0.1524)
				(type default)
			)
			(layer "F.SilkS")
		)
		(fp_line
			(start 0.7874 -0.4064)
			(end 0.7874 0.4064)
			(stroke
				(width 0.1524)
				(type default)
			)
			(layer "F.SilkS")
		)
		(fp_line
			(start -0.67945 0.3048)
			(end -0.67945 -0.305054)
			(stroke
				(width 0.1)
				(type default)
			)
			(layer "F.Fab")
		)
		(fp_line
			(start -0.12065 0.3048)
			(end -0.67945 0.3048)
			(stroke
				(width 0.1)
				(type default)
			)
			(layer "F.Fab")
		)
		(fp_line
			(start 0.120396 0.3048)
			(end 0.120396 0.2794)
			(stroke
				(width 0.1)
				(type default)
			)
			(layer "F.Fab")
		)
		(fp_line
			(start 0.67945 0.3048)
			(end 0.120396 0.3048)
			(stroke
				(width 0.1)
				(type default)
			)
			(layer "F.Fab")
		)
		(fp_line
			(start -0.12065 0.2794)
			(end -0.12065 0.3048)
			(stroke
				(width 0.1)
				(type default)
			)
			(layer "F.Fab")
		)
		(fp_line
			(start 0.120396 0.2794)
			(end -0.12065 0.2794)
			(stroke
				(width 0.1)
				(type default)
			)
			(layer "F.Fab")
		)
		(fp_line
			(start -0.12065 -0.2794)
			(end 0.12065 -0.2794)
			(stroke
				(width 0.1)
				(type default)
			)
			(layer "F.Fab")
		)
		(fp_line
			(start 0.12065 -0.2794)
			(end 0.12065 -0.3048)
			(stroke
				(width 0.1)
				(type default)
			)
			(layer "F.Fab")
		)
		(fp_line
			(start 0.12065 -0.3048)
			(end 0.67945 -0.3048)
			(stroke
				(width 0.1)
				(type default)
			)
			(layer "F.Fab")
		)
		(fp_line
			(start 0.67945 -0.3048)
			(end 0.67945 0.3048)
			(stroke
				(width 0.1)
				(type default)
			)
			(layer "F.Fab")
		)
		(fp_line
			(start -0.67945 -0.305054)
			(end -0.12065 -0.305054)
			(stroke
				(width 0.1)
				(type default)
			)
			(layer "F.Fab")
		)
		(fp_line
			(start -0.12065 -0.305054)
			(end -0.12065 -0.2794)
			(stroke
				(width 0.1)
				(type default)
			)
			(layer "F.Fab")
		)
		(pad "1" smd circle
			(at -0.40005 0 270)
			(size 0 0)
			(layers "F.Cu" "F.Mask" "F.Paste")
			(net "SPI_BMC_BIOS_CS0_N")
		)
		(pad "2" smd circle
			(at 0.40005 0 270)
			(size 0 0)
			(layers "F.Cu" "F.Mask" "F.Paste")
			(net "SPI_BMC_BIOS_CS0_R1_N")
		)
	)
	(footprint ""
		(layer "F.Cu")
		(at 13.169646 -52.008532 -90)
		(property "Reference" "PR521"
			(at 0 0 270)
			(layer "F.SilkS")
			(hide yes)
			(effects
				(font
					(size 1.27 1.27)
				)
			)
		)
		(property "Value" ""
			(at 0 0 270)
			(layer "F.Fab")
			(effects
				(font
					(size 1.27 1.27)
				)
			)
		)
		(duplicate_pad_numbers_are_jumpers no)
		(fp_line
			(start -0.7874 0.4064)
			(end -0.7874 -0.4064)
			(stroke
				(width 0.1524)
				(type default)
			)
			(layer "F.SilkS")
		)
		(fp_line
			(start 0.7874 0.4064)
			(end -0.7874 0.4064)
			(stroke
				(width 0.1524)
				(type default)
			)
			(layer "F.SilkS")
		)
		(fp_line
			(start -0.7874 -0.4064)
			(end 0.7874 -0.4064)
			(stroke
				(width 0.1524)
				(type default)
			)
			(layer "F.SilkS")
		)
		(fp_line
			(start 0.7874 -0.4064)
			(end 0.7874 0.4064)
			(stroke
				(width 0.1524)
				(type default)
			)
			(layer "F.SilkS")
		)
		(fp_line
			(start -0.67945 0.3048)
			(end -0.67945 -0.305054)
			(stroke
				(width 0.1)
				(type default)
			)
			(layer "F.Fab")
		)
		(fp_line
			(start -0.12065 0.3048)
			(end -0.67945 0.3048)
			(stroke
				(width 0.1)
				(type default)
			)
			(layer "F.Fab")
		)
		(fp_line
			(start 0.120396 0.3048)
			(end 0.120396 0.2794)
			(stroke
				(width 0.1)
				(type default)
			)
			(layer "F.Fab")
		)
		(fp_line
			(start 0.67945 0.3048)
			(end 0.120396 0.3048)
			(stroke
				(width 0.1)
				(type default)
			)
			(layer "F.Fab")
		)
		(fp_line
			(start -0.12065 0.2794)
			(end -0.12065 0.3048)
			(stroke
				(width 0.1)
				(type default)
			)
			(layer "F.Fab")
		)
		(fp_line
			(start 0.120396 0.2794)
			(end -0.12065 0.2794)
			(stroke
				(width 0.1)
				(type default)
			)
			(layer "F.Fab")
		)
		(fp_line
			(start -0.12065 -0.2794)
			(end 0.12065 -0.2794)
			(stroke
				(width 0.1)
				(type default)
			)
			(layer "F.Fab")
		)
		(fp_line
			(start 0.12065 -0.2794)
			(end 0.12065 -0.3048)
			(stroke
				(width 0.1)
				(type default)
			)
			(layer "F.Fab")
		)
		(fp_line
			(start 0.12065 -0.3048)
			(end 0.67945 -0.3048)
			(stroke
				(width 0.1)
				(type default)
			)
			(layer "F.Fab")
		)
		(fp_line
			(start 0.67945 -0.3048)
			(end 0.67945 0.3048)
			(stroke
				(width 0.1)
				(type default)
			)
			(layer "F.Fab")
		)
		(fp_line
			(start -0.67945 -0.305054)
			(end -0.12065 -0.305054)
			(stroke
				(width 0.1)
				(type default)
			)
			(layer "F.Fab")
		)
		(fp_line
			(start -0.12065 -0.305054)
			(end -0.12065 -0.2794)
			(stroke
				(width 0.1)
				(type default)
			)
			(layer "F.Fab")
		)
		(pad "1" smd circle
			(at -0.40005 0 270)
			(size 0 0)
			(layers "F.Cu" "F.Mask" "F.Paste")
			(net "P12V_AUX")
		)
		(pad "2" smd circle
			(at 0.40005 0 270)
			(size 0 0)
			(layers "F.Cu" "F.Mask" "F.Paste")
			(net "EN_P5V_AUX")
		)
	)
	(footprint ""
		(layer "F.Cu")
		(at 40.648128 -55.427626 -90)
		(property "Reference" "R832"
			(at 0 0 270)
			(layer "F.SilkS")
			(hide yes)
			(effects
				(font
					(size 1.27 1.27)
				)
			)
		)
		(property "Value" ""
			(at 0 0 270)
			(layer "F.Fab")
			(effects
				(font
					(size 1.27 1.27)
				)
			)
		)
		(duplicate_pad_numbers_are_jumpers no)
		(fp_line
			(start -0.7874 0.4064)
			(end -0.7874 -0.4064)
			(stroke
				(width 0.1524)
				(type default)
			)
			(layer "F.SilkS")
		)
		(fp_line
			(start 0.7874 0.4064)
			(end -0.7874 0.4064)
			(stroke
				(width 0.1524)
				(type default)
			)
			(layer "F.SilkS")
		)
		(fp_line
			(start -0.7874 -0.4064)
			(end 0.7874 -0.4064)
			(stroke
				(width 0.1524)
				(type default)
			)
			(layer "F.SilkS")
		)
		(fp_line
			(start 0.7874 -0.4064)
			(end 0.7874 0.4064)
			(stroke
				(width 0.1524)
				(type default)
			)
			(layer "F.SilkS")
		)
		(fp_line
			(start -0.67945 0.3048)
			(end -0.67945 -0.305054)
			(stroke
				(width 0.1)
				(type default)
			)
			(layer "F.Fab")
		)
		(fp_line
			(start -0.12065 0.3048)
			(end -0.67945 0.3048)
			(stroke
				(width 0.1)
				(type default)
			)
			(layer "F.Fab")
		)
		(fp_line
			(start 0.120396 0.3048)
			(end 0.120396 0.2794)
			(stroke
				(width 0.1)
				(type default)
			)
			(layer "F.Fab")
		)
		(fp_line
			(start 0.67945 0.3048)
			(end 0.120396 0.3048)
			(stroke
				(width 0.1)
				(type default)
			)
			(layer "F.Fab")
		)
		(fp_line
			(start -0.12065 0.2794)
			(end -0.12065 0.3048)
			(stroke
				(width 0.1)
				(type default)
			)
			(layer "F.Fab")
		)
		(fp_line
			(start 0.120396 0.2794)
			(end -0.12065 0.2794)
			(stroke
				(width 0.1)
				(type default)
			)
			(layer "F.Fab")
		)
		(fp_line
			(start -0.12065 -0.2794)
			(end 0.12065 -0.2794)
			(stroke
				(width 0.1)
				(type default)
			)
			(layer "F.Fab")
		)
		(fp_line
			(start 0.12065 -0.2794)
			(end 0.12065 -0.3048)
			(stroke
				(width 0.1)
				(type default)
			)
			(layer "F.Fab")
		)
		(fp_line
			(start 0.12065 -0.3048)
			(end 0.67945 -0.3048)
			(stroke
				(width 0.1)
				(type default)
			)
			(layer "F.Fab")
		)
		(fp_line
			(start 0.67945 -0.3048)
			(end 0.67945 0.3048)
			(stroke
				(width 0.1)
				(type default)
			)
			(layer "F.Fab")
		)
		(fp_line
			(start -0.67945 -0.305054)
			(end -0.12065 -0.305054)
			(stroke
				(width 0.1)
				(type default)
			)
			(layer "F.Fab")
		)
		(fp_line
			(start -0.12065 -0.305054)
			(end -0.12065 -0.2794)
			(stroke
				(width 0.1)
				(type default)
			)
			(layer "F.Fab")
		)
		(pad "1" smd circle
			(at -0.40005 0 270)
			(size 0 0)
			(layers "F.Cu" "F.Mask" "F.Paste")
			(net "U41_ADJ")
		)
		(pad "2" smd circle
			(at 0.40005 0 270)
			(size 0 0)
			(layers "F.Cu" "F.Mask" "F.Paste")
			(net "GND")
		)
	)
	(footprint ""
		(layer "F.Cu")
		(at 27.559 -102.743 -90)
		(property "Reference" "R578"
			(at 0 0 270)
			(layer "F.SilkS")
			(hide yes)
			(effects
				(font
					(size 1.27 1.27)
				)
			)
		)
		(property "Value" ""
			(at 0 0 270)
			(layer "F.Fab")
			(effects
				(font
					(size 1.27 1.27)
				)
			)
		)
		(duplicate_pad_numbers_are_jumpers no)
		(fp_line
			(start -0.7874 0.4064)
			(end -0.7874 -0.4064)
			(stroke
				(width 0.1524)
				(type default)
			)
			(layer "F.SilkS")
		)
		(fp_line
			(start 0.7874 0.4064)
			(end -0.7874 0.4064)
			(stroke
				(width 0.1524)
				(type default)
			)
			(layer "F.SilkS")
		)
		(fp_line
			(start -0.7874 -0.4064)
			(end 0.7874 -0.4064)
			(stroke
				(width 0.1524)
				(type default)
			)
			(layer "F.SilkS")
		)
		(fp_line
			(start 0.7874 -0.4064)
			(end 0.7874 0.4064)
			(stroke
				(width 0.1524)
				(type default)
			)
			(layer "F.SilkS")
		)
		(fp_line
			(start -0.67945 0.3048)
			(end -0.67945 -0.305054)
			(stroke
				(width 0.1)
				(type default)
			)
			(layer "F.Fab")
		)
		(fp_line
			(start -0.12065 0.3048)
			(end -0.67945 0.3048)
			(stroke
				(width 0.1)
				(type default)
			)
			(layer "F.Fab")
		)
		(fp_line
			(start 0.120396 0.3048)
			(end 0.120396 0.2794)
			(stroke
				(width 0.1)
				(type default)
			)
			(layer "F.Fab")
		)
		(fp_line
			(start 0.67945 0.3048)
			(end 0.120396 0.3048)
			(stroke
				(width 0.1)
				(type default)
			)
			(layer "F.Fab")
		)
		(fp_line
			(start -0.12065 0.2794)
			(end -0.12065 0.3048)
			(stroke
				(width 0.1)
				(type default)
			)
			(layer "F.Fab")
		)
		(fp_line
			(start 0.120396 0.2794)
			(end -0.12065 0.2794)
			(stroke
				(width 0.1)
				(type default)
			)
			(layer "F.Fab")
		)
		(fp_line
			(start -0.12065 -0.2794)
			(end 0.12065 -0.2794)
			(stroke
				(width 0.1)
				(type default)
			)
			(layer "F.Fab")
		)
		(fp_line
			(start 0.12065 -0.2794)
			(end 0.12065 -0.3048)
			(stroke
				(width 0.1)
				(type default)
			)
			(layer "F.Fab")
		)
		(fp_line
			(start 0.12065 -0.3048)
			(end 0.67945 -0.3048)
			(stroke
				(width 0.1)
				(type default)
			)
			(layer "F.Fab")
		)
		(fp_line
			(start 0.67945 -0.3048)
			(end 0.67945 0.3048)
			(stroke
				(width 0.1)
				(type default)
			)
			(layer "F.Fab")
		)
		(fp_line
			(start -0.67945 -0.305054)
			(end -0.12065 -0.305054)
			(stroke
				(width 0.1)
				(type default)
			)
			(layer "F.Fab")
		)
		(fp_line
			(start -0.12065 -0.305054)
			(end -0.12065 -0.2794)
			(stroke
				(width 0.1)
				(type default)
			)
			(layer "F.Fab")
		)
		(pad "1" smd circle
			(at -0.40005 0 270)
			(size 0 0)
			(layers "F.Cu" "F.Mask" "F.Paste")
			(net "PWRGD_DSW_PWROK")
		)
		(pad "2" smd circle
			(at 0.40005 0 270)
			(size 0 0)
			(layers "F.Cu" "F.Mask" "F.Paste")
			(net "PWRGD_DSW_PWROK_R2")
		)
	)
	(footprint ""
		(layer "F.Cu")
		(at 25.4 -24.003 90)
		(property "Reference" "PC266"
			(at 0 0 90)
			(layer "F.SilkS")
			(hide yes)
			(effects
				(font
					(size 1.27 1.27)
				)
			)
		)
		(property "Value" ""
			(at 0 0 90)
			(layer "F.Fab")
			(effects
				(font
					(size 1.27 1.27)
				)
			)
		)
		(duplicate_pad_numbers_are_jumpers no)
		(fp_line
			(start 0.7874 -0.4064)
			(end 0.7874 0.4064)
			(stroke
				(width 0.1524)
				(type default)
			)
			(layer "F.SilkS")
		)
		(fp_line
			(start -0.7874 -0.4064)
			(end 0.7874 -0.4064)
			(stroke
				(width 0.1524)
				(type default)
			)
			(layer "F.SilkS")
		)
		(fp_line
			(start 0.7874 0.4064)
			(end -0.7874 0.4064)
			(stroke
				(width 0.1524)
				(type default)
			)
			(layer "F.SilkS")
		)
		(fp_line
			(start -0.7874 0.4064)
			(end -0.7874 -0.4064)
			(stroke
				(width 0.1524)
				(type default)
			)
			(layer "F.SilkS")
		)
		(fp_line
			(start -0.12065 -0.305054)
			(end -0.12065 -0.2794)
			(stroke
				(width 0.1)
				(type default)
			)
			(layer "F.Fab")
		)
		(fp_line
			(start -0.67945 -0.305054)
			(end -0.12065 -0.305054)
			(stroke
				(width 0.1)
				(type default)
			)
			(layer "F.Fab")
		)
		(fp_line
			(start 0.67945 -0.3048)
			(end 0.67945 0.3048)
			(stroke
				(width 0.1)
				(type default)
			)
			(layer "F.Fab")
		)
		(fp_line
			(start 0.12065 -0.3048)
			(end 0.67945 -0.3048)
			(stroke
				(width 0.1)
				(type default)
			)
			(layer "F.Fab")
		)
		(fp_line
			(start 0.12065 -0.2794)
			(end 0.12065 -0.3048)
			(stroke
				(width 0.1)
				(type default)
			)
			(layer "F.Fab")
		)
		(fp_line
			(start -0.12065 -0.2794)
			(end 0.12065 -0.2794)
			(stroke
				(width 0.1)
				(type default)
			)
			(layer "F.Fab")
		)
		(fp_line
			(start 0.120396 0.2794)
			(end -0.12065 0.2794)
			(stroke
				(width 0.1)
				(type default)
			)
			(layer "F.Fab")
		)
		(fp_line
			(start -0.12065 0.2794)
			(end -0.12065 0.3048)
			(stroke
				(width 0.1)
				(type default)
			)
			(layer "F.Fab")
		)
		(fp_line
			(start 0.67945 0.3048)
			(end 0.120396 0.3048)
			(stroke
				(width 0.1)
				(type default)
			)
			(layer "F.Fab")
		)
		(fp_line
			(start 0.120396 0.3048)
			(end 0.120396 0.2794)
			(stroke
				(width 0.1)
				(type default)
			)
			(layer "F.Fab")
		)
		(fp_line
			(start -0.12065 0.3048)
			(end -0.67945 0.3048)
			(stroke
				(width 0.1)
				(type default)
			)
			(layer "F.Fab")
		)
		(fp_line
			(start -0.67945 0.3048)
			(end -0.67945 -0.305054)
			(stroke
				(width 0.1)
				(type default)
			)
			(layer "F.Fab")
		)
		(pad "1" smd circle
			(at -0.40005 0 90)
			(size 0 0)
			(layers "F.Cu" "F.Mask" "F.Paste")
			(net "P1V0_AUX")
		)
		(pad "2" smd circle
			(at 0.40005 0 90)
			(size 0 0)
			(layers "F.Cu" "F.Mask" "F.Paste")
			(net "GND")
		)
	)
	(footprint ""
		(layer "F.Cu")
		(at 78.9432 -10.668)
		(property "Reference" ""
			(at 0 0 0)
			(layer "F.SilkS")
			(hide yes)
			(effects
				(font
					(size 1.27 1.27)
				)
			)
		)
		(property "Value" ""
			(at 0 0 0)
			(layer "F.Fab")
			(effects
				(font
					(size 1.27 1.27)
				)
			)
		)
		(duplicate_pad_numbers_are_jumpers no)
		(pad "1" smd circle
			(at 0 0)
			(size 0.9906 0.9906)
			(layers "F.Cu" "F.Mask" "F.Paste")
			(net "Net_325")
		)
		(zone
			(layer "F.Cu")
			(hatch none 0.5)
			(connect_pads
				(clearance 0)
			)
			(min_thickness 0.25)
			(keepout
				(tracks not_allowed)
				(vias allowed)
				(pads allowed)
				(copperpour not_allowed)
				(footprints allowed)
			)
			(placement
				(enabled no)
				(sheetname "")
			)
			(fill
				(thermal_gap 0.5)
				(thermal_bridge_width 0.5)
				(island_removal_mode 0)
			)
			(polygon
				(pts
					(arc
						(start 80.5688 -10.668)
						(mid 77.3176 -10.668)
						(end 80.5688 -10.668)
					)
				)
			)
		)
	)
	(footprint ""
		(layer "F.Cu")
		(at 38.354 -36.068 180)
		(property "Reference" "R232"
			(at 0 0 180)
			(layer "F.SilkS")
			(hide yes)
			(effects
				(font
					(size 1.27 1.27)
				)
			)
		)
		(property "Value" ""
			(at 0 0 180)
			(layer "F.Fab")
			(effects
				(font
					(size 1.27 1.27)
				)
			)
		)
		(duplicate_pad_numbers_are_jumpers no)
		(fp_line
			(start 0.7874 0.4064)
			(end -0.7874 0.4064)
			(stroke
				(width 0.1524)
				(type default)
			)
			(layer "F.SilkS")
		)
		(fp_line
			(start 0.7874 -0.4064)
			(end 0.7874 0.4064)
			(stroke
				(width 0.1524)
				(type default)
			)
			(layer "F.SilkS")
		)
		(fp_line
			(start -0.7874 0.4064)
			(end -0.7874 -0.4064)
			(stroke
				(width 0.1524)
				(type default)
			)
			(layer "F.SilkS")
		)
		(fp_line
			(start -0.7874 -0.4064)
			(end 0.7874 -0.4064)
			(stroke
				(width 0.1524)
				(type default)
			)
			(layer "F.SilkS")
		)
		(fp_line
			(start 0.67945 0.3048)
			(end 0.120396 0.3048)
			(stroke
				(width 0.1)
				(type default)
			)
			(layer "F.Fab")
		)
		(fp_line
			(start 0.67945 -0.3048)
			(end 0.67945 0.3048)
			(stroke
				(width 0.1)
				(type default)
			)
			(layer "F.Fab")
		)
		(fp_line
			(start 0.12065 -0.2794)
			(end 0.12065 -0.3048)
			(stroke
				(width 0.1)
				(type default)
			)
			(layer "F.Fab")
		)
		(fp_line
			(start 0.12065 -0.3048)
			(end 0.67945 -0.3048)
			(stroke
				(width 0.1)
				(type default)
			)
			(layer "F.Fab")
		)
		(fp_line
			(start 0.120396 0.3048)
			(end 0.120396 0.2794)
			(stroke
				(width 0.1)
				(type default)
			)
			(layer "F.Fab")
		)
		(fp_line
			(start 0.120396 0.2794)
			(end -0.12065 0.2794)
			(stroke
				(width 0.1)
				(type default)
			)
			(layer "F.Fab")
		)
		(fp_line
			(start -0.12065 0.3048)
			(end -0.67945 0.3048)
			(stroke
				(width 0.1)
				(type default)
			)
			(layer "F.Fab")
		)
		(fp_line
			(start -0.12065 0.2794)
			(end -0.12065 0.3048)
			(stroke
				(width 0.1)
				(type default)
			)
			(layer "F.Fab")
		)
		(fp_line
			(start -0.12065 -0.2794)
			(end 0.12065 -0.2794)
			(stroke
				(width 0.1)
				(type default)
			)
			(layer "F.Fab")
		)
		(fp_line
			(start -0.12065 -0.305054)
			(end -0.12065 -0.2794)
			(stroke
				(width 0.1)
				(type default)
			)
			(layer "F.Fab")
		)
		(fp_line
			(start -0.67945 0.3048)
			(end -0.67945 -0.305054)
			(stroke
				(width 0.1)
				(type default)
			)
			(layer "F.Fab")
		)
		(fp_line
			(start -0.67945 -0.305054)
			(end -0.12065 -0.305054)
			(stroke
				(width 0.1)
				(type default)
			)
			(layer "F.Fab")
		)
		(pad "1" smd circle
			(at -0.40005 0 180)
			(size 0 0)
			(layers "F.Cu" "F.Mask" "F.Paste")
			(net "P1V8_AUX")
		)
		(pad "2" smd circle
			(at 0.40005 0 180)
			(size 0 0)
			(layers "F.Cu" "F.Mask" "F.Paste")
			(net "P3V3_P1V8_I2C_I3C")
		)
	)
	(footprint ""
		(layer "F.Cu")
		(at 56.204612 -34.637726 -90)
		(property "Reference" "R19"
			(at 0 0 270)
			(layer "F.SilkS")
			(hide yes)
			(effects
				(font
					(size 1.27 1.27)
				)
			)
		)
		(property "Value" ""
			(at 0 0 270)
			(layer "F.Fab")
			(effects
				(font
					(size 1.27 1.27)
				)
			)
		)
		(duplicate_pad_numbers_are_jumpers no)
		(fp_line
			(start -0.7874 0.4064)
			(end -0.7874 -0.4064)
			(stroke
				(width 0.1524)
				(type default)
			)
			(layer "F.SilkS")
		)
		(fp_line
			(start 0.7874 0.4064)
			(end -0.7874 0.4064)
			(stroke
				(width 0.1524)
				(type default)
			)
			(layer "F.SilkS")
		)
		(fp_line
			(start -0.7874 -0.4064)
			(end 0.7874 -0.4064)
			(stroke
				(width 0.1524)
				(type default)
			)
			(layer "F.SilkS")
		)
		(fp_line
			(start 0.7874 -0.4064)
			(end 0.7874 0.4064)
			(stroke
				(width 0.1524)
				(type default)
			)
			(layer "F.SilkS")
		)
		(fp_line
			(start -0.67945 0.3048)
			(end -0.67945 -0.305054)
			(stroke
				(width 0.1)
				(type default)
			)
			(layer "F.Fab")
		)
		(fp_line
			(start -0.12065 0.3048)
			(end -0.67945 0.3048)
			(stroke
				(width 0.1)
				(type default)
			)
			(layer "F.Fab")
		)
		(fp_line
			(start 0.120396 0.3048)
			(end 0.120396 0.2794)
			(stroke
				(width 0.1)
				(type default)
			)
			(layer "F.Fab")
		)
		(fp_line
			(start 0.67945 0.3048)
			(end 0.120396 0.3048)
			(stroke
				(width 0.1)
				(type default)
			)
			(layer "F.Fab")
		)
		(fp_line
			(start -0.12065 0.2794)
			(end -0.12065 0.3048)
			(stroke
				(width 0.1)
				(type default)
			)
			(layer "F.Fab")
		)
		(fp_line
			(start 0.120396 0.2794)
			(end -0.12065 0.2794)
			(stroke
				(width 0.1)
				(type default)
			)
			(layer "F.Fab")
		)
		(fp_line
			(start -0.12065 -0.2794)
			(end 0.12065 -0.2794)
			(stroke
				(width 0.1)
				(type default)
			)
			(layer "F.Fab")
		)
		(fp_line
			(start 0.12065 -0.2794)
			(end 0.12065 -0.3048)
			(stroke
				(width 0.1)
				(type default)
			)
			(layer "F.Fab")
		)
		(fp_line
			(start 0.12065 -0.3048)
			(end 0.67945 -0.3048)
			(stroke
				(width 0.1)
				(type default)
			)
			(layer "F.Fab")
		)
		(fp_line
			(start 0.67945 -0.3048)
			(end 0.67945 0.3048)
			(stroke
				(width 0.1)
				(type default)
			)
			(layer "F.Fab")
		)
		(fp_line
			(start -0.67945 -0.305054)
			(end -0.12065 -0.305054)
			(stroke
				(width 0.1)
				(type default)
			)
			(layer "F.Fab")
		)
		(fp_line
			(start -0.12065 -0.305054)
			(end -0.12065 -0.2794)
			(stroke
				(width 0.1)
				(type default)
			)
			(layer "F.Fab")
		)
		(pad "1" smd circle
			(at -0.40005 0 270)
			(size 0 0)
			(layers "F.Cu" "F.Mask" "F.Paste")
			(net "V_VGAHS_R")
		)
		(pad "2" smd circle
			(at 0.40005 0 270)
			(size 0 0)
			(layers "F.Cu" "F.Mask" "F.Paste")
			(net "V_VGAHS")
		)
	)
	(footprint ""
		(layer "F.Cu")
		(at 114.554 112.776 -90)
		(property "Reference" "X24"
			(at -1.81483 3.0353 0)
			(unlocked yes)
			(layer "F.SilkS")
			(effects
				(font
					(size 0.7874 0.5842)
					(thickness 0.1524)
				)
				(justify left)
			)
		)
		(property "Value" ""
			(at 0 0 270)
			(layer "F.Fab")
			(effects
				(font
					(size 1.27 1.27)
				)
			)
		)
		(property "Device Type" "TP_TDR_4P_FTS_TH-TP_TDR_4P_DIPA"
			(at 1.30175 1.27 0)
			(unlocked yes)
			(layer "F.Fab")
			(hide yes)
			(effects
				(font
					(size 0.635 0.4064)
					(thickness 0.1524)
				)
			)
		)
		(property "User Part Number" "N_A"
			(at 1.30175 1.27 0)
			(unlocked yes)
			(layer "Cmts.User")
			(hide yes)
			(effects
				(font
					(size 0.635 0.4064)
					(thickness 0.1524)
				)
			)
		)
		(duplicate_pad_numbers_are_jumpers no)
		(fp_line
			(start 0 3.81)
			(end 2.54 3.81)
			(stroke
				(width 0.1524)
				(type default)
			)
			(layer "F.SilkS")
		)
		(fp_line
			(start 2.54 3.81)
			(end 2.54 3.6703)
			(stroke
				(width 0.1524)
				(type default)
			)
			(layer "F.SilkS")
		)
		(fp_line
			(start 0 3.175)
			(end 0 3.81)
			(stroke
				(width 0.1524)
				(type default)
			)
			(layer "F.SilkS")
		)
		(fp_line
			(start 2.54 1.4097)
			(end 2.54 1.1303)
			(stroke
				(width 0.1524)
				(type default)
			)
			(layer "F.SilkS")
		)
		(fp_line
			(start 0 0.635)
			(end 0 1.905)
			(stroke
				(width 0.1524)
				(type default)
			)
			(layer "F.SilkS")
		)
		(fp_line
			(start 2.54 -1.1303)
			(end 2.54 -1.27)
			(stroke
				(width 0.1524)
				(type default)
			)
			(layer "F.SilkS")
		)
		(fp_line
			(start 0 -1.27)
			(end 0 -0.635)
			(stroke
				(width 0.1524)
				(type default)
			)
			(layer "F.SilkS")
		)
		(fp_line
			(start 2.54 -1.27)
			(end 0 -1.27)
			(stroke
				(width 0.1524)
				(type default)
			)
			(layer "F.SilkS")
		)
		(fp_poly
			(pts
				(xy -0.761746 0) (xy -2.285746 -0.762) (xy -2.285746 0.762)
			)
			(stroke
				(width 0)
				(type default)
			)
			(fill yes)
			(layer "F.SilkS")
		)
		(fp_line
			(start 0 3.81)
			(end 2.54 3.81)
			(stroke
				(width 0.1)
				(type default)
			)
			(layer "F.Fab")
		)
		(fp_line
			(start 2.54 3.81)
			(end 2.54 -1.27)
			(stroke
				(width 0.1)
				(type default)
			)
			(layer "F.Fab")
		)
		(fp_line
			(start 0 -1.27)
			(end 0 3.81)
			(stroke
				(width 0.1)
				(type default)
			)
			(layer "F.Fab")
		)
		(fp_line
			(start 2.54 -1.27)
			(end 0 -1.27)
			(stroke
				(width 0.1)
				(type default)
			)
			(layer "F.Fab")
		)
		(fp_poly
			(pts
				(xy -0.761746 0) (xy -2.285746 -0.762) (xy -2.285746 0.762)
			)
			(stroke
				(width 0)
				(type default)
			)
			(fill yes)
			(layer "F.Fab")
		)
		(pad "1" thru_hole circle
			(at 0 0 270)
			(size 1.0033 1.0033)
			(drill 0.249936)
			(layers "*.Cu" "*.Mask")
			(remove_unused_layers no)
			(net "TDR_DIFF_100_BOT_DN")
			(clearance 0.10795)
			(thermal_gap 0.10795)
			(padstack
				(mode front_inner_back)
				(layer "Inner"
					(shape circle)
					(size 0.8001 0.8001)
					(clearance 0.1524)
				)
				(layer "B.Cu"
					(shape circle)
					(size 1.0033 1.0033)
					(clearance 0.10795)
				)
			)
		)
		(pad "2" thru_hole circle
			(at 2.54 0 270)
			(size 1.9939 1.9939)
			(drill 0.249936)
			(layers "*.Cu" "*.Mask")
			(remove_unused_layers no)
			(net "GND_P1")
			(clearance 0.10795)
			(thermal_gap 0.10795)
			(padstack
				(mode front_inner_back)
				(layer "Inner"
					(shape circle)
					(size 0.8001 0.8001)
					(clearance 0.1524)
				)
				(layer "B.Cu"
					(shape circle)
					(size 1.9939 1.9939)
					(clearance 0.10795)
				)
			)
		)
		(pad "3" thru_hole circle
			(at 2.54 2.54 270)
			(size 1.9939 1.9939)
			(drill 0.249936)
			(layers "*.Cu" "*.Mask")
			(remove_unused_layers no)
			(net "GND_P1")
			(clearance 0.10795)
			(thermal_gap 0.10795)
			(padstack
				(mode front_inner_back)
				(layer "Inner"
					(shape circle)
					(size 0.8001 0.8001)
					(clearance 0.1524)
				)
				(layer "B.Cu"
					(shape circle)
					(size 1.9939 1.9939)
					(clearance 0.10795)
				)
			)
		)
		(pad "4" thru_hole circle
			(at 0 2.54 270)
			(size 1.0033 1.0033)
			(drill 0.249936)
			(layers "*.Cu" "*.Mask")
			(remove_unused_layers no)
			(net "TDR_DIFF_100_BOT_DP")
			(clearance 0.10795)
			(thermal_gap 0.10795)
			(padstack
				(mode front_inner_back)
				(layer "Inner"
					(shape circle)
					(size 0.8001 0.8001)
					(clearance 0.1524)
				)
				(layer "B.Cu"
					(shape circle)
					(size 1.0033 1.0033)
					(clearance 0.10795)
				)
			)
		)
	)
	(footprint ""
		(layer "F.Cu")
		(at 64.9732 -25.0444 180)
		(property "Reference" "R512"
			(at 0 0 180)
			(layer "F.SilkS")
			(hide yes)
			(effects
				(font
					(size 1.27 1.27)
				)
			)
		)
		(property "Value" ""
			(at 0 0 180)
			(layer "F.Fab")
			(effects
				(font
					(size 1.27 1.27)
				)
			)
		)
		(duplicate_pad_numbers_are_jumpers no)
		(fp_line
			(start 0.7874 0.4064)
			(end -0.7874 0.4064)
			(stroke
				(width 0.1524)
				(type default)
			)
			(layer "F.SilkS")
		)
		(fp_line
			(start 0.7874 -0.4064)
			(end 0.7874 0.4064)
			(stroke
				(width 0.1524)
				(type default)
			)
			(layer "F.SilkS")
		)
		(fp_line
			(start -0.7874 0.4064)
			(end -0.7874 -0.4064)
			(stroke
				(width 0.1524)
				(type default)
			)
			(layer "F.SilkS")
		)
		(fp_line
			(start -0.7874 -0.4064)
			(end 0.7874 -0.4064)
			(stroke
				(width 0.1524)
				(type default)
			)
			(layer "F.SilkS")
		)
		(fp_line
			(start 0.67945 0.3048)
			(end 0.120396 0.3048)
			(stroke
				(width 0.1)
				(type default)
			)
			(layer "F.Fab")
		)
		(fp_line
			(start 0.67945 -0.3048)
			(end 0.67945 0.3048)
			(stroke
				(width 0.1)
				(type default)
			)
			(layer "F.Fab")
		)
		(fp_line
			(start 0.12065 -0.2794)
			(end 0.12065 -0.3048)
			(stroke
				(width 0.1)
				(type default)
			)
			(layer "F.Fab")
		)
		(fp_line
			(start 0.12065 -0.3048)
			(end 0.67945 -0.3048)
			(stroke
				(width 0.1)
				(type default)
			)
			(layer "F.Fab")
		)
		(fp_line
			(start 0.120396 0.3048)
			(end 0.120396 0.2794)
			(stroke
				(width 0.1)
				(type default)
			)
			(layer "F.Fab")
		)
		(fp_line
			(start 0.120396 0.2794)
			(end -0.12065 0.2794)
			(stroke
				(width 0.1)
				(type default)
			)
			(layer "F.Fab")
		)
		(fp_line
			(start -0.12065 0.3048)
			(end -0.67945 0.3048)
			(stroke
				(width 0.1)
				(type default)
			)
			(layer "F.Fab")
		)
		(fp_line
			(start -0.12065 0.2794)
			(end -0.12065 0.3048)
			(stroke
				(width 0.1)
				(type default)
			)
			(layer "F.Fab")
		)
		(fp_line
			(start -0.12065 -0.2794)
			(end 0.12065 -0.2794)
			(stroke
				(width 0.1)
				(type default)
			)
			(layer "F.Fab")
		)
		(fp_line
			(start -0.12065 -0.305054)
			(end -0.12065 -0.2794)
			(stroke
				(width 0.1)
				(type default)
			)
			(layer "F.Fab")
		)
		(fp_line
			(start -0.67945 0.3048)
			(end -0.67945 -0.305054)
			(stroke
				(width 0.1)
				(type default)
			)
			(layer "F.Fab")
		)
		(fp_line
			(start -0.67945 -0.305054)
			(end -0.12065 -0.305054)
			(stroke
				(width 0.1)
				(type default)
			)
			(layer "F.Fab")
		)
		(pad "1" smd circle
			(at -0.40005 0 180)
			(size 0 0)
			(layers "F.Cu" "F.Mask" "F.Paste")
			(net "JTAG_SCM_TDI")
		)
		(pad "2" smd circle
			(at 0.40005 0 180)
			(size 0 0)
			(layers "F.Cu" "F.Mask" "F.Paste")
			(net "JTAG_SCM_PLD_TDI")
		)
	)
	(footprint ""
		(layer "F.Cu")
		(at 63.246 -79.629)
		(property "Reference" "R506"
			(at 0 0 0)
			(layer "F.SilkS")
			(hide yes)
			(effects
				(font
					(size 1.27 1.27)
				)
			)
		)
		(property "Value" ""
			(at 0 0 0)
			(layer "F.Fab")
			(effects
				(font
					(size 1.27 1.27)
				)
			)
		)
		(duplicate_pad_numbers_are_jumpers no)
		(fp_line
			(start -0.7874 -0.4064)
			(end 0.7874 -0.4064)
			(stroke
				(width 0.1524)
				(type default)
			)
			(layer "F.SilkS")
		)
		(fp_line
			(start -0.7874 0.4064)
			(end -0.7874 -0.4064)
			(stroke
				(width 0.1524)
				(type default)
			)
			(layer "F.SilkS")
		)
		(fp_line
			(start 0.7874 -0.4064)
			(end 0.7874 0.4064)
			(stroke
				(width 0.1524)
				(type default)
			)
			(layer "F.SilkS")
		)
		(fp_line
			(start 0.7874 0.4064)
			(end -0.7874 0.4064)
			(stroke
				(width 0.1524)
				(type default)
			)
			(layer "F.SilkS")
		)
		(fp_line
			(start -0.67945 -0.305054)
			(end -0.12065 -0.305054)
			(stroke
				(width 0.1)
				(type default)
			)
			(layer "F.Fab")
		)
		(fp_line
			(start -0.67945 0.3048)
			(end -0.67945 -0.305054)
			(stroke
				(width 0.1)
				(type default)
			)
			(layer "F.Fab")
		)
		(fp_line
			(start -0.12065 -0.305054)
			(end -0.12065 -0.2794)
			(stroke
				(width 0.1)
				(type default)
			)
			(layer "F.Fab")
		)
		(fp_line
			(start -0.12065 -0.2794)
			(end 0.12065 -0.2794)
			(stroke
				(width 0.1)
				(type default)
			)
			(layer "F.Fab")
		)
		(fp_line
			(start -0.12065 0.2794)
			(end -0.12065 0.3048)
			(stroke
				(width 0.1)
				(type default)
			)
			(layer "F.Fab")
		)
		(fp_line
			(start -0.12065 0.3048)
			(end -0.67945 0.3048)
			(stroke
				(width 0.1)
				(type default)
			)
			(layer "F.Fab")
		)
		(fp_line
			(start 0.120396 0.2794)
			(end -0.12065 0.2794)
			(stroke
				(width 0.1)
				(type default)
			)
			(layer "F.Fab")
		)
		(fp_line
			(start 0.120396 0.3048)
			(end 0.120396 0.2794)
			(stroke
				(width 0.1)
				(type default)
			)
			(layer "F.Fab")
		)
		(fp_line
			(start 0.12065 -0.3048)
			(end 0.67945 -0.3048)
			(stroke
				(width 0.1)
				(type default)
			)
			(layer "F.Fab")
		)
		(fp_line
			(start 0.12065 -0.2794)
			(end 0.12065 -0.3048)
			(stroke
				(width 0.1)
				(type default)
			)
			(layer "F.Fab")
		)
		(fp_line
			(start 0.67945 -0.3048)
			(end 0.67945 0.3048)
			(stroke
				(width 0.1)
				(type default)
			)
			(layer "F.Fab")
		)
		(fp_line
			(start 0.67945 0.3048)
			(end 0.120396 0.3048)
			(stroke
				(width 0.1)
				(type default)
			)
			(layer "F.Fab")
		)
		(pad "1" smd circle
			(at -0.40005 0)
			(size 0 0)
			(layers "F.Cu" "F.Mask" "F.Paste")
			(net "FM_BMC_DEBUG_SW_N")
		)
		(pad "2" smd circle
			(at 0.40005 0)
			(size 0 0)
			(layers "F.Cu" "F.Mask" "F.Paste")
			(net "GND")
		)
	)
	(footprint ""
		(layer "F.Cu")
		(at 44.196 -67.7672)
		(property "Reference" "D8"
			(at -3.470656 -0.119634 0)
			(unlocked yes)
			(layer "F.SilkS")
			(effects
				(font
					(size 0.7874 0.5842)
					(thickness 0.1524)
				)
				(justify left)
			)
		)
		(property "Value" ""
			(at 0 0 0)
			(layer "F.Fab")
			(effects
				(font
					(size 1.27 1.27)
				)
			)
		)
		(duplicate_pad_numbers_are_jumpers no)
		(fp_line
			(start -1.3208 -0.5588)
			(end 1.3208 -0.5588)
			(stroke
				(width 0.1524)
				(type default)
			)
			(layer "F.SilkS")
		)
		(fp_line
			(start -1.3208 0.5588)
			(end -1.3208 -0.5588)
			(stroke
				(width 0.1524)
				(type default)
			)
			(layer "F.SilkS")
		)
		(fp_line
			(start 1.3208 -0.5588)
			(end 1.3208 0.5588)
			(stroke
				(width 0.1524)
				(type default)
			)
			(layer "F.SilkS")
		)
		(fp_line
			(start 1.3208 0.5588)
			(end -1.3208 0.5588)
			(stroke
				(width 0.1524)
				(type default)
			)
			(layer "F.SilkS")
		)
		(fp_line
			(start 1.4732 -0.5588)
			(end 1.4732 0.5588)
			(stroke
				(width 0.1524)
				(type default)
			)
			(layer "F.SilkS")
		)
		(fp_line
			(start 1.6256 0.5588)
			(end 1.6256 -0.5588)
			(stroke
				(width 0.1524)
				(type default)
			)
			(layer "F.SilkS")
		)
		(fp_line
			(start 1.778 -0.5588)
			(end 1.3208 -0.5588)
			(stroke
				(width 0.1524)
				(type default)
			)
			(layer "F.SilkS")
		)
		(fp_line
			(start 1.778 -0.5588)
			(end 1.778 0.5588)
			(stroke
				(width 0.1524)
				(type default)
			)
			(layer "F.SilkS")
		)
		(fp_line
			(start 1.778 0.5588)
			(end 1.3208 0.5588)
			(stroke
				(width 0.1524)
				(type default)
			)
			(layer "F.SilkS")
		)
		(fp_line
			(start -1.235964 -0.508)
			(end -1.235964 0.508)
			(stroke
				(width 0.1)
				(type default)
			)
			(layer "F.Fab")
		)
		(fp_line
			(start -1.235964 0.508)
			(end -1.1684 0.508)
			(stroke
				(width 0.1)
				(type default)
			)
			(layer "F.Fab")
		)
		(fp_line
			(start -1.1684 -0.508)
			(end -1.235964 -0.508)
			(stroke
				(width 0.1)
				(type default)
			)
			(layer "F.Fab")
		)
		(fp_line
			(start -1.1684 0.508)
			(end 1.1684 0.508)
			(stroke
				(width 0.1)
				(type default)
			)
			(layer "F.Fab")
		)
		(fp_line
			(start 1.1684 -0.508)
			(end -1.1684 -0.508)
			(stroke
				(width 0.1)
				(type default)
			)
			(layer "F.Fab")
		)
		(fp_line
			(start 1.1684 0.508)
			(end 1.236726 0.508)
			(stroke
				(width 0.1)
				(type default)
			)
			(layer "F.Fab")
		)
		(fp_line
			(start 1.236726 -0.508)
			(end 1.1684 -0.508)
			(stroke
				(width 0.1)
				(type default)
			)
			(layer "F.Fab")
		)
		(fp_line
			(start 1.236726 0.508)
			(end 1.236726 -0.508)
			(stroke
				(width 0.1)
				(type default)
			)
			(layer "F.Fab")
		)
		(fp_text user "+"
			(at -2.286 -1.06045 0)
			(unlocked yes)
			(layer "F.SilkS")
			(effects
				(font
					(size 1.905 1.4224)
					(thickness 0.1524)
				)
				(justify left)
			)
		)
		(fp_text user "-"
			(at 2.00025 0.7112 90)
			(unlocked yes)
			(layer "F.SilkS")
			(effects
				(font
					(size 1.905 1.4224)
					(thickness 0.1524)
				)
				(justify left)
			)
		)
		(fp_text user "+"
			(at -2.5654 -0.24765 0)
			(unlocked yes)
			(layer "F.Fab")
			(effects
				(font
					(size 1.905 1.4224)
					(thickness 0.1524)
				)
				(justify left)
			)
		)
		(fp_text user "-"
			(at 1.524 -0.24765 0)
			(unlocked yes)
			(layer "F.Fab")
			(effects
				(font
					(size 1.905 1.4224)
					(thickness 0.1524)
				)
				(justify left)
			)
		)
		(pad "A" smd rect
			(at -0.750062 0)
			(size 0.8128 0.8128)
			(layers "F.Cu" "F.Mask" "F.Paste")
			(net "BMC_HEARTBEAT_R_N")
		)
		(pad "C" smd rect
			(at 0.750062 0)
			(size 0.8128 0.8128)
			(layers "F.Cu" "F.Mask" "F.Paste")
			(net "BMC_HEARTBEAT_N")
		)
	)
	(footprint ""
		(layer "F.Cu")
		(at 12.319 -83.312 180)
		(property "Reference" "R439"
			(at 0 0 180)
			(layer "F.SilkS")
			(hide yes)
			(effects
				(font
					(size 1.27 1.27)
				)
			)
		)
		(property "Value" ""
			(at 0 0 180)
			(layer "F.Fab")
			(effects
				(font
					(size 1.27 1.27)
				)
			)
		)
		(duplicate_pad_numbers_are_jumpers no)
		(fp_line
			(start 0.7874 0.4064)
			(end -0.7874 0.4064)
			(stroke
				(width 0.1524)
				(type default)
			)
			(layer "F.SilkS")
		)
		(fp_line
			(start 0.7874 -0.4064)
			(end 0.7874 0.4064)
			(stroke
				(width 0.1524)
				(type default)
			)
			(layer "F.SilkS")
		)
		(fp_line
			(start -0.7874 0.4064)
			(end -0.7874 -0.4064)
			(stroke
				(width 0.1524)
				(type default)
			)
			(layer "F.SilkS")
		)
		(fp_line
			(start -0.7874 -0.4064)
			(end 0.7874 -0.4064)
			(stroke
				(width 0.1524)
				(type default)
			)
			(layer "F.SilkS")
		)
		(fp_line
			(start 0.67945 0.3048)
			(end 0.120396 0.3048)
			(stroke
				(width 0.1)
				(type default)
			)
			(layer "F.Fab")
		)
		(fp_line
			(start 0.67945 -0.3048)
			(end 0.67945 0.3048)
			(stroke
				(width 0.1)
				(type default)
			)
			(layer "F.Fab")
		)
		(fp_line
			(start 0.12065 -0.2794)
			(end 0.12065 -0.3048)
			(stroke
				(width 0.1)
				(type default)
			)
			(layer "F.Fab")
		)
		(fp_line
			(start 0.12065 -0.3048)
			(end 0.67945 -0.3048)
			(stroke
				(width 0.1)
				(type default)
			)
			(layer "F.Fab")
		)
		(fp_line
			(start 0.120396 0.3048)
			(end 0.120396 0.2794)
			(stroke
				(width 0.1)
				(type default)
			)
			(layer "F.Fab")
		)
		(fp_line
			(start 0.120396 0.2794)
			(end -0.12065 0.2794)
			(stroke
				(width 0.1)
				(type default)
			)
			(layer "F.Fab")
		)
		(fp_line
			(start -0.12065 0.3048)
			(end -0.67945 0.3048)
			(stroke
				(width 0.1)
				(type default)
			)
			(layer "F.Fab")
		)
		(fp_line
			(start -0.12065 0.2794)
			(end -0.12065 0.3048)
			(stroke
				(width 0.1)
				(type default)
			)
			(layer "F.Fab")
		)
		(fp_line
			(start -0.12065 -0.2794)
			(end 0.12065 -0.2794)
			(stroke
				(width 0.1)
				(type default)
			)
			(layer "F.Fab")
		)
		(fp_line
			(start -0.12065 -0.305054)
			(end -0.12065 -0.2794)
			(stroke
				(width 0.1)
				(type default)
			)
			(layer "F.Fab")
		)
		(fp_line
			(start -0.67945 0.3048)
			(end -0.67945 -0.305054)
			(stroke
				(width 0.1)
				(type default)
			)
			(layer "F.Fab")
		)
		(fp_line
			(start -0.67945 -0.305054)
			(end -0.12065 -0.305054)
			(stroke
				(width 0.1)
				(type default)
			)
			(layer "F.Fab")
		)
		(pad "1" smd circle
			(at -0.40005 0 180)
			(size 0 0)
			(layers "F.Cu" "F.Mask" "F.Paste")
			(net "FM_PECI_SEL_N")
		)
		(pad "2" smd circle
			(at 0.40005 0 180)
			(size 0 0)
			(layers "F.Cu" "F.Mask" "F.Paste")
			(net "FM_PECI_SEL_R_N")
		)
	)
	(footprint ""
		(layer "F.Cu")
		(at 69.0626 -108.0262 -90)
		(property "Reference" "R594"
			(at 0 0 270)
			(layer "F.SilkS")
			(hide yes)
			(effects
				(font
					(size 1.27 1.27)
				)
			)
		)
		(property "Value" ""
			(at 0 0 270)
			(layer "F.Fab")
			(effects
				(font
					(size 1.27 1.27)
				)
			)
		)
		(duplicate_pad_numbers_are_jumpers no)
		(fp_line
			(start -0.7874 0.4064)
			(end -0.7874 -0.4064)
			(stroke
				(width 0.1524)
				(type default)
			)
			(layer "F.SilkS")
		)
		(fp_line
			(start 0.7874 0.4064)
			(end -0.7874 0.4064)
			(stroke
				(width 0.1524)
				(type default)
			)
			(layer "F.SilkS")
		)
		(fp_line
			(start -0.7874 -0.4064)
			(end 0.7874 -0.4064)
			(stroke
				(width 0.1524)
				(type default)
			)
			(layer "F.SilkS")
		)
		(fp_line
			(start 0.7874 -0.4064)
			(end 0.7874 0.4064)
			(stroke
				(width 0.1524)
				(type default)
			)
			(layer "F.SilkS")
		)
		(fp_line
			(start -0.67945 0.3048)
			(end -0.67945 -0.305054)
			(stroke
				(width 0.1)
				(type default)
			)
			(layer "F.Fab")
		)
		(fp_line
			(start -0.12065 0.3048)
			(end -0.67945 0.3048)
			(stroke
				(width 0.1)
				(type default)
			)
			(layer "F.Fab")
		)
		(fp_line
			(start 0.120396 0.3048)
			(end 0.120396 0.2794)
			(stroke
				(width 0.1)
				(type default)
			)
			(layer "F.Fab")
		)
		(fp_line
			(start 0.67945 0.3048)
			(end 0.120396 0.3048)
			(stroke
				(width 0.1)
				(type default)
			)
			(layer "F.Fab")
		)
		(fp_line
			(start -0.12065 0.2794)
			(end -0.12065 0.3048)
			(stroke
				(width 0.1)
				(type default)
			)
			(layer "F.Fab")
		)
		(fp_line
			(start 0.120396 0.2794)
			(end -0.12065 0.2794)
			(stroke
				(width 0.1)
				(type default)
			)
			(layer "F.Fab")
		)
		(fp_line
			(start -0.12065 -0.2794)
			(end 0.12065 -0.2794)
			(stroke
				(width 0.1)
				(type default)
			)
			(layer "F.Fab")
		)
		(fp_line
			(start 0.12065 -0.2794)
			(end 0.12065 -0.3048)
			(stroke
				(width 0.1)
				(type default)
			)
			(layer "F.Fab")
		)
		(fp_line
			(start 0.12065 -0.3048)
			(end 0.67945 -0.3048)
			(stroke
				(width 0.1)
				(type default)
			)
			(layer "F.Fab")
		)
		(fp_line
			(start 0.67945 -0.3048)
			(end 0.67945 0.3048)
			(stroke
				(width 0.1)
				(type default)
			)
			(layer "F.Fab")
		)
		(fp_line
			(start -0.67945 -0.305054)
			(end -0.12065 -0.305054)
			(stroke
				(width 0.1)
				(type default)
			)
			(layer "F.Fab")
		)
		(fp_line
			(start -0.12065 -0.305054)
			(end -0.12065 -0.2794)
			(stroke
				(width 0.1)
				(type default)
			)
			(layer "F.Fab")
		)
		(pad "1" smd circle
			(at -0.40005 0 270)
			(size 0 0)
			(layers "F.Cu" "F.Mask" "F.Paste")
			(net "SPI_TPM_CS_N")
		)
		(pad "2" smd circle
			(at 0.40005 0 270)
			(size 0 0)
			(layers "F.Cu" "F.Mask" "F.Paste")
			(net "SPI_TPM_CS_R_N")
		)
	)
	(footprint ""
		(layer "F.Cu")
		(at 75.646534 -31.764986 -90)
		(property "Reference" "D6"
			(at 4.129786 -8.123936 90)
			(unlocked yes)
			(layer "F.SilkS")
			(effects
				(font
					(size 0.7874 0.5842)
					(thickness 0.1524)
				)
				(justify left)
			)
		)
		(property "Value" ""
			(at 0 0 270)
			(layer "F.Fab")
			(effects
				(font
					(size 1.27 1.27)
				)
			)
		)
		(duplicate_pad_numbers_are_jumpers no)
		(fp_line
			(start -1.3208 0.5588)
			(end -1.3208 -0.5588)
			(stroke
				(width 0.1524)
				(type default)
			)
			(layer "F.SilkS")
		)
		(fp_line
			(start 1.3208 0.5588)
			(end -1.3208 0.5588)
			(stroke
				(width 0.1524)
				(type default)
			)
			(layer "F.SilkS")
		)
		(fp_line
			(start 1.6256 0.5588)
			(end 1.6256 -0.5588)
			(stroke
				(width 0.1524)
				(type default)
			)
			(layer "F.SilkS")
		)
		(fp_line
			(start 1.778 0.5588)
			(end 1.3208 0.5588)
			(stroke
				(width 0.1524)
				(type default)
			)
			(layer "F.SilkS")
		)
		(fp_line
			(start -1.3208 -0.5588)
			(end 1.3208 -0.5588)
			(stroke
				(width 0.1524)
				(type default)
			)
			(layer "F.SilkS")
		)
		(fp_line
			(start 1.3208 -0.5588)
			(end 1.3208 0.5588)
			(stroke
				(width 0.1524)
				(type default)
			)
			(layer "F.SilkS")
		)
		(fp_line
			(start 1.4732 -0.5588)
			(end 1.4732 0.5588)
			(stroke
				(width 0.1524)
				(type default)
			)
			(layer "F.SilkS")
		)
		(fp_line
			(start 1.778 -0.5588)
			(end 1.778 0.5588)
			(stroke
				(width 0.1524)
				(type default)
			)
			(layer "F.SilkS")
		)
		(fp_line
			(start 1.778 -0.5588)
			(end 1.3208 -0.5588)
			(stroke
				(width 0.1524)
				(type default)
			)
			(layer "F.SilkS")
		)
		(fp_line
			(start -0.8001 0.40005)
			(end -0.8001 -0.40005)
			(stroke
				(width 0.1)
				(type default)
			)
			(layer "F.Fab")
		)
		(fp_line
			(start 0.8001 0.40005)
			(end -0.8001 0.40005)
			(stroke
				(width 0.1)
				(type default)
			)
			(layer "F.Fab")
		)
		(fp_line
			(start -0.8001 -0.40005)
			(end 0.8001 -0.40005)
			(stroke
				(width 0.1)
				(type default)
			)
			(layer "F.Fab")
		)
		(fp_line
			(start 0.8001 -0.40005)
			(end 0.8001 0.40005)
			(stroke
				(width 0.1)
				(type default)
			)
			(layer "F.Fab")
		)
		(fp_text user "+"
			(at -1.718564 -0.604266 180)
			(unlocked yes)
			(layer "F.SilkS")
			(effects
				(font
					(size 1.905 1.4224)
					(thickness 0.1524)
				)
				(justify left)
			)
		)
		(fp_text user "-"
			(at 0.472186 -1.029716 270)
			(unlocked yes)
			(layer "F.SilkS")
			(effects
				(font
					(size 1.905 1.4224)
					(thickness 0.1524)
				)
				(justify left)
			)
		)
		(fp_text user "+"
			(at -2.5654 -0.22225 270)
			(unlocked yes)
			(layer "F.Fab")
			(effects
				(font
					(size 1.905 1.4224)
					(thickness 0.1524)
				)
				(justify left)
			)
		)
		(fp_text user "-"
			(at 1.6256 -0.22225 270)
			(unlocked yes)
			(layer "F.Fab")
			(effects
				(font
					(size 1.905 1.4224)
					(thickness 0.1524)
				)
				(justify left)
			)
		)
		(pad "A" smd rect
			(at -0.750062 0 270)
			(size 0.8128 0.8128)
			(layers "F.Cu" "F.Mask" "F.Paste")
			(net "LED_POSTCODE_6_R")
		)
		(pad "C" smd rect
			(at 0.750062 0 270)
			(size 0.8128 0.8128)
			(layers "F.Cu" "F.Mask" "F.Paste")
			(net "GND")
		)
	)
	(footprint ""
		(layer "F.Cu")
		(at 14.351 -109.347 90)
		(property "Reference" "C272"
			(at 0 0 90)
			(layer "F.SilkS")
			(hide yes)
			(effects
				(font
					(size 1.27 1.27)
				)
			)
		)
		(property "Value" ""
			(at 0 0 90)
			(layer "F.Fab")
			(effects
				(font
					(size 1.27 1.27)
				)
			)
		)
		(duplicate_pad_numbers_are_jumpers no)
		(fp_line
			(start -0.4572 -0.4064)
			(end 0.381 -0.4064)
			(stroke
				(width 0.1524)
				(type default)
			)
			(layer "F.SilkS")
		)
		(fp_line
			(start 0.7874 0.0254)
			(end 0.7874 0.4064)
			(stroke
				(width 0.1524)
				(type default)
			)
			(layer "F.SilkS")
		)
		(fp_line
			(start 0.7874 0.4064)
			(end -0.7874 0.4064)
			(stroke
				(width 0.1524)
				(type default)
			)
			(layer "F.SilkS")
		)
		(fp_line
			(start -0.7874 0.4064)
			(end -0.7874 0.0254)
			(stroke
				(width 0.1524)
				(type default)
			)
			(layer "F.SilkS")
		)
		(fp_line
			(start -0.12065 -0.305054)
			(end -0.12065 -0.2794)
			(stroke
				(width 0.1)
				(type default)
			)
			(layer "F.Fab")
		)
		(fp_line
			(start -0.67945 -0.305054)
			(end -0.12065 -0.305054)
			(stroke
				(width 0.1)
				(type default)
			)
			(layer "F.Fab")
		)
		(fp_line
			(start 0.67945 -0.3048)
			(end 0.67945 0.3048)
			(stroke
				(width 0.1)
				(type default)
			)
			(layer "F.Fab")
		)
		(fp_line
			(start 0.12065 -0.3048)
			(end 0.67945 -0.3048)
			(stroke
				(width 0.1)
				(type default)
			)
			(layer "F.Fab")
		)
		(fp_line
			(start 0.12065 -0.2794)
			(end 0.12065 -0.3048)
			(stroke
				(width 0.1)
				(type default)
			)
			(layer "F.Fab")
		)
		(fp_line
			(start -0.12065 -0.2794)
			(end 0.12065 -0.2794)
			(stroke
				(width 0.1)
				(type default)
			)
			(layer "F.Fab")
		)
		(fp_line
			(start 0.120396 0.2794)
			(end -0.12065 0.2794)
			(stroke
				(width 0.1)
				(type default)
			)
			(layer "F.Fab")
		)
		(fp_line
			(start -0.12065 0.2794)
			(end -0.12065 0.3048)
			(stroke
				(width 0.1)
				(type default)
			)
			(layer "F.Fab")
		)
		(fp_line
			(start 0.67945 0.3048)
			(end 0.120396 0.3048)
			(stroke
				(width 0.1)
				(type default)
			)
			(layer "F.Fab")
		)
		(fp_line
			(start 0.120396 0.3048)
			(end 0.120396 0.2794)
			(stroke
				(width 0.1)
				(type default)
			)
			(layer "F.Fab")
		)
		(fp_line
			(start -0.12065 0.3048)
			(end -0.67945 0.3048)
			(stroke
				(width 0.1)
				(type default)
			)
			(layer "F.Fab")
		)
		(fp_line
			(start -0.67945 0.3048)
			(end -0.67945 -0.305054)
			(stroke
				(width 0.1)
				(type default)
			)
			(layer "F.Fab")
		)
		(pad "1" smd circle
			(at -0.40005 0 90)
			(size 0 0)
			(layers "F.Cu" "F.Mask" "F.Paste")
			(net "P2E_GPU_TX_DP")
		)
		(pad "2" smd circle
			(at 0.40005 0 90)
			(size 0 0)
			(layers "F.Cu" "F.Mask" "F.Paste")
			(net "P2E_GPU_TX_C_DP")
		)
	)
	(footprint ""
		(layer "F.Cu")
		(at 21.168614 -25.111202 -90)
		(property "Reference" "PL33"
			(at 0 0 270)
			(layer "F.SilkS")
			(hide yes)
			(effects
				(font
					(size 1.27 1.27)
				)
			)
		)
		(property "Value" ""
			(at 0 0 270)
			(layer "F.Fab")
			(effects
				(font
					(size 1.27 1.27)
				)
			)
		)
		(duplicate_pad_numbers_are_jumpers no)
		(fp_line
			(start -3.64998 3.350006)
			(end -3.64998 1.8288)
			(stroke
				(width 0.1524)
				(type default)
			)
			(layer "F.SilkS")
		)
		(fp_line
			(start 3.64998 3.350006)
			(end -3.64998 3.350006)
			(stroke
				(width 0.1524)
				(type default)
			)
			(layer "F.SilkS")
		)
		(fp_line
			(start 3.64998 1.8034)
			(end 3.64998 3.350006)
			(stroke
				(width 0.1524)
				(type default)
			)
			(layer "F.SilkS")
		)
		(fp_line
			(start -3.64998 -1.8034)
			(end -3.64998 -3.350006)
			(stroke
				(width 0.1524)
				(type default)
			)
			(layer "F.SilkS")
		)
		(fp_line
			(start -3.6576 -3.350006)
			(end 3.64998 -3.350006)
			(stroke
				(width 0.1524)
				(type default)
			)
			(layer "F.SilkS")
		)
		(fp_line
			(start 3.64998 -3.350006)
			(end 3.64998 -1.8034)
			(stroke
				(width 0.1524)
				(type default)
			)
			(layer "F.SilkS")
		)
		(fp_line
			(start -3.64998 3.350006)
			(end -3.64998 -3.350006)
			(stroke
				(width 0.1)
				(type default)
			)
			(layer "F.Fab")
		)
		(fp_line
			(start 3.64998 3.350006)
			(end -3.64998 3.350006)
			(stroke
				(width 0.1)
				(type default)
			)
			(layer "F.Fab")
		)
		(fp_line
			(start -3.64998 -3.350006)
			(end 3.64998 -3.350006)
			(stroke
				(width 0.1)
				(type default)
			)
			(layer "F.Fab")
		)
		(fp_line
			(start 3.64998 -3.350006)
			(end 3.64998 3.350006)
			(stroke
				(width 0.1)
				(type default)
			)
			(layer "F.Fab")
		)
		(pad "1" smd rect
			(at -2.92481 0 270)
			(size 2.15392 3.302)
			(layers "F.Cu" "F.Mask" "F.Paste")
			(net "SW_P1V0_AUX_SW")
		)
		(pad "2" smd rect
			(at 2.92481 0 270)
			(size 2.15392 3.302)
			(layers "F.Cu" "F.Mask" "F.Paste")
			(net "P1V0_AUX")
		)
	)
	(footprint ""
		(layer "F.Cu")
		(at 53.594 -10.795 90)
		(property "Reference" "R107"
			(at 0 0 90)
			(layer "F.SilkS")
			(hide yes)
			(effects
				(font
					(size 1.27 1.27)
				)
			)
		)
		(property "Value" ""
			(at 0 0 90)
			(layer "F.Fab")
			(effects
				(font
					(size 1.27 1.27)
				)
			)
		)
		(duplicate_pad_numbers_are_jumpers no)
		(fp_line
			(start 0.7874 -0.4064)
			(end 0.7874 0.4064)
			(stroke
				(width 0.1524)
				(type default)
			)
			(layer "F.SilkS")
		)
		(fp_line
			(start -0.7874 -0.4064)
			(end 0.7874 -0.4064)
			(stroke
				(width 0.1524)
				(type default)
			)
			(layer "F.SilkS")
		)
		(fp_line
			(start 0.7874 0.4064)
			(end -0.7874 0.4064)
			(stroke
				(width 0.1524)
				(type default)
			)
			(layer "F.SilkS")
		)
		(fp_line
			(start -0.7874 0.4064)
			(end -0.7874 -0.4064)
			(stroke
				(width 0.1524)
				(type default)
			)
			(layer "F.SilkS")
		)
		(fp_line
			(start -0.12065 -0.305054)
			(end -0.12065 -0.2794)
			(stroke
				(width 0.1)
				(type default)
			)
			(layer "F.Fab")
		)
		(fp_line
			(start -0.67945 -0.305054)
			(end -0.12065 -0.305054)
			(stroke
				(width 0.1)
				(type default)
			)
			(layer "F.Fab")
		)
		(fp_line
			(start 0.67945 -0.3048)
			(end 0.67945 0.3048)
			(stroke
				(width 0.1)
				(type default)
			)
			(layer "F.Fab")
		)
		(fp_line
			(start 0.12065 -0.3048)
			(end 0.67945 -0.3048)
			(stroke
				(width 0.1)
				(type default)
			)
			(layer "F.Fab")
		)
		(fp_line
			(start 0.12065 -0.2794)
			(end 0.12065 -0.3048)
			(stroke
				(width 0.1)
				(type default)
			)
			(layer "F.Fab")
		)
		(fp_line
			(start -0.12065 -0.2794)
			(end 0.12065 -0.2794)
			(stroke
				(width 0.1)
				(type default)
			)
			(layer "F.Fab")
		)
		(fp_line
			(start 0.120396 0.2794)
			(end -0.12065 0.2794)
			(stroke
				(width 0.1)
				(type default)
			)
			(layer "F.Fab")
		)
		(fp_line
			(start -0.12065 0.2794)
			(end -0.12065 0.3048)
			(stroke
				(width 0.1)
				(type default)
			)
			(layer "F.Fab")
		)
		(fp_line
			(start 0.67945 0.3048)
			(end 0.120396 0.3048)
			(stroke
				(width 0.1)
				(type default)
			)
			(layer "F.Fab")
		)
		(fp_line
			(start 0.120396 0.3048)
			(end 0.120396 0.2794)
			(stroke
				(width 0.1)
				(type default)
			)
			(layer "F.Fab")
		)
		(fp_line
			(start -0.12065 0.3048)
			(end -0.67945 0.3048)
			(stroke
				(width 0.1)
				(type default)
			)
			(layer "F.Fab")
		)
		(fp_line
			(start -0.67945 0.3048)
			(end -0.67945 -0.305054)
			(stroke
				(width 0.1)
				(type default)
			)
			(layer "F.Fab")
		)
		(pad "1" smd circle
			(at -0.40005 0 90)
			(size 0 0)
			(layers "F.Cu" "F.Mask" "F.Paste")
			(net "LED_D21_R3")
		)
		(pad "2" smd circle
			(at 0.40005 0 90)
			(size 0 0)
			(layers "F.Cu" "F.Mask" "F.Paste")
			(net "LED_D21_R2")
		)
	)
	(footprint ""
		(layer "F.Cu")
		(at 29.27604 -70.536054 90)
		(property "Reference" "R650"
			(at 0 0 90)
			(layer "F.SilkS")
			(hide yes)
			(effects
				(font
					(size 1.27 1.27)
				)
			)
		)
		(property "Value" ""
			(at 0 0 90)
			(layer "F.Fab")
			(effects
				(font
					(size 1.27 1.27)
				)
			)
		)
		(duplicate_pad_numbers_are_jumpers no)
		(fp_line
			(start 0.7874 -0.4064)
			(end 0.7874 0.4064)
			(stroke
				(width 0.1524)
				(type default)
			)
			(layer "F.SilkS")
		)
		(fp_line
			(start -0.7874 -0.4064)
			(end 0.7874 -0.4064)
			(stroke
				(width 0.1524)
				(type default)
			)
			(layer "F.SilkS")
		)
		(fp_line
			(start 0.7874 0.4064)
			(end -0.7874 0.4064)
			(stroke
				(width 0.1524)
				(type default)
			)
			(layer "F.SilkS")
		)
		(fp_line
			(start -0.7874 0.4064)
			(end -0.7874 -0.4064)
			(stroke
				(width 0.1524)
				(type default)
			)
			(layer "F.SilkS")
		)
		(fp_line
			(start -0.12065 -0.305054)
			(end -0.12065 -0.2794)
			(stroke
				(width 0.1)
				(type default)
			)
			(layer "F.Fab")
		)
		(fp_line
			(start -0.67945 -0.305054)
			(end -0.12065 -0.305054)
			(stroke
				(width 0.1)
				(type default)
			)
			(layer "F.Fab")
		)
		(fp_line
			(start 0.67945 -0.3048)
			(end 0.67945 0.3048)
			(stroke
				(width 0.1)
				(type default)
			)
			(layer "F.Fab")
		)
		(fp_line
			(start 0.12065 -0.3048)
			(end 0.67945 -0.3048)
			(stroke
				(width 0.1)
				(type default)
			)
			(layer "F.Fab")
		)
		(fp_line
			(start 0.12065 -0.2794)
			(end 0.12065 -0.3048)
			(stroke
				(width 0.1)
				(type default)
			)
			(layer "F.Fab")
		)
		(fp_line
			(start -0.12065 -0.2794)
			(end 0.12065 -0.2794)
			(stroke
				(width 0.1)
				(type default)
			)
			(layer "F.Fab")
		)
		(fp_line
			(start 0.120396 0.2794)
			(end -0.12065 0.2794)
			(stroke
				(width 0.1)
				(type default)
			)
			(layer "F.Fab")
		)
		(fp_line
			(start -0.12065 0.2794)
			(end -0.12065 0.3048)
			(stroke
				(width 0.1)
				(type default)
			)
			(layer "F.Fab")
		)
		(fp_line
			(start 0.67945 0.3048)
			(end 0.120396 0.3048)
			(stroke
				(width 0.1)
				(type default)
			)
			(layer "F.Fab")
		)
		(fp_line
			(start 0.120396 0.3048)
			(end 0.120396 0.2794)
			(stroke
				(width 0.1)
				(type default)
			)
			(layer "F.Fab")
		)
		(fp_line
			(start -0.12065 0.3048)
			(end -0.67945 0.3048)
			(stroke
				(width 0.1)
				(type default)
			)
			(layer "F.Fab")
		)
		(fp_line
			(start -0.67945 0.3048)
			(end -0.67945 -0.305054)
			(stroke
				(width 0.1)
				(type default)
			)
			(layer "F.Fab")
		)
		(pad "1" smd circle
			(at -0.40005 0 90)
			(size 0 0)
			(layers "F.Cu" "F.Mask" "F.Paste")
			(net "BMC_EMMC_DT7")
		)
		(pad "2" smd circle
			(at 0.40005 0 90)
			(size 0 0)
			(layers "F.Cu" "F.Mask" "F.Paste")
			(net "EMMC_DT7_R")
		)
	)
	(footprint ""
		(layer "F.Cu")
		(at 52.6542 -109.3978 -90)
		(property "Reference" "R863"
			(at 0 0 270)
			(layer "F.SilkS")
			(hide yes)
			(effects
				(font
					(size 1.27 1.27)
				)
			)
		)
		(property "Value" ""
			(at 0 0 270)
			(layer "F.Fab")
			(effects
				(font
					(size 1.27 1.27)
				)
			)
		)
		(duplicate_pad_numbers_are_jumpers no)
		(fp_line
			(start -0.7874 0.4064)
			(end -0.7874 -0.4064)
			(stroke
				(width 0.1524)
				(type default)
			)
			(layer "F.SilkS")
		)
		(fp_line
			(start 0.7874 0.4064)
			(end -0.7874 0.4064)
			(stroke
				(width 0.1524)
				(type default)
			)
			(layer "F.SilkS")
		)
		(fp_line
			(start -0.7874 -0.4064)
			(end 0.7874 -0.4064)
			(stroke
				(width 0.1524)
				(type default)
			)
			(layer "F.SilkS")
		)
		(fp_line
			(start 0.7874 -0.4064)
			(end 0.7874 0.4064)
			(stroke
				(width 0.1524)
				(type default)
			)
			(layer "F.SilkS")
		)
		(fp_line
			(start -0.67945 0.3048)
			(end -0.67945 -0.305054)
			(stroke
				(width 0.1)
				(type default)
			)
			(layer "F.Fab")
		)
		(fp_line
			(start -0.12065 0.3048)
			(end -0.67945 0.3048)
			(stroke
				(width 0.1)
				(type default)
			)
			(layer "F.Fab")
		)
		(fp_line
			(start 0.120396 0.3048)
			(end 0.120396 0.2794)
			(stroke
				(width 0.1)
				(type default)
			)
			(layer "F.Fab")
		)
		(fp_line
			(start 0.67945 0.3048)
			(end 0.120396 0.3048)
			(stroke
				(width 0.1)
				(type default)
			)
			(layer "F.Fab")
		)
		(fp_line
			(start -0.12065 0.2794)
			(end -0.12065 0.3048)
			(stroke
				(width 0.1)
				(type default)
			)
			(layer "F.Fab")
		)
		(fp_line
			(start 0.120396 0.2794)
			(end -0.12065 0.2794)
			(stroke
				(width 0.1)
				(type default)
			)
			(layer "F.Fab")
		)
		(fp_line
			(start -0.12065 -0.2794)
			(end 0.12065 -0.2794)
			(stroke
				(width 0.1)
				(type default)
			)
			(layer "F.Fab")
		)
		(fp_line
			(start 0.12065 -0.2794)
			(end 0.12065 -0.3048)
			(stroke
				(width 0.1)
				(type default)
			)
			(layer "F.Fab")
		)
		(fp_line
			(start 0.12065 -0.3048)
			(end 0.67945 -0.3048)
			(stroke
				(width 0.1)
				(type default)
			)
			(layer "F.Fab")
		)
		(fp_line
			(start 0.67945 -0.3048)
			(end 0.67945 0.3048)
			(stroke
				(width 0.1)
				(type default)
			)
			(layer "F.Fab")
		)
		(fp_line
			(start -0.67945 -0.305054)
			(end -0.12065 -0.305054)
			(stroke
				(width 0.1)
				(type default)
			)
			(layer "F.Fab")
		)
		(fp_line
			(start -0.12065 -0.305054)
			(end -0.12065 -0.2794)
			(stroke
				(width 0.1)
				(type default)
			)
			(layer "F.Fab")
		)
		(pad "1" smd circle
			(at -0.40005 0 270)
			(size 0 0)
			(layers "F.Cu" "F.Mask" "F.Paste")
			(net "SPI_SYS_HOLD_R_IO3")
		)
		(pad "2" smd circle
			(at 0.40005 0 270)
			(size 0 0)
			(layers "F.Cu" "F.Mask" "F.Paste")
			(net "SPI_SYS_MUX_HOLD_IO3")
		)
	)
	(footprint ""
		(layer "F.Cu")
		(at 41.916604 -87.679784 -90)
		(property "Reference" "R487"
			(at 0 0 270)
			(layer "F.SilkS")
			(hide yes)
			(effects
				(font
					(size 1.27 1.27)
				)
			)
		)
		(property "Value" ""
			(at 0 0 270)
			(layer "F.Fab")
			(effects
				(font
					(size 1.27 1.27)
				)
			)
		)
		(duplicate_pad_numbers_are_jumpers no)
		(fp_line
			(start -0.7874 0.4064)
			(end -0.7874 -0.4064)
			(stroke
				(width 0.1524)
				(type default)
			)
			(layer "F.SilkS")
		)
		(fp_line
			(start 0.7874 0.4064)
			(end -0.7874 0.4064)
			(stroke
				(width 0.1524)
				(type default)
			)
			(layer "F.SilkS")
		)
		(fp_line
			(start -0.7874 -0.4064)
			(end 0.7874 -0.4064)
			(stroke
				(width 0.1524)
				(type default)
			)
			(layer "F.SilkS")
		)
		(fp_line
			(start 0.7874 -0.4064)
			(end 0.7874 0.4064)
			(stroke
				(width 0.1524)
				(type default)
			)
			(layer "F.SilkS")
		)
		(fp_line
			(start -0.67945 0.3048)
			(end -0.67945 -0.305054)
			(stroke
				(width 0.1)
				(type default)
			)
			(layer "F.Fab")
		)
		(fp_line
			(start -0.12065 0.3048)
			(end -0.67945 0.3048)
			(stroke
				(width 0.1)
				(type default)
			)
			(layer "F.Fab")
		)
		(fp_line
			(start 0.120396 0.3048)
			(end 0.120396 0.2794)
			(stroke
				(width 0.1)
				(type default)
			)
			(layer "F.Fab")
		)
		(fp_line
			(start 0.67945 0.3048)
			(end 0.120396 0.3048)
			(stroke
				(width 0.1)
				(type default)
			)
			(layer "F.Fab")
		)
		(fp_line
			(start -0.12065 0.2794)
			(end -0.12065 0.3048)
			(stroke
				(width 0.1)
				(type default)
			)
			(layer "F.Fab")
		)
		(fp_line
			(start 0.120396 0.2794)
			(end -0.12065 0.2794)
			(stroke
				(width 0.1)
				(type default)
			)
			(layer "F.Fab")
		)
		(fp_line
			(start -0.12065 -0.2794)
			(end 0.12065 -0.2794)
			(stroke
				(width 0.1)
				(type default)
			)
			(layer "F.Fab")
		)
		(fp_line
			(start 0.12065 -0.2794)
			(end 0.12065 -0.3048)
			(stroke
				(width 0.1)
				(type default)
			)
			(layer "F.Fab")
		)
		(fp_line
			(start 0.12065 -0.3048)
			(end 0.67945 -0.3048)
			(stroke
				(width 0.1)
				(type default)
			)
			(layer "F.Fab")
		)
		(fp_line
			(start 0.67945 -0.3048)
			(end 0.67945 0.3048)
			(stroke
				(width 0.1)
				(type default)
			)
			(layer "F.Fab")
		)
		(fp_line
			(start -0.67945 -0.305054)
			(end -0.12065 -0.305054)
			(stroke
				(width 0.1)
				(type default)
			)
			(layer "F.Fab")
		)
		(fp_line
			(start -0.12065 -0.305054)
			(end -0.12065 -0.2794)
			(stroke
				(width 0.1)
				(type default)
			)
			(layer "F.Fab")
		)
		(pad "1" smd circle
			(at -0.40005 0 270)
			(size 0 0)
			(layers "F.Cu" "F.Mask" "F.Paste")
			(net "SPI_PCH_CS0_FLASH_R1_N")
		)
		(pad "2" smd circle
			(at 0.40005 0 270)
			(size 0 0)
			(layers "F.Cu" "F.Mask" "F.Paste")
			(net "GND")
		)
	)
	(footprint ""
		(layer "F.Cu")
		(at 48.4378 -79.0194 180)
		(property "Reference" "C313"
			(at 0 0 180)
			(layer "F.SilkS")
			(hide yes)
			(effects
				(font
					(size 1.27 1.27)
				)
			)
		)
		(property "Value" ""
			(at 0 0 180)
			(layer "F.Fab")
			(effects
				(font
					(size 1.27 1.27)
				)
			)
		)
		(duplicate_pad_numbers_are_jumpers no)
		(fp_line
			(start 0.7874 0.4064)
			(end -0.7874 0.4064)
			(stroke
				(width 0.1524)
				(type default)
			)
			(layer "F.SilkS")
		)
		(fp_line
			(start 0.7874 -0.4064)
			(end 0.7874 0.4064)
			(stroke
				(width 0.1524)
				(type default)
			)
			(layer "F.SilkS")
		)
		(fp_line
			(start -0.7874 0.4064)
			(end -0.7874 -0.4064)
			(stroke
				(width 0.1524)
				(type default)
			)
			(layer "F.SilkS")
		)
		(fp_line
			(start -0.7874 -0.4064)
			(end 0.7874 -0.4064)
			(stroke
				(width 0.1524)
				(type default)
			)
			(layer "F.SilkS")
		)
		(fp_line
			(start 0.67945 0.3048)
			(end 0.120396 0.3048)
			(stroke
				(width 0.1)
				(type default)
			)
			(layer "F.Fab")
		)
		(fp_line
			(start 0.67945 -0.3048)
			(end 0.67945 0.3048)
			(stroke
				(width 0.1)
				(type default)
			)
			(layer "F.Fab")
		)
		(fp_line
			(start 0.12065 -0.2794)
			(end 0.12065 -0.3048)
			(stroke
				(width 0.1)
				(type default)
			)
			(layer "F.Fab")
		)
		(fp_line
			(start 0.12065 -0.3048)
			(end 0.67945 -0.3048)
			(stroke
				(width 0.1)
				(type default)
			)
			(layer "F.Fab")
		)
		(fp_line
			(start 0.120396 0.3048)
			(end 0.120396 0.2794)
			(stroke
				(width 0.1)
				(type default)
			)
			(layer "F.Fab")
		)
		(fp_line
			(start 0.120396 0.2794)
			(end -0.12065 0.2794)
			(stroke
				(width 0.1)
				(type default)
			)
			(layer "F.Fab")
		)
		(fp_line
			(start -0.12065 0.3048)
			(end -0.67945 0.3048)
			(stroke
				(width 0.1)
				(type default)
			)
			(layer "F.Fab")
		)
		(fp_line
			(start -0.12065 0.2794)
			(end -0.12065 0.3048)
			(stroke
				(width 0.1)
				(type default)
			)
			(layer "F.Fab")
		)
		(fp_line
			(start -0.12065 -0.2794)
			(end 0.12065 -0.2794)
			(stroke
				(width 0.1)
				(type default)
			)
			(layer "F.Fab")
		)
		(fp_line
			(start -0.12065 -0.305054)
			(end -0.12065 -0.2794)
			(stroke
				(width 0.1)
				(type default)
			)
			(layer "F.Fab")
		)
		(fp_line
			(start -0.67945 0.3048)
			(end -0.67945 -0.305054)
			(stroke
				(width 0.1)
				(type default)
			)
			(layer "F.Fab")
		)
		(fp_line
			(start -0.67945 -0.305054)
			(end -0.12065 -0.305054)
			(stroke
				(width 0.1)
				(type default)
			)
			(layer "F.Fab")
		)
		(pad "1" smd circle
			(at -0.40005 0 180)
			(size 0 0)
			(layers "F.Cu" "F.Mask" "F.Paste")
			(net "P3V3_AUX")
		)
		(pad "2" smd circle
			(at 0.40005 0 180)
			(size 0 0)
			(layers "F.Cu" "F.Mask" "F.Paste")
			(net "GND")
		)
	)
	(footprint ""
		(layer "F.Cu")
		(at 18.4912 -46.3042 -90)
		(property "Reference" "R563"
			(at 0 0 270)
			(layer "F.SilkS")
			(hide yes)
			(effects
				(font
					(size 1.27 1.27)
				)
			)
		)
		(property "Value" ""
			(at 0 0 270)
			(layer "F.Fab")
			(effects
				(font
					(size 1.27 1.27)
				)
			)
		)
		(duplicate_pad_numbers_are_jumpers no)
		(fp_line
			(start -0.7874 0.4064)
			(end -0.7874 -0.4064)
			(stroke
				(width 0.1524)
				(type default)
			)
			(layer "F.SilkS")
		)
		(fp_line
			(start 0.7874 0.4064)
			(end -0.7874 0.4064)
			(stroke
				(width 0.1524)
				(type default)
			)
			(layer "F.SilkS")
		)
		(fp_line
			(start -0.7874 -0.4064)
			(end 0.7874 -0.4064)
			(stroke
				(width 0.1524)
				(type default)
			)
			(layer "F.SilkS")
		)
		(fp_line
			(start 0.7874 -0.4064)
			(end 0.7874 0.4064)
			(stroke
				(width 0.1524)
				(type default)
			)
			(layer "F.SilkS")
		)
		(fp_line
			(start -0.67945 0.3048)
			(end -0.67945 -0.305054)
			(stroke
				(width 0.1)
				(type default)
			)
			(layer "F.Fab")
		)
		(fp_line
			(start -0.12065 0.3048)
			(end -0.67945 0.3048)
			(stroke
				(width 0.1)
				(type default)
			)
			(layer "F.Fab")
		)
		(fp_line
			(start 0.120396 0.3048)
			(end 0.120396 0.2794)
			(stroke
				(width 0.1)
				(type default)
			)
			(layer "F.Fab")
		)
		(fp_line
			(start 0.67945 0.3048)
			(end 0.120396 0.3048)
			(stroke
				(width 0.1)
				(type default)
			)
			(layer "F.Fab")
		)
		(fp_line
			(start -0.12065 0.2794)
			(end -0.12065 0.3048)
			(stroke
				(width 0.1)
				(type default)
			)
			(layer "F.Fab")
		)
		(fp_line
			(start 0.120396 0.2794)
			(end -0.12065 0.2794)
			(stroke
				(width 0.1)
				(type default)
			)
			(layer "F.Fab")
		)
		(fp_line
			(start -0.12065 -0.2794)
			(end 0.12065 -0.2794)
			(stroke
				(width 0.1)
				(type default)
			)
			(layer "F.Fab")
		)
		(fp_line
			(start 0.12065 -0.2794)
			(end 0.12065 -0.3048)
			(stroke
				(width 0.1)
				(type default)
			)
			(layer "F.Fab")
		)
		(fp_line
			(start 0.12065 -0.3048)
			(end 0.67945 -0.3048)
			(stroke
				(width 0.1)
				(type default)
			)
			(layer "F.Fab")
		)
		(fp_line
			(start 0.67945 -0.3048)
			(end 0.67945 0.3048)
			(stroke
				(width 0.1)
				(type default)
			)
			(layer "F.Fab")
		)
		(fp_line
			(start -0.67945 -0.305054)
			(end -0.12065 -0.305054)
			(stroke
				(width 0.1)
				(type default)
			)
			(layer "F.Fab")
		)
		(fp_line
			(start -0.12065 -0.305054)
			(end -0.12065 -0.2794)
			(stroke
				(width 0.1)
				(type default)
			)
			(layer "F.Fab")
		)
		(pad "1" smd circle
			(at -0.40005 0 270)
			(size 0 0)
			(layers "F.Cu" "F.Mask" "F.Paste")
			(net "P3V3_AUX")
		)
		(pad "2" smd circle
			(at 0.40005 0 270)
			(size 0 0)
			(layers "F.Cu" "F.Mask" "F.Paste")
			(net "RST_SPI_FLASH_BUF_N")
		)
	)
	(footprint ""
		(layer "F.Cu")
		(at 31.983172 -83.816952 -90)
		(property "Reference" "R658"
			(at 0 0 270)
			(layer "F.SilkS")
			(hide yes)
			(effects
				(font
					(size 1.27 1.27)
				)
			)
		)
		(property "Value" ""
			(at 0 0 270)
			(layer "F.Fab")
			(effects
				(font
					(size 1.27 1.27)
				)
			)
		)
		(duplicate_pad_numbers_are_jumpers no)
		(fp_line
			(start -0.7874 0.4064)
			(end -0.7874 -0.4064)
			(stroke
				(width 0.1524)
				(type default)
			)
			(layer "F.SilkS")
		)
		(fp_line
			(start 0.7874 0.4064)
			(end -0.7874 0.4064)
			(stroke
				(width 0.1524)
				(type default)
			)
			(layer "F.SilkS")
		)
		(fp_line
			(start -0.7874 -0.4064)
			(end 0.7874 -0.4064)
			(stroke
				(width 0.1524)
				(type default)
			)
			(layer "F.SilkS")
		)
		(fp_line
			(start 0.7874 -0.4064)
			(end 0.7874 0.4064)
			(stroke
				(width 0.1524)
				(type default)
			)
			(layer "F.SilkS")
		)
		(fp_line
			(start -0.67945 0.3048)
			(end -0.67945 -0.305054)
			(stroke
				(width 0.1)
				(type default)
			)
			(layer "F.Fab")
		)
		(fp_line
			(start -0.12065 0.3048)
			(end -0.67945 0.3048)
			(stroke
				(width 0.1)
				(type default)
			)
			(layer "F.Fab")
		)
		(fp_line
			(start 0.120396 0.3048)
			(end 0.120396 0.2794)
			(stroke
				(width 0.1)
				(type default)
			)
			(layer "F.Fab")
		)
		(fp_line
			(start 0.67945 0.3048)
			(end 0.120396 0.3048)
			(stroke
				(width 0.1)
				(type default)
			)
			(layer "F.Fab")
		)
		(fp_line
			(start -0.12065 0.2794)
			(end -0.12065 0.3048)
			(stroke
				(width 0.1)
				(type default)
			)
			(layer "F.Fab")
		)
		(fp_line
			(start 0.120396 0.2794)
			(end -0.12065 0.2794)
			(stroke
				(width 0.1)
				(type default)
			)
			(layer "F.Fab")
		)
		(fp_line
			(start -0.12065 -0.2794)
			(end 0.12065 -0.2794)
			(stroke
				(width 0.1)
				(type default)
			)
			(layer "F.Fab")
		)
		(fp_line
			(start 0.12065 -0.2794)
			(end 0.12065 -0.3048)
			(stroke
				(width 0.1)
				(type default)
			)
			(layer "F.Fab")
		)
		(fp_line
			(start 0.12065 -0.3048)
			(end 0.67945 -0.3048)
			(stroke
				(width 0.1)
				(type default)
			)
			(layer "F.Fab")
		)
		(fp_line
			(start 0.67945 -0.3048)
			(end 0.67945 0.3048)
			(stroke
				(width 0.1)
				(type default)
			)
			(layer "F.Fab")
		)
		(fp_line
			(start -0.67945 -0.305054)
			(end -0.12065 -0.305054)
			(stroke
				(width 0.1)
				(type default)
			)
			(layer "F.Fab")
		)
		(fp_line
			(start -0.12065 -0.305054)
			(end -0.12065 -0.2794)
			(stroke
				(width 0.1)
				(type default)
			)
			(layer "F.Fab")
		)
		(pad "1" smd circle
			(at -0.40005 0 270)
			(size 0 0)
			(layers "F.Cu" "F.Mask" "F.Paste")
			(net "P3V3_AUX")
		)
		(pad "2" smd circle
			(at 0.40005 0 270)
			(size 0 0)
			(layers "F.Cu" "F.Mask" "F.Paste")
			(net "EMMC_DT3_R")
		)
	)
	(footprint ""
		(layer "F.Cu")
		(at 31.75 -28.956)
		(property "Reference" "R87"
			(at 0 0 0)
			(layer "F.SilkS")
			(hide yes)
			(effects
				(font
					(size 1.27 1.27)
				)
			)
		)
		(property "Value" ""
			(at 0 0 0)
			(layer "F.Fab")
			(effects
				(font
					(size 1.27 1.27)
				)
			)
		)
		(duplicate_pad_numbers_are_jumpers no)
		(fp_line
			(start -0.7874 -0.4064)
			(end 0.7874 -0.4064)
			(stroke
				(width 0.1524)
				(type default)
			)
			(layer "F.SilkS")
		)
		(fp_line
			(start -0.7874 0.4064)
			(end -0.7874 -0.4064)
			(stroke
				(width 0.1524)
				(type default)
			)
			(layer "F.SilkS")
		)
		(fp_line
			(start 0.7874 -0.4064)
			(end 0.7874 0.4064)
			(stroke
				(width 0.1524)
				(type default)
			)
			(layer "F.SilkS")
		)
		(fp_line
			(start 0.7874 0.4064)
			(end -0.7874 0.4064)
			(stroke
				(width 0.1524)
				(type default)
			)
			(layer "F.SilkS")
		)
		(fp_line
			(start -0.67945 -0.305054)
			(end -0.12065 -0.305054)
			(stroke
				(width 0.1)
				(type default)
			)
			(layer "F.Fab")
		)
		(fp_line
			(start -0.67945 0.3048)
			(end -0.67945 -0.305054)
			(stroke
				(width 0.1)
				(type default)
			)
			(layer "F.Fab")
		)
		(fp_line
			(start -0.12065 -0.305054)
			(end -0.12065 -0.2794)
			(stroke
				(width 0.1)
				(type default)
			)
			(layer "F.Fab")
		)
		(fp_line
			(start -0.12065 -0.2794)
			(end 0.12065 -0.2794)
			(stroke
				(width 0.1)
				(type default)
			)
			(layer "F.Fab")
		)
		(fp_line
			(start -0.12065 0.2794)
			(end -0.12065 0.3048)
			(stroke
				(width 0.1)
				(type default)
			)
			(layer "F.Fab")
		)
		(fp_line
			(start -0.12065 0.3048)
			(end -0.67945 0.3048)
			(stroke
				(width 0.1)
				(type default)
			)
			(layer "F.Fab")
		)
		(fp_line
			(start 0.120396 0.2794)
			(end -0.12065 0.2794)
			(stroke
				(width 0.1)
				(type default)
			)
			(layer "F.Fab")
		)
		(fp_line
			(start 0.120396 0.3048)
			(end 0.120396 0.2794)
			(stroke
				(width 0.1)
				(type default)
			)
			(layer "F.Fab")
		)
		(fp_line
			(start 0.12065 -0.3048)
			(end 0.67945 -0.3048)
			(stroke
				(width 0.1)
				(type default)
			)
			(layer "F.Fab")
		)
		(fp_line
			(start 0.12065 -0.2794)
			(end 0.12065 -0.3048)
			(stroke
				(width 0.1)
				(type default)
			)
			(layer "F.Fab")
		)
		(fp_line
			(start 0.67945 -0.3048)
			(end 0.67945 0.3048)
			(stroke
				(width 0.1)
				(type default)
			)
			(layer "F.Fab")
		)
		(fp_line
			(start 0.67945 0.3048)
			(end 0.120396 0.3048)
			(stroke
				(width 0.1)
				(type default)
			)
			(layer "F.Fab")
		)
		(pad "1" smd circle
			(at -0.40005 0)
			(size 0 0)
			(layers "F.Cu" "F.Mask" "F.Paste")
			(net "V_DACB_IO")
		)
		(pad "2" smd circle
			(at 0.40005 0)
			(size 0 0)
			(layers "F.Cu" "F.Mask" "F.Paste")
			(net "GND")
		)
	)
	(footprint ""
		(layer "F.Cu")
		(at 83.217258 -36.683442 180)
		(property "Reference" "R829"
			(at 0 0 180)
			(layer "F.SilkS")
			(hide yes)
			(effects
				(font
					(size 1.27 1.27)
				)
			)
		)
		(property "Value" ""
			(at 0 0 180)
			(layer "F.Fab")
			(effects
				(font
					(size 1.27 1.27)
				)
			)
		)
		(duplicate_pad_numbers_are_jumpers no)
		(fp_line
			(start 0.7874 0.4064)
			(end -0.7874 0.4064)
			(stroke
				(width 0.1524)
				(type default)
			)
			(layer "F.SilkS")
		)
		(fp_line
			(start 0.7874 -0.4064)
			(end 0.7874 0.4064)
			(stroke
				(width 0.1524)
				(type default)
			)
			(layer "F.SilkS")
		)
		(fp_line
			(start -0.7874 0.4064)
			(end -0.7874 -0.4064)
			(stroke
				(width 0.1524)
				(type default)
			)
			(layer "F.SilkS")
		)
		(fp_line
			(start -0.7874 -0.4064)
			(end 0.7874 -0.4064)
			(stroke
				(width 0.1524)
				(type default)
			)
			(layer "F.SilkS")
		)
		(fp_line
			(start 0.67945 0.3048)
			(end 0.120396 0.3048)
			(stroke
				(width 0.1)
				(type default)
			)
			(layer "F.Fab")
		)
		(fp_line
			(start 0.67945 -0.3048)
			(end 0.67945 0.3048)
			(stroke
				(width 0.1)
				(type default)
			)
			(layer "F.Fab")
		)
		(fp_line
			(start 0.12065 -0.2794)
			(end 0.12065 -0.3048)
			(stroke
				(width 0.1)
				(type default)
			)
			(layer "F.Fab")
		)
		(fp_line
			(start 0.12065 -0.3048)
			(end 0.67945 -0.3048)
			(stroke
				(width 0.1)
				(type default)
			)
			(layer "F.Fab")
		)
		(fp_line
			(start 0.120396 0.3048)
			(end 0.120396 0.2794)
			(stroke
				(width 0.1)
				(type default)
			)
			(layer "F.Fab")
		)
		(fp_line
			(start 0.120396 0.2794)
			(end -0.12065 0.2794)
			(stroke
				(width 0.1)
				(type default)
			)
			(layer "F.Fab")
		)
		(fp_line
			(start -0.12065 0.3048)
			(end -0.67945 0.3048)
			(stroke
				(width 0.1)
				(type default)
			)
			(layer "F.Fab")
		)
		(fp_line
			(start -0.12065 0.2794)
			(end -0.12065 0.3048)
			(stroke
				(width 0.1)
				(type default)
			)
			(layer "F.Fab")
		)
		(fp_line
			(start -0.12065 -0.2794)
			(end 0.12065 -0.2794)
			(stroke
				(width 0.1)
				(type default)
			)
			(layer "F.Fab")
		)
		(fp_line
			(start -0.12065 -0.305054)
			(end -0.12065 -0.2794)
			(stroke
				(width 0.1)
				(type default)
			)
			(layer "F.Fab")
		)
		(fp_line
			(start -0.67945 0.3048)
			(end -0.67945 -0.305054)
			(stroke
				(width 0.1)
				(type default)
			)
			(layer "F.Fab")
		)
		(fp_line
			(start -0.67945 -0.305054)
			(end -0.12065 -0.305054)
			(stroke
				(width 0.1)
				(type default)
			)
			(layer "F.Fab")
		)
		(pad "1" smd circle
			(at -0.40005 0 180)
			(size 0 0)
			(layers "F.Cu" "F.Mask" "F.Paste")
			(net "P2V5_AUX")
		)
		(pad "2" smd circle
			(at 0.40005 0 180)
			(size 0 0)
			(layers "F.Cu" "F.Mask" "F.Paste")
			(net "U39_ADJ")
		)
	)
	(footprint ""
		(layer "F.Cu")
		(at 6.096 -55.372 180)
		(property "Reference" "PC206"
			(at 0 0 180)
			(layer "F.SilkS")
			(hide yes)
			(effects
				(font
					(size 1.27 1.27)
				)
			)
		)
		(property "Value" ""
			(at 0 0 180)
			(layer "F.Fab")
			(effects
				(font
					(size 1.27 1.27)
				)
			)
		)
		(duplicate_pad_numbers_are_jumpers no)
		(fp_line
			(start 1.524 0.762)
			(end -1.524 0.762)
			(stroke
				(width 0.1524)
				(type default)
			)
			(layer "F.SilkS")
		)
		(fp_line
			(start 1.524 -0.762)
			(end 1.524 0.762)
			(stroke
				(width 0.1524)
				(type default)
			)
			(layer "F.SilkS")
		)
		(fp_line
			(start -1.524 0.762)
			(end -1.524 -0.762)
			(stroke
				(width 0.1524)
				(type default)
			)
			(layer "F.SilkS")
		)
		(fp_line
			(start -1.524 -0.762)
			(end 1.524 -0.762)
			(stroke
				(width 0.1524)
				(type default)
			)
			(layer "F.SilkS")
		)
		(fp_line
			(start 1.1049 0.724916)
			(end 1.1049 -0.724916)
			(stroke
				(width 0.1)
				(type default)
			)
			(layer "F.Fab")
		)
		(fp_line
			(start 1.1049 -0.724916)
			(end -1.1049 -0.724916)
			(stroke
				(width 0.1)
				(type default)
			)
			(layer "F.Fab")
		)
		(fp_line
			(start -1.1049 0.724916)
			(end 1.1049 0.724916)
			(stroke
				(width 0.1)
				(type default)
			)
			(layer "F.Fab")
		)
		(fp_line
			(start -1.1049 -0.724916)
			(end -1.1049 0.724916)
			(stroke
				(width 0.1)
				(type default)
			)
			(layer "F.Fab")
		)
		(pad "1" smd rect
			(at -0.889 0)
			(size 1.016 1.27)
			(layers "F.Cu" "F.Mask" "F.Paste")
			(net "SW_P5V_AUX_FLT")
		)
		(pad "2" smd rect
			(at 0.889 0)
			(size 1.016 1.27)
			(layers "F.Cu" "F.Mask" "F.Paste")
			(net "GND")
		)
	)
	(footprint ""
		(layer "F.Cu")
		(at 9.779 -9.652 180)
		(property "Reference" "C198"
			(at 0 0 180)
			(layer "F.SilkS")
			(hide yes)
			(effects
				(font
					(size 1.27 1.27)
				)
			)
		)
		(property "Value" ""
			(at 0 0 180)
			(layer "F.Fab")
			(effects
				(font
					(size 1.27 1.27)
				)
			)
		)
		(duplicate_pad_numbers_are_jumpers no)
		(fp_line
			(start 0.7874 0.4064)
			(end -0.7874 0.4064)
			(stroke
				(width 0.1524)
				(type default)
			)
			(layer "F.SilkS")
		)
		(fp_line
			(start 0.7874 -0.4064)
			(end 0.7874 0.4064)
			(stroke
				(width 0.1524)
				(type default)
			)
			(layer "F.SilkS")
		)
		(fp_line
			(start -0.7874 0.4064)
			(end -0.7874 -0.4064)
			(stroke
				(width 0.1524)
				(type default)
			)
			(layer "F.SilkS")
		)
		(fp_line
			(start -0.7874 -0.4064)
			(end 0.7874 -0.4064)
			(stroke
				(width 0.1524)
				(type default)
			)
			(layer "F.SilkS")
		)
		(fp_line
			(start 0.67945 0.3048)
			(end 0.120396 0.3048)
			(stroke
				(width 0.1)
				(type default)
			)
			(layer "F.Fab")
		)
		(fp_line
			(start 0.67945 -0.3048)
			(end 0.67945 0.3048)
			(stroke
				(width 0.1)
				(type default)
			)
			(layer "F.Fab")
		)
		(fp_line
			(start 0.12065 -0.2794)
			(end 0.12065 -0.3048)
			(stroke
				(width 0.1)
				(type default)
			)
			(layer "F.Fab")
		)
		(fp_line
			(start 0.12065 -0.3048)
			(end 0.67945 -0.3048)
			(stroke
				(width 0.1)
				(type default)
			)
			(layer "F.Fab")
		)
		(fp_line
			(start 0.120396 0.3048)
			(end 0.120396 0.2794)
			(stroke
				(width 0.1)
				(type default)
			)
			(layer "F.Fab")
		)
		(fp_line
			(start 0.120396 0.2794)
			(end -0.12065 0.2794)
			(stroke
				(width 0.1)
				(type default)
			)
			(layer "F.Fab")
		)
		(fp_line
			(start -0.12065 0.3048)
			(end -0.67945 0.3048)
			(stroke
				(width 0.1)
				(type default)
			)
			(layer "F.Fab")
		)
		(fp_line
			(start -0.12065 0.2794)
			(end -0.12065 0.3048)
			(stroke
				(width 0.1)
				(type default)
			)
			(layer "F.Fab")
		)
		(fp_line
			(start -0.12065 -0.2794)
			(end 0.12065 -0.2794)
			(stroke
				(width 0.1)
				(type default)
			)
			(layer "F.Fab")
		)
		(fp_line
			(start -0.12065 -0.305054)
			(end -0.12065 -0.2794)
			(stroke
				(width 0.1)
				(type default)
			)
			(layer "F.Fab")
		)
		(fp_line
			(start -0.67945 0.3048)
			(end -0.67945 -0.305054)
			(stroke
				(width 0.1)
				(type default)
			)
			(layer "F.Fab")
		)
		(fp_line
			(start -0.67945 -0.305054)
			(end -0.12065 -0.305054)
			(stroke
				(width 0.1)
				(type default)
			)
			(layer "F.Fab")
		)
		(pad "1" smd circle
			(at -0.40005 0 180)
			(size 0 0)
			(layers "F.Cu" "F.Mask" "F.Paste")
			(net "REAR_PWR_BTN_N")
		)
		(pad "2" smd circle
			(at 0.40005 0 180)
			(size 0 0)
			(layers "F.Cu" "F.Mask" "F.Paste")
			(net "GND")
		)
	)
	(footprint ""
		(layer "F.Cu")
		(at 51.816 -69.342)
		(property "Reference" "R699"
			(at 0 0 0)
			(layer "F.SilkS")
			(hide yes)
			(effects
				(font
					(size 1.27 1.27)
				)
			)
		)
		(property "Value" ""
			(at 0 0 0)
			(layer "F.Fab")
			(effects
				(font
					(size 1.27 1.27)
				)
			)
		)
		(duplicate_pad_numbers_are_jumpers no)
		(fp_line
			(start -0.7874 -0.4064)
			(end 0.7874 -0.4064)
			(stroke
				(width 0.1524)
				(type default)
			)
			(layer "F.SilkS")
		)
		(fp_line
			(start -0.7874 0.4064)
			(end -0.7874 -0.4064)
			(stroke
				(width 0.1524)
				(type default)
			)
			(layer "F.SilkS")
		)
		(fp_line
			(start 0.7874 -0.4064)
			(end 0.7874 0.4064)
			(stroke
				(width 0.1524)
				(type default)
			)
			(layer "F.SilkS")
		)
		(fp_line
			(start 0.7874 0.4064)
			(end -0.7874 0.4064)
			(stroke
				(width 0.1524)
				(type default)
			)
			(layer "F.SilkS")
		)
		(fp_line
			(start -0.67945 -0.305054)
			(end -0.12065 -0.305054)
			(stroke
				(width 0.1)
				(type default)
			)
			(layer "F.Fab")
		)
		(fp_line
			(start -0.67945 0.3048)
			(end -0.67945 -0.305054)
			(stroke
				(width 0.1)
				(type default)
			)
			(layer "F.Fab")
		)
		(fp_line
			(start -0.12065 -0.305054)
			(end -0.12065 -0.2794)
			(stroke
				(width 0.1)
				(type default)
			)
			(layer "F.Fab")
		)
		(fp_line
			(start -0.12065 -0.2794)
			(end 0.12065 -0.2794)
			(stroke
				(width 0.1)
				(type default)
			)
			(layer "F.Fab")
		)
		(fp_line
			(start -0.12065 0.2794)
			(end -0.12065 0.3048)
			(stroke
				(width 0.1)
				(type default)
			)
			(layer "F.Fab")
		)
		(fp_line
			(start -0.12065 0.3048)
			(end -0.67945 0.3048)
			(stroke
				(width 0.1)
				(type default)
			)
			(layer "F.Fab")
		)
		(fp_line
			(start 0.120396 0.2794)
			(end -0.12065 0.2794)
			(stroke
				(width 0.1)
				(type default)
			)
			(layer "F.Fab")
		)
		(fp_line
			(start 0.120396 0.3048)
			(end 0.120396 0.2794)
			(stroke
				(width 0.1)
				(type default)
			)
			(layer "F.Fab")
		)
		(fp_line
			(start 0.12065 -0.3048)
			(end 0.67945 -0.3048)
			(stroke
				(width 0.1)
				(type default)
			)
			(layer "F.Fab")
		)
		(fp_line
			(start 0.12065 -0.2794)
			(end 0.12065 -0.3048)
			(stroke
				(width 0.1)
				(type default)
			)
			(layer "F.Fab")
		)
		(fp_line
			(start 0.67945 -0.3048)
			(end 0.67945 0.3048)
			(stroke
				(width 0.1)
				(type default)
			)
			(layer "F.Fab")
		)
		(fp_line
			(start 0.67945 0.3048)
			(end 0.120396 0.3048)
			(stroke
				(width 0.1)
				(type default)
			)
			(layer "F.Fab")
		)
		(pad "1" smd circle
			(at -0.40005 0)
			(size 0 0)
			(layers "F.Cu" "F.Mask" "F.Paste")
			(net "P3V3_AUX")
		)
		(pad "2" smd circle
			(at 0.40005 0)
			(size 0 0)
			(layers "F.Cu" "F.Mask" "F.Paste")
			(net "SPI_BMC_BOOT_CLK")
		)
	)
	(footprint ""
		(layer "F.Cu")
		(at 114.554 -3.048 -90)
		(property "Reference" "X6"
			(at -1.73863 -0.8382 0)
			(unlocked yes)
			(layer "F.SilkS")
			(effects
				(font
					(size 0.7874 0.5842)
					(thickness 0.1524)
				)
				(justify left)
			)
		)
		(property "Value" ""
			(at 0 0 270)
			(layer "F.Fab")
			(effects
				(font
					(size 1.27 1.27)
				)
			)
		)
		(property "Device Type" "TP_TDR_4P_FTS_TH-TP_TDR_4P_DIPA"
			(at 1.30175 1.27 0)
			(unlocked yes)
			(layer "F.Fab")
			(hide yes)
			(effects
				(font
					(size 0.635 0.4064)
					(thickness 0.1524)
				)
			)
		)
		(property "User Part Number" "N_A"
			(at 1.30175 1.27 0)
			(unlocked yes)
			(layer "Cmts.User")
			(hide yes)
			(effects
				(font
					(size 0.635 0.4064)
					(thickness 0.1524)
				)
			)
		)
		(duplicate_pad_numbers_are_jumpers no)
		(fp_line
			(start 0 3.81)
			(end 2.54 3.81)
			(stroke
				(width 0.1524)
				(type default)
			)
			(layer "F.SilkS")
		)
		(fp_line
			(start 2.54 3.81)
			(end 2.54 3.6703)
			(stroke
				(width 0.1524)
				(type default)
			)
			(layer "F.SilkS")
		)
		(fp_line
			(start 0 3.175)
			(end 0 3.81)
			(stroke
				(width 0.1524)
				(type default)
			)
			(layer "F.SilkS")
		)
		(fp_line
			(start 2.54 1.4097)
			(end 2.54 1.1303)
			(stroke
				(width 0.1524)
				(type default)
			)
			(layer "F.SilkS")
		)
		(fp_line
			(start 0 0.635)
			(end 0 1.905)
			(stroke
				(width 0.1524)
				(type default)
			)
			(layer "F.SilkS")
		)
		(fp_line
			(start 2.54 -1.1303)
			(end 2.54 -1.27)
			(stroke
				(width 0.1524)
				(type default)
			)
			(layer "F.SilkS")
		)
		(fp_line
			(start 0 -1.27)
			(end 0 -0.635)
			(stroke
				(width 0.1524)
				(type default)
			)
			(layer "F.SilkS")
		)
		(fp_line
			(start 2.54 -1.27)
			(end 0 -1.27)
			(stroke
				(width 0.1524)
				(type default)
			)
			(layer "F.SilkS")
		)
		(fp_poly
			(pts
				(xy -0.761746 0) (xy -2.285746 -0.762) (xy -2.285746 0.762)
			)
			(stroke
				(width 0)
				(type default)
			)
			(fill yes)
			(layer "F.SilkS")
		)
		(fp_line
			(start 0 3.81)
			(end 2.54 3.81)
			(stroke
				(width 0.1)
				(type default)
			)
			(layer "F.Fab")
		)
		(fp_line
			(start 2.54 3.81)
			(end 2.54 -1.27)
			(stroke
				(width 0.1)
				(type default)
			)
			(layer "F.Fab")
		)
		(fp_line
			(start 0 -1.27)
			(end 0 3.81)
			(stroke
				(width 0.1)
				(type default)
			)
			(layer "F.Fab")
		)
		(fp_line
			(start 2.54 -1.27)
			(end 0 -1.27)
			(stroke
				(width 0.1)
				(type default)
			)
			(layer "F.Fab")
		)
		(fp_poly
			(pts
				(xy -0.761746 0) (xy -2.285746 -0.762) (xy -2.285746 0.762)
			)
			(stroke
				(width 0)
				(type default)
			)
			(fill yes)
			(layer "F.Fab")
		)
		(pad "1" thru_hole circle
			(at 0 0 270)
			(size 1.0033 1.0033)
			(drill 0.249936)
			(layers "*.Cu" "*.Mask")
			(remove_unused_layers no)
			(net "TDR_DIFF_85_BOT_DP")
			(clearance 0.10795)
			(thermal_gap 0.10795)
			(padstack
				(mode front_inner_back)
				(layer "Inner"
					(shape circle)
					(size 0.8001 0.8001)
					(clearance 0.1524)
				)
				(layer "B.Cu"
					(shape circle)
					(size 1.0033 1.0033)
					(clearance 0.10795)
				)
			)
		)
		(pad "2" thru_hole circle
			(at 2.54 0 270)
			(size 1.9939 1.9939)
			(drill 0.249936)
			(layers "*.Cu" "*.Mask")
			(remove_unused_layers no)
			(net "GND_P1")
			(clearance 0.10795)
			(thermal_gap 0.10795)
			(padstack
				(mode front_inner_back)
				(layer "Inner"
					(shape circle)
					(size 0.8001 0.8001)
					(clearance 0.1524)
				)
				(layer "B.Cu"
					(shape circle)
					(size 1.9939 1.9939)
					(clearance 0.10795)
				)
			)
		)
		(pad "3" thru_hole circle
			(at 2.54 2.54 270)
			(size 1.9939 1.9939)
			(drill 0.249936)
			(layers "*.Cu" "*.Mask")
			(remove_unused_layers no)
			(net "GND_P1")
			(clearance 0.10795)
			(thermal_gap 0.10795)
			(padstack
				(mode front_inner_back)
				(layer "Inner"
					(shape circle)
					(size 0.8001 0.8001)
					(clearance 0.1524)
				)
				(layer "B.Cu"
					(shape circle)
					(size 1.9939 1.9939)
					(clearance 0.10795)
				)
			)
		)
		(pad "4" thru_hole circle
			(at 0 2.54 270)
			(size 1.0033 1.0033)
			(drill 0.249936)
			(layers "*.Cu" "*.Mask")
			(remove_unused_layers no)
			(net "TDR_DIFF_85_BOT_DN")
			(clearance 0.10795)
			(thermal_gap 0.10795)
			(padstack
				(mode front_inner_back)
				(layer "Inner"
					(shape circle)
					(size 0.8001 0.8001)
					(clearance 0.1524)
				)
				(layer "B.Cu"
					(shape circle)
					(size 1.0033 1.0033)
					(clearance 0.10795)
				)
			)
		)
	)
	(footprint ""
		(layer "F.Cu")
		(at 9.1694 -105.5878)
		(property "Reference" "C215"
			(at 0 0 0)
			(layer "F.SilkS")
			(hide yes)
			(effects
				(font
					(size 1.27 1.27)
				)
			)
		)
		(property "Value" ""
			(at 0 0 0)
			(layer "F.Fab")
			(effects
				(font
					(size 1.27 1.27)
				)
			)
		)
		(duplicate_pad_numbers_are_jumpers no)
		(fp_line
			(start -0.7874 -0.4064)
			(end 0.7874 -0.4064)
			(stroke
				(width 0.1524)
				(type default)
			)
			(layer "F.SilkS")
		)
		(fp_line
			(start -0.7874 0.4064)
			(end -0.7874 -0.4064)
			(stroke
				(width 0.1524)
				(type default)
			)
			(layer "F.SilkS")
		)
		(fp_line
			(start 0.7874 -0.4064)
			(end 0.7874 0.4064)
			(stroke
				(width 0.1524)
				(type default)
			)
			(layer "F.SilkS")
		)
		(fp_line
			(start 0.7874 0.4064)
			(end -0.7874 0.4064)
			(stroke
				(width 0.1524)
				(type default)
			)
			(layer "F.SilkS")
		)
		(fp_line
			(start -0.67945 -0.305054)
			(end -0.12065 -0.305054)
			(stroke
				(width 0.1)
				(type default)
			)
			(layer "F.Fab")
		)
		(fp_line
			(start -0.67945 0.3048)
			(end -0.67945 -0.305054)
			(stroke
				(width 0.1)
				(type default)
			)
			(layer "F.Fab")
		)
		(fp_line
			(start -0.12065 -0.305054)
			(end -0.12065 -0.2794)
			(stroke
				(width 0.1)
				(type default)
			)
			(layer "F.Fab")
		)
		(fp_line
			(start -0.12065 -0.2794)
			(end 0.12065 -0.2794)
			(stroke
				(width 0.1)
				(type default)
			)
			(layer "F.Fab")
		)
		(fp_line
			(start -0.12065 0.2794)
			(end -0.12065 0.3048)
			(stroke
				(width 0.1)
				(type default)
			)
			(layer "F.Fab")
		)
		(fp_line
			(start -0.12065 0.3048)
			(end -0.67945 0.3048)
			(stroke
				(width 0.1)
				(type default)
			)
			(layer "F.Fab")
		)
		(fp_line
			(start 0.120396 0.2794)
			(end -0.12065 0.2794)
			(stroke
				(width 0.1)
				(type default)
			)
			(layer "F.Fab")
		)
		(fp_line
			(start 0.120396 0.3048)
			(end 0.120396 0.2794)
			(stroke
				(width 0.1)
				(type default)
			)
			(layer "F.Fab")
		)
		(fp_line
			(start 0.12065 -0.3048)
			(end 0.67945 -0.3048)
			(stroke
				(width 0.1)
				(type default)
			)
			(layer "F.Fab")
		)
		(fp_line
			(start 0.12065 -0.2794)
			(end 0.12065 -0.3048)
			(stroke
				(width 0.1)
				(type default)
			)
			(layer "F.Fab")
		)
		(fp_line
			(start 0.67945 -0.3048)
			(end 0.67945 0.3048)
			(stroke
				(width 0.1)
				(type default)
			)
			(layer "F.Fab")
		)
		(fp_line
			(start 0.67945 0.3048)
			(end 0.120396 0.3048)
			(stroke
				(width 0.1)
				(type default)
			)
			(layer "F.Fab")
		)
		(pad "1" smd circle
			(at -0.40005 0)
			(size 0 0)
			(layers "F.Cu" "F.Mask" "F.Paste")
			(net "J7_P1")
		)
		(pad "2" smd circle
			(at 0.40005 0)
			(size 0 0)
			(layers "F.Cu" "F.Mask" "F.Paste")
			(net "GND")
		)
	)
	(footprint ""
		(layer "F.Cu")
		(at 60.579 -84.709 -90)
		(property "Reference" "R164"
			(at 0 0 270)
			(layer "F.SilkS")
			(hide yes)
			(effects
				(font
					(size 1.27 1.27)
				)
			)
		)
		(property "Value" ""
			(at 0 0 270)
			(layer "F.Fab")
			(effects
				(font
					(size 1.27 1.27)
				)
			)
		)
		(duplicate_pad_numbers_are_jumpers no)
		(fp_line
			(start -0.7874 0.4064)
			(end -0.7874 -0.4064)
			(stroke
				(width 0.1524)
				(type default)
			)
			(layer "F.SilkS")
		)
		(fp_line
			(start 0.7874 0.4064)
			(end -0.7874 0.4064)
			(stroke
				(width 0.1524)
				(type default)
			)
			(layer "F.SilkS")
		)
		(fp_line
			(start -0.7874 -0.4064)
			(end 0.7874 -0.4064)
			(stroke
				(width 0.1524)
				(type default)
			)
			(layer "F.SilkS")
		)
		(fp_line
			(start 0.7874 -0.4064)
			(end 0.7874 0.4064)
			(stroke
				(width 0.1524)
				(type default)
			)
			(layer "F.SilkS")
		)
		(fp_line
			(start -0.67945 0.3048)
			(end -0.67945 -0.305054)
			(stroke
				(width 0.1)
				(type default)
			)
			(layer "F.Fab")
		)
		(fp_line
			(start -0.12065 0.3048)
			(end -0.67945 0.3048)
			(stroke
				(width 0.1)
				(type default)
			)
			(layer "F.Fab")
		)
		(fp_line
			(start 0.120396 0.3048)
			(end 0.120396 0.2794)
			(stroke
				(width 0.1)
				(type default)
			)
			(layer "F.Fab")
		)
		(fp_line
			(start 0.67945 0.3048)
			(end 0.120396 0.3048)
			(stroke
				(width 0.1)
				(type default)
			)
			(layer "F.Fab")
		)
		(fp_line
			(start -0.12065 0.2794)
			(end -0.12065 0.3048)
			(stroke
				(width 0.1)
				(type default)
			)
			(layer "F.Fab")
		)
		(fp_line
			(start 0.120396 0.2794)
			(end -0.12065 0.2794)
			(stroke
				(width 0.1)
				(type default)
			)
			(layer "F.Fab")
		)
		(fp_line
			(start -0.12065 -0.2794)
			(end 0.12065 -0.2794)
			(stroke
				(width 0.1)
				(type default)
			)
			(layer "F.Fab")
		)
		(fp_line
			(start 0.12065 -0.2794)
			(end 0.12065 -0.3048)
			(stroke
				(width 0.1)
				(type default)
			)
			(layer "F.Fab")
		)
		(fp_line
			(start 0.12065 -0.3048)
			(end 0.67945 -0.3048)
			(stroke
				(width 0.1)
				(type default)
			)
			(layer "F.Fab")
		)
		(fp_line
			(start 0.67945 -0.3048)
			(end 0.67945 0.3048)
			(stroke
				(width 0.1)
				(type default)
			)
			(layer "F.Fab")
		)
		(fp_line
			(start -0.67945 -0.305054)
			(end -0.12065 -0.305054)
			(stroke
				(width 0.1)
				(type default)
			)
			(layer "F.Fab")
		)
		(fp_line
			(start -0.12065 -0.305054)
			(end -0.12065 -0.2794)
			(stroke
				(width 0.1)
				(type default)
			)
			(layer "F.Fab")
		)
		(pad "1" smd circle
			(at -0.40005 0 270)
			(size 0 0)
			(layers "F.Cu" "F.Mask" "F.Paste")
			(net "SPI_BMC_BOOT_MISO")
		)
		(pad "2" smd circle
			(at 0.40005 0 270)
			(size 0 0)
			(layers "F.Cu" "F.Mask" "F.Paste")
			(net "GND")
		)
	)
	(footprint ""
		(layer "F.Cu")
		(at 20.209764 -30.026864 180)
		(property "Reference" "PC264"
			(at 0 0 180)
			(layer "F.SilkS")
			(hide yes)
			(effects
				(font
					(size 1.27 1.27)
				)
			)
		)
		(property "Value" ""
			(at 0 0 180)
			(layer "F.Fab")
			(effects
				(font
					(size 1.27 1.27)
				)
			)
		)
		(duplicate_pad_numbers_are_jumpers no)
		(fp_line
			(start 0.7874 0.4064)
			(end -0.7874 0.4064)
			(stroke
				(width 0.1524)
				(type default)
			)
			(layer "F.SilkS")
		)
		(fp_line
			(start 0.7874 -0.4064)
			(end 0.7874 0.4064)
			(stroke
				(width 0.1524)
				(type default)
			)
			(layer "F.SilkS")
		)
		(fp_line
			(start -0.7874 0.4064)
			(end -0.7874 -0.4064)
			(stroke
				(width 0.1524)
				(type default)
			)
			(layer "F.SilkS")
		)
		(fp_line
			(start -0.7874 -0.4064)
			(end 0.7874 -0.4064)
			(stroke
				(width 0.1524)
				(type default)
			)
			(layer "F.SilkS")
		)
		(fp_line
			(start 0.67945 0.3048)
			(end 0.120396 0.3048)
			(stroke
				(width 0.1)
				(type default)
			)
			(layer "F.Fab")
		)
		(fp_line
			(start 0.67945 -0.3048)
			(end 0.67945 0.3048)
			(stroke
				(width 0.1)
				(type default)
			)
			(layer "F.Fab")
		)
		(fp_line
			(start 0.12065 -0.2794)
			(end 0.12065 -0.3048)
			(stroke
				(width 0.1)
				(type default)
			)
			(layer "F.Fab")
		)
		(fp_line
			(start 0.12065 -0.3048)
			(end 0.67945 -0.3048)
			(stroke
				(width 0.1)
				(type default)
			)
			(layer "F.Fab")
		)
		(fp_line
			(start 0.120396 0.3048)
			(end 0.120396 0.2794)
			(stroke
				(width 0.1)
				(type default)
			)
			(layer "F.Fab")
		)
		(fp_line
			(start 0.120396 0.2794)
			(end -0.12065 0.2794)
			(stroke
				(width 0.1)
				(type default)
			)
			(layer "F.Fab")
		)
		(fp_line
			(start -0.12065 0.3048)
			(end -0.67945 0.3048)
			(stroke
				(width 0.1)
				(type default)
			)
			(layer "F.Fab")
		)
		(fp_line
			(start -0.12065 0.2794)
			(end -0.12065 0.3048)
			(stroke
				(width 0.1)
				(type default)
			)
			(layer "F.Fab")
		)
		(fp_line
			(start -0.12065 -0.2794)
			(end 0.12065 -0.2794)
			(stroke
				(width 0.1)
				(type default)
			)
			(layer "F.Fab")
		)
		(fp_line
			(start -0.12065 -0.305054)
			(end -0.12065 -0.2794)
			(stroke
				(width 0.1)
				(type default)
			)
			(layer "F.Fab")
		)
		(fp_line
			(start -0.67945 0.3048)
			(end -0.67945 -0.305054)
			(stroke
				(width 0.1)
				(type default)
			)
			(layer "F.Fab")
		)
		(fp_line
			(start -0.67945 -0.305054)
			(end -0.12065 -0.305054)
			(stroke
				(width 0.1)
				(type default)
			)
			(layer "F.Fab")
		)
		(pad "1" smd circle
			(at -0.40005 0 180)
			(size 0 0)
			(layers "F.Cu" "F.Mask" "F.Paste")
			(net "SW_P1V0_AUX_BST")
		)
		(pad "2" smd circle
			(at 0.40005 0 180)
			(size 0 0)
			(layers "F.Cu" "F.Mask" "F.Paste")
			(net "SW_P1V0_AUX_SW")
		)
	)
	(footprint ""
		(layer "F.Cu")
		(at 66.167 -28.0162)
		(property "Reference" "R441"
			(at 0 0 0)
			(layer "F.SilkS")
			(hide yes)
			(effects
				(font
					(size 1.27 1.27)
				)
			)
		)
		(property "Value" ""
			(at 0 0 0)
			(layer "F.Fab")
			(effects
				(font
					(size 1.27 1.27)
				)
			)
		)
		(duplicate_pad_numbers_are_jumpers no)
		(fp_line
			(start -0.5588 -0.4064)
			(end 0.7874 -0.4064)
			(stroke
				(width 0.1524)
				(type default)
			)
			(layer "F.SilkS")
		)
		(fp_line
			(start 0.7874 -0.4064)
			(end 0.7874 0.4064)
			(stroke
				(width 0.1524)
				(type default)
			)
			(layer "F.SilkS")
		)
		(fp_line
			(start 0.7874 0.4064)
			(end -0.4318 0.4064)
			(stroke
				(width 0.1524)
				(type default)
			)
			(layer "F.SilkS")
		)
		(fp_line
			(start -0.67945 -0.305054)
			(end -0.12065 -0.305054)
			(stroke
				(width 0.1)
				(type default)
			)
			(layer "F.Fab")
		)
		(fp_line
			(start -0.67945 0.3048)
			(end -0.67945 -0.305054)
			(stroke
				(width 0.1)
				(type default)
			)
			(layer "F.Fab")
		)
		(fp_line
			(start -0.12065 -0.305054)
			(end -0.12065 -0.2794)
			(stroke
				(width 0.1)
				(type default)
			)
			(layer "F.Fab")
		)
		(fp_line
			(start -0.12065 -0.2794)
			(end 0.12065 -0.2794)
			(stroke
				(width 0.1)
				(type default)
			)
			(layer "F.Fab")
		)
		(fp_line
			(start -0.12065 0.2794)
			(end -0.12065 0.3048)
			(stroke
				(width 0.1)
				(type default)
			)
			(layer "F.Fab")
		)
		(fp_line
			(start -0.12065 0.3048)
			(end -0.67945 0.3048)
			(stroke
				(width 0.1)
				(type default)
			)
			(layer "F.Fab")
		)
		(fp_line
			(start 0.120396 0.2794)
			(end -0.12065 0.2794)
			(stroke
				(width 0.1)
				(type default)
			)
			(layer "F.Fab")
		)
		(fp_line
			(start 0.120396 0.3048)
			(end 0.120396 0.2794)
			(stroke
				(width 0.1)
				(type default)
			)
			(layer "F.Fab")
		)
		(fp_line
			(start 0.12065 -0.3048)
			(end 0.67945 -0.3048)
			(stroke
				(width 0.1)
				(type default)
			)
			(layer "F.Fab")
		)
		(fp_line
			(start 0.12065 -0.2794)
			(end 0.12065 -0.3048)
			(stroke
				(width 0.1)
				(type default)
			)
			(layer "F.Fab")
		)
		(fp_line
			(start 0.67945 -0.3048)
			(end 0.67945 0.3048)
			(stroke
				(width 0.1)
				(type default)
			)
			(layer "F.Fab")
		)
		(fp_line
			(start 0.67945 0.3048)
			(end 0.120396 0.3048)
			(stroke
				(width 0.1)
				(type default)
			)
			(layer "F.Fab")
		)
		(pad "1" smd circle
			(at -0.40005 0)
			(size 0 0)
			(layers "F.Cu" "F.Mask" "F.Paste")
			(net "USB_HOST_BMC_A_DN")
		)
		(pad "2" smd circle
			(at 0.40005 0)
			(size 0 0)
			(layers "F.Cu" "F.Mask" "F.Paste")
			(net "GND")
		)
	)
	(footprint ""
		(layer "F.Cu")
		(at 77.947774 -69.407024 180)
		(property "Reference" "PR496"
			(at 0 0 180)
			(layer "F.SilkS")
			(hide yes)
			(effects
				(font
					(size 1.27 1.27)
				)
			)
		)
		(property "Value" ""
			(at 0 0 180)
			(layer "F.Fab")
			(effects
				(font
					(size 1.27 1.27)
				)
			)
		)
		(duplicate_pad_numbers_are_jumpers no)
		(fp_line
			(start 0.7874 0.4064)
			(end -0.7874 0.4064)
			(stroke
				(width 0.1524)
				(type default)
			)
			(layer "F.SilkS")
		)
		(fp_line
			(start 0.7874 -0.4064)
			(end 0.7874 0.4064)
			(stroke
				(width 0.1524)
				(type default)
			)
			(layer "F.SilkS")
		)
		(fp_line
			(start -0.7874 0.4064)
			(end -0.7874 -0.4064)
			(stroke
				(width 0.1524)
				(type default)
			)
			(layer "F.SilkS")
		)
		(fp_line
			(start -0.7874 -0.4064)
			(end 0.7874 -0.4064)
			(stroke
				(width 0.1524)
				(type default)
			)
			(layer "F.SilkS")
		)
		(fp_line
			(start 0.67945 0.3048)
			(end 0.120396 0.3048)
			(stroke
				(width 0.1)
				(type default)
			)
			(layer "F.Fab")
		)
		(fp_line
			(start 0.67945 -0.3048)
			(end 0.67945 0.3048)
			(stroke
				(width 0.1)
				(type default)
			)
			(layer "F.Fab")
		)
		(fp_line
			(start 0.12065 -0.2794)
			(end 0.12065 -0.3048)
			(stroke
				(width 0.1)
				(type default)
			)
			(layer "F.Fab")
		)
		(fp_line
			(start 0.12065 -0.3048)
			(end 0.67945 -0.3048)
			(stroke
				(width 0.1)
				(type default)
			)
			(layer "F.Fab")
		)
		(fp_line
			(start 0.120396 0.3048)
			(end 0.120396 0.2794)
			(stroke
				(width 0.1)
				(type default)
			)
			(layer "F.Fab")
		)
		(fp_line
			(start 0.120396 0.2794)
			(end -0.12065 0.2794)
			(stroke
				(width 0.1)
				(type default)
			)
			(layer "F.Fab")
		)
		(fp_line
			(start -0.12065 0.3048)
			(end -0.67945 0.3048)
			(stroke
				(width 0.1)
				(type default)
			)
			(layer "F.Fab")
		)
		(fp_line
			(start -0.12065 0.2794)
			(end -0.12065 0.3048)
			(stroke
				(width 0.1)
				(type default)
			)
			(layer "F.Fab")
		)
		(fp_line
			(start -0.12065 -0.2794)
			(end 0.12065 -0.2794)
			(stroke
				(width 0.1)
				(type default)
			)
			(layer "F.Fab")
		)
		(fp_line
			(start -0.12065 -0.305054)
			(end -0.12065 -0.2794)
			(stroke
				(width 0.1)
				(type default)
			)
			(layer "F.Fab")
		)
		(fp_line
			(start -0.67945 0.3048)
			(end -0.67945 -0.305054)
			(stroke
				(width 0.1)
				(type default)
			)
			(layer "F.Fab")
		)
		(fp_line
			(start -0.67945 -0.305054)
			(end -0.12065 -0.305054)
			(stroke
				(width 0.1)
				(type default)
			)
			(layer "F.Fab")
		)
		(pad "1" smd circle
			(at -0.40005 0 180)
			(size 0 0)
			(layers "F.Cu" "F.Mask" "F.Paste")
			(net "P1V2_AUX_MODE")
		)
		(pad "2" smd circle
			(at 0.40005 0 180)
			(size 0 0)
			(layers "F.Cu" "F.Mask" "F.Paste")
			(net "GND")
		)
	)
	(footprint ""
		(layer "F.Cu")
		(at 4.318 -80.899 -90)
		(property "Reference" "R388"
			(at 0 0 270)
			(layer "F.SilkS")
			(hide yes)
			(effects
				(font
					(size 1.27 1.27)
				)
			)
		)
		(property "Value" ""
			(at 0 0 270)
			(layer "F.Fab")
			(effects
				(font
					(size 1.27 1.27)
				)
			)
		)
		(duplicate_pad_numbers_are_jumpers no)
		(fp_line
			(start -0.7874 0.4064)
			(end -0.7874 -0.4064)
			(stroke
				(width 0.1524)
				(type default)
			)
			(layer "F.SilkS")
		)
		(fp_line
			(start 0.7874 0.4064)
			(end -0.7874 0.4064)
			(stroke
				(width 0.1524)
				(type default)
			)
			(layer "F.SilkS")
		)
		(fp_line
			(start -0.7874 -0.4064)
			(end 0.7874 -0.4064)
			(stroke
				(width 0.1524)
				(type default)
			)
			(layer "F.SilkS")
		)
		(fp_line
			(start 0.7874 -0.4064)
			(end 0.7874 0.4064)
			(stroke
				(width 0.1524)
				(type default)
			)
			(layer "F.SilkS")
		)
		(fp_line
			(start -0.67945 0.3048)
			(end -0.67945 -0.305054)
			(stroke
				(width 0.1)
				(type default)
			)
			(layer "F.Fab")
		)
		(fp_line
			(start -0.12065 0.3048)
			(end -0.67945 0.3048)
			(stroke
				(width 0.1)
				(type default)
			)
			(layer "F.Fab")
		)
		(fp_line
			(start 0.120396 0.3048)
			(end 0.120396 0.2794)
			(stroke
				(width 0.1)
				(type default)
			)
			(layer "F.Fab")
		)
		(fp_line
			(start 0.67945 0.3048)
			(end 0.120396 0.3048)
			(stroke
				(width 0.1)
				(type default)
			)
			(layer "F.Fab")
		)
		(fp_line
			(start -0.12065 0.2794)
			(end -0.12065 0.3048)
			(stroke
				(width 0.1)
				(type default)
			)
			(layer "F.Fab")
		)
		(fp_line
			(start 0.120396 0.2794)
			(end -0.12065 0.2794)
			(stroke
				(width 0.1)
				(type default)
			)
			(layer "F.Fab")
		)
		(fp_line
			(start -0.12065 -0.2794)
			(end 0.12065 -0.2794)
			(stroke
				(width 0.1)
				(type default)
			)
			(layer "F.Fab")
		)
		(fp_line
			(start 0.12065 -0.2794)
			(end 0.12065 -0.3048)
			(stroke
				(width 0.1)
				(type default)
			)
			(layer "F.Fab")
		)
		(fp_line
			(start 0.12065 -0.3048)
			(end 0.67945 -0.3048)
			(stroke
				(width 0.1)
				(type default)
			)
			(layer "F.Fab")
		)
		(fp_line
			(start 0.67945 -0.3048)
			(end 0.67945 0.3048)
			(stroke
				(width 0.1)
				(type default)
			)
			(layer "F.Fab")
		)
		(fp_line
			(start -0.67945 -0.305054)
			(end -0.12065 -0.305054)
			(stroke
				(width 0.1)
				(type default)
			)
			(layer "F.Fab")
		)
		(fp_line
			(start -0.12065 -0.305054)
			(end -0.12065 -0.2794)
			(stroke
				(width 0.1)
				(type default)
			)
			(layer "F.Fab")
		)
		(pad "1" smd circle
			(at -0.40005 0 270)
			(size 0 0)
			(layers "F.Cu" "F.Mask" "F.Paste")
			(net "RST_SRST_PLD_BMC_R_N")
		)
		(pad "2" smd circle
			(at 0.40005 0 270)
			(size 0 0)
			(layers "F.Cu" "F.Mask" "F.Paste")
			(net "RST_SRST_PLD_BMC_R1_N")
		)
	)
	(footprint ""
		(layer "F.Cu")
		(at 75.057 -21.336 180)
		(property "Reference" "D18"
			(at 1.143 1.11633 0)
			(unlocked yes)
			(layer "F.SilkS")
			(effects
				(font
					(size 0.7874 0.5842)
					(thickness 0.1524)
				)
				(justify left)
			)
		)
		(property "Value" ""
			(at 0 0 180)
			(layer "F.Fab")
			(effects
				(font
					(size 1.27 1.27)
				)
			)
		)
		(duplicate_pad_numbers_are_jumpers no)
		(fp_line
			(start 1.16078 0.4826)
			(end -0.64008 0.4826)
			(stroke
				(width 0.1524)
				(type default)
			)
			(layer "F.SilkS")
		)
		(fp_line
			(start 1.16078 -0.4826)
			(end 1.16078 0.4826)
			(stroke
				(width 0.1524)
				(type default)
			)
			(layer "F.SilkS")
		)
		(fp_line
			(start 1.03378 0.4826)
			(end -0.79248 0.4826)
			(stroke
				(width 0.1524)
				(type default)
			)
			(layer "F.SilkS")
		)
		(fp_line
			(start 1.03378 -0.4826)
			(end 1.03378 0.4826)
			(stroke
				(width 0.1524)
				(type default)
			)
			(layer "F.SilkS")
		)
		(fp_line
			(start 0.90678 0.4826)
			(end -0.90678 0.4826)
			(stroke
				(width 0.1524)
				(type default)
			)
			(layer "F.SilkS")
		)
		(fp_line
			(start 0.90678 -0.4826)
			(end 0.90678 0.4826)
			(stroke
				(width 0.1524)
				(type default)
			)
			(layer "F.SilkS")
		)
		(fp_line
			(start -0.64008 -0.4826)
			(end 1.16078 -0.4826)
			(stroke
				(width 0.1524)
				(type default)
			)
			(layer "F.SilkS")
		)
		(fp_line
			(start -0.79248 -0.4826)
			(end 1.03378 -0.4826)
			(stroke
				(width 0.1524)
				(type default)
			)
			(layer "F.SilkS")
		)
		(fp_line
			(start -0.89408 -0.4826)
			(end 0.90678 -0.4826)
			(stroke
				(width 0.1524)
				(type default)
			)
			(layer "F.SilkS")
		)
		(fp_line
			(start -0.90678 0.4826)
			(end -0.90678 -0.4699)
			(stroke
				(width 0.1524)
				(type default)
			)
			(layer "F.SilkS")
		)
		(fp_line
			(start 0.499872 0.249936)
			(end -0.499872 0.249936)
			(stroke
				(width 0.1)
				(type default)
			)
			(layer "F.Fab")
		)
		(fp_line
			(start 0.499872 -0.249936)
			(end 0.499872 0.249936)
			(stroke
				(width 0.1)
				(type default)
			)
			(layer "F.Fab")
		)
		(fp_line
			(start -0.499872 0.249936)
			(end -0.499872 -0.249936)
			(stroke
				(width 0.1)
				(type default)
			)
			(layer "F.Fab")
		)
		(fp_line
			(start -0.499872 -0.249936)
			(end 0.499872 -0.249936)
			(stroke
				(width 0.1)
				(type default)
			)
			(layer "F.Fab")
		)
		(pad "A" smd rect
			(at -0.47498 0 180)
			(size 0.6096 0.7112)
			(layers "F.Cu" "F.Mask" "F.Paste")
			(net "P3V3_AUX")
		)
		(pad "C" smd rect
			(at 0.47498 0 180)
			(size 0.6096 0.7112)
			(layers "F.Cu" "F.Mask" "F.Paste")
			(net "FM_UARTSW_LSB_R1_N")
		)
	)
	(footprint ""
		(layer "F.Cu")
		(at 27.559 -10.287 -90)
		(property "Reference" "R813"
			(at 0 0 270)
			(layer "F.SilkS")
			(hide yes)
			(effects
				(font
					(size 1.27 1.27)
				)
			)
		)
		(property "Value" ""
			(at 0 0 270)
			(layer "F.Fab")
			(effects
				(font
					(size 1.27 1.27)
				)
			)
		)
		(duplicate_pad_numbers_are_jumpers no)
		(fp_line
			(start -0.7874 0.4064)
			(end -0.7874 -0.4064)
			(stroke
				(width 0.1524)
				(type default)
			)
			(layer "F.SilkS")
		)
		(fp_line
			(start 0.7874 0.4064)
			(end -0.7874 0.4064)
			(stroke
				(width 0.1524)
				(type default)
			)
			(layer "F.SilkS")
		)
		(fp_line
			(start -0.7874 -0.4064)
			(end 0.7874 -0.4064)
			(stroke
				(width 0.1524)
				(type default)
			)
			(layer "F.SilkS")
		)
		(fp_line
			(start 0.7874 -0.4064)
			(end 0.7874 0.4064)
			(stroke
				(width 0.1524)
				(type default)
			)
			(layer "F.SilkS")
		)
		(fp_line
			(start -0.67945 0.3048)
			(end -0.67945 -0.305054)
			(stroke
				(width 0.1)
				(type default)
			)
			(layer "F.Fab")
		)
		(fp_line
			(start -0.12065 0.3048)
			(end -0.67945 0.3048)
			(stroke
				(width 0.1)
				(type default)
			)
			(layer "F.Fab")
		)
		(fp_line
			(start 0.120396 0.3048)
			(end 0.120396 0.2794)
			(stroke
				(width 0.1)
				(type default)
			)
			(layer "F.Fab")
		)
		(fp_line
			(start 0.67945 0.3048)
			(end 0.120396 0.3048)
			(stroke
				(width 0.1)
				(type default)
			)
			(layer "F.Fab")
		)
		(fp_line
			(start -0.12065 0.2794)
			(end -0.12065 0.3048)
			(stroke
				(width 0.1)
				(type default)
			)
			(layer "F.Fab")
		)
		(fp_line
			(start 0.120396 0.2794)
			(end -0.12065 0.2794)
			(stroke
				(width 0.1)
				(type default)
			)
			(layer "F.Fab")
		)
		(fp_line
			(start -0.12065 -0.2794)
			(end 0.12065 -0.2794)
			(stroke
				(width 0.1)
				(type default)
			)
			(layer "F.Fab")
		)
		(fp_line
			(start 0.12065 -0.2794)
			(end 0.12065 -0.3048)
			(stroke
				(width 0.1)
				(type default)
			)
			(layer "F.Fab")
		)
		(fp_line
			(start 0.12065 -0.3048)
			(end 0.67945 -0.3048)
			(stroke
				(width 0.1)
				(type default)
			)
			(layer "F.Fab")
		)
		(fp_line
			(start 0.67945 -0.3048)
			(end 0.67945 0.3048)
			(stroke
				(width 0.1)
				(type default)
			)
			(layer "F.Fab")
		)
		(fp_line
			(start -0.67945 -0.305054)
			(end -0.12065 -0.305054)
			(stroke
				(width 0.1)
				(type default)
			)
			(layer "F.Fab")
		)
		(fp_line
			(start -0.12065 -0.305054)
			(end -0.12065 -0.2794)
			(stroke
				(width 0.1)
				(type default)
			)
			(layer "F.Fab")
		)
		(pad "1" smd circle
			(at -0.40005 0 270)
			(size 0 0)
			(layers "F.Cu" "F.Mask" "F.Paste")
			(net "HDD_LED_BUF")
		)
		(pad "2" smd circle
			(at 0.40005 0 270)
			(size 0 0)
			(layers "F.Cu" "F.Mask" "F.Paste")
			(net "HDD_LED_BUF_R")
		)
	)
	(footprint ""
		(layer "F.Cu")
		(at 21.463 -102.743 -90)
		(property "Reference" "R747"
			(at 0 0 270)
			(layer "F.SilkS")
			(hide yes)
			(effects
				(font
					(size 1.27 1.27)
				)
			)
		)
		(property "Value" ""
			(at 0 0 270)
			(layer "F.Fab")
			(effects
				(font
					(size 1.27 1.27)
				)
			)
		)
		(duplicate_pad_numbers_are_jumpers no)
		(fp_line
			(start -0.7874 0.4064)
			(end -0.7874 -0.4064)
			(stroke
				(width 0.1524)
				(type default)
			)
			(layer "F.SilkS")
		)
		(fp_line
			(start 0.7874 0.4064)
			(end -0.7874 0.4064)
			(stroke
				(width 0.1524)
				(type default)
			)
			(layer "F.SilkS")
		)
		(fp_line
			(start -0.7874 -0.4064)
			(end 0.7874 -0.4064)
			(stroke
				(width 0.1524)
				(type default)
			)
			(layer "F.SilkS")
		)
		(fp_line
			(start 0.7874 -0.4064)
			(end 0.7874 0.4064)
			(stroke
				(width 0.1524)
				(type default)
			)
			(layer "F.SilkS")
		)
		(fp_line
			(start -0.67945 0.3048)
			(end -0.67945 -0.305054)
			(stroke
				(width 0.1)
				(type default)
			)
			(layer "F.Fab")
		)
		(fp_line
			(start -0.12065 0.3048)
			(end -0.67945 0.3048)
			(stroke
				(width 0.1)
				(type default)
			)
			(layer "F.Fab")
		)
		(fp_line
			(start 0.120396 0.3048)
			(end 0.120396 0.2794)
			(stroke
				(width 0.1)
				(type default)
			)
			(layer "F.Fab")
		)
		(fp_line
			(start 0.67945 0.3048)
			(end 0.120396 0.3048)
			(stroke
				(width 0.1)
				(type default)
			)
			(layer "F.Fab")
		)
		(fp_line
			(start -0.12065 0.2794)
			(end -0.12065 0.3048)
			(stroke
				(width 0.1)
				(type default)
			)
			(layer "F.Fab")
		)
		(fp_line
			(start 0.120396 0.2794)
			(end -0.12065 0.2794)
			(stroke
				(width 0.1)
				(type default)
			)
			(layer "F.Fab")
		)
		(fp_line
			(start -0.12065 -0.2794)
			(end 0.12065 -0.2794)
			(stroke
				(width 0.1)
				(type default)
			)
			(layer "F.Fab")
		)
		(fp_line
			(start 0.12065 -0.2794)
			(end 0.12065 -0.3048)
			(stroke
				(width 0.1)
				(type default)
			)
			(layer "F.Fab")
		)
		(fp_line
			(start 0.12065 -0.3048)
			(end 0.67945 -0.3048)
			(stroke
				(width 0.1)
				(type default)
			)
			(layer "F.Fab")
		)
		(fp_line
			(start 0.67945 -0.3048)
			(end 0.67945 0.3048)
			(stroke
				(width 0.1)
				(type default)
			)
			(layer "F.Fab")
		)
		(fp_line
			(start -0.67945 -0.305054)
			(end -0.12065 -0.305054)
			(stroke
				(width 0.1)
				(type default)
			)
			(layer "F.Fab")
		)
		(fp_line
			(start -0.12065 -0.305054)
			(end -0.12065 -0.2794)
			(stroke
				(width 0.1)
				(type default)
			)
			(layer "F.Fab")
		)
		(pad "1" smd circle
			(at -0.40005 0 270)
			(size 0 0)
			(layers "F.Cu" "F.Mask" "F.Paste")
			(net "FM_BMC_CRASHLOG_TRIG_N")
		)
		(pad "2" smd circle
			(at 0.40005 0 270)
			(size 0 0)
			(layers "F.Cu" "F.Mask" "F.Paste")
			(net "FM_BMC_CRASHLOG_TRIG_R2_N")
		)
	)
	(footprint ""
		(layer "F.Cu")
		(at 43.6626 -34.6456 -90)
		(property "Reference" "R112"
			(at 0 0 270)
			(layer "F.SilkS")
			(hide yes)
			(effects
				(font
					(size 1.27 1.27)
				)
			)
		)
		(property "Value" ""
			(at 0 0 270)
			(layer "F.Fab")
			(effects
				(font
					(size 1.27 1.27)
				)
			)
		)
		(duplicate_pad_numbers_are_jumpers no)
		(fp_line
			(start -0.7874 0.4064)
			(end -0.7874 -0.4064)
			(stroke
				(width 0.1524)
				(type default)
			)
			(layer "F.SilkS")
		)
		(fp_line
			(start 0.7874 0.4064)
			(end -0.7874 0.4064)
			(stroke
				(width 0.1524)
				(type default)
			)
			(layer "F.SilkS")
		)
		(fp_line
			(start -0.7874 -0.4064)
			(end 0.7874 -0.4064)
			(stroke
				(width 0.1524)
				(type default)
			)
			(layer "F.SilkS")
		)
		(fp_line
			(start 0.7874 -0.4064)
			(end 0.7874 0.4064)
			(stroke
				(width 0.1524)
				(type default)
			)
			(layer "F.SilkS")
		)
		(fp_line
			(start -0.67945 0.3048)
			(end -0.67945 -0.305054)
			(stroke
				(width 0.1)
				(type default)
			)
			(layer "F.Fab")
		)
		(fp_line
			(start -0.12065 0.3048)
			(end -0.67945 0.3048)
			(stroke
				(width 0.1)
				(type default)
			)
			(layer "F.Fab")
		)
		(fp_line
			(start 0.120396 0.3048)
			(end 0.120396 0.2794)
			(stroke
				(width 0.1)
				(type default)
			)
			(layer "F.Fab")
		)
		(fp_line
			(start 0.67945 0.3048)
			(end 0.120396 0.3048)
			(stroke
				(width 0.1)
				(type default)
			)
			(layer "F.Fab")
		)
		(fp_line
			(start -0.12065 0.2794)
			(end -0.12065 0.3048)
			(stroke
				(width 0.1)
				(type default)
			)
			(layer "F.Fab")
		)
		(fp_line
			(start 0.120396 0.2794)
			(end -0.12065 0.2794)
			(stroke
				(width 0.1)
				(type default)
			)
			(layer "F.Fab")
		)
		(fp_line
			(start -0.12065 -0.2794)
			(end 0.12065 -0.2794)
			(stroke
				(width 0.1)
				(type default)
			)
			(layer "F.Fab")
		)
		(fp_line
			(start 0.12065 -0.2794)
			(end 0.12065 -0.3048)
			(stroke
				(width 0.1)
				(type default)
			)
			(layer "F.Fab")
		)
		(fp_line
			(start 0.12065 -0.3048)
			(end 0.67945 -0.3048)
			(stroke
				(width 0.1)
				(type default)
			)
			(layer "F.Fab")
		)
		(fp_line
			(start 0.67945 -0.3048)
			(end 0.67945 0.3048)
			(stroke
				(width 0.1)
				(type default)
			)
			(layer "F.Fab")
		)
		(fp_line
			(start -0.67945 -0.305054)
			(end -0.12065 -0.305054)
			(stroke
				(width 0.1)
				(type default)
			)
			(layer "F.Fab")
		)
		(fp_line
			(start -0.12065 -0.305054)
			(end -0.12065 -0.2794)
			(stroke
				(width 0.1)
				(type default)
			)
			(layer "F.Fab")
		)
		(pad "1" smd circle
			(at -0.40005 0 270)
			(size 0 0)
			(layers "F.Cu" "F.Mask" "F.Paste")
			(net "FM_BIOS_DEBUG_EN_R_N")
		)
		(pad "2" smd circle
			(at 0.40005 0 270)
			(size 0 0)
			(layers "F.Cu" "F.Mask" "F.Paste")
			(net "FM_BIOS_DEBUG_EN_N")
		)
	)
	(footprint ""
		(layer "F.Cu")
		(at 77.55128 -59.065922 -90)
		(property "Reference" "PC259"
			(at 0 0 270)
			(layer "F.SilkS")
			(hide yes)
			(effects
				(font
					(size 1.27 1.27)
				)
			)
		)
		(property "Value" ""
			(at 0 0 270)
			(layer "F.Fab")
			(effects
				(font
					(size 1.27 1.27)
				)
			)
		)
		(duplicate_pad_numbers_are_jumpers no)
		(fp_line
			(start -1.651 0.8382)
			(end -1.651 -0.8382)
			(stroke
				(width 0.1524)
				(type default)
			)
			(layer "F.SilkS")
		)
		(fp_line
			(start 0 0.8382)
			(end 0 -0.8382)
			(stroke
				(width 0.1524)
				(type default)
			)
			(layer "F.SilkS")
		)
		(fp_line
			(start 1.651 0.8382)
			(end -1.651 0.8382)
			(stroke
				(width 0.1524)
				(type default)
			)
			(layer "F.SilkS")
		)
		(fp_line
			(start -1.651 -0.8382)
			(end 1.651 -0.8382)
			(stroke
				(width 0.1524)
				(type default)
			)
			(layer "F.SilkS")
		)
		(fp_line
			(start 1.651 -0.8382)
			(end 1.651 0.8382)
			(stroke
				(width 0.1524)
				(type default)
			)
			(layer "F.SilkS")
		)
		(fp_line
			(start -1.55956 0.7366)
			(end -1.524 0.7366)
			(stroke
				(width 0.1)
				(type default)
			)
			(layer "F.Fab")
		)
		(fp_line
			(start -1.524 0.7366)
			(end 1.524 0.7366)
			(stroke
				(width 0.1)
				(type default)
			)
			(layer "F.Fab")
		)
		(fp_line
			(start 1.524 0.7366)
			(end 1.55956 0.7366)
			(stroke
				(width 0.1)
				(type default)
			)
			(layer "F.Fab")
		)
		(fp_line
			(start 1.55956 0.7366)
			(end 1.55956 -0.7366)
			(stroke
				(width 0.1)
				(type default)
			)
			(layer "F.Fab")
		)
		(fp_line
			(start -1.55956 -0.7366)
			(end -1.55956 0.7366)
			(stroke
				(width 0.1)
				(type default)
			)
			(layer "F.Fab")
		)
		(fp_line
			(start -1.524 -0.7366)
			(end -1.55956 -0.7366)
			(stroke
				(width 0.1)
				(type default)
			)
			(layer "F.Fab")
		)
		(fp_line
			(start 1.524 -0.7366)
			(end -1.524 -0.7366)
			(stroke
				(width 0.1)
				(type default)
			)
			(layer "F.Fab")
		)
		(fp_line
			(start 1.55956 -0.7366)
			(end 1.524 -0.7366)
			(stroke
				(width 0.1)
				(type default)
			)
			(layer "F.Fab")
		)
		(pad "1" smd rect
			(at -0.94996 0 90)
			(size 1.1176 1.3716)
			(layers "F.Cu" "F.Mask" "F.Paste")
			(net "P1V2_AUX")
		)
		(pad "2" smd rect
			(at 0.94996 0 90)
			(size 1.1176 1.3716)
			(layers "F.Cu" "F.Mask" "F.Paste")
			(net "GND")
		)
	)
	(footprint ""
		(layer "F.Cu")
		(at 81.788 -37.211 90)
		(property "Reference" "C153"
			(at 0 0 90)
			(layer "F.SilkS")
			(hide yes)
			(effects
				(font
					(size 1.27 1.27)
				)
			)
		)
		(property "Value" ""
			(at 0 0 90)
			(layer "F.Fab")
			(effects
				(font
					(size 1.27 1.27)
				)
			)
		)
		(duplicate_pad_numbers_are_jumpers no)
		(fp_line
			(start 0.7874 -0.4064)
			(end 0.7874 0.4064)
			(stroke
				(width 0.1524)
				(type default)
			)
			(layer "F.SilkS")
		)
		(fp_line
			(start -0.7874 -0.4064)
			(end 0.7874 -0.4064)
			(stroke
				(width 0.1524)
				(type default)
			)
			(layer "F.SilkS")
		)
		(fp_line
			(start 0.7874 0.4064)
			(end -0.7874 0.4064)
			(stroke
				(width 0.1524)
				(type default)
			)
			(layer "F.SilkS")
		)
		(fp_line
			(start -0.7874 0.4064)
			(end -0.7874 -0.4064)
			(stroke
				(width 0.1524)
				(type default)
			)
			(layer "F.SilkS")
		)
		(fp_line
			(start -0.12065 -0.305054)
			(end -0.12065 -0.2794)
			(stroke
				(width 0.1)
				(type default)
			)
			(layer "F.Fab")
		)
		(fp_line
			(start -0.67945 -0.305054)
			(end -0.12065 -0.305054)
			(stroke
				(width 0.1)
				(type default)
			)
			(layer "F.Fab")
		)
		(fp_line
			(start 0.67945 -0.3048)
			(end 0.67945 0.3048)
			(stroke
				(width 0.1)
				(type default)
			)
			(layer "F.Fab")
		)
		(fp_line
			(start 0.12065 -0.3048)
			(end 0.67945 -0.3048)
			(stroke
				(width 0.1)
				(type default)
			)
			(layer "F.Fab")
		)
		(fp_line
			(start 0.12065 -0.2794)
			(end 0.12065 -0.3048)
			(stroke
				(width 0.1)
				(type default)
			)
			(layer "F.Fab")
		)
		(fp_line
			(start -0.12065 -0.2794)
			(end 0.12065 -0.2794)
			(stroke
				(width 0.1)
				(type default)
			)
			(layer "F.Fab")
		)
		(fp_line
			(start 0.120396 0.2794)
			(end -0.12065 0.2794)
			(stroke
				(width 0.1)
				(type default)
			)
			(layer "F.Fab")
		)
		(fp_line
			(start -0.12065 0.2794)
			(end -0.12065 0.3048)
			(stroke
				(width 0.1)
				(type default)
			)
			(layer "F.Fab")
		)
		(fp_line
			(start 0.67945 0.3048)
			(end 0.120396 0.3048)
			(stroke
				(width 0.1)
				(type default)
			)
			(layer "F.Fab")
		)
		(fp_line
			(start 0.120396 0.3048)
			(end 0.120396 0.2794)
			(stroke
				(width 0.1)
				(type default)
			)
			(layer "F.Fab")
		)
		(fp_line
			(start -0.12065 0.3048)
			(end -0.67945 0.3048)
			(stroke
				(width 0.1)
				(type default)
			)
			(layer "F.Fab")
		)
		(fp_line
			(start -0.67945 0.3048)
			(end -0.67945 -0.305054)
			(stroke
				(width 0.1)
				(type default)
			)
			(layer "F.Fab")
		)
		(pad "1" smd circle
			(at -0.40005 0 90)
			(size 0 0)
			(layers "F.Cu" "F.Mask" "F.Paste")
			(net "PWRGD_P2V5_AUX_R")
		)
		(pad "2" smd circle
			(at 0.40005 0 90)
			(size 0 0)
			(layers "F.Cu" "F.Mask" "F.Paste")
			(net "GND")
		)
	)
	(footprint ""
		(layer "F.Cu")
		(at 84.201 -91.059)
		(property "Reference" "R408"
			(at 0 0 0)
			(layer "F.SilkS")
			(hide yes)
			(effects
				(font
					(size 1.27 1.27)
				)
			)
		)
		(property "Value" ""
			(at 0 0 0)
			(layer "F.Fab")
			(effects
				(font
					(size 1.27 1.27)
				)
			)
		)
		(duplicate_pad_numbers_are_jumpers no)
		(fp_line
			(start -0.7874 -0.4064)
			(end 0.7874 -0.4064)
			(stroke
				(width 0.1524)
				(type default)
			)
			(layer "F.SilkS")
		)
		(fp_line
			(start -0.7874 0.4064)
			(end -0.7874 -0.4064)
			(stroke
				(width 0.1524)
				(type default)
			)
			(layer "F.SilkS")
		)
		(fp_line
			(start 0.7874 -0.4064)
			(end 0.7874 0.4064)
			(stroke
				(width 0.1524)
				(type default)
			)
			(layer "F.SilkS")
		)
		(fp_line
			(start 0.7874 0.4064)
			(end -0.7874 0.4064)
			(stroke
				(width 0.1524)
				(type default)
			)
			(layer "F.SilkS")
		)
		(fp_line
			(start -0.67945 -0.305054)
			(end -0.12065 -0.305054)
			(stroke
				(width 0.1)
				(type default)
			)
			(layer "F.Fab")
		)
		(fp_line
			(start -0.67945 0.3048)
			(end -0.67945 -0.305054)
			(stroke
				(width 0.1)
				(type default)
			)
			(layer "F.Fab")
		)
		(fp_line
			(start -0.12065 -0.305054)
			(end -0.12065 -0.2794)
			(stroke
				(width 0.1)
				(type default)
			)
			(layer "F.Fab")
		)
		(fp_line
			(start -0.12065 -0.2794)
			(end 0.12065 -0.2794)
			(stroke
				(width 0.1)
				(type default)
			)
			(layer "F.Fab")
		)
		(fp_line
			(start -0.12065 0.2794)
			(end -0.12065 0.3048)
			(stroke
				(width 0.1)
				(type default)
			)
			(layer "F.Fab")
		)
		(fp_line
			(start -0.12065 0.3048)
			(end -0.67945 0.3048)
			(stroke
				(width 0.1)
				(type default)
			)
			(layer "F.Fab")
		)
		(fp_line
			(start 0.120396 0.2794)
			(end -0.12065 0.2794)
			(stroke
				(width 0.1)
				(type default)
			)
			(layer "F.Fab")
		)
		(fp_line
			(start 0.120396 0.3048)
			(end 0.120396 0.2794)
			(stroke
				(width 0.1)
				(type default)
			)
			(layer "F.Fab")
		)
		(fp_line
			(start 0.12065 -0.3048)
			(end 0.67945 -0.3048)
			(stroke
				(width 0.1)
				(type default)
			)
			(layer "F.Fab")
		)
		(fp_line
			(start 0.12065 -0.2794)
			(end 0.12065 -0.3048)
			(stroke
				(width 0.1)
				(type default)
			)
			(layer "F.Fab")
		)
		(fp_line
			(start 0.67945 -0.3048)
			(end 0.67945 0.3048)
			(stroke
				(width 0.1)
				(type default)
			)
			(layer "F.Fab")
		)
		(fp_line
			(start 0.67945 0.3048)
			(end 0.120396 0.3048)
			(stroke
				(width 0.1)
				(type default)
			)
			(layer "F.Fab")
		)
		(pad "1" smd circle
			(at -0.40005 0)
			(size 0 0)
			(layers "F.Cu" "F.Mask" "F.Paste")
			(net "P3V3_AUX")
		)
		(pad "2" smd circle
			(at 0.40005 0)
			(size 0 0)
			(layers "F.Cu" "F.Mask" "F.Paste")
			(net "SPI_BMC_TPM_CLK")
		)
	)
	(footprint ""
		(layer "F.Cu")
		(at 72.277732 -35.154362 180)
		(property "Reference" "C129"
			(at 0 0 180)
			(layer "F.SilkS")
			(hide yes)
			(effects
				(font
					(size 1.27 1.27)
				)
			)
		)
		(property "Value" ""
			(at 0 0 180)
			(layer "F.Fab")
			(effects
				(font
					(size 1.27 1.27)
				)
			)
		)
		(duplicate_pad_numbers_are_jumpers no)
		(fp_line
			(start 0.7874 0.4064)
			(end -0.7874 0.4064)
			(stroke
				(width 0.1524)
				(type default)
			)
			(layer "F.SilkS")
		)
		(fp_line
			(start 0.7874 -0.4064)
			(end 0.7874 0.4064)
			(stroke
				(width 0.1524)
				(type default)
			)
			(layer "F.SilkS")
		)
		(fp_line
			(start -0.7874 0.4064)
			(end -0.7874 -0.4064)
			(stroke
				(width 0.1524)
				(type default)
			)
			(layer "F.SilkS")
		)
		(fp_line
			(start -0.7874 -0.4064)
			(end 0.7874 -0.4064)
			(stroke
				(width 0.1524)
				(type default)
			)
			(layer "F.SilkS")
		)
		(fp_line
			(start 0.67945 0.3048)
			(end 0.120396 0.3048)
			(stroke
				(width 0.1)
				(type default)
			)
			(layer "F.Fab")
		)
		(fp_line
			(start 0.67945 -0.3048)
			(end 0.67945 0.3048)
			(stroke
				(width 0.1)
				(type default)
			)
			(layer "F.Fab")
		)
		(fp_line
			(start 0.12065 -0.2794)
			(end 0.12065 -0.3048)
			(stroke
				(width 0.1)
				(type default)
			)
			(layer "F.Fab")
		)
		(fp_line
			(start 0.12065 -0.3048)
			(end 0.67945 -0.3048)
			(stroke
				(width 0.1)
				(type default)
			)
			(layer "F.Fab")
		)
		(fp_line
			(start 0.120396 0.3048)
			(end 0.120396 0.2794)
			(stroke
				(width 0.1)
				(type default)
			)
			(layer "F.Fab")
		)
		(fp_line
			(start 0.120396 0.2794)
			(end -0.12065 0.2794)
			(stroke
				(width 0.1)
				(type default)
			)
			(layer "F.Fab")
		)
		(fp_line
			(start -0.12065 0.3048)
			(end -0.67945 0.3048)
			(stroke
				(width 0.1)
				(type default)
			)
			(layer "F.Fab")
		)
		(fp_line
			(start -0.12065 0.2794)
			(end -0.12065 0.3048)
			(stroke
				(width 0.1)
				(type default)
			)
			(layer "F.Fab")
		)
		(fp_line
			(start -0.12065 -0.2794)
			(end 0.12065 -0.2794)
			(stroke
				(width 0.1)
				(type default)
			)
			(layer "F.Fab")
		)
		(fp_line
			(start -0.12065 -0.305054)
			(end -0.12065 -0.2794)
			(stroke
				(width 0.1)
				(type default)
			)
			(layer "F.Fab")
		)
		(fp_line
			(start -0.67945 0.3048)
			(end -0.67945 -0.305054)
			(stroke
				(width 0.1)
				(type default)
			)
			(layer "F.Fab")
		)
		(fp_line
			(start -0.67945 -0.305054)
			(end -0.12065 -0.305054)
			(stroke
				(width 0.1)
				(type default)
			)
			(layer "F.Fab")
		)
		(pad "1" smd circle
			(at -0.40005 0 180)
			(size 0 0)
			(layers "F.Cu" "F.Mask" "F.Paste")
			(net "P1V2_AUX")
		)
		(pad "2" smd circle
			(at 0.40005 0 180)
			(size 0 0)
			(layers "F.Cu" "F.Mask" "F.Paste")
			(net "GND")
		)
	)
	(footprint ""
		(layer "F.Cu")
		(at 12.319 -85.344)
		(property "Reference" "R453"
			(at 0 0 0)
			(layer "F.SilkS")
			(hide yes)
			(effects
				(font
					(size 1.27 1.27)
				)
			)
		)
		(property "Value" ""
			(at 0 0 0)
			(layer "F.Fab")
			(effects
				(font
					(size 1.27 1.27)
				)
			)
		)
		(duplicate_pad_numbers_are_jumpers no)
		(fp_line
			(start -0.7874 -0.4064)
			(end 0.7874 -0.4064)
			(stroke
				(width 0.1524)
				(type default)
			)
			(layer "F.SilkS")
		)
		(fp_line
			(start -0.7874 0.4064)
			(end -0.7874 -0.4064)
			(stroke
				(width 0.1524)
				(type default)
			)
			(layer "F.SilkS")
		)
		(fp_line
			(start 0.7874 -0.4064)
			(end 0.7874 0.4064)
			(stroke
				(width 0.1524)
				(type default)
			)
			(layer "F.SilkS")
		)
		(fp_line
			(start 0.7874 0.4064)
			(end -0.7874 0.4064)
			(stroke
				(width 0.1524)
				(type default)
			)
			(layer "F.SilkS")
		)
		(fp_line
			(start -0.67945 -0.305054)
			(end -0.12065 -0.305054)
			(stroke
				(width 0.1)
				(type default)
			)
			(layer "F.Fab")
		)
		(fp_line
			(start -0.67945 0.3048)
			(end -0.67945 -0.305054)
			(stroke
				(width 0.1)
				(type default)
			)
			(layer "F.Fab")
		)
		(fp_line
			(start -0.12065 -0.305054)
			(end -0.12065 -0.2794)
			(stroke
				(width 0.1)
				(type default)
			)
			(layer "F.Fab")
		)
		(fp_line
			(start -0.12065 -0.2794)
			(end 0.12065 -0.2794)
			(stroke
				(width 0.1)
				(type default)
			)
			(layer "F.Fab")
		)
		(fp_line
			(start -0.12065 0.2794)
			(end -0.12065 0.3048)
			(stroke
				(width 0.1)
				(type default)
			)
			(layer "F.Fab")
		)
		(fp_line
			(start -0.12065 0.3048)
			(end -0.67945 0.3048)
			(stroke
				(width 0.1)
				(type default)
			)
			(layer "F.Fab")
		)
		(fp_line
			(start 0.120396 0.2794)
			(end -0.12065 0.2794)
			(stroke
				(width 0.1)
				(type default)
			)
			(layer "F.Fab")
		)
		(fp_line
			(start 0.120396 0.3048)
			(end 0.120396 0.2794)
			(stroke
				(width 0.1)
				(type default)
			)
			(layer "F.Fab")
		)
		(fp_line
			(start 0.12065 -0.3048)
			(end 0.67945 -0.3048)
			(stroke
				(width 0.1)
				(type default)
			)
			(layer "F.Fab")
		)
		(fp_line
			(start 0.12065 -0.2794)
			(end 0.12065 -0.3048)
			(stroke
				(width 0.1)
				(type default)
			)
			(layer "F.Fab")
		)
		(fp_line
			(start 0.67945 -0.3048)
			(end 0.67945 0.3048)
			(stroke
				(width 0.1)
				(type default)
			)
			(layer "F.Fab")
		)
		(fp_line
			(start 0.67945 0.3048)
			(end 0.120396 0.3048)
			(stroke
				(width 0.1)
				(type default)
			)
			(layer "F.Fab")
		)
		(pad "1" smd circle
			(at -0.40005 0)
			(size 0 0)
			(layers "F.Cu" "F.Mask" "F.Paste")
			(net "SMB_BMC_ALERT3_N")
		)
		(pad "2" smd circle
			(at 0.40005 0)
			(size 0 0)
			(layers "F.Cu" "F.Mask" "F.Paste")
			(net "SMB_BMC_ALERT3_R1_N")
		)
	)
	(footprint ""
		(layer "F.Cu")
		(at 112.014 -50.8 90)
		(property "Reference" "X5"
			(at -0.0508 5.50037 90)
			(unlocked yes)
			(layer "F.SilkS")
			(effects
				(font
					(size 0.7874 0.5842)
					(thickness 0.1524)
				)
				(justify left)
			)
		)
		(property "Value" ""
			(at 0 0 90)
			(layer "F.Fab")
			(effects
				(font
					(size 1.27 1.27)
				)
			)
		)
		(property "Device Type" "TP_TDR_4P_FTS_TH-TP_TDR_4P_DIPA"
			(at 1.30175 1.27 180)
			(unlocked yes)
			(layer "F.Fab")
			(hide yes)
			(effects
				(font
					(size 0.635 0.4064)
					(thickness 0.1524)
				)
			)
		)
		(property "User Part Number" "N_A"
			(at 1.30175 1.27 180)
			(unlocked yes)
			(layer "Cmts.User")
			(hide yes)
			(effects
				(font
					(size 0.635 0.4064)
					(thickness 0.1524)
				)
			)
		)
		(duplicate_pad_numbers_are_jumpers no)
		(fp_line
			(start 2.54 -1.27)
			(end 0 -1.27)
			(stroke
				(width 0.1524)
				(type default)
			)
			(layer "F.SilkS")
		)
		(fp_line
			(start 0 -1.27)
			(end 0 -0.635)
			(stroke
				(width 0.1524)
				(type default)
			)
			(layer "F.SilkS")
		)
		(fp_line
			(start 2.54 -1.1303)
			(end 2.54 -1.27)
			(stroke
				(width 0.1524)
				(type default)
			)
			(layer "F.SilkS")
		)
		(fp_line
			(start 0 0.635)
			(end 0 1.905)
			(stroke
				(width 0.1524)
				(type default)
			)
			(layer "F.SilkS")
		)
		(fp_line
			(start 2.54 1.4097)
			(end 2.54 1.1303)
			(stroke
				(width 0.1524)
				(type default)
			)
			(layer "F.SilkS")
		)
		(fp_line
			(start 0 3.175)
			(end 0 3.81)
			(stroke
				(width 0.1524)
				(type default)
			)
			(layer "F.SilkS")
		)
		(fp_line
			(start 2.54 3.81)
			(end 2.54 3.6703)
			(stroke
				(width 0.1524)
				(type default)
			)
			(layer "F.SilkS")
		)
		(fp_line
			(start 0 3.81)
			(end 2.54 3.81)
			(stroke
				(width 0.1524)
				(type default)
			)
			(layer "F.SilkS")
		)
		(fp_poly
			(pts
				(xy -0.761746 0) (xy -2.285746 -0.762) (xy -2.285746 0.762)
			)
			(stroke
				(width 0)
				(type default)
			)
			(fill yes)
			(layer "F.SilkS")
		)
		(fp_line
			(start 2.54 -1.27)
			(end 0 -1.27)
			(stroke
				(width 0.1)
				(type default)
			)
			(layer "F.Fab")
		)
		(fp_line
			(start 0 -1.27)
			(end 0 3.81)
			(stroke
				(width 0.1)
				(type default)
			)
			(layer "F.Fab")
		)
		(fp_line
			(start 2.54 3.81)
			(end 2.54 -1.27)
			(stroke
				(width 0.1)
				(type default)
			)
			(layer "F.Fab")
		)
		(fp_line
			(start 0 3.81)
			(end 2.54 3.81)
			(stroke
				(width 0.1)
				(type default)
			)
			(layer "F.Fab")
		)
		(fp_poly
			(pts
				(xy -0.761746 0) (xy -2.285746 -0.762) (xy -2.285746 0.762)
			)
			(stroke
				(width 0)
				(type default)
			)
			(fill yes)
			(layer "F.Fab")
		)
		(pad "1" thru_hole circle
			(at 0 0 90)
			(size 1.0033 1.0033)
			(drill 0.249936)
			(layers "*.Cu" "*.Mask")
			(remove_unused_layers no)
			(net "TDR_DIFF_85_IN4_DP")
			(clearance 0.10795)
			(thermal_gap 0.10795)
			(padstack
				(mode front_inner_back)
				(layer "Inner"
					(shape circle)
					(size 0.8001 0.8001)
					(clearance 0.1524)
				)
				(layer "B.Cu"
					(shape circle)
					(size 1.0033 1.0033)
					(clearance 0.10795)
				)
			)
		)
		(pad "2" thru_hole circle
			(at 2.54 0 90)
			(size 1.9939 1.9939)
			(drill 0.249936)
			(layers "*.Cu" "*.Mask")
			(remove_unused_layers no)
			(net "GND_P1")
			(clearance 0.10795)
			(thermal_gap 0.10795)
			(padstack
				(mode front_inner_back)
				(layer "Inner"
					(shape circle)
					(size 0.8001 0.8001)
					(clearance 0.1524)
				)
				(layer "B.Cu"
					(shape circle)
					(size 1.9939 1.9939)
					(clearance 0.10795)
				)
			)
		)
		(pad "3" thru_hole circle
			(at 2.54 2.54 90)
			(size 1.9939 1.9939)
			(drill 0.249936)
			(layers "*.Cu" "*.Mask")
			(remove_unused_layers no)
			(net "GND_P1")
			(clearance 0.10795)
			(thermal_gap 0.10795)
			(padstack
				(mode front_inner_back)
				(layer "Inner"
					(shape circle)
					(size 0.8001 0.8001)
					(clearance 0.1524)
				)
				(layer "B.Cu"
					(shape circle)
					(size 1.9939 1.9939)
					(clearance 0.10795)
				)
			)
		)
		(pad "4" thru_hole circle
			(at 0 2.54 90)
			(size 1.0033 1.0033)
			(drill 0.249936)
			(layers "*.Cu" "*.Mask")
			(remove_unused_layers no)
			(net "TDR_DIFF_85_IN4_DN")
			(clearance 0.10795)
			(thermal_gap 0.10795)
			(padstack
				(mode front_inner_back)
				(layer "Inner"
					(shape circle)
					(size 0.8001 0.8001)
					(clearance 0.1524)
				)
				(layer "B.Cu"
					(shape circle)
					(size 1.0033 1.0033)
					(clearance 0.10795)
				)
			)
		)
	)
	(footprint ""
		(layer "F.Cu")
		(at 32.70504 -70.536054 90)
		(property "Reference" "R653"
			(at 0 0 90)
			(layer "F.SilkS")
			(hide yes)
			(effects
				(font
					(size 1.27 1.27)
				)
			)
		)
		(property "Value" ""
			(at 0 0 90)
			(layer "F.Fab")
			(effects
				(font
					(size 1.27 1.27)
				)
			)
		)
		(duplicate_pad_numbers_are_jumpers no)
		(fp_line
			(start 0.7874 -0.4064)
			(end 0.7874 0.4064)
			(stroke
				(width 0.1524)
				(type default)
			)
			(layer "F.SilkS")
		)
		(fp_line
			(start -0.7874 -0.4064)
			(end 0.7874 -0.4064)
			(stroke
				(width 0.1524)
				(type default)
			)
			(layer "F.SilkS")
		)
		(fp_line
			(start 0.7874 0.4064)
			(end -0.7874 0.4064)
			(stroke
				(width 0.1524)
				(type default)
			)
			(layer "F.SilkS")
		)
		(fp_line
			(start -0.7874 0.4064)
			(end -0.7874 -0.4064)
			(stroke
				(width 0.1524)
				(type default)
			)
			(layer "F.SilkS")
		)
		(fp_line
			(start -0.12065 -0.305054)
			(end -0.12065 -0.2794)
			(stroke
				(width 0.1)
				(type default)
			)
			(layer "F.Fab")
		)
		(fp_line
			(start -0.67945 -0.305054)
			(end -0.12065 -0.305054)
			(stroke
				(width 0.1)
				(type default)
			)
			(layer "F.Fab")
		)
		(fp_line
			(start 0.67945 -0.3048)
			(end 0.67945 0.3048)
			(stroke
				(width 0.1)
				(type default)
			)
			(layer "F.Fab")
		)
		(fp_line
			(start 0.12065 -0.3048)
			(end 0.67945 -0.3048)
			(stroke
				(width 0.1)
				(type default)
			)
			(layer "F.Fab")
		)
		(fp_line
			(start 0.12065 -0.2794)
			(end 0.12065 -0.3048)
			(stroke
				(width 0.1)
				(type default)
			)
			(layer "F.Fab")
		)
		(fp_line
			(start -0.12065 -0.2794)
			(end 0.12065 -0.2794)
			(stroke
				(width 0.1)
				(type default)
			)
			(layer "F.Fab")
		)
		(fp_line
			(start 0.120396 0.2794)
			(end -0.12065 0.2794)
			(stroke
				(width 0.1)
				(type default)
			)
			(layer "F.Fab")
		)
		(fp_line
			(start -0.12065 0.2794)
			(end -0.12065 0.3048)
			(stroke
				(width 0.1)
				(type default)
			)
			(layer "F.Fab")
		)
		(fp_line
			(start 0.67945 0.3048)
			(end 0.120396 0.3048)
			(stroke
				(width 0.1)
				(type default)
			)
			(layer "F.Fab")
		)
		(fp_line
			(start 0.120396 0.3048)
			(end 0.120396 0.2794)
			(stroke
				(width 0.1)
				(type default)
			)
			(layer "F.Fab")
		)
		(fp_line
			(start -0.12065 0.3048)
			(end -0.67945 0.3048)
			(stroke
				(width 0.1)
				(type default)
			)
			(layer "F.Fab")
		)
		(fp_line
			(start -0.67945 0.3048)
			(end -0.67945 -0.305054)
			(stroke
				(width 0.1)
				(type default)
			)
			(layer "F.Fab")
		)
		(pad "1" smd circle
			(at -0.40005 0 90)
			(size 0 0)
			(layers "F.Cu" "F.Mask" "F.Paste")
			(net "BMC_EMMC_DT4")
		)
		(pad "2" smd circle
			(at 0.40005 0 90)
			(size 0 0)
			(layers "F.Cu" "F.Mask" "F.Paste")
			(net "EMMC_DT4_R")
		)
	)
	(footprint ""
		(layer "B.Cu")
		(at 52.891182 -72.842628 180)
		(property "Reference" "R781"
			(at 0 0 0)
			(layer "B.SilkS")
			(hide yes)
			(effects
				(font
					(size 1.27 1.27)
				)
				(justify mirror)
			)
		)
		(property "Value" ""
			(at 0 0 0)
			(layer "B.Fab")
			(effects
				(font
					(size 1.27 1.27)
				)
				(justify mirror)
			)
		)
		(duplicate_pad_numbers_are_jumpers no)
		(fp_line
			(start 0.7874 0.4064)
			(end 0.7874 -0.4064)
			(stroke
				(width 0.1524)
				(type default)
			)
			(layer "B.SilkS")
		)
		(fp_line
			(start 0.7874 -0.4064)
			(end -0.7874 -0.4064)
			(stroke
				(width 0.1524)
				(type default)
			)
			(layer "B.SilkS")
		)
		(fp_line
			(start -0.7874 0.4064)
			(end 0.7874 0.4064)
			(stroke
				(width 0.1524)
				(type default)
			)
			(layer "B.SilkS")
		)
		(fp_line
			(start -0.7874 -0.4064)
			(end -0.7874 0.4064)
			(stroke
				(width 0.1524)
				(type default)
			)
			(layer "B.SilkS")
		)
		(fp_line
			(start 0.67945 0.3048)
			(end 0.67945 -0.305054)
			(stroke
				(width 0.1)
				(type default)
			)
			(layer "B.Fab")
		)
		(fp_line
			(start 0.67945 -0.305054)
			(end 0.12065 -0.305054)
			(stroke
				(width 0.1)
				(type default)
			)
			(layer "B.Fab")
		)
		(fp_line
			(start 0.12065 0.3048)
			(end 0.67945 0.3048)
			(stroke
				(width 0.1)
				(type default)
			)
			(layer "B.Fab")
		)
		(fp_line
			(start 0.12065 0.2794)
			(end 0.12065 0.3048)
			(stroke
				(width 0.1)
				(type default)
			)
			(layer "B.Fab")
		)
		(fp_line
			(start 0.12065 -0.2794)
			(end -0.12065 -0.2794)
			(stroke
				(width 0.1)
				(type default)
			)
			(layer "B.Fab")
		)
		(fp_line
			(start 0.12065 -0.305054)
			(end 0.12065 -0.2794)
			(stroke
				(width 0.1)
				(type default)
			)
			(layer "B.Fab")
		)
		(fp_line
			(start -0.120396 0.3048)
			(end -0.120396 0.2794)
			(stroke
				(width 0.1)
				(type default)
			)
			(layer "B.Fab")
		)
		(fp_line
			(start -0.120396 0.2794)
			(end 0.12065 0.2794)
			(stroke
				(width 0.1)
				(type default)
			)
			(layer "B.Fab")
		)
		(fp_line
			(start -0.12065 -0.2794)
			(end -0.12065 -0.3048)
			(stroke
				(width 0.1)
				(type default)
			)
			(layer "B.Fab")
		)
		(fp_line
			(start -0.12065 -0.3048)
			(end -0.67945 -0.3048)
			(stroke
				(width 0.1)
				(type default)
			)
			(layer "B.Fab")
		)
		(fp_line
			(start -0.67945 0.3048)
			(end -0.120396 0.3048)
			(stroke
				(width 0.1)
				(type default)
			)
			(layer "B.Fab")
		)
		(fp_line
			(start -0.67945 -0.3048)
			(end -0.67945 0.3048)
			(stroke
				(width 0.1)
				(type default)
			)
			(layer "B.Fab")
		)
		(pad "1" smd circle
			(at 0.40005 0)
			(size 0 0)
			(layers "B.Cu" "B.Mask" "B.Paste")
			(net "P1V8_AUX")
		)
		(pad "2" smd circle
			(at -0.40005 0)
			(size 0 0)
			(layers "B.Cu" "B.Mask" "B.Paste")
			(net "ADCVREFEXT1")
		)
	)
	(footprint ""
		(layer "B.Cu")
		(at 56.6674 -63.7032 90)
		(property "Reference" "R239"
			(at 0 0 90)
			(layer "B.SilkS")
			(hide yes)
			(effects
				(font
					(size 1.27 1.27)
				)
				(justify mirror)
			)
		)
		(property "Value" ""
			(at 0 0 90)
			(layer "B.Fab")
			(effects
				(font
					(size 1.27 1.27)
				)
				(justify mirror)
			)
		)
		(duplicate_pad_numbers_are_jumpers no)
		(fp_line
			(start 0.7874 -0.4064)
			(end -0.7874 -0.4064)
			(stroke
				(width 0.1524)
				(type default)
			)
			(layer "B.SilkS")
		)
		(fp_line
			(start -0.7874 -0.4064)
			(end -0.7874 0.4064)
			(stroke
				(width 0.1524)
				(type default)
			)
			(layer "B.SilkS")
		)
		(fp_line
			(start 0.7874 0.4064)
			(end 0.7874 -0.4064)
			(stroke
				(width 0.1524)
				(type default)
			)
			(layer "B.SilkS")
		)
		(fp_line
			(start -0.7874 0.4064)
			(end 0.7874 0.4064)
			(stroke
				(width 0.1524)
				(type default)
			)
			(layer "B.SilkS")
		)
		(fp_line
			(start 0.67945 -0.305054)
			(end 0.12065 -0.305054)
			(stroke
				(width 0.1)
				(type default)
			)
			(layer "B.Fab")
		)
		(fp_line
			(start 0.12065 -0.305054)
			(end 0.12065 -0.2794)
			(stroke
				(width 0.1)
				(type default)
			)
			(layer "B.Fab")
		)
		(fp_line
			(start -0.12065 -0.3048)
			(end -0.67945 -0.3048)
			(stroke
				(width 0.1)
				(type default)
			)
			(layer "B.Fab")
		)
		(fp_line
			(start -0.67945 -0.3048)
			(end -0.67945 0.3048)
			(stroke
				(width 0.1)
				(type default)
			)
			(layer "B.Fab")
		)
		(fp_line
			(start 0.12065 -0.2794)
			(end -0.12065 -0.2794)
			(stroke
				(width 0.1)
				(type default)
			)
			(layer "B.Fab")
		)
		(fp_line
			(start -0.12065 -0.2794)
			(end -0.12065 -0.3048)
			(stroke
				(width 0.1)
				(type default)
			)
			(layer "B.Fab")
		)
		(fp_line
			(start 0.12065 0.2794)
			(end 0.12065 0.3048)
			(stroke
				(width 0.1)
				(type default)
			)
			(layer "B.Fab")
		)
		(fp_line
			(start -0.120396 0.2794)
			(end 0.12065 0.2794)
			(stroke
				(width 0.1)
				(type default)
			)
			(layer "B.Fab")
		)
		(fp_line
			(start 0.67945 0.3048)
			(end 0.67945 -0.305054)
			(stroke
				(width 0.1)
				(type default)
			)
			(layer "B.Fab")
		)
		(fp_line
			(start 0.12065 0.3048)
			(end 0.67945 0.3048)
			(stroke
				(width 0.1)
				(type default)
			)
			(layer "B.Fab")
		)
		(fp_line
			(start -0.120396 0.3048)
			(end -0.120396 0.2794)
			(stroke
				(width 0.1)
				(type default)
			)
			(layer "B.Fab")
		)
		(fp_line
			(start -0.67945 0.3048)
			(end -0.120396 0.3048)
			(stroke
				(width 0.1)
				(type default)
			)
			(layer "B.Fab")
		)
		(pad "1" smd circle
			(at 0.40005 0 270)
			(size 0 0)
			(layers "B.Cu" "B.Mask" "B.Paste")
			(net "P3V3_AUX")
		)
		(pad "2" smd circle
			(at -0.40005 0 270)
			(size 0 0)
			(layers "B.Cu" "B.Mask" "B.Paste")
			(net "PU_BMC_FWSPIABR_N")
		)
	)
	(footprint ""
		(layer "B.Cu")
		(at 38.0238 -46.25594 180)
		(property "Reference" "R428"
			(at 0 0 0)
			(layer "B.SilkS")
			(hide yes)
			(effects
				(font
					(size 1.27 1.27)
				)
				(justify mirror)
			)
		)
		(property "Value" ""
			(at 0 0 0)
			(layer "B.Fab")
			(effects
				(font
					(size 1.27 1.27)
				)
				(justify mirror)
			)
		)
		(duplicate_pad_numbers_are_jumpers no)
		(fp_line
			(start 0.7874 0.4064)
			(end 0.7874 -0.4064)
			(stroke
				(width 0.1524)
				(type default)
			)
			(layer "B.SilkS")
		)
		(fp_line
			(start 0.7874 -0.4064)
			(end -0.7874 -0.4064)
			(stroke
				(width 0.1524)
				(type default)
			)
			(layer "B.SilkS")
		)
		(fp_line
			(start -0.7874 0.4064)
			(end 0.7874 0.4064)
			(stroke
				(width 0.1524)
				(type default)
			)
			(layer "B.SilkS")
		)
		(fp_line
			(start -0.7874 -0.4064)
			(end -0.7874 0.4064)
			(stroke
				(width 0.1524)
				(type default)
			)
			(layer "B.SilkS")
		)
		(fp_line
			(start 0.67945 0.3048)
			(end 0.67945 -0.305054)
			(stroke
				(width 0.1)
				(type default)
			)
			(layer "B.Fab")
		)
		(fp_line
			(start 0.67945 -0.305054)
			(end 0.12065 -0.305054)
			(stroke
				(width 0.1)
				(type default)
			)
			(layer "B.Fab")
		)
		(fp_line
			(start 0.12065 0.3048)
			(end 0.67945 0.3048)
			(stroke
				(width 0.1)
				(type default)
			)
			(layer "B.Fab")
		)
		(fp_line
			(start 0.12065 0.2794)
			(end 0.12065 0.3048)
			(stroke
				(width 0.1)
				(type default)
			)
			(layer "B.Fab")
		)
		(fp_line
			(start 0.12065 -0.2794)
			(end -0.12065 -0.2794)
			(stroke
				(width 0.1)
				(type default)
			)
			(layer "B.Fab")
		)
		(fp_line
			(start 0.12065 -0.305054)
			(end 0.12065 -0.2794)
			(stroke
				(width 0.1)
				(type default)
			)
			(layer "B.Fab")
		)
		(fp_line
			(start -0.120396 0.3048)
			(end -0.120396 0.2794)
			(stroke
				(width 0.1)
				(type default)
			)
			(layer "B.Fab")
		)
		(fp_line
			(start -0.120396 0.2794)
			(end 0.12065 0.2794)
			(stroke
				(width 0.1)
				(type default)
			)
			(layer "B.Fab")
		)
		(fp_line
			(start -0.12065 -0.2794)
			(end -0.12065 -0.3048)
			(stroke
				(width 0.1)
				(type default)
			)
			(layer "B.Fab")
		)
		(fp_line
			(start -0.12065 -0.3048)
			(end -0.67945 -0.3048)
			(stroke
				(width 0.1)
				(type default)
			)
			(layer "B.Fab")
		)
		(fp_line
			(start -0.67945 0.3048)
			(end -0.120396 0.3048)
			(stroke
				(width 0.1)
				(type default)
			)
			(layer "B.Fab")
		)
		(fp_line
			(start -0.67945 -0.3048)
			(end -0.67945 0.3048)
			(stroke
				(width 0.1)
				(type default)
			)
			(layer "B.Fab")
		)
		(pad "1" smd circle
			(at 0.40005 0)
			(size 0 0)
			(layers "B.Cu" "B.Mask" "B.Paste")
			(net "P3V3_AUX")
		)
		(pad "2" smd circle
			(at -0.40005 0)
			(size 0 0)
			(layers "B.Cu" "B.Mask" "B.Paste")
			(net "SMB_BMC_MM13_SDA")
		)
	)
	(footprint ""
		(layer "B.Cu")
		(at 13.2588 -83.693 90)
		(property "Reference" "R690"
			(at 0 0 90)
			(layer "B.SilkS")
			(hide yes)
			(effects
				(font
					(size 1.27 1.27)
				)
				(justify mirror)
			)
		)
		(property "Value" ""
			(at 0 0 90)
			(layer "B.Fab")
			(effects
				(font
					(size 1.27 1.27)
				)
				(justify mirror)
			)
		)
		(duplicate_pad_numbers_are_jumpers no)
		(fp_line
			(start 0.7874 -0.4064)
			(end -0.7874 -0.4064)
			(stroke
				(width 0.1524)
				(type default)
			)
			(layer "B.SilkS")
		)
		(fp_line
			(start -0.7874 -0.4064)
			(end -0.7874 0.4064)
			(stroke
				(width 0.1524)
				(type default)
			)
			(layer "B.SilkS")
		)
		(fp_line
			(start 0.7874 0.4064)
			(end 0.7874 -0.4064)
			(stroke
				(width 0.1524)
				(type default)
			)
			(layer "B.SilkS")
		)
		(fp_line
			(start -0.7874 0.4064)
			(end 0.7874 0.4064)
			(stroke
				(width 0.1524)
				(type default)
			)
			(layer "B.SilkS")
		)
		(fp_line
			(start 0.67945 -0.305054)
			(end 0.12065 -0.305054)
			(stroke
				(width 0.1)
				(type default)
			)
			(layer "B.Fab")
		)
		(fp_line
			(start 0.12065 -0.305054)
			(end 0.12065 -0.2794)
			(stroke
				(width 0.1)
				(type default)
			)
			(layer "B.Fab")
		)
		(fp_line
			(start -0.12065 -0.3048)
			(end -0.67945 -0.3048)
			(stroke
				(width 0.1)
				(type default)
			)
			(layer "B.Fab")
		)
		(fp_line
			(start -0.67945 -0.3048)
			(end -0.67945 0.3048)
			(stroke
				(width 0.1)
				(type default)
			)
			(layer "B.Fab")
		)
		(fp_line
			(start 0.12065 -0.2794)
			(end -0.12065 -0.2794)
			(stroke
				(width 0.1)
				(type default)
			)
			(layer "B.Fab")
		)
		(fp_line
			(start -0.12065 -0.2794)
			(end -0.12065 -0.3048)
			(stroke
				(width 0.1)
				(type default)
			)
			(layer "B.Fab")
		)
		(fp_line
			(start 0.12065 0.2794)
			(end 0.12065 0.3048)
			(stroke
				(width 0.1)
				(type default)
			)
			(layer "B.Fab")
		)
		(fp_line
			(start -0.120396 0.2794)
			(end 0.12065 0.2794)
			(stroke
				(width 0.1)
				(type default)
			)
			(layer "B.Fab")
		)
		(fp_line
			(start 0.67945 0.3048)
			(end 0.67945 -0.305054)
			(stroke
				(width 0.1)
				(type default)
			)
			(layer "B.Fab")
		)
		(fp_line
			(start 0.12065 0.3048)
			(end 0.67945 0.3048)
			(stroke
				(width 0.1)
				(type default)
			)
			(layer "B.Fab")
		)
		(fp_line
			(start -0.120396 0.3048)
			(end -0.120396 0.2794)
			(stroke
				(width 0.1)
				(type default)
			)
			(layer "B.Fab")
		)
		(fp_line
			(start -0.67945 0.3048)
			(end -0.120396 0.3048)
			(stroke
				(width 0.1)
				(type default)
			)
			(layer "B.Fab")
		)
		(pad "1" smd circle
			(at 0.40005 0 270)
			(size 0 0)
			(layers "B.Cu" "B.Mask" "B.Paste")
			(net "IRQ_SGPIO_R_N")
		)
		(pad "2" smd circle
			(at -0.40005 0 270)
			(size 0 0)
			(layers "B.Cu" "B.Mask" "B.Paste")
			(net "IRQ_SGPIO_N")
		)
	)
	(footprint ""
		(layer "B.Cu")
		(at 74.715878 -96.50984 90)
		(property "Reference" "Q7"
			(at 2.24409 0.315722 0)
			(unlocked yes)
			(layer "B.SilkS")
			(effects
				(font
					(size 0.7874 0.5842)
					(thickness 0.1524)
				)
				(justify left mirror)
			)
		)
		(property "Value" ""
			(at 0 0 90)
			(layer "B.Fab")
			(effects
				(font
					(size 1.27 1.27)
				)
				(justify mirror)
			)
		)
		(duplicate_pad_numbers_are_jumpers no)
		(fp_line
			(start 1.603248 -1.500124)
			(end -1.603248 -1.500124)
			(stroke
				(width 0.1524)
				(type default)
			)
			(layer "B.SilkS")
		)
		(fp_line
			(start -1.603248 -1.500124)
			(end -1.603248 1.500124)
			(stroke
				(width 0.1524)
				(type default)
			)
			(layer "B.SilkS")
		)
		(fp_line
			(start 1.603248 1.500124)
			(end 1.603248 -1.500124)
			(stroke
				(width 0.1524)
				(type default)
			)
			(layer "B.SilkS")
		)
		(fp_line
			(start -1.603248 1.500124)
			(end 1.603248 1.500124)
			(stroke
				(width 0.1524)
				(type default)
			)
			(layer "B.SilkS")
		)
		(fp_line
			(start 0.700024 -1.500124)
			(end 0.700024 -1.169924)
			(stroke
				(width 0.1)
				(type default)
			)
			(layer "B.Fab")
		)
		(fp_line
			(start -0.700024 -1.500124)
			(end 0.700024 -1.500124)
			(stroke
				(width 0.1)
				(type default)
			)
			(layer "B.Fab")
		)
		(fp_line
			(start 1.249934 -1.169924)
			(end 1.249934 -0.729996)
			(stroke
				(width 0.1)
				(type default)
			)
			(layer "B.Fab")
		)
		(fp_line
			(start 0.700024 -1.169924)
			(end 1.249934 -1.169924)
			(stroke
				(width 0.1)
				(type default)
			)
			(layer "B.Fab")
		)
		(fp_line
			(start 1.249934 -0.729996)
			(end 0.6985 -0.729996)
			(stroke
				(width 0.1)
				(type default)
			)
			(layer "B.Fab")
		)
		(fp_line
			(start 0.6985 -0.729996)
			(end 0.6985 0.729996)
			(stroke
				(width 0.1)
				(type default)
			)
			(layer "B.Fab")
		)
		(fp_line
			(start -0.700024 -0.219964)
			(end -0.700024 -1.500124)
			(stroke
				(width 0.1)
				(type default)
			)
			(layer "B.Fab")
		)
		(fp_line
			(start -1.249934 -0.219964)
			(end -0.700024 -0.219964)
			(stroke
				(width 0.1)
				(type default)
			)
			(layer "B.Fab")
		)
		(fp_line
			(start -0.700024 0.219964)
			(end -1.249934 0.219964)
			(stroke
				(width 0.1)
				(type default)
			)
			(layer "B.Fab")
		)
		(fp_line
			(start -1.249934 0.219964)
			(end -1.249934 -0.219964)
			(stroke
				(width 0.1)
				(type default)
			)
			(layer "B.Fab")
		)
		(fp_line
			(start 1.249934 0.729996)
			(end 1.249934 1.169924)
			(stroke
				(width 0.1)
				(type default)
			)
			(layer "B.Fab")
		)
		(fp_line
			(start 0.6985 0.729996)
			(end 1.249934 0.729996)
			(stroke
				(width 0.1)
				(type default)
			)
			(layer "B.Fab")
		)
		(fp_line
			(start 1.249934 1.169924)
			(end 0.700024 1.169924)
			(stroke
				(width 0.1)
				(type default)
			)
			(layer "B.Fab")
		)
		(fp_line
			(start 0.700024 1.169924)
			(end 0.700024 1.500124)
			(stroke
				(width 0.1)
				(type default)
			)
			(layer "B.Fab")
		)
		(fp_line
			(start 0.700024 1.500124)
			(end -0.700024 1.500124)
			(stroke
				(width 0.1)
				(type default)
			)
			(layer "B.Fab")
		)
		(fp_line
			(start -0.700024 1.500124)
			(end -0.700024 0.219964)
			(stroke
				(width 0.1)
				(type default)
			)
			(layer "B.Fab")
		)
		(fp_rect
			(start 0.700024 1.500124)
			(end -0.700024 -1.500124)
			(stroke
				(width 0)
				(type default)
			)
			(fill no)
			(layer "B.Fab")
		)
		(pad "D" smd rect
			(at -0.999998 0)
			(size 0.8128 0.9144)
			(layers "B.Cu" "B.Mask" "B.Paste")
			(net "Q7_D")
		)
		(pad "G" smd rect
			(at 0.999998 -0.94996)
			(size 0.8128 0.9144)
			(layers "B.Cu" "B.Mask" "B.Paste")
			(net "LPC_ESPI_SEL_R1")
		)
		(pad "S" smd rect
			(at 0.999998 0.94996)
			(size 0.8128 0.9144)
			(layers "B.Cu" "B.Mask" "B.Paste")
			(net "SPI_BMC_TPM_MOSI")
		)
	)
	(footprint ""
		(layer "B.Cu")
		(at 49.5046 -53.2638 180)
		(property "Reference" "C139"
			(at 0 0 0)
			(layer "B.SilkS")
			(hide yes)
			(effects
				(font
					(size 1.27 1.27)
				)
				(justify mirror)
			)
		)
		(property "Value" ""
			(at 0 0 0)
			(layer "B.Fab")
			(effects
				(font
					(size 1.27 1.27)
				)
				(justify mirror)
			)
		)
		(duplicate_pad_numbers_are_jumpers no)
		(fp_line
			(start 0.7874 0.4064)
			(end 0.7874 -0.4064)
			(stroke
				(width 0.1524)
				(type default)
			)
			(layer "B.SilkS")
		)
		(fp_line
			(start 0.7874 -0.4064)
			(end -0.7874 -0.4064)
			(stroke
				(width 0.1524)
				(type default)
			)
			(layer "B.SilkS")
		)
		(fp_line
			(start -0.7874 0.4064)
			(end 0.7874 0.4064)
			(stroke
				(width 0.1524)
				(type default)
			)
			(layer "B.SilkS")
		)
		(fp_line
			(start -0.7874 -0.4064)
			(end -0.7874 0.4064)
			(stroke
				(width 0.1524)
				(type default)
			)
			(layer "B.SilkS")
		)
		(fp_line
			(start 0.67945 0.3048)
			(end 0.67945 -0.305054)
			(stroke
				(width 0.1)
				(type default)
			)
			(layer "B.Fab")
		)
		(fp_line
			(start 0.67945 -0.305054)
			(end 0.12065 -0.305054)
			(stroke
				(width 0.1)
				(type default)
			)
			(layer "B.Fab")
		)
		(fp_line
			(start 0.12065 0.3048)
			(end 0.67945 0.3048)
			(stroke
				(width 0.1)
				(type default)
			)
			(layer "B.Fab")
		)
		(fp_line
			(start 0.12065 0.2794)
			(end 0.12065 0.3048)
			(stroke
				(width 0.1)
				(type default)
			)
			(layer "B.Fab")
		)
		(fp_line
			(start 0.12065 -0.2794)
			(end -0.12065 -0.2794)
			(stroke
				(width 0.1)
				(type default)
			)
			(layer "B.Fab")
		)
		(fp_line
			(start 0.12065 -0.305054)
			(end 0.12065 -0.2794)
			(stroke
				(width 0.1)
				(type default)
			)
			(layer "B.Fab")
		)
		(fp_line
			(start -0.120396 0.3048)
			(end -0.120396 0.2794)
			(stroke
				(width 0.1)
				(type default)
			)
			(layer "B.Fab")
		)
		(fp_line
			(start -0.120396 0.2794)
			(end 0.12065 0.2794)
			(stroke
				(width 0.1)
				(type default)
			)
			(layer "B.Fab")
		)
		(fp_line
			(start -0.12065 -0.2794)
			(end -0.12065 -0.3048)
			(stroke
				(width 0.1)
				(type default)
			)
			(layer "B.Fab")
		)
		(fp_line
			(start -0.12065 -0.3048)
			(end -0.67945 -0.3048)
			(stroke
				(width 0.1)
				(type default)
			)
			(layer "B.Fab")
		)
		(fp_line
			(start -0.67945 0.3048)
			(end -0.120396 0.3048)
			(stroke
				(width 0.1)
				(type default)
			)
			(layer "B.Fab")
		)
		(fp_line
			(start -0.67945 -0.3048)
			(end -0.67945 0.3048)
			(stroke
				(width 0.1)
				(type default)
			)
			(layer "B.Fab")
		)
		(pad "1" smd circle
			(at 0.40005 0)
			(size 0 0)
			(layers "B.Cu" "B.Mask" "B.Paste")
			(net "P1V2_P1V0_I3C_VDDL1")
		)
		(pad "2" smd circle
			(at -0.40005 0)
			(size 0 0)
			(layers "B.Cu" "B.Mask" "B.Paste")
			(net "GND")
		)
	)
	(footprint ""
		(layer "B.Cu")
		(at 15.367 -106.426 90)
		(property "Reference" "R899"
			(at 0 0 90)
			(layer "B.SilkS")
			(hide yes)
			(effects
				(font
					(size 1.27 1.27)
				)
				(justify mirror)
			)
		)
		(property "Value" ""
			(at 0 0 90)
			(layer "B.Fab")
			(effects
				(font
					(size 1.27 1.27)
				)
				(justify mirror)
			)
		)
		(duplicate_pad_numbers_are_jumpers no)
		(fp_line
			(start 0.7874 -0.4064)
			(end -0.7874 -0.4064)
			(stroke
				(width 0.1524)
				(type default)
			)
			(layer "B.SilkS")
		)
		(fp_line
			(start -0.7874 -0.4064)
			(end -0.7874 0.4064)
			(stroke
				(width 0.1524)
				(type default)
			)
			(layer "B.SilkS")
		)
		(fp_line
			(start 0.7874 0.4064)
			(end 0.7874 -0.4064)
			(stroke
				(width 0.1524)
				(type default)
			)
			(layer "B.SilkS")
		)
		(fp_line
			(start -0.7874 0.4064)
			(end 0.7874 0.4064)
			(stroke
				(width 0.1524)
				(type default)
			)
			(layer "B.SilkS")
		)
		(fp_line
			(start 0.67945 -0.305054)
			(end 0.12065 -0.305054)
			(stroke
				(width 0.1)
				(type default)
			)
			(layer "B.Fab")
		)
		(fp_line
			(start 0.12065 -0.305054)
			(end 0.12065 -0.2794)
			(stroke
				(width 0.1)
				(type default)
			)
			(layer "B.Fab")
		)
		(fp_line
			(start -0.12065 -0.3048)
			(end -0.67945 -0.3048)
			(stroke
				(width 0.1)
				(type default)
			)
			(layer "B.Fab")
		)
		(fp_line
			(start -0.67945 -0.3048)
			(end -0.67945 0.3048)
			(stroke
				(width 0.1)
				(type default)
			)
			(layer "B.Fab")
		)
		(fp_line
			(start 0.12065 -0.2794)
			(end -0.12065 -0.2794)
			(stroke
				(width 0.1)
				(type default)
			)
			(layer "B.Fab")
		)
		(fp_line
			(start -0.12065 -0.2794)
			(end -0.12065 -0.3048)
			(stroke
				(width 0.1)
				(type default)
			)
			(layer "B.Fab")
		)
		(fp_line
			(start 0.12065 0.2794)
			(end 0.12065 0.3048)
			(stroke
				(width 0.1)
				(type default)
			)
			(layer "B.Fab")
		)
		(fp_line
			(start -0.120396 0.2794)
			(end 0.12065 0.2794)
			(stroke
				(width 0.1)
				(type default)
			)
			(layer "B.Fab")
		)
		(fp_line
			(start 0.67945 0.3048)
			(end 0.67945 -0.305054)
			(stroke
				(width 0.1)
				(type default)
			)
			(layer "B.Fab")
		)
		(fp_line
			(start 0.12065 0.3048)
			(end 0.67945 0.3048)
			(stroke
				(width 0.1)
				(type default)
			)
			(layer "B.Fab")
		)
		(fp_line
			(start -0.120396 0.3048)
			(end -0.120396 0.2794)
			(stroke
				(width 0.1)
				(type default)
			)
			(layer "B.Fab")
		)
		(fp_line
			(start -0.67945 0.3048)
			(end -0.120396 0.3048)
			(stroke
				(width 0.1)
				(type default)
			)
			(layer "B.Fab")
		)
		(pad "1" smd circle
			(at 0.40005 0 270)
			(size 0 0)
			(layers "B.Cu" "B.Mask" "B.Paste")
			(net "FM_UARTSW_MSB_R_N")
		)
		(pad "2" smd circle
			(at -0.40005 0 270)
			(size 0 0)
			(layers "B.Cu" "B.Mask" "B.Paste")
			(net "FM_UARTSW_MSB_N")
		)
	)
	(footprint ""
		(layer "B.Cu")
		(at 40.889936 -51.38547 180)
		(property "Reference" "R280"
			(at 0 0 0)
			(layer "B.SilkS")
			(hide yes)
			(effects
				(font
					(size 1.27 1.27)
				)
				(justify mirror)
			)
		)
		(property "Value" ""
			(at 0 0 0)
			(layer "B.Fab")
			(effects
				(font
					(size 1.27 1.27)
				)
				(justify mirror)
			)
		)
		(duplicate_pad_numbers_are_jumpers no)
		(fp_line
			(start 0.7874 0.4064)
			(end 0.7874 -0.4064)
			(stroke
				(width 0.1524)
				(type default)
			)
			(layer "B.SilkS")
		)
		(fp_line
			(start 0.7874 -0.4064)
			(end -0.7874 -0.4064)
			(stroke
				(width 0.1524)
				(type default)
			)
			(layer "B.SilkS")
		)
		(fp_line
			(start -0.7874 0.4064)
			(end 0.7874 0.4064)
			(stroke
				(width 0.1524)
				(type default)
			)
			(layer "B.SilkS")
		)
		(fp_line
			(start -0.7874 -0.4064)
			(end -0.7874 0.4064)
			(stroke
				(width 0.1524)
				(type default)
			)
			(layer "B.SilkS")
		)
		(fp_line
			(start 0.67945 0.3048)
			(end 0.67945 -0.305054)
			(stroke
				(width 0.1)
				(type default)
			)
			(layer "B.Fab")
		)
		(fp_line
			(start 0.67945 -0.305054)
			(end 0.12065 -0.305054)
			(stroke
				(width 0.1)
				(type default)
			)
			(layer "B.Fab")
		)
		(fp_line
			(start 0.12065 0.3048)
			(end 0.67945 0.3048)
			(stroke
				(width 0.1)
				(type default)
			)
			(layer "B.Fab")
		)
		(fp_line
			(start 0.12065 0.2794)
			(end 0.12065 0.3048)
			(stroke
				(width 0.1)
				(type default)
			)
			(layer "B.Fab")
		)
		(fp_line
			(start 0.12065 -0.2794)
			(end -0.12065 -0.2794)
			(stroke
				(width 0.1)
				(type default)
			)
			(layer "B.Fab")
		)
		(fp_line
			(start 0.12065 -0.305054)
			(end 0.12065 -0.2794)
			(stroke
				(width 0.1)
				(type default)
			)
			(layer "B.Fab")
		)
		(fp_line
			(start -0.120396 0.3048)
			(end -0.120396 0.2794)
			(stroke
				(width 0.1)
				(type default)
			)
			(layer "B.Fab")
		)
		(fp_line
			(start -0.120396 0.2794)
			(end 0.12065 0.2794)
			(stroke
				(width 0.1)
				(type default)
			)
			(layer "B.Fab")
		)
		(fp_line
			(start -0.12065 -0.2794)
			(end -0.12065 -0.3048)
			(stroke
				(width 0.1)
				(type default)
			)
			(layer "B.Fab")
		)
		(fp_line
			(start -0.12065 -0.3048)
			(end -0.67945 -0.3048)
			(stroke
				(width 0.1)
				(type default)
			)
			(layer "B.Fab")
		)
		(fp_line
			(start -0.67945 0.3048)
			(end -0.120396 0.3048)
			(stroke
				(width 0.1)
				(type default)
			)
			(layer "B.Fab")
		)
		(fp_line
			(start -0.67945 -0.3048)
			(end -0.67945 0.3048)
			(stroke
				(width 0.1)
				(type default)
			)
			(layer "B.Fab")
		)
		(pad "1" smd circle
			(at 0.40005 0)
			(size 0 0)
			(layers "B.Cu" "B.Mask" "B.Paste")
			(net "P1V2_AUX")
		)
		(pad "2" smd circle
			(at -0.40005 0)
			(size 0 0)
			(layers "B.Cu" "B.Mask" "B.Paste")
			(net "P1V2_P1V0_I3C_VDDL2")
		)
	)
	(footprint ""
		(layer "B.Cu")
		(at 56.173116 -74.242676 90)
		(property "Reference" "C309"
			(at 0 0 90)
			(layer "B.SilkS")
			(hide yes)
			(effects
				(font
					(size 1.27 1.27)
				)
				(justify mirror)
			)
		)
		(property "Value" ""
			(at 0 0 90)
			(layer "B.Fab")
			(effects
				(font
					(size 1.27 1.27)
				)
				(justify mirror)
			)
		)
		(duplicate_pad_numbers_are_jumpers no)
		(fp_line
			(start 0.7874 -0.4064)
			(end -0.7874 -0.4064)
			(stroke
				(width 0.1524)
				(type default)
			)
			(layer "B.SilkS")
		)
		(fp_line
			(start -0.7874 -0.4064)
			(end -0.7874 0.4064)
			(stroke
				(width 0.1524)
				(type default)
			)
			(layer "B.SilkS")
		)
		(fp_line
			(start 0.7874 0.4064)
			(end 0.7874 -0.4064)
			(stroke
				(width 0.1524)
				(type default)
			)
			(layer "B.SilkS")
		)
		(fp_line
			(start -0.7874 0.4064)
			(end 0.7874 0.4064)
			(stroke
				(width 0.1524)
				(type default)
			)
			(layer "B.SilkS")
		)
		(fp_line
			(start 0.67945 -0.305054)
			(end 0.12065 -0.305054)
			(stroke
				(width 0.1)
				(type default)
			)
			(layer "B.Fab")
		)
		(fp_line
			(start 0.12065 -0.305054)
			(end 0.12065 -0.2794)
			(stroke
				(width 0.1)
				(type default)
			)
			(layer "B.Fab")
		)
		(fp_line
			(start -0.12065 -0.3048)
			(end -0.67945 -0.3048)
			(stroke
				(width 0.1)
				(type default)
			)
			(layer "B.Fab")
		)
		(fp_line
			(start -0.67945 -0.3048)
			(end -0.67945 0.3048)
			(stroke
				(width 0.1)
				(type default)
			)
			(layer "B.Fab")
		)
		(fp_line
			(start 0.12065 -0.2794)
			(end -0.12065 -0.2794)
			(stroke
				(width 0.1)
				(type default)
			)
			(layer "B.Fab")
		)
		(fp_line
			(start -0.12065 -0.2794)
			(end -0.12065 -0.3048)
			(stroke
				(width 0.1)
				(type default)
			)
			(layer "B.Fab")
		)
		(fp_line
			(start 0.12065 0.2794)
			(end 0.12065 0.3048)
			(stroke
				(width 0.1)
				(type default)
			)
			(layer "B.Fab")
		)
		(fp_line
			(start -0.120396 0.2794)
			(end 0.12065 0.2794)
			(stroke
				(width 0.1)
				(type default)
			)
			(layer "B.Fab")
		)
		(fp_line
			(start 0.67945 0.3048)
			(end 0.67945 -0.305054)
			(stroke
				(width 0.1)
				(type default)
			)
			(layer "B.Fab")
		)
		(fp_line
			(start 0.12065 0.3048)
			(end 0.67945 0.3048)
			(stroke
				(width 0.1)
				(type default)
			)
			(layer "B.Fab")
		)
		(fp_line
			(start -0.120396 0.3048)
			(end -0.120396 0.2794)
			(stroke
				(width 0.1)
				(type default)
			)
			(layer "B.Fab")
		)
		(fp_line
			(start -0.67945 0.3048)
			(end -0.120396 0.3048)
			(stroke
				(width 0.1)
				(type default)
			)
			(layer "B.Fab")
		)
		(pad "1" smd circle
			(at 0.40005 0 270)
			(size 0 0)
			(layers "B.Cu" "B.Mask" "B.Paste")
			(net "P1V2_SENSOR")
		)
		(pad "2" smd circle
			(at -0.40005 0 270)
			(size 0 0)
			(layers "B.Cu" "B.Mask" "B.Paste")
			(net "GND")
		)
	)
	(footprint ""
		(layer "B.Cu")
		(at 43.1038 -62.1792 90)
		(property "Reference" "R235"
			(at 0 0 90)
			(layer "B.SilkS")
			(hide yes)
			(effects
				(font
					(size 1.27 1.27)
				)
				(justify mirror)
			)
		)
		(property "Value" ""
			(at 0 0 90)
			(layer "B.Fab")
			(effects
				(font
					(size 1.27 1.27)
				)
				(justify mirror)
			)
		)
		(duplicate_pad_numbers_are_jumpers no)
		(fp_line
			(start 0.7874 -0.4064)
			(end -0.7874 -0.4064)
			(stroke
				(width 0.1524)
				(type default)
			)
			(layer "B.SilkS")
		)
		(fp_line
			(start -0.7874 -0.4064)
			(end -0.7874 0.4064)
			(stroke
				(width 0.1524)
				(type default)
			)
			(layer "B.SilkS")
		)
		(fp_line
			(start 0.7874 0.4064)
			(end 0.7874 -0.4064)
			(stroke
				(width 0.1524)
				(type default)
			)
			(layer "B.SilkS")
		)
		(fp_line
			(start -0.7874 0.4064)
			(end 0.7874 0.4064)
			(stroke
				(width 0.1524)
				(type default)
			)
			(layer "B.SilkS")
		)
		(fp_line
			(start 0.67945 -0.305054)
			(end 0.12065 -0.305054)
			(stroke
				(width 0.1)
				(type default)
			)
			(layer "B.Fab")
		)
		(fp_line
			(start 0.12065 -0.305054)
			(end 0.12065 -0.2794)
			(stroke
				(width 0.1)
				(type default)
			)
			(layer "B.Fab")
		)
		(fp_line
			(start -0.12065 -0.3048)
			(end -0.67945 -0.3048)
			(stroke
				(width 0.1)
				(type default)
			)
			(layer "B.Fab")
		)
		(fp_line
			(start -0.67945 -0.3048)
			(end -0.67945 0.3048)
			(stroke
				(width 0.1)
				(type default)
			)
			(layer "B.Fab")
		)
		(fp_line
			(start 0.12065 -0.2794)
			(end -0.12065 -0.2794)
			(stroke
				(width 0.1)
				(type default)
			)
			(layer "B.Fab")
		)
		(fp_line
			(start -0.12065 -0.2794)
			(end -0.12065 -0.3048)
			(stroke
				(width 0.1)
				(type default)
			)
			(layer "B.Fab")
		)
		(fp_line
			(start 0.12065 0.2794)
			(end 0.12065 0.3048)
			(stroke
				(width 0.1)
				(type default)
			)
			(layer "B.Fab")
		)
		(fp_line
			(start -0.120396 0.2794)
			(end 0.12065 0.2794)
			(stroke
				(width 0.1)
				(type default)
			)
			(layer "B.Fab")
		)
		(fp_line
			(start 0.67945 0.3048)
			(end 0.67945 -0.305054)
			(stroke
				(width 0.1)
				(type default)
			)
			(layer "B.Fab")
		)
		(fp_line
			(start 0.12065 0.3048)
			(end 0.67945 0.3048)
			(stroke
				(width 0.1)
				(type default)
			)
			(layer "B.Fab")
		)
		(fp_line
			(start -0.120396 0.3048)
			(end -0.120396 0.2794)
			(stroke
				(width 0.1)
				(type default)
			)
			(layer "B.Fab")
		)
		(fp_line
			(start -0.67945 0.3048)
			(end -0.120396 0.3048)
			(stroke
				(width 0.1)
				(type default)
			)
			(layer "B.Fab")
		)
		(pad "1" smd circle
			(at 0.40005 0 270)
			(size 0 0)
			(layers "B.Cu" "B.Mask" "B.Paste")
			(net "GND")
		)
		(pad "2" smd circle
			(at -0.40005 0 270)
			(size 0 0)
			(layers "B.Cu" "B.Mask" "B.Paste")
			(net "A_BMC_DACREST")
		)
	)
	(footprint ""
		(layer "B.Cu")
		(at 80.512666 -49.261776 90)
		(property "Reference" "C2"
			(at 0 0 90)
			(layer "B.SilkS")
			(hide yes)
			(effects
				(font
					(size 1.27 1.27)
				)
				(justify mirror)
			)
		)
		(property "Value" ""
			(at 0 0 90)
			(layer "B.Fab")
			(effects
				(font
					(size 1.27 1.27)
				)
				(justify mirror)
			)
		)
		(duplicate_pad_numbers_are_jumpers no)
		(fp_line
			(start 0.7874 -0.4064)
			(end -0.7874 -0.4064)
			(stroke
				(width 0.1524)
				(type default)
			)
			(layer "B.SilkS")
		)
		(fp_line
			(start -0.7874 -0.4064)
			(end -0.7874 0.4064)
			(stroke
				(width 0.1524)
				(type default)
			)
			(layer "B.SilkS")
		)
		(fp_line
			(start 0.7874 0.4064)
			(end 0.7874 -0.4064)
			(stroke
				(width 0.1524)
				(type default)
			)
			(layer "B.SilkS")
		)
		(fp_line
			(start -0.7874 0.4064)
			(end 0.7874 0.4064)
			(stroke
				(width 0.1524)
				(type default)
			)
			(layer "B.SilkS")
		)
		(fp_line
			(start 0.67945 -0.305054)
			(end 0.12065 -0.305054)
			(stroke
				(width 0.1)
				(type default)
			)
			(layer "B.Fab")
		)
		(fp_line
			(start 0.12065 -0.305054)
			(end 0.12065 -0.2794)
			(stroke
				(width 0.1)
				(type default)
			)
			(layer "B.Fab")
		)
		(fp_line
			(start -0.12065 -0.3048)
			(end -0.67945 -0.3048)
			(stroke
				(width 0.1)
				(type default)
			)
			(layer "B.Fab")
		)
		(fp_line
			(start -0.67945 -0.3048)
			(end -0.67945 0.3048)
			(stroke
				(width 0.1)
				(type default)
			)
			(layer "B.Fab")
		)
		(fp_line
			(start 0.12065 -0.2794)
			(end -0.12065 -0.2794)
			(stroke
				(width 0.1)
				(type default)
			)
			(layer "B.Fab")
		)
		(fp_line
			(start -0.12065 -0.2794)
			(end -0.12065 -0.3048)
			(stroke
				(width 0.1)
				(type default)
			)
			(layer "B.Fab")
		)
		(fp_line
			(start 0.12065 0.2794)
			(end 0.12065 0.3048)
			(stroke
				(width 0.1)
				(type default)
			)
			(layer "B.Fab")
		)
		(fp_line
			(start -0.120396 0.2794)
			(end 0.12065 0.2794)
			(stroke
				(width 0.1)
				(type default)
			)
			(layer "B.Fab")
		)
		(fp_line
			(start 0.67945 0.3048)
			(end 0.67945 -0.305054)
			(stroke
				(width 0.1)
				(type default)
			)
			(layer "B.Fab")
		)
		(fp_line
			(start 0.12065 0.3048)
			(end 0.67945 0.3048)
			(stroke
				(width 0.1)
				(type default)
			)
			(layer "B.Fab")
		)
		(fp_line
			(start -0.120396 0.3048)
			(end -0.120396 0.2794)
			(stroke
				(width 0.1)
				(type default)
			)
			(layer "B.Fab")
		)
		(fp_line
			(start -0.67945 0.3048)
			(end -0.120396 0.3048)
			(stroke
				(width 0.1)
				(type default)
			)
			(layer "B.Fab")
		)
		(pad "1" smd circle
			(at 0.40005 0 270)
			(size 0 0)
			(layers "B.Cu" "B.Mask" "B.Paste")
			(net "P1V2_AUX")
		)
		(pad "2" smd circle
			(at -0.40005 0 270)
			(size 0 0)
			(layers "B.Cu" "B.Mask" "B.Paste")
			(net "GND")
		)
	)
	(footprint ""
		(layer "B.Cu")
		(at 50.54346 -61.852048 90)
		(property "Reference" "C133"
			(at 0 0 90)
			(layer "B.SilkS")
			(hide yes)
			(effects
				(font
					(size 1.27 1.27)
				)
				(justify mirror)
			)
		)
		(property "Value" ""
			(at 0 0 90)
			(layer "B.Fab")
			(effects
				(font
					(size 1.27 1.27)
				)
				(justify mirror)
			)
		)
		(duplicate_pad_numbers_are_jumpers no)
		(fp_line
			(start 0.7874 -0.4064)
			(end -0.7874 -0.4064)
			(stroke
				(width 0.1524)
				(type default)
			)
			(layer "B.SilkS")
		)
		(fp_line
			(start -0.7874 -0.4064)
			(end -0.7874 0.4064)
			(stroke
				(width 0.1524)
				(type default)
			)
			(layer "B.SilkS")
		)
		(fp_line
			(start 0.7874 0.4064)
			(end 0.7874 -0.4064)
			(stroke
				(width 0.1524)
				(type default)
			)
			(layer "B.SilkS")
		)
		(fp_line
			(start -0.7874 0.4064)
			(end 0.7874 0.4064)
			(stroke
				(width 0.1524)
				(type default)
			)
			(layer "B.SilkS")
		)
		(fp_line
			(start 0.67945 -0.305054)
			(end 0.12065 -0.305054)
			(stroke
				(width 0.1)
				(type default)
			)
			(layer "B.Fab")
		)
		(fp_line
			(start 0.12065 -0.305054)
			(end 0.12065 -0.2794)
			(stroke
				(width 0.1)
				(type default)
			)
			(layer "B.Fab")
		)
		(fp_line
			(start -0.12065 -0.3048)
			(end -0.67945 -0.3048)
			(stroke
				(width 0.1)
				(type default)
			)
			(layer "B.Fab")
		)
		(fp_line
			(start -0.67945 -0.3048)
			(end -0.67945 0.3048)
			(stroke
				(width 0.1)
				(type default)
			)
			(layer "B.Fab")
		)
		(fp_line
			(start 0.12065 -0.2794)
			(end -0.12065 -0.2794)
			(stroke
				(width 0.1)
				(type default)
			)
			(layer "B.Fab")
		)
		(fp_line
			(start -0.12065 -0.2794)
			(end -0.12065 -0.3048)
			(stroke
				(width 0.1)
				(type default)
			)
			(layer "B.Fab")
		)
		(fp_line
			(start 0.12065 0.2794)
			(end 0.12065 0.3048)
			(stroke
				(width 0.1)
				(type default)
			)
			(layer "B.Fab")
		)
		(fp_line
			(start -0.120396 0.2794)
			(end 0.12065 0.2794)
			(stroke
				(width 0.1)
				(type default)
			)
			(layer "B.Fab")
		)
		(fp_line
			(start 0.67945 0.3048)
			(end 0.67945 -0.305054)
			(stroke
				(width 0.1)
				(type default)
			)
			(layer "B.Fab")
		)
		(fp_line
			(start 0.12065 0.3048)
			(end 0.67945 0.3048)
			(stroke
				(width 0.1)
				(type default)
			)
			(layer "B.Fab")
		)
		(fp_line
			(start -0.120396 0.3048)
			(end -0.120396 0.2794)
			(stroke
				(width 0.1)
				(type default)
			)
			(layer "B.Fab")
		)
		(fp_line
			(start -0.67945 0.3048)
			(end -0.120396 0.3048)
			(stroke
				(width 0.1)
				(type default)
			)
			(layer "B.Fab")
		)
		(pad "1" smd circle
			(at 0.40005 0 270)
			(size 0 0)
			(layers "B.Cu" "B.Mask" "B.Paste")
			(net "GND")
		)
		(pad "2" smd circle
			(at -0.40005 0 270)
			(size 0 0)
			(layers "B.Cu" "B.Mask" "B.Paste")
			(net "A_BMC_ADCVREFN1")
		)
	)
	(footprint ""
		(layer "B.Cu")
		(at 57.531 -34.671 90)
		(property "Reference" "R147"
			(at 0 0 90)
			(layer "B.SilkS")
			(hide yes)
			(effects
				(font
					(size 1.27 1.27)
				)
				(justify mirror)
			)
		)
		(property "Value" ""
			(at 0 0 90)
			(layer "B.Fab")
			(effects
				(font
					(size 1.27 1.27)
				)
				(justify mirror)
			)
		)
		(duplicate_pad_numbers_are_jumpers no)
		(fp_line
			(start 0.7874 -0.4064)
			(end -0.7874 -0.4064)
			(stroke
				(width 0.1524)
				(type default)
			)
			(layer "B.SilkS")
		)
		(fp_line
			(start -0.7874 -0.4064)
			(end -0.7874 0.4064)
			(stroke
				(width 0.1524)
				(type default)
			)
			(layer "B.SilkS")
		)
		(fp_line
			(start 0.7874 0.4064)
			(end 0.7874 -0.4064)
			(stroke
				(width 0.1524)
				(type default)
			)
			(layer "B.SilkS")
		)
		(fp_line
			(start -0.7874 0.4064)
			(end 0.7874 0.4064)
			(stroke
				(width 0.1524)
				(type default)
			)
			(layer "B.SilkS")
		)
		(fp_line
			(start 0.67945 -0.305054)
			(end 0.12065 -0.305054)
			(stroke
				(width 0.1)
				(type default)
			)
			(layer "B.Fab")
		)
		(fp_line
			(start 0.12065 -0.305054)
			(end 0.12065 -0.2794)
			(stroke
				(width 0.1)
				(type default)
			)
			(layer "B.Fab")
		)
		(fp_line
			(start -0.12065 -0.3048)
			(end -0.67945 -0.3048)
			(stroke
				(width 0.1)
				(type default)
			)
			(layer "B.Fab")
		)
		(fp_line
			(start -0.67945 -0.3048)
			(end -0.67945 0.3048)
			(stroke
				(width 0.1)
				(type default)
			)
			(layer "B.Fab")
		)
		(fp_line
			(start 0.12065 -0.2794)
			(end -0.12065 -0.2794)
			(stroke
				(width 0.1)
				(type default)
			)
			(layer "B.Fab")
		)
		(fp_line
			(start -0.12065 -0.2794)
			(end -0.12065 -0.3048)
			(stroke
				(width 0.1)
				(type default)
			)
			(layer "B.Fab")
		)
		(fp_line
			(start 0.12065 0.2794)
			(end 0.12065 0.3048)
			(stroke
				(width 0.1)
				(type default)
			)
			(layer "B.Fab")
		)
		(fp_line
			(start -0.120396 0.2794)
			(end 0.12065 0.2794)
			(stroke
				(width 0.1)
				(type default)
			)
			(layer "B.Fab")
		)
		(fp_line
			(start 0.67945 0.3048)
			(end 0.67945 -0.305054)
			(stroke
				(width 0.1)
				(type default)
			)
			(layer "B.Fab")
		)
		(fp_line
			(start 0.12065 0.3048)
			(end 0.67945 0.3048)
			(stroke
				(width 0.1)
				(type default)
			)
			(layer "B.Fab")
		)
		(fp_line
			(start -0.120396 0.3048)
			(end -0.120396 0.2794)
			(stroke
				(width 0.1)
				(type default)
			)
			(layer "B.Fab")
		)
		(fp_line
			(start -0.67945 0.3048)
			(end -0.120396 0.3048)
			(stroke
				(width 0.1)
				(type default)
			)
			(layer "B.Fab")
		)
		(pad "1" smd circle
			(at 0.40005 0 270)
			(size 0 0)
			(layers "B.Cu" "B.Mask" "B.Paste")
			(net "SMB_BMC_MM8_R_SDA")
		)
		(pad "2" smd circle
			(at -0.40005 0 270)
			(size 0 0)
			(layers "B.Cu" "B.Mask" "B.Paste")
			(net "SMB_BMC_MM8_SDA")
		)
	)
	(footprint ""
		(layer "B.Cu")
		(at 20.193 -19.304 180)
		(property "Reference" "R52"
			(at 0 0 0)
			(layer "B.SilkS")
			(hide yes)
			(effects
				(font
					(size 1.27 1.27)
				)
				(justify mirror)
			)
		)
		(property "Value" ""
			(at 0 0 0)
			(layer "B.Fab")
			(effects
				(font
					(size 1.27 1.27)
				)
				(justify mirror)
			)
		)
		(duplicate_pad_numbers_are_jumpers no)
		(fp_line
			(start 0.7874 0.4064)
			(end 0.7874 -0.4064)
			(stroke
				(width 0.1524)
				(type default)
			)
			(layer "B.SilkS")
		)
		(fp_line
			(start 0.7874 -0.4064)
			(end -0.7874 -0.4064)
			(stroke
				(width 0.1524)
				(type default)
			)
			(layer "B.SilkS")
		)
		(fp_line
			(start -0.7874 0.4064)
			(end 0.7874 0.4064)
			(stroke
				(width 0.1524)
				(type default)
			)
			(layer "B.SilkS")
		)
		(fp_line
			(start -0.7874 -0.4064)
			(end -0.7874 0.4064)
			(stroke
				(width 0.1524)
				(type default)
			)
			(layer "B.SilkS")
		)
		(fp_line
			(start 0.67945 0.3048)
			(end 0.67945 -0.305054)
			(stroke
				(width 0.1)
				(type default)
			)
			(layer "B.Fab")
		)
		(fp_line
			(start 0.67945 -0.305054)
			(end 0.12065 -0.305054)
			(stroke
				(width 0.1)
				(type default)
			)
			(layer "B.Fab")
		)
		(fp_line
			(start 0.12065 0.3048)
			(end 0.67945 0.3048)
			(stroke
				(width 0.1)
				(type default)
			)
			(layer "B.Fab")
		)
		(fp_line
			(start 0.12065 0.2794)
			(end 0.12065 0.3048)
			(stroke
				(width 0.1)
				(type default)
			)
			(layer "B.Fab")
		)
		(fp_line
			(start 0.12065 -0.2794)
			(end -0.12065 -0.2794)
			(stroke
				(width 0.1)
				(type default)
			)
			(layer "B.Fab")
		)
		(fp_line
			(start 0.12065 -0.305054)
			(end 0.12065 -0.2794)
			(stroke
				(width 0.1)
				(type default)
			)
			(layer "B.Fab")
		)
		(fp_line
			(start -0.120396 0.3048)
			(end -0.120396 0.2794)
			(stroke
				(width 0.1)
				(type default)
			)
			(layer "B.Fab")
		)
		(fp_line
			(start -0.120396 0.2794)
			(end 0.12065 0.2794)
			(stroke
				(width 0.1)
				(type default)
			)
			(layer "B.Fab")
		)
		(fp_line
			(start -0.12065 -0.2794)
			(end -0.12065 -0.3048)
			(stroke
				(width 0.1)
				(type default)
			)
			(layer "B.Fab")
		)
		(fp_line
			(start -0.12065 -0.3048)
			(end -0.67945 -0.3048)
			(stroke
				(width 0.1)
				(type default)
			)
			(layer "B.Fab")
		)
		(fp_line
			(start -0.67945 0.3048)
			(end -0.120396 0.3048)
			(stroke
				(width 0.1)
				(type default)
			)
			(layer "B.Fab")
		)
		(fp_line
			(start -0.67945 -0.3048)
			(end -0.67945 0.3048)
			(stroke
				(width 0.1)
				(type default)
			)
			(layer "B.Fab")
		)
		(pad "1" smd circle
			(at 0.40005 0)
			(size 0 0)
			(layers "B.Cu" "B.Mask" "B.Paste")
			(net "P3V3_AUX")
		)
		(pad "2" smd circle
			(at -0.40005 0)
			(size 0 0)
			(layers "B.Cu" "B.Mask" "B.Paste")
			(net "TMC75_A1")
		)
	)
	(footprint ""
		(layer "B.Cu")
		(at 45.339 -96.8248 90)
		(property "Reference" "C239"
			(at 0 0 90)
			(layer "B.SilkS")
			(hide yes)
			(effects
				(font
					(size 1.27 1.27)
				)
				(justify mirror)
			)
		)
		(property "Value" ""
			(at 0 0 90)
			(layer "B.Fab")
			(effects
				(font
					(size 1.27 1.27)
				)
				(justify mirror)
			)
		)
		(duplicate_pad_numbers_are_jumpers no)
		(fp_line
			(start 0.7874 -0.4064)
			(end -0.7874 -0.4064)
			(stroke
				(width 0.1524)
				(type default)
			)
			(layer "B.SilkS")
		)
		(fp_line
			(start -0.7874 -0.4064)
			(end -0.7874 0.4064)
			(stroke
				(width 0.1524)
				(type default)
			)
			(layer "B.SilkS")
		)
		(fp_line
			(start 0.7874 0.4064)
			(end 0.7874 -0.4064)
			(stroke
				(width 0.1524)
				(type default)
			)
			(layer "B.SilkS")
		)
		(fp_line
			(start -0.7874 0.4064)
			(end 0.7874 0.4064)
			(stroke
				(width 0.1524)
				(type default)
			)
			(layer "B.SilkS")
		)
		(fp_line
			(start 0.67945 -0.305054)
			(end 0.12065 -0.305054)
			(stroke
				(width 0.1)
				(type default)
			)
			(layer "B.Fab")
		)
		(fp_line
			(start 0.12065 -0.305054)
			(end 0.12065 -0.2794)
			(stroke
				(width 0.1)
				(type default)
			)
			(layer "B.Fab")
		)
		(fp_line
			(start -0.12065 -0.3048)
			(end -0.67945 -0.3048)
			(stroke
				(width 0.1)
				(type default)
			)
			(layer "B.Fab")
		)
		(fp_line
			(start -0.67945 -0.3048)
			(end -0.67945 0.3048)
			(stroke
				(width 0.1)
				(type default)
			)
			(layer "B.Fab")
		)
		(fp_line
			(start 0.12065 -0.2794)
			(end -0.12065 -0.2794)
			(stroke
				(width 0.1)
				(type default)
			)
			(layer "B.Fab")
		)
		(fp_line
			(start -0.12065 -0.2794)
			(end -0.12065 -0.3048)
			(stroke
				(width 0.1)
				(type default)
			)
			(layer "B.Fab")
		)
		(fp_line
			(start 0.12065 0.2794)
			(end 0.12065 0.3048)
			(stroke
				(width 0.1)
				(type default)
			)
			(layer "B.Fab")
		)
		(fp_line
			(start -0.120396 0.2794)
			(end 0.12065 0.2794)
			(stroke
				(width 0.1)
				(type default)
			)
			(layer "B.Fab")
		)
		(fp_line
			(start 0.67945 0.3048)
			(end 0.67945 -0.305054)
			(stroke
				(width 0.1)
				(type default)
			)
			(layer "B.Fab")
		)
		(fp_line
			(start 0.12065 0.3048)
			(end 0.67945 0.3048)
			(stroke
				(width 0.1)
				(type default)
			)
			(layer "B.Fab")
		)
		(fp_line
			(start -0.120396 0.3048)
			(end -0.120396 0.2794)
			(stroke
				(width 0.1)
				(type default)
			)
			(layer "B.Fab")
		)
		(fp_line
			(start -0.67945 0.3048)
			(end -0.120396 0.3048)
			(stroke
				(width 0.1)
				(type default)
			)
			(layer "B.Fab")
		)
		(pad "1" smd circle
			(at 0.40005 0 270)
			(size 0 0)
			(layers "B.Cu" "B.Mask" "B.Paste")
			(net "USB3_FPNL_TXN")
		)
		(pad "2" smd circle
			(at -0.40005 0 270)
			(size 0 0)
			(layers "B.Cu" "B.Mask" "B.Paste")
			(net "USB3_01_TXN_C")
		)
	)
	(footprint ""
		(layer "B.Cu")
		(at 22.653244 -93.606112)
		(property "Reference" "C162"
			(at 0 0 0)
			(layer "B.SilkS")
			(hide yes)
			(effects
				(font
					(size 1.27 1.27)
				)
				(justify mirror)
			)
		)
		(property "Value" ""
			(at 0 0 0)
			(layer "B.Fab")
			(effects
				(font
					(size 1.27 1.27)
				)
				(justify mirror)
			)
		)
		(duplicate_pad_numbers_are_jumpers no)
		(fp_line
			(start -0.69215 -0.2921)
			(end -0.69215 0.2921)
			(stroke
				(width 0.1524)
				(type default)
			)
			(layer "B.SilkS")
		)
		(fp_line
			(start -0.69215 0.2921)
			(end 0.69215 0.2921)
			(stroke
				(width 0.1524)
				(type default)
			)
			(layer "B.SilkS")
		)
		(fp_line
			(start 0.69215 -0.2921)
			(end -0.69215 -0.2921)
			(stroke
				(width 0.1524)
				(type default)
			)
			(layer "B.SilkS")
		)
		(fp_line
			(start 0.69215 0.2921)
			(end 0.69215 -0.2921)
			(stroke
				(width 0.1524)
				(type default)
			)
			(layer "B.SilkS")
		)
		(fp_line
			(start -0.51435 -0.2794)
			(end -0.51435 0.2794)
			(stroke
				(width 0.1)
				(type default)
			)
			(layer "B.Fab")
		)
		(fp_line
			(start -0.51435 0.2794)
			(end 0.51435 0.2794)
			(stroke
				(width 0.1)
				(type default)
			)
			(layer "B.Fab")
		)
		(fp_line
			(start 0.51435 -0.2794)
			(end -0.51435 -0.2794)
			(stroke
				(width 0.1)
				(type default)
			)
			(layer "B.Fab")
		)
		(fp_line
			(start 0.51435 0.2794)
			(end 0.51435 -0.2794)
			(stroke
				(width 0.1)
				(type default)
			)
			(layer "B.Fab")
		)
		(pad "1" smd circle
			(at 0.40005 0 180)
			(size 0 0)
			(layers "B.Cu" "B.Mask" "B.Paste")
			(net "VCCIO4")
		)
		(pad "2" smd circle
			(at -0.40005 0 180)
			(size 0 0)
			(layers "B.Cu" "B.Mask" "B.Paste")
			(net "GND")
		)
		(zone
			(layer "B.Cu")
			(hatch none 0.5)
			(connect_pads
				(clearance 0)
			)
			(min_thickness 0.25)
			(keepout
				(tracks not_allowed)
				(vias allowed)
				(pads allowed)
				(copperpour not_allowed)
				(footprints allowed)
			)
			(placement
				(enabled no)
				(sheetname "")
			)
			(fill
				(thermal_gap 0.5)
				(thermal_bridge_width 0.5)
				(island_removal_mode 0)
			)
			(polygon
				(pts
					(xy 22.843744 -93.518482) (xy 22.752304 -93.460316) (xy 22.552914 -93.460316) (xy 22.462744 -93.518482)
					(xy 22.462744 -93.693742) (xy 22.552914 -93.752162) (xy 22.752304 -93.752162) (xy 22.843744 -93.693996)
				)
			)
		)
	)
	(footprint ""
		(layer "B.Cu")
		(at 79.629 -93.726 180)
		(property "Reference" "C270"
			(at 0 0 0)
			(layer "B.SilkS")
			(hide yes)
			(effects
				(font
					(size 1.27 1.27)
				)
				(justify mirror)
			)
		)
		(property "Value" ""
			(at 0 0 0)
			(layer "B.Fab")
			(effects
				(font
					(size 1.27 1.27)
				)
				(justify mirror)
			)
		)
		(duplicate_pad_numbers_are_jumpers no)
		(fp_line
			(start 0.7874 0.4064)
			(end 0.7874 -0.4064)
			(stroke
				(width 0.1524)
				(type default)
			)
			(layer "B.SilkS")
		)
		(fp_line
			(start 0.7874 -0.4064)
			(end -0.7874 -0.4064)
			(stroke
				(width 0.1524)
				(type default)
			)
			(layer "B.SilkS")
		)
		(fp_line
			(start -0.7874 0.4064)
			(end 0.7874 0.4064)
			(stroke
				(width 0.1524)
				(type default)
			)
			(layer "B.SilkS")
		)
		(fp_line
			(start -0.7874 -0.4064)
			(end -0.7874 0.4064)
			(stroke
				(width 0.1524)
				(type default)
			)
			(layer "B.SilkS")
		)
		(fp_line
			(start 0.67945 0.3048)
			(end 0.67945 -0.305054)
			(stroke
				(width 0.1)
				(type default)
			)
			(layer "B.Fab")
		)
		(fp_line
			(start 0.67945 -0.305054)
			(end 0.12065 -0.305054)
			(stroke
				(width 0.1)
				(type default)
			)
			(layer "B.Fab")
		)
		(fp_line
			(start 0.12065 0.3048)
			(end 0.67945 0.3048)
			(stroke
				(width 0.1)
				(type default)
			)
			(layer "B.Fab")
		)
		(fp_line
			(start 0.12065 0.2794)
			(end 0.12065 0.3048)
			(stroke
				(width 0.1)
				(type default)
			)
			(layer "B.Fab")
		)
		(fp_line
			(start 0.12065 -0.2794)
			(end -0.12065 -0.2794)
			(stroke
				(width 0.1)
				(type default)
			)
			(layer "B.Fab")
		)
		(fp_line
			(start 0.12065 -0.305054)
			(end 0.12065 -0.2794)
			(stroke
				(width 0.1)
				(type default)
			)
			(layer "B.Fab")
		)
		(fp_line
			(start -0.120396 0.3048)
			(end -0.120396 0.2794)
			(stroke
				(width 0.1)
				(type default)
			)
			(layer "B.Fab")
		)
		(fp_line
			(start -0.120396 0.2794)
			(end 0.12065 0.2794)
			(stroke
				(width 0.1)
				(type default)
			)
			(layer "B.Fab")
		)
		(fp_line
			(start -0.12065 -0.2794)
			(end -0.12065 -0.3048)
			(stroke
				(width 0.1)
				(type default)
			)
			(layer "B.Fab")
		)
		(fp_line
			(start -0.12065 -0.3048)
			(end -0.67945 -0.3048)
			(stroke
				(width 0.1)
				(type default)
			)
			(layer "B.Fab")
		)
		(fp_line
			(start -0.67945 0.3048)
			(end -0.120396 0.3048)
			(stroke
				(width 0.1)
				(type default)
			)
			(layer "B.Fab")
		)
		(fp_line
			(start -0.67945 -0.3048)
			(end -0.67945 0.3048)
			(stroke
				(width 0.1)
				(type default)
			)
			(layer "B.Fab")
		)
		(pad "1" smd circle
			(at 0.40005 0)
			(size 0 0)
			(layers "B.Cu" "B.Mask" "B.Paste")
			(net "LPC_ESPI_SEL_N")
		)
		(pad "2" smd circle
			(at -0.40005 0)
			(size 0 0)
			(layers "B.Cu" "B.Mask" "B.Paste")
			(net "GND")
		)
	)
	(footprint ""
		(layer "B.Cu")
		(at 57.242202 -66.0654 -90)
		(property "Reference" "R240"
			(at 0 0 90)
			(layer "B.SilkS")
			(hide yes)
			(effects
				(font
					(size 1.27 1.27)
				)
				(justify mirror)
			)
		)
		(property "Value" ""
			(at 0 0 90)
			(layer "B.Fab")
			(effects
				(font
					(size 1.27 1.27)
				)
				(justify mirror)
			)
		)
		(duplicate_pad_numbers_are_jumpers no)
		(fp_line
			(start -0.7874 0.4064)
			(end 0.7874 0.4064)
			(stroke
				(width 0.1524)
				(type default)
			)
			(layer "B.SilkS")
		)
		(fp_line
			(start 0.7874 0.4064)
			(end 0.7874 -0.4064)
			(stroke
				(width 0.1524)
				(type default)
			)
			(layer "B.SilkS")
		)
		(fp_line
			(start -0.7874 -0.4064)
			(end -0.7874 0.4064)
			(stroke
				(width 0.1524)
				(type default)
			)
			(layer "B.SilkS")
		)
		(fp_line
			(start 0.7874 -0.4064)
			(end -0.7874 -0.4064)
			(stroke
				(width 0.1524)
				(type default)
			)
			(layer "B.SilkS")
		)
		(fp_line
			(start -0.67945 0.3048)
			(end -0.120396 0.3048)
			(stroke
				(width 0.1)
				(type default)
			)
			(layer "B.Fab")
		)
		(fp_line
			(start -0.120396 0.3048)
			(end -0.120396 0.2794)
			(stroke
				(width 0.1)
				(type default)
			)
			(layer "B.Fab")
		)
		(fp_line
			(start 0.12065 0.3048)
			(end 0.67945 0.3048)
			(stroke
				(width 0.1)
				(type default)
			)
			(layer "B.Fab")
		)
		(fp_line
			(start 0.67945 0.3048)
			(end 0.67945 -0.305054)
			(stroke
				(width 0.1)
				(type default)
			)
			(layer "B.Fab")
		)
		(fp_line
			(start -0.120396 0.2794)
			(end 0.12065 0.2794)
			(stroke
				(width 0.1)
				(type default)
			)
			(layer "B.Fab")
		)
		(fp_line
			(start 0.12065 0.2794)
			(end 0.12065 0.3048)
			(stroke
				(width 0.1)
				(type default)
			)
			(layer "B.Fab")
		)
		(fp_line
			(start -0.12065 -0.2794)
			(end -0.12065 -0.3048)
			(stroke
				(width 0.1)
				(type default)
			)
			(layer "B.Fab")
		)
		(fp_line
			(start 0.12065 -0.2794)
			(end -0.12065 -0.2794)
			(stroke
				(width 0.1)
				(type default)
			)
			(layer "B.Fab")
		)
		(fp_line
			(start -0.67945 -0.3048)
			(end -0.67945 0.3048)
			(stroke
				(width 0.1)
				(type default)
			)
			(layer "B.Fab")
		)
		(fp_line
			(start -0.12065 -0.3048)
			(end -0.67945 -0.3048)
			(stroke
				(width 0.1)
				(type default)
			)
			(layer "B.Fab")
		)
		(fp_line
			(start 0.12065 -0.305054)
			(end 0.12065 -0.2794)
			(stroke
				(width 0.1)
				(type default)
			)
			(layer "B.Fab")
		)
		(fp_line
			(start 0.67945 -0.305054)
			(end 0.12065 -0.305054)
			(stroke
				(width 0.1)
				(type default)
			)
			(layer "B.Fab")
		)
		(pad "1" smd circle
			(at 0.40005 0 90)
			(size 0 0)
			(layers "B.Cu" "B.Mask" "B.Paste")
			(net "P3V3_AUX")
		)
		(pad "2" smd circle
			(at -0.40005 0 90)
			(size 0 0)
			(layers "B.Cu" "B.Mask" "B.Paste")
			(net "PU_FWSPIWP_N")
		)
	)
	(footprint ""
		(layer "B.Cu")
		(at 79.756 -33.4645 -90)
		(property "Reference" "R35"
			(at 0 0 90)
			(layer "B.SilkS")
			(hide yes)
			(effects
				(font
					(size 1.27 1.27)
				)
				(justify mirror)
			)
		)
		(property "Value" ""
			(at 0 0 90)
			(layer "B.Fab")
			(effects
				(font
					(size 1.27 1.27)
				)
				(justify mirror)
			)
		)
		(duplicate_pad_numbers_are_jumpers no)
		(fp_line
			(start -0.7874 0.4064)
			(end 0.7874 0.4064)
			(stroke
				(width 0.1524)
				(type default)
			)
			(layer "B.SilkS")
		)
		(fp_line
			(start 0.7874 0.4064)
			(end 0.7874 -0.4064)
			(stroke
				(width 0.1524)
				(type default)
			)
			(layer "B.SilkS")
		)
		(fp_line
			(start -0.7874 -0.4064)
			(end -0.7874 0.4064)
			(stroke
				(width 0.1524)
				(type default)
			)
			(layer "B.SilkS")
		)
		(fp_line
			(start 0.7874 -0.4064)
			(end -0.7874 -0.4064)
			(stroke
				(width 0.1524)
				(type default)
			)
			(layer "B.SilkS")
		)
		(fp_line
			(start -0.67945 0.3048)
			(end -0.120396 0.3048)
			(stroke
				(width 0.1)
				(type default)
			)
			(layer "B.Fab")
		)
		(fp_line
			(start -0.120396 0.3048)
			(end -0.120396 0.2794)
			(stroke
				(width 0.1)
				(type default)
			)
			(layer "B.Fab")
		)
		(fp_line
			(start 0.12065 0.3048)
			(end 0.67945 0.3048)
			(stroke
				(width 0.1)
				(type default)
			)
			(layer "B.Fab")
		)
		(fp_line
			(start 0.67945 0.3048)
			(end 0.67945 -0.305054)
			(stroke
				(width 0.1)
				(type default)
			)
			(layer "B.Fab")
		)
		(fp_line
			(start -0.120396 0.2794)
			(end 0.12065 0.2794)
			(stroke
				(width 0.1)
				(type default)
			)
			(layer "B.Fab")
		)
		(fp_line
			(start 0.12065 0.2794)
			(end 0.12065 0.3048)
			(stroke
				(width 0.1)
				(type default)
			)
			(layer "B.Fab")
		)
		(fp_line
			(start -0.12065 -0.2794)
			(end -0.12065 -0.3048)
			(stroke
				(width 0.1)
				(type default)
			)
			(layer "B.Fab")
		)
		(fp_line
			(start 0.12065 -0.2794)
			(end -0.12065 -0.2794)
			(stroke
				(width 0.1)
				(type default)
			)
			(layer "B.Fab")
		)
		(fp_line
			(start -0.67945 -0.3048)
			(end -0.67945 0.3048)
			(stroke
				(width 0.1)
				(type default)
			)
			(layer "B.Fab")
		)
		(fp_line
			(start -0.12065 -0.3048)
			(end -0.67945 -0.3048)
			(stroke
				(width 0.1)
				(type default)
			)
			(layer "B.Fab")
		)
		(fp_line
			(start 0.12065 -0.305054)
			(end 0.12065 -0.2794)
			(stroke
				(width 0.1)
				(type default)
			)
			(layer "B.Fab")
		)
		(fp_line
			(start 0.67945 -0.305054)
			(end 0.12065 -0.305054)
			(stroke
				(width 0.1)
				(type default)
			)
			(layer "B.Fab")
		)
		(pad "1" smd circle
			(at 0.40005 0 90)
			(size 0 0)
			(layers "B.Cu" "B.Mask" "B.Paste")
			(net "PWRGD_P2V5_AUX")
		)
		(pad "2" smd circle
			(at -0.40005 0 90)
			(size 0 0)
			(layers "B.Cu" "B.Mask" "B.Paste")
			(net "PWRGD_P2V5_AUX_R")
		)
	)
	(footprint ""
		(layer "B.Cu")
		(at 81.129886 -39.974012)
		(property "Reference" "R345"
			(at 0 0 0)
			(layer "B.SilkS")
			(hide yes)
			(effects
				(font
					(size 1.27 1.27)
				)
				(justify mirror)
			)
		)
		(property "Value" ""
			(at 0 0 0)
			(layer "B.Fab")
			(effects
				(font
					(size 1.27 1.27)
				)
				(justify mirror)
			)
		)
		(duplicate_pad_numbers_are_jumpers no)
		(fp_line
			(start -0.7874 -0.4064)
			(end -0.7874 0.4064)
			(stroke
				(width 0.1524)
				(type default)
			)
			(layer "B.SilkS")
		)
		(fp_line
			(start -0.7874 0.4064)
			(end 0.7874 0.4064)
			(stroke
				(width 0.1524)
				(type default)
			)
			(layer "B.SilkS")
		)
		(fp_line
			(start 0.7874 -0.4064)
			(end -0.7874 -0.4064)
			(stroke
				(width 0.1524)
				(type default)
			)
			(layer "B.SilkS")
		)
		(fp_line
			(start 0.7874 0.4064)
			(end 0.7874 -0.4064)
			(stroke
				(width 0.1524)
				(type default)
			)
			(layer "B.SilkS")
		)
		(fp_line
			(start -0.67945 -0.3048)
			(end -0.67945 0.3048)
			(stroke
				(width 0.1)
				(type default)
			)
			(layer "B.Fab")
		)
		(fp_line
			(start -0.67945 0.3048)
			(end -0.120396 0.3048)
			(stroke
				(width 0.1)
				(type default)
			)
			(layer "B.Fab")
		)
		(fp_line
			(start -0.12065 -0.3048)
			(end -0.67945 -0.3048)
			(stroke
				(width 0.1)
				(type default)
			)
			(layer "B.Fab")
		)
		(fp_line
			(start -0.12065 -0.2794)
			(end -0.12065 -0.3048)
			(stroke
				(width 0.1)
				(type default)
			)
			(layer "B.Fab")
		)
		(fp_line
			(start -0.120396 0.2794)
			(end 0.12065 0.2794)
			(stroke
				(width 0.1)
				(type default)
			)
			(layer "B.Fab")
		)
		(fp_line
			(start -0.120396 0.3048)
			(end -0.120396 0.2794)
			(stroke
				(width 0.1)
				(type default)
			)
			(layer "B.Fab")
		)
		(fp_line
			(start 0.12065 -0.305054)
			(end 0.12065 -0.2794)
			(stroke
				(width 0.1)
				(type default)
			)
			(layer "B.Fab")
		)
		(fp_line
			(start 0.12065 -0.2794)
			(end -0.12065 -0.2794)
			(stroke
				(width 0.1)
				(type default)
			)
			(layer "B.Fab")
		)
		(fp_line
			(start 0.12065 0.2794)
			(end 0.12065 0.3048)
			(stroke
				(width 0.1)
				(type default)
			)
			(layer "B.Fab")
		)
		(fp_line
			(start 0.12065 0.3048)
			(end 0.67945 0.3048)
			(stroke
				(width 0.1)
				(type default)
			)
			(layer "B.Fab")
		)
		(fp_line
			(start 0.67945 -0.305054)
			(end 0.12065 -0.305054)
			(stroke
				(width 0.1)
				(type default)
			)
			(layer "B.Fab")
		)
		(fp_line
			(start 0.67945 0.3048)
			(end 0.67945 -0.305054)
			(stroke
				(width 0.1)
				(type default)
			)
			(layer "B.Fab")
		)
		(pad "1" smd circle
			(at 0.40005 0 180)
			(size 0 0)
			(layers "B.Cu" "B.Mask" "B.Paste")
			(net "GND")
		)
		(pad "2" smd circle
			(at -0.40005 0 180)
			(size 0 0)
			(layers "B.Cu" "B.Mask" "B.Paste")
			(net "M_BMC_DDR4_MBG0")
		)
	)
	(footprint ""
		(layer "B.Cu")
		(at 21.3106 -90.8558 90)
		(property "Reference" "C189"
			(at 0 0 90)
			(layer "B.SilkS")
			(hide yes)
			(effects
				(font
					(size 1.27 1.27)
				)
				(justify mirror)
			)
		)
		(property "Value" ""
			(at 0 0 90)
			(layer "B.Fab")
			(effects
				(font
					(size 1.27 1.27)
				)
				(justify mirror)
			)
		)
		(duplicate_pad_numbers_are_jumpers no)
		(fp_line
			(start 0.69215 -0.2921)
			(end -0.69215 -0.2921)
			(stroke
				(width 0.1524)
				(type default)
			)
			(layer "B.SilkS")
		)
		(fp_line
			(start -0.69215 -0.2921)
			(end -0.69215 0.2921)
			(stroke
				(width 0.1524)
				(type default)
			)
			(layer "B.SilkS")
		)
		(fp_line
			(start 0.69215 0.2921)
			(end 0.69215 -0.2921)
			(stroke
				(width 0.1524)
				(type default)
			)
			(layer "B.SilkS")
		)
		(fp_line
			(start -0.69215 0.2921)
			(end 0.69215 0.2921)
			(stroke
				(width 0.1524)
				(type default)
			)
			(layer "B.SilkS")
		)
		(fp_line
			(start 0.51435 -0.2794)
			(end -0.51435 -0.2794)
			(stroke
				(width 0.1)
				(type default)
			)
			(layer "B.Fab")
		)
		(fp_line
			(start -0.51435 -0.2794)
			(end -0.51435 0.2794)
			(stroke
				(width 0.1)
				(type default)
			)
			(layer "B.Fab")
		)
		(fp_line
			(start 0.51435 0.2794)
			(end 0.51435 -0.2794)
			(stroke
				(width 0.1)
				(type default)
			)
			(layer "B.Fab")
		)
		(fp_line
			(start -0.51435 0.2794)
			(end 0.51435 0.2794)
			(stroke
				(width 0.1)
				(type default)
			)
			(layer "B.Fab")
		)
		(pad "1" smd circle
			(at 0.40005 0 270)
			(size 0 0)
			(layers "B.Cu" "B.Mask" "B.Paste")
			(net "VCCIO0")
		)
		(pad "2" smd circle
			(at -0.40005 0 270)
			(size 0 0)
			(layers "B.Cu" "B.Mask" "B.Paste")
			(net "GND")
		)
		(zone
			(layer "B.Cu")
			(hatch none 0.5)
			(connect_pads
				(clearance 0)
			)
			(min_thickness 0.25)
			(keepout
				(tracks not_allowed)
				(vias allowed)
				(pads allowed)
				(copperpour not_allowed)
				(footprints allowed)
			)
			(placement
				(enabled no)
				(sheetname "")
			)
			(fill
				(thermal_gap 0.5)
				(thermal_bridge_width 0.5)
				(island_removal_mode 0)
			)
			(polygon
				(pts
					(xy 21.39823 -91.0463) (xy 21.456396 -90.95486) (xy 21.456396 -90.75547) (xy 21.39823 -90.6653)
					(xy 21.22297 -90.6653) (xy 21.16455 -90.75547) (xy 21.16455 -90.95486) (xy 21.222716 -91.0463)
				)
			)
		)
	)
	(footprint ""
		(layer "B.Cu")
		(at 66.3956 -106.4387 -90)
		(property "Reference" "R46"
			(at 0 0 90)
			(layer "B.SilkS")
			(hide yes)
			(effects
				(font
					(size 1.27 1.27)
				)
				(justify mirror)
			)
		)
		(property "Value" ""
			(at 0 0 90)
			(layer "B.Fab")
			(effects
				(font
					(size 1.27 1.27)
				)
				(justify mirror)
			)
		)
		(duplicate_pad_numbers_are_jumpers no)
		(fp_line
			(start -0.7874 0.4064)
			(end 0.7874 0.4064)
			(stroke
				(width 0.1524)
				(type default)
			)
			(layer "B.SilkS")
		)
		(fp_line
			(start 0.7874 0.4064)
			(end 0.7874 -0.4064)
			(stroke
				(width 0.1524)
				(type default)
			)
			(layer "B.SilkS")
		)
		(fp_line
			(start -0.7874 -0.4064)
			(end -0.7874 0.4064)
			(stroke
				(width 0.1524)
				(type default)
			)
			(layer "B.SilkS")
		)
		(fp_line
			(start 0.7874 -0.4064)
			(end -0.7874 -0.4064)
			(stroke
				(width 0.1524)
				(type default)
			)
			(layer "B.SilkS")
		)
		(fp_line
			(start -0.67945 0.3048)
			(end -0.120396 0.3048)
			(stroke
				(width 0.1)
				(type default)
			)
			(layer "B.Fab")
		)
		(fp_line
			(start -0.120396 0.3048)
			(end -0.120396 0.2794)
			(stroke
				(width 0.1)
				(type default)
			)
			(layer "B.Fab")
		)
		(fp_line
			(start 0.12065 0.3048)
			(end 0.67945 0.3048)
			(stroke
				(width 0.1)
				(type default)
			)
			(layer "B.Fab")
		)
		(fp_line
			(start 0.67945 0.3048)
			(end 0.67945 -0.305054)
			(stroke
				(width 0.1)
				(type default)
			)
			(layer "B.Fab")
		)
		(fp_line
			(start -0.120396 0.2794)
			(end 0.12065 0.2794)
			(stroke
				(width 0.1)
				(type default)
			)
			(layer "B.Fab")
		)
		(fp_line
			(start 0.12065 0.2794)
			(end 0.12065 0.3048)
			(stroke
				(width 0.1)
				(type default)
			)
			(layer "B.Fab")
		)
		(fp_line
			(start -0.12065 -0.2794)
			(end -0.12065 -0.3048)
			(stroke
				(width 0.1)
				(type default)
			)
			(layer "B.Fab")
		)
		(fp_line
			(start 0.12065 -0.2794)
			(end -0.12065 -0.2794)
			(stroke
				(width 0.1)
				(type default)
			)
			(layer "B.Fab")
		)
		(fp_line
			(start -0.67945 -0.3048)
			(end -0.67945 0.3048)
			(stroke
				(width 0.1)
				(type default)
			)
			(layer "B.Fab")
		)
		(fp_line
			(start -0.12065 -0.3048)
			(end -0.67945 -0.3048)
			(stroke
				(width 0.1)
				(type default)
			)
			(layer "B.Fab")
		)
		(fp_line
			(start 0.12065 -0.305054)
			(end 0.12065 -0.2794)
			(stroke
				(width 0.1)
				(type default)
			)
			(layer "B.Fab")
		)
		(fp_line
			(start 0.67945 -0.305054)
			(end 0.12065 -0.305054)
			(stroke
				(width 0.1)
				(type default)
			)
			(layer "B.Fab")
		)
		(pad "1" smd circle
			(at 0.40005 0 90)
			(size 0 0)
			(layers "B.Cu" "B.Mask" "B.Paste")
			(net "SMB_BMC_MM14_SDA")
		)
		(pad "2" smd circle
			(at -0.40005 0 90)
			(size 0 0)
			(layers "B.Cu" "B.Mask" "B.Paste")
			(net "SMB_BMC_MM14_R1_SDA")
		)
	)
	(footprint ""
		(layer "B.Cu")
		(at 54.853332 -50.652934 -90)
		(property "Reference" "C111"
			(at 0 0 90)
			(layer "B.SilkS")
			(hide yes)
			(effects
				(font
					(size 1.27 1.27)
				)
				(justify mirror)
			)
		)
		(property "Value" ""
			(at 0 0 90)
			(layer "B.Fab")
			(effects
				(font
					(size 1.27 1.27)
				)
				(justify mirror)
			)
		)
		(duplicate_pad_numbers_are_jumpers no)
		(fp_line
			(start -0.7874 0.4064)
			(end 0.7874 0.4064)
			(stroke
				(width 0.1524)
				(type default)
			)
			(layer "B.SilkS")
		)
		(fp_line
			(start 0.7874 0.4064)
			(end 0.7874 -0.4064)
			(stroke
				(width 0.1524)
				(type default)
			)
			(layer "B.SilkS")
		)
		(fp_line
			(start -0.7874 -0.4064)
			(end -0.7874 0.4064)
			(stroke
				(width 0.1524)
				(type default)
			)
			(layer "B.SilkS")
		)
		(fp_line
			(start 0.7874 -0.4064)
			(end -0.7874 -0.4064)
			(stroke
				(width 0.1524)
				(type default)
			)
			(layer "B.SilkS")
		)
		(fp_line
			(start -0.67945 0.3048)
			(end -0.120396 0.3048)
			(stroke
				(width 0.1)
				(type default)
			)
			(layer "B.Fab")
		)
		(fp_line
			(start -0.120396 0.3048)
			(end -0.120396 0.2794)
			(stroke
				(width 0.1)
				(type default)
			)
			(layer "B.Fab")
		)
		(fp_line
			(start 0.12065 0.3048)
			(end 0.67945 0.3048)
			(stroke
				(width 0.1)
				(type default)
			)
			(layer "B.Fab")
		)
		(fp_line
			(start 0.67945 0.3048)
			(end 0.67945 -0.305054)
			(stroke
				(width 0.1)
				(type default)
			)
			(layer "B.Fab")
		)
		(fp_line
			(start -0.120396 0.2794)
			(end 0.12065 0.2794)
			(stroke
				(width 0.1)
				(type default)
			)
			(layer "B.Fab")
		)
		(fp_line
			(start 0.12065 0.2794)
			(end 0.12065 0.3048)
			(stroke
				(width 0.1)
				(type default)
			)
			(layer "B.Fab")
		)
		(fp_line
			(start -0.12065 -0.2794)
			(end -0.12065 -0.3048)
			(stroke
				(width 0.1)
				(type default)
			)
			(layer "B.Fab")
		)
		(fp_line
			(start 0.12065 -0.2794)
			(end -0.12065 -0.2794)
			(stroke
				(width 0.1)
				(type default)
			)
			(layer "B.Fab")
		)
		(fp_line
			(start -0.67945 -0.3048)
			(end -0.67945 0.3048)
			(stroke
				(width 0.1)
				(type default)
			)
			(layer "B.Fab")
		)
		(fp_line
			(start -0.12065 -0.3048)
			(end -0.67945 -0.3048)
			(stroke
				(width 0.1)
				(type default)
			)
			(layer "B.Fab")
		)
		(fp_line
			(start 0.12065 -0.305054)
			(end 0.12065 -0.2794)
			(stroke
				(width 0.1)
				(type default)
			)
			(layer "B.Fab")
		)
		(fp_line
			(start 0.67945 -0.305054)
			(end 0.12065 -0.305054)
			(stroke
				(width 0.1)
				(type default)
			)
			(layer "B.Fab")
		)
		(pad "1" smd circle
			(at 0.40005 0 90)
			(size 0 0)
			(layers "B.Cu" "B.Mask" "B.Paste")
			(net "P1V8_AUX")
		)
		(pad "2" smd circle
			(at -0.40005 0 90)
			(size 0 0)
			(layers "B.Cu" "B.Mask" "B.Paste")
			(net "GND")
		)
	)
	(footprint ""
		(layer "B.Cu")
		(at 81.129886 -43.022012 180)
		(property "Reference" "C8"
			(at 0 0 0)
			(layer "B.SilkS")
			(hide yes)
			(effects
				(font
					(size 1.27 1.27)
				)
				(justify mirror)
			)
		)
		(property "Value" ""
			(at 0 0 0)
			(layer "B.Fab")
			(effects
				(font
					(size 1.27 1.27)
				)
				(justify mirror)
			)
		)
		(duplicate_pad_numbers_are_jumpers no)
		(fp_line
			(start 0.7874 0.4064)
			(end 0.7874 -0.4064)
			(stroke
				(width 0.1524)
				(type default)
			)
			(layer "B.SilkS")
		)
		(fp_line
			(start 0.7874 -0.4064)
			(end -0.7874 -0.4064)
			(stroke
				(width 0.1524)
				(type default)
			)
			(layer "B.SilkS")
		)
		(fp_line
			(start -0.7874 0.4064)
			(end 0.7874 0.4064)
			(stroke
				(width 0.1524)
				(type default)
			)
			(layer "B.SilkS")
		)
		(fp_line
			(start -0.7874 -0.4064)
			(end -0.7874 0.4064)
			(stroke
				(width 0.1524)
				(type default)
			)
			(layer "B.SilkS")
		)
		(fp_line
			(start 0.67945 0.3048)
			(end 0.67945 -0.305054)
			(stroke
				(width 0.1)
				(type default)
			)
			(layer "B.Fab")
		)
		(fp_line
			(start 0.67945 -0.305054)
			(end 0.12065 -0.305054)
			(stroke
				(width 0.1)
				(type default)
			)
			(layer "B.Fab")
		)
		(fp_line
			(start 0.12065 0.3048)
			(end 0.67945 0.3048)
			(stroke
				(width 0.1)
				(type default)
			)
			(layer "B.Fab")
		)
		(fp_line
			(start 0.12065 0.2794)
			(end 0.12065 0.3048)
			(stroke
				(width 0.1)
				(type default)
			)
			(layer "B.Fab")
		)
		(fp_line
			(start 0.12065 -0.2794)
			(end -0.12065 -0.2794)
			(stroke
				(width 0.1)
				(type default)
			)
			(layer "B.Fab")
		)
		(fp_line
			(start 0.12065 -0.305054)
			(end 0.12065 -0.2794)
			(stroke
				(width 0.1)
				(type default)
			)
			(layer "B.Fab")
		)
		(fp_line
			(start -0.120396 0.3048)
			(end -0.120396 0.2794)
			(stroke
				(width 0.1)
				(type default)
			)
			(layer "B.Fab")
		)
		(fp_line
			(start -0.120396 0.2794)
			(end 0.12065 0.2794)
			(stroke
				(width 0.1)
				(type default)
			)
			(layer "B.Fab")
		)
		(fp_line
			(start -0.12065 -0.2794)
			(end -0.12065 -0.3048)
			(stroke
				(width 0.1)
				(type default)
			)
			(layer "B.Fab")
		)
		(fp_line
			(start -0.12065 -0.3048)
			(end -0.67945 -0.3048)
			(stroke
				(width 0.1)
				(type default)
			)
			(layer "B.Fab")
		)
		(fp_line
			(start -0.67945 0.3048)
			(end -0.120396 0.3048)
			(stroke
				(width 0.1)
				(type default)
			)
			(layer "B.Fab")
		)
		(fp_line
			(start -0.67945 -0.3048)
			(end -0.67945 0.3048)
			(stroke
				(width 0.1)
				(type default)
			)
			(layer "B.Fab")
		)
		(pad "1" smd circle
			(at 0.40005 0)
			(size 0 0)
			(layers "B.Cu" "B.Mask" "B.Paste")
			(net "P2V5_AUX")
		)
		(pad "2" smd circle
			(at -0.40005 0)
			(size 0 0)
			(layers "B.Cu" "B.Mask" "B.Paste")
			(net "GND")
		)
	)
	(footprint ""
		(layer "B.Cu")
		(at 20.282408 -92.8116 -90)
		(property "Reference" "C176"
			(at 0 0 90)
			(layer "B.SilkS")
			(hide yes)
			(effects
				(font
					(size 1.27 1.27)
				)
				(justify mirror)
			)
		)
		(property "Value" ""
			(at 0 0 90)
			(layer "B.Fab")
			(effects
				(font
					(size 1.27 1.27)
				)
				(justify mirror)
			)
		)
		(duplicate_pad_numbers_are_jumpers no)
		(fp_line
			(start -0.69215 0.2921)
			(end 0.69215 0.2921)
			(stroke
				(width 0.1524)
				(type default)
			)
			(layer "B.SilkS")
		)
		(fp_line
			(start 0.69215 0.2921)
			(end 0.69215 -0.2921)
			(stroke
				(width 0.1524)
				(type default)
			)
			(layer "B.SilkS")
		)
		(fp_line
			(start -0.69215 -0.2921)
			(end -0.69215 0.2921)
			(stroke
				(width 0.1524)
				(type default)
			)
			(layer "B.SilkS")
		)
		(fp_line
			(start 0.69215 -0.2921)
			(end -0.69215 -0.2921)
			(stroke
				(width 0.1524)
				(type default)
			)
			(layer "B.SilkS")
		)
		(fp_line
			(start -0.51435 0.2794)
			(end 0.51435 0.2794)
			(stroke
				(width 0.1)
				(type default)
			)
			(layer "B.Fab")
		)
		(fp_line
			(start 0.51435 0.2794)
			(end 0.51435 -0.2794)
			(stroke
				(width 0.1)
				(type default)
			)
			(layer "B.Fab")
		)
		(fp_line
			(start -0.51435 -0.2794)
			(end -0.51435 0.2794)
			(stroke
				(width 0.1)
				(type default)
			)
			(layer "B.Fab")
		)
		(fp_line
			(start 0.51435 -0.2794)
			(end -0.51435 -0.2794)
			(stroke
				(width 0.1)
				(type default)
			)
			(layer "B.Fab")
		)
		(pad "1" smd circle
			(at 0.40005 0 90)
			(size 0 0)
			(layers "B.Cu" "B.Mask" "B.Paste")
			(net "PVCCA_AUX_PLD")
		)
		(pad "2" smd circle
			(at -0.40005 0 90)
			(size 0 0)
			(layers "B.Cu" "B.Mask" "B.Paste")
			(net "GND")
		)
		(zone
			(layer "B.Cu")
			(hatch none 0.5)
			(connect_pads
				(clearance 0)
			)
			(min_thickness 0.25)
			(keepout
				(tracks not_allowed)
				(vias allowed)
				(pads allowed)
				(copperpour not_allowed)
				(footprints allowed)
			)
			(placement
				(enabled no)
				(sheetname "")
			)
			(fill
				(thermal_gap 0.5)
				(thermal_bridge_width 0.5)
				(island_removal_mode 0)
			)
			(polygon
				(pts
					(xy 20.194778 -92.6211) (xy 20.136612 -92.71254) (xy 20.136612 -92.91193) (xy 20.194778 -93.0021)
					(xy 20.370038 -93.0021) (xy 20.428458 -92.91193) (xy 20.428458 -92.71254) (xy 20.370292 -92.6211)
				)
			)
		)
	)
	(footprint ""
		(layer "B.Cu")
		(at 31.623 -41.4147 -90)
		(property "Reference" "C203"
			(at 0 0 90)
			(layer "B.SilkS")
			(hide yes)
			(effects
				(font
					(size 1.27 1.27)
				)
				(justify mirror)
			)
		)
		(property "Value" ""
			(at 0 0 90)
			(layer "B.Fab")
			(effects
				(font
					(size 1.27 1.27)
				)
				(justify mirror)
			)
		)
		(duplicate_pad_numbers_are_jumpers no)
		(fp_line
			(start -0.7874 0.4064)
			(end 0.7874 0.4064)
			(stroke
				(width 0.1524)
				(type default)
			)
			(layer "B.SilkS")
		)
		(fp_line
			(start 0.7874 0.4064)
			(end 0.7874 -0.4064)
			(stroke
				(width 0.1524)
				(type default)
			)
			(layer "B.SilkS")
		)
		(fp_line
			(start -0.7874 -0.4064)
			(end -0.7874 0.4064)
			(stroke
				(width 0.1524)
				(type default)
			)
			(layer "B.SilkS")
		)
		(fp_line
			(start 0.7874 -0.4064)
			(end -0.7874 -0.4064)
			(stroke
				(width 0.1524)
				(type default)
			)
			(layer "B.SilkS")
		)
		(fp_line
			(start -0.67945 0.3048)
			(end -0.120396 0.3048)
			(stroke
				(width 0.1)
				(type default)
			)
			(layer "B.Fab")
		)
		(fp_line
			(start -0.120396 0.3048)
			(end -0.120396 0.2794)
			(stroke
				(width 0.1)
				(type default)
			)
			(layer "B.Fab")
		)
		(fp_line
			(start 0.12065 0.3048)
			(end 0.67945 0.3048)
			(stroke
				(width 0.1)
				(type default)
			)
			(layer "B.Fab")
		)
		(fp_line
			(start 0.67945 0.3048)
			(end 0.67945 -0.305054)
			(stroke
				(width 0.1)
				(type default)
			)
			(layer "B.Fab")
		)
		(fp_line
			(start -0.120396 0.2794)
			(end 0.12065 0.2794)
			(stroke
				(width 0.1)
				(type default)
			)
			(layer "B.Fab")
		)
		(fp_line
			(start 0.12065 0.2794)
			(end 0.12065 0.3048)
			(stroke
				(width 0.1)
				(type default)
			)
			(layer "B.Fab")
		)
		(fp_line
			(start -0.12065 -0.2794)
			(end -0.12065 -0.3048)
			(stroke
				(width 0.1)
				(type default)
			)
			(layer "B.Fab")
		)
		(fp_line
			(start 0.12065 -0.2794)
			(end -0.12065 -0.2794)
			(stroke
				(width 0.1)
				(type default)
			)
			(layer "B.Fab")
		)
		(fp_line
			(start -0.67945 -0.3048)
			(end -0.67945 0.3048)
			(stroke
				(width 0.1)
				(type default)
			)
			(layer "B.Fab")
		)
		(fp_line
			(start -0.12065 -0.3048)
			(end -0.67945 -0.3048)
			(stroke
				(width 0.1)
				(type default)
			)
			(layer "B.Fab")
		)
		(fp_line
			(start 0.12065 -0.305054)
			(end 0.12065 -0.2794)
			(stroke
				(width 0.1)
				(type default)
			)
			(layer "B.Fab")
		)
		(fp_line
			(start 0.67945 -0.305054)
			(end 0.12065 -0.305054)
			(stroke
				(width 0.1)
				(type default)
			)
			(layer "B.Fab")
		)
		(pad "1" smd circle
			(at 0.40005 0 90)
			(size 0 0)
			(layers "B.Cu" "B.Mask" "B.Paste")
			(net "P5V_AUX")
		)
		(pad "2" smd circle
			(at -0.40005 0 90)
			(size 0 0)
			(layers "B.Cu" "B.Mask" "B.Paste")
			(net "GND")
		)
	)
	(footprint ""
		(layer "B.Cu")
		(at 77.2795 -100.935028)
		(property "Reference" "C273"
			(at 0 0 0)
			(layer "B.SilkS")
			(hide yes)
			(effects
				(font
					(size 1.27 1.27)
				)
				(justify mirror)
			)
		)
		(property "Value" ""
			(at 0 0 0)
			(layer "B.Fab")
			(effects
				(font
					(size 1.27 1.27)
				)
				(justify mirror)
			)
		)
		(duplicate_pad_numbers_are_jumpers no)
		(fp_line
			(start -0.7874 -0.4064)
			(end -0.7874 0.4064)
			(stroke
				(width 0.1524)
				(type default)
			)
			(layer "B.SilkS")
		)
		(fp_line
			(start -0.7874 0.4064)
			(end 0.7874 0.4064)
			(stroke
				(width 0.1524)
				(type default)
			)
			(layer "B.SilkS")
		)
		(fp_line
			(start 0.7874 -0.4064)
			(end -0.7874 -0.4064)
			(stroke
				(width 0.1524)
				(type default)
			)
			(layer "B.SilkS")
		)
		(fp_line
			(start 0.7874 0.4064)
			(end 0.7874 -0.4064)
			(stroke
				(width 0.1524)
				(type default)
			)
			(layer "B.SilkS")
		)
		(fp_line
			(start -0.67945 -0.3048)
			(end -0.67945 0.3048)
			(stroke
				(width 0.1)
				(type default)
			)
			(layer "B.Fab")
		)
		(fp_line
			(start -0.67945 0.3048)
			(end -0.120396 0.3048)
			(stroke
				(width 0.1)
				(type default)
			)
			(layer "B.Fab")
		)
		(fp_line
			(start -0.12065 -0.3048)
			(end -0.67945 -0.3048)
			(stroke
				(width 0.1)
				(type default)
			)
			(layer "B.Fab")
		)
		(fp_line
			(start -0.12065 -0.2794)
			(end -0.12065 -0.3048)
			(stroke
				(width 0.1)
				(type default)
			)
			(layer "B.Fab")
		)
		(fp_line
			(start -0.120396 0.2794)
			(end 0.12065 0.2794)
			(stroke
				(width 0.1)
				(type default)
			)
			(layer "B.Fab")
		)
		(fp_line
			(start -0.120396 0.3048)
			(end -0.120396 0.2794)
			(stroke
				(width 0.1)
				(type default)
			)
			(layer "B.Fab")
		)
		(fp_line
			(start 0.12065 -0.305054)
			(end 0.12065 -0.2794)
			(stroke
				(width 0.1)
				(type default)
			)
			(layer "B.Fab")
		)
		(fp_line
			(start 0.12065 -0.2794)
			(end -0.12065 -0.2794)
			(stroke
				(width 0.1)
				(type default)
			)
			(layer "B.Fab")
		)
		(fp_line
			(start 0.12065 0.2794)
			(end 0.12065 0.3048)
			(stroke
				(width 0.1)
				(type default)
			)
			(layer "B.Fab")
		)
		(fp_line
			(start 0.12065 0.3048)
			(end 0.67945 0.3048)
			(stroke
				(width 0.1)
				(type default)
			)
			(layer "B.Fab")
		)
		(fp_line
			(start 0.67945 -0.305054)
			(end 0.12065 -0.305054)
			(stroke
				(width 0.1)
				(type default)
			)
			(layer "B.Fab")
		)
		(fp_line
			(start 0.67945 0.3048)
			(end 0.67945 -0.305054)
			(stroke
				(width 0.1)
				(type default)
			)
			(layer "B.Fab")
		)
		(pad "1" smd circle
			(at 0.40005 0 180)
			(size 0 0)
			(layers "B.Cu" "B.Mask" "B.Paste")
			(net "LPC_ESPI_SEL_R")
		)
		(pad "2" smd circle
			(at -0.40005 0 180)
			(size 0 0)
			(layers "B.Cu" "B.Mask" "B.Paste")
			(net "GND")
		)
	)
	(footprint ""
		(layer "B.Cu")
		(at 41.966134 -44.92879 180)
		(property "Reference" "R166"
			(at 0 0 0)
			(layer "B.SilkS")
			(hide yes)
			(effects
				(font
					(size 1.27 1.27)
				)
				(justify mirror)
			)
		)
		(property "Value" ""
			(at 0 0 0)
			(layer "B.Fab")
			(effects
				(font
					(size 1.27 1.27)
				)
				(justify mirror)
			)
		)
		(duplicate_pad_numbers_are_jumpers no)
		(fp_line
			(start 0.7874 0.4064)
			(end 0.7874 -0.4064)
			(stroke
				(width 0.1524)
				(type default)
			)
			(layer "B.SilkS")
		)
		(fp_line
			(start 0.7874 -0.4064)
			(end -0.7874 -0.4064)
			(stroke
				(width 0.1524)
				(type default)
			)
			(layer "B.SilkS")
		)
		(fp_line
			(start -0.7874 0.4064)
			(end 0.7874 0.4064)
			(stroke
				(width 0.1524)
				(type default)
			)
			(layer "B.SilkS")
		)
		(fp_line
			(start -0.7874 -0.4064)
			(end -0.7874 0.4064)
			(stroke
				(width 0.1524)
				(type default)
			)
			(layer "B.SilkS")
		)
		(fp_line
			(start 0.67945 0.3048)
			(end 0.67945 -0.305054)
			(stroke
				(width 0.1)
				(type default)
			)
			(layer "B.Fab")
		)
		(fp_line
			(start 0.67945 -0.305054)
			(end 0.12065 -0.305054)
			(stroke
				(width 0.1)
				(type default)
			)
			(layer "B.Fab")
		)
		(fp_line
			(start 0.12065 0.3048)
			(end 0.67945 0.3048)
			(stroke
				(width 0.1)
				(type default)
			)
			(layer "B.Fab")
		)
		(fp_line
			(start 0.12065 0.2794)
			(end 0.12065 0.3048)
			(stroke
				(width 0.1)
				(type default)
			)
			(layer "B.Fab")
		)
		(fp_line
			(start 0.12065 -0.2794)
			(end -0.12065 -0.2794)
			(stroke
				(width 0.1)
				(type default)
			)
			(layer "B.Fab")
		)
		(fp_line
			(start 0.12065 -0.305054)
			(end 0.12065 -0.2794)
			(stroke
				(width 0.1)
				(type default)
			)
			(layer "B.Fab")
		)
		(fp_line
			(start -0.120396 0.3048)
			(end -0.120396 0.2794)
			(stroke
				(width 0.1)
				(type default)
			)
			(layer "B.Fab")
		)
		(fp_line
			(start -0.120396 0.2794)
			(end 0.12065 0.2794)
			(stroke
				(width 0.1)
				(type default)
			)
			(layer "B.Fab")
		)
		(fp_line
			(start -0.12065 -0.2794)
			(end -0.12065 -0.3048)
			(stroke
				(width 0.1)
				(type default)
			)
			(layer "B.Fab")
		)
		(fp_line
			(start -0.12065 -0.3048)
			(end -0.67945 -0.3048)
			(stroke
				(width 0.1)
				(type default)
			)
			(layer "B.Fab")
		)
		(fp_line
			(start -0.67945 0.3048)
			(end -0.120396 0.3048)
			(stroke
				(width 0.1)
				(type default)
			)
			(layer "B.Fab")
		)
		(fp_line
			(start -0.67945 -0.3048)
			(end -0.67945 0.3048)
			(stroke
				(width 0.1)
				(type default)
			)
			(layer "B.Fab")
		)
		(pad "1" smd circle
			(at 0.40005 0)
			(size 0 0)
			(layers "B.Cu" "B.Mask" "B.Paste")
			(net "IRQ_BMC_CPU_NMI_R")
		)
		(pad "2" smd circle
			(at -0.40005 0)
			(size 0 0)
			(layers "B.Cu" "B.Mask" "B.Paste")
			(net "IRQ_BMC_CPU_NMI")
		)
	)
	(footprint ""
		(layer "B.Cu")
		(at 39.414958 -82.836512 180)
		(property "Reference" "R430"
			(at 0 0 0)
			(layer "B.SilkS")
			(hide yes)
			(effects
				(font
					(size 1.27 1.27)
				)
				(justify mirror)
			)
		)
		(property "Value" ""
			(at 0 0 0)
			(layer "B.Fab")
			(effects
				(font
					(size 1.27 1.27)
				)
				(justify mirror)
			)
		)
		(duplicate_pad_numbers_are_jumpers no)
		(fp_line
			(start 0.7874 0.4064)
			(end 0.7874 -0.4064)
			(stroke
				(width 0.1524)
				(type default)
			)
			(layer "B.SilkS")
		)
		(fp_line
			(start 0.7874 -0.4064)
			(end -0.7874 -0.4064)
			(stroke
				(width 0.1524)
				(type default)
			)
			(layer "B.SilkS")
		)
		(fp_line
			(start -0.7874 0.4064)
			(end 0.7874 0.4064)
			(stroke
				(width 0.1524)
				(type default)
			)
			(layer "B.SilkS")
		)
		(fp_line
			(start -0.7874 -0.4064)
			(end -0.7874 0.4064)
			(stroke
				(width 0.1524)
				(type default)
			)
			(layer "B.SilkS")
		)
		(fp_line
			(start 0.67945 0.3048)
			(end 0.67945 -0.305054)
			(stroke
				(width 0.1)
				(type default)
			)
			(layer "B.Fab")
		)
		(fp_line
			(start 0.67945 -0.305054)
			(end 0.12065 -0.305054)
			(stroke
				(width 0.1)
				(type default)
			)
			(layer "B.Fab")
		)
		(fp_line
			(start 0.12065 0.3048)
			(end 0.67945 0.3048)
			(stroke
				(width 0.1)
				(type default)
			)
			(layer "B.Fab")
		)
		(fp_line
			(start 0.12065 0.2794)
			(end 0.12065 0.3048)
			(stroke
				(width 0.1)
				(type default)
			)
			(layer "B.Fab")
		)
		(fp_line
			(start 0.12065 -0.2794)
			(end -0.12065 -0.2794)
			(stroke
				(width 0.1)
				(type default)
			)
			(layer "B.Fab")
		)
		(fp_line
			(start 0.12065 -0.305054)
			(end 0.12065 -0.2794)
			(stroke
				(width 0.1)
				(type default)
			)
			(layer "B.Fab")
		)
		(fp_line
			(start -0.120396 0.3048)
			(end -0.120396 0.2794)
			(stroke
				(width 0.1)
				(type default)
			)
			(layer "B.Fab")
		)
		(fp_line
			(start -0.120396 0.2794)
			(end 0.12065 0.2794)
			(stroke
				(width 0.1)
				(type default)
			)
			(layer "B.Fab")
		)
		(fp_line
			(start -0.12065 -0.2794)
			(end -0.12065 -0.3048)
			(stroke
				(width 0.1)
				(type default)
			)
			(layer "B.Fab")
		)
		(fp_line
			(start -0.12065 -0.3048)
			(end -0.67945 -0.3048)
			(stroke
				(width 0.1)
				(type default)
			)
			(layer "B.Fab")
		)
		(fp_line
			(start -0.67945 0.3048)
			(end -0.120396 0.3048)
			(stroke
				(width 0.1)
				(type default)
			)
			(layer "B.Fab")
		)
		(fp_line
			(start -0.67945 -0.3048)
			(end -0.67945 0.3048)
			(stroke
				(width 0.1)
				(type default)
			)
			(layer "B.Fab")
		)
		(pad "1" smd circle
			(at 0.40005 0)
			(size 0 0)
			(layers "B.Cu" "B.Mask" "B.Paste")
			(net "P3V3_AUX")
		)
		(pad "2" smd circle
			(at -0.40005 0)
			(size 0 0)
			(layers "B.Cu" "B.Mask" "B.Paste")
			(net "FM_BMC_ONCTL_R_N")
		)
	)
	(footprint ""
		(layer "B.Cu")
		(at 78.7908 -33.4645 -90)
		(property "Reference" "R873"
			(at 0 0 90)
			(layer "B.SilkS")
			(hide yes)
			(effects
				(font
					(size 1.27 1.27)
				)
				(justify mirror)
			)
		)
		(property "Value" ""
			(at 0 0 90)
			(layer "B.Fab")
			(effects
				(font
					(size 1.27 1.27)
				)
				(justify mirror)
			)
		)
		(duplicate_pad_numbers_are_jumpers no)
		(fp_line
			(start -0.7874 0.4064)
			(end 0.7874 0.4064)
			(stroke
				(width 0.1524)
				(type default)
			)
			(layer "B.SilkS")
		)
		(fp_line
			(start 0.7874 0.4064)
			(end 0.7874 -0.4064)
			(stroke
				(width 0.1524)
				(type default)
			)
			(layer "B.SilkS")
		)
		(fp_line
			(start -0.7874 -0.4064)
			(end -0.7874 0.4064)
			(stroke
				(width 0.1524)
				(type default)
			)
			(layer "B.SilkS")
		)
		(fp_line
			(start 0.7874 -0.4064)
			(end -0.7874 -0.4064)
			(stroke
				(width 0.1524)
				(type default)
			)
			(layer "B.SilkS")
		)
		(fp_line
			(start -0.67945 0.3048)
			(end -0.120396 0.3048)
			(stroke
				(width 0.1)
				(type default)
			)
			(layer "B.Fab")
		)
		(fp_line
			(start -0.120396 0.3048)
			(end -0.120396 0.2794)
			(stroke
				(width 0.1)
				(type default)
			)
			(layer "B.Fab")
		)
		(fp_line
			(start 0.12065 0.3048)
			(end 0.67945 0.3048)
			(stroke
				(width 0.1)
				(type default)
			)
			(layer "B.Fab")
		)
		(fp_line
			(start 0.67945 0.3048)
			(end 0.67945 -0.305054)
			(stroke
				(width 0.1)
				(type default)
			)
			(layer "B.Fab")
		)
		(fp_line
			(start -0.120396 0.2794)
			(end 0.12065 0.2794)
			(stroke
				(width 0.1)
				(type default)
			)
			(layer "B.Fab")
		)
		(fp_line
			(start 0.12065 0.2794)
			(end 0.12065 0.3048)
			(stroke
				(width 0.1)
				(type default)
			)
			(layer "B.Fab")
		)
		(fp_line
			(start -0.12065 -0.2794)
			(end -0.12065 -0.3048)
			(stroke
				(width 0.1)
				(type default)
			)
			(layer "B.Fab")
		)
		(fp_line
			(start 0.12065 -0.2794)
			(end -0.12065 -0.2794)
			(stroke
				(width 0.1)
				(type default)
			)
			(layer "B.Fab")
		)
		(fp_line
			(start -0.67945 -0.3048)
			(end -0.67945 0.3048)
			(stroke
				(width 0.1)
				(type default)
			)
			(layer "B.Fab")
		)
		(fp_line
			(start -0.12065 -0.3048)
			(end -0.67945 -0.3048)
			(stroke
				(width 0.1)
				(type default)
			)
			(layer "B.Fab")
		)
		(fp_line
			(start 0.12065 -0.305054)
			(end 0.12065 -0.2794)
			(stroke
				(width 0.1)
				(type default)
			)
			(layer "B.Fab")
		)
		(fp_line
			(start 0.67945 -0.305054)
			(end 0.12065 -0.305054)
			(stroke
				(width 0.1)
				(type default)
			)
			(layer "B.Fab")
		)
		(pad "1" smd circle
			(at 0.40005 0 90)
			(size 0 0)
			(layers "B.Cu" "B.Mask" "B.Paste")
			(net "PWRGD_P2V5_AUX_R3")
		)
		(pad "2" smd circle
			(at -0.40005 0 90)
			(size 0 0)
			(layers "B.Cu" "B.Mask" "B.Paste")
			(net "PWRGD_P2V5_AUX")
		)
	)
	(footprint ""
		(layer "B.Cu")
		(at 47.340774 -49.363122)
		(property "Reference" "C88"
			(at 0 0 0)
			(layer "B.SilkS")
			(hide yes)
			(effects
				(font
					(size 1.27 1.27)
				)
				(justify mirror)
			)
		)
		(property "Value" ""
			(at 0 0 0)
			(layer "B.Fab")
			(effects
				(font
					(size 1.27 1.27)
				)
				(justify mirror)
			)
		)
		(duplicate_pad_numbers_are_jumpers no)
		(fp_line
			(start -0.7874 -0.4064)
			(end -0.7874 0.4064)
			(stroke
				(width 0.1524)
				(type default)
			)
			(layer "B.SilkS")
		)
		(fp_line
			(start -0.7874 0.4064)
			(end 0.7874 0.4064)
			(stroke
				(width 0.1524)
				(type default)
			)
			(layer "B.SilkS")
		)
		(fp_line
			(start 0.7874 -0.4064)
			(end -0.7874 -0.4064)
			(stroke
				(width 0.1524)
				(type default)
			)
			(layer "B.SilkS")
		)
		(fp_line
			(start 0.7874 0.4064)
			(end 0.7874 -0.4064)
			(stroke
				(width 0.1524)
				(type default)
			)
			(layer "B.SilkS")
		)
		(fp_line
			(start -0.67945 -0.3048)
			(end -0.67945 0.3048)
			(stroke
				(width 0.1)
				(type default)
			)
			(layer "B.Fab")
		)
		(fp_line
			(start -0.67945 0.3048)
			(end -0.120396 0.3048)
			(stroke
				(width 0.1)
				(type default)
			)
			(layer "B.Fab")
		)
		(fp_line
			(start -0.12065 -0.3048)
			(end -0.67945 -0.3048)
			(stroke
				(width 0.1)
				(type default)
			)
			(layer "B.Fab")
		)
		(fp_line
			(start -0.12065 -0.2794)
			(end -0.12065 -0.3048)
			(stroke
				(width 0.1)
				(type default)
			)
			(layer "B.Fab")
		)
		(fp_line
			(start -0.120396 0.2794)
			(end 0.12065 0.2794)
			(stroke
				(width 0.1)
				(type default)
			)
			(layer "B.Fab")
		)
		(fp_line
			(start -0.120396 0.3048)
			(end -0.120396 0.2794)
			(stroke
				(width 0.1)
				(type default)
			)
			(layer "B.Fab")
		)
		(fp_line
			(start 0.12065 -0.305054)
			(end 0.12065 -0.2794)
			(stroke
				(width 0.1)
				(type default)
			)
			(layer "B.Fab")
		)
		(fp_line
			(start 0.12065 -0.2794)
			(end -0.12065 -0.2794)
			(stroke
				(width 0.1)
				(type default)
			)
			(layer "B.Fab")
		)
		(fp_line
			(start 0.12065 0.2794)
			(end 0.12065 0.3048)
			(stroke
				(width 0.1)
				(type default)
			)
			(layer "B.Fab")
		)
		(fp_line
			(start 0.12065 0.3048)
			(end 0.67945 0.3048)
			(stroke
				(width 0.1)
				(type default)
			)
			(layer "B.Fab")
		)
		(fp_line
			(start 0.67945 -0.305054)
			(end 0.12065 -0.305054)
			(stroke
				(width 0.1)
				(type default)
			)
			(layer "B.Fab")
		)
		(fp_line
			(start 0.67945 0.3048)
			(end 0.67945 -0.305054)
			(stroke
				(width 0.1)
				(type default)
			)
			(layer "B.Fab")
		)
		(pad "1" smd circle
			(at 0.40005 0 180)
			(size 0 0)
			(layers "B.Cu" "B.Mask" "B.Paste")
			(net "P3V3_AUX")
		)
		(pad "2" smd circle
			(at -0.40005 0 180)
			(size 0 0)
			(layers "B.Cu" "B.Mask" "B.Paste")
			(net "GND")
		)
	)
	(footprint ""
		(layer "B.Cu")
		(at 112.014 27.178 90)
		(property "Reference" "X13"
			(at 1.86563 3.2385 0)
			(unlocked yes)
			(layer "B.SilkS")
			(effects
				(font
					(size 0.7874 0.5842)
					(thickness 0.1524)
				)
				(justify left mirror)
			)
		)
		(property "Value" ""
			(at 0 0 90)
			(layer "B.Fab")
			(effects
				(font
					(size 1.27 1.27)
				)
				(justify mirror)
			)
		)
		(property "Device Type" "TP_TDR_4P_FTS_TH-TP_TDR_4P_DIPA"
			(at -1.30175 1.27 0)
			(unlocked yes)
			(layer "B.Fab")
			(hide yes)
			(effects
				(font
					(size 0.635 0.4064)
					(thickness 0.1524)
				)
				(justify mirror)
			)
		)
		(property "User Part Number" "N_A"
			(at -1.30175 1.27 0)
			(unlocked yes)
			(layer "Cmts.User")
			(hide yes)
			(effects
				(font
					(size 0.635 0.4064)
					(thickness 0.1524)
				)
				(justify mirror)
			)
		)
		(duplicate_pad_numbers_are_jumpers no)
		(fp_line
			(start 0 -1.27)
			(end 0 -0.635)
			(stroke
				(width 0.1524)
				(type default)
			)
			(layer "B.SilkS")
		)
		(fp_line
			(start -2.54 -1.27)
			(end 0 -1.27)
			(stroke
				(width 0.1524)
				(type default)
			)
			(layer "B.SilkS")
		)
		(fp_line
			(start -2.54 -1.1303)
			(end -2.54 -1.27)
			(stroke
				(width 0.1524)
				(type default)
			)
			(layer "B.SilkS")
		)
		(fp_line
			(start 0 0.635)
			(end 0 1.905)
			(stroke
				(width 0.1524)
				(type default)
			)
			(layer "B.SilkS")
		)
		(fp_line
			(start -2.54 1.4097)
			(end -2.54 1.1303)
			(stroke
				(width 0.1524)
				(type default)
			)
			(layer "B.SilkS")
		)
		(fp_line
			(start 0 3.175)
			(end 0 3.81)
			(stroke
				(width 0.1524)
				(type default)
			)
			(layer "B.SilkS")
		)
		(fp_line
			(start 0 3.81)
			(end -2.54 3.81)
			(stroke
				(width 0.1524)
				(type default)
			)
			(layer "B.SilkS")
		)
		(fp_line
			(start -2.54 3.81)
			(end -2.54 3.6703)
			(stroke
				(width 0.1524)
				(type default)
			)
			(layer "B.SilkS")
		)
		(fp_poly
			(pts
				(xy 0.761746 0) (xy 2.285746 -0.762) (xy 2.285746 0.762)
			)
			(stroke
				(width 0)
				(type default)
			)
			(fill yes)
			(layer "B.SilkS")
		)
		(fp_line
			(start 0 -1.27)
			(end 0 3.81)
			(stroke
				(width 0.1)
				(type default)
			)
			(layer "B.Fab")
		)
		(fp_line
			(start -2.54 -1.27)
			(end 0 -1.27)
			(stroke
				(width 0.1)
				(type default)
			)
			(layer "B.Fab")
		)
		(fp_line
			(start 0 3.81)
			(end -2.54 3.81)
			(stroke
				(width 0.1)
				(type default)
			)
			(layer "B.Fab")
		)
		(fp_line
			(start -2.54 3.81)
			(end -2.54 -1.27)
			(stroke
				(width 0.1)
				(type default)
			)
			(layer "B.Fab")
		)
		(fp_poly
			(pts
				(xy 0.761746 0) (xy 2.285746 -0.762) (xy 2.285746 0.762)
			)
			(stroke
				(width 0)
				(type default)
			)
			(fill yes)
			(layer "B.Fab")
		)
		(pad "1" thru_hole circle
			(at 0 0 270)
			(size 1.0033 1.0033)
			(drill 0.249936)
			(layers "*.Cu" "*.Mask")
			(remove_unused_layers no)
			(net "TDR_DIFF_100_TOP_DP")
			(clearance 0.10795)
			(padstack
				(mode front_inner_back)
				(layer "Inner"
					(shape circle)
					(size 0.8001 0.8001)
					(clearance 0.1524)
				)
				(layer "B.Cu"
					(shape circle)
					(size 1.0033 1.0033)
					(thermal_gap 0.10795)
					(clearance 0.10795)
				)
			)
		)
		(pad "2" thru_hole circle
			(at -2.54 0 270)
			(size 1.9939 1.9939)
			(drill 0.249936)
			(layers "*.Cu" "*.Mask")
			(remove_unused_layers no)
			(net "GND_P1")
			(clearance 0.10795)
			(padstack
				(mode front_inner_back)
				(layer "Inner"
					(shape circle)
					(size 0.8001 0.8001)
					(clearance 0.1524)
				)
				(layer "B.Cu"
					(shape circle)
					(size 1.9939 1.9939)
					(thermal_gap 0.10795)
					(clearance 0.10795)
				)
			)
		)
		(pad "3" thru_hole circle
			(at -2.54 2.54 270)
			(size 1.9939 1.9939)
			(drill 0.249936)
			(layers "*.Cu" "*.Mask")
			(remove_unused_layers no)
			(net "GND_P1")
			(clearance 0.10795)
			(padstack
				(mode front_inner_back)
				(layer "Inner"
					(shape circle)
					(size 0.8001 0.8001)
					(clearance 0.1524)
				)
				(layer "B.Cu"
					(shape circle)
					(size 1.9939 1.9939)
					(thermal_gap 0.10795)
					(clearance 0.10795)
				)
			)
		)
		(pad "4" thru_hole circle
			(at 0 2.54 270)
			(size 1.0033 1.0033)
			(drill 0.249936)
			(layers "*.Cu" "*.Mask")
			(remove_unused_layers no)
			(net "TDR_DIFF_100_TOP_DN")
			(clearance 0.10795)
			(padstack
				(mode front_inner_back)
				(layer "Inner"
					(shape circle)
					(size 0.8001 0.8001)
					(clearance 0.1524)
				)
				(layer "B.Cu"
					(shape circle)
					(size 1.0033 1.0033)
					(thermal_gap 0.10795)
					(clearance 0.10795)
				)
			)
		)
	)
	(footprint ""
		(layer "B.Cu")
		(at 48.895254 -63.946278 90)
		(property "Reference" "R448"
			(at 0 0 90)
			(layer "B.SilkS")
			(hide yes)
			(effects
				(font
					(size 1.27 1.27)
				)
				(justify mirror)
			)
		)
		(property "Value" ""
			(at 0 0 90)
			(layer "B.Fab")
			(effects
				(font
					(size 1.27 1.27)
				)
				(justify mirror)
			)
		)
		(duplicate_pad_numbers_are_jumpers no)
		(fp_line
			(start 0.7874 -0.4064)
			(end -0.7874 -0.4064)
			(stroke
				(width 0.1524)
				(type default)
			)
			(layer "B.SilkS")
		)
		(fp_line
			(start -0.7874 -0.4064)
			(end -0.7874 0.4064)
			(stroke
				(width 0.1524)
				(type default)
			)
			(layer "B.SilkS")
		)
		(fp_line
			(start 0.7874 0.4064)
			(end 0.7874 -0.4064)
			(stroke
				(width 0.1524)
				(type default)
			)
			(layer "B.SilkS")
		)
		(fp_line
			(start -0.7874 0.4064)
			(end 0.7874 0.4064)
			(stroke
				(width 0.1524)
				(type default)
			)
			(layer "B.SilkS")
		)
		(fp_line
			(start 0.67945 -0.305054)
			(end 0.12065 -0.305054)
			(stroke
				(width 0.1)
				(type default)
			)
			(layer "B.Fab")
		)
		(fp_line
			(start 0.12065 -0.305054)
			(end 0.12065 -0.2794)
			(stroke
				(width 0.1)
				(type default)
			)
			(layer "B.Fab")
		)
		(fp_line
			(start -0.12065 -0.3048)
			(end -0.67945 -0.3048)
			(stroke
				(width 0.1)
				(type default)
			)
			(layer "B.Fab")
		)
		(fp_line
			(start -0.67945 -0.3048)
			(end -0.67945 0.3048)
			(stroke
				(width 0.1)
				(type default)
			)
			(layer "B.Fab")
		)
		(fp_line
			(start 0.12065 -0.2794)
			(end -0.12065 -0.2794)
			(stroke
				(width 0.1)
				(type default)
			)
			(layer "B.Fab")
		)
		(fp_line
			(start -0.12065 -0.2794)
			(end -0.12065 -0.3048)
			(stroke
				(width 0.1)
				(type default)
			)
			(layer "B.Fab")
		)
		(fp_line
			(start 0.12065 0.2794)
			(end 0.12065 0.3048)
			(stroke
				(width 0.1)
				(type default)
			)
			(layer "B.Fab")
		)
		(fp_line
			(start -0.120396 0.2794)
			(end 0.12065 0.2794)
			(stroke
				(width 0.1)
				(type default)
			)
			(layer "B.Fab")
		)
		(fp_line
			(start 0.67945 0.3048)
			(end 0.67945 -0.305054)
			(stroke
				(width 0.1)
				(type default)
			)
			(layer "B.Fab")
		)
		(fp_line
			(start 0.12065 0.3048)
			(end 0.67945 0.3048)
			(stroke
				(width 0.1)
				(type default)
			)
			(layer "B.Fab")
		)
		(fp_line
			(start -0.120396 0.3048)
			(end -0.120396 0.2794)
			(stroke
				(width 0.1)
				(type default)
			)
			(layer "B.Fab")
		)
		(fp_line
			(start -0.67945 0.3048)
			(end -0.120396 0.3048)
			(stroke
				(width 0.1)
				(type default)
			)
			(layer "B.Fab")
		)
		(pad "1" smd circle
			(at 0.40005 0 270)
			(size 0 0)
			(layers "B.Cu" "B.Mask" "B.Paste")
			(net "SMB_BMC_ALERT9_N")
		)
		(pad "2" smd circle
			(at -0.40005 0 270)
			(size 0 0)
			(layers "B.Cu" "B.Mask" "B.Paste")
			(net "SMB_BMC_ALERT9_R_N")
		)
	)
	(footprint ""
		(layer "B.Cu")
		(at 41.5036 -3.6068 90)
		(property "Reference" "R30"
			(at 0 0 90)
			(layer "B.SilkS")
			(hide yes)
			(effects
				(font
					(size 1.27 1.27)
				)
				(justify mirror)
			)
		)
		(property "Value" ""
			(at 0 0 90)
			(layer "B.Fab")
			(effects
				(font
					(size 1.27 1.27)
				)
				(justify mirror)
			)
		)
		(duplicate_pad_numbers_are_jumpers no)
		(fp_line
			(start 0.7874 -0.4064)
			(end -0.7874 -0.4064)
			(stroke
				(width 0.1524)
				(type default)
			)
			(layer "B.SilkS")
		)
		(fp_line
			(start -0.7874 -0.4064)
			(end -0.7874 0.4064)
			(stroke
				(width 0.1524)
				(type default)
			)
			(layer "B.SilkS")
		)
		(fp_line
			(start 0.7874 0.4064)
			(end 0.7874 -0.4064)
			(stroke
				(width 0.1524)
				(type default)
			)
			(layer "B.SilkS")
		)
		(fp_line
			(start -0.7874 0.4064)
			(end 0.7874 0.4064)
			(stroke
				(width 0.1524)
				(type default)
			)
			(layer "B.SilkS")
		)
		(fp_line
			(start 0.67945 -0.305054)
			(end 0.12065 -0.305054)
			(stroke
				(width 0.1)
				(type default)
			)
			(layer "B.Fab")
		)
		(fp_line
			(start 0.12065 -0.305054)
			(end 0.12065 -0.2794)
			(stroke
				(width 0.1)
				(type default)
			)
			(layer "B.Fab")
		)
		(fp_line
			(start -0.12065 -0.3048)
			(end -0.67945 -0.3048)
			(stroke
				(width 0.1)
				(type default)
			)
			(layer "B.Fab")
		)
		(fp_line
			(start -0.67945 -0.3048)
			(end -0.67945 0.3048)
			(stroke
				(width 0.1)
				(type default)
			)
			(layer "B.Fab")
		)
		(fp_line
			(start 0.12065 -0.2794)
			(end -0.12065 -0.2794)
			(stroke
				(width 0.1)
				(type default)
			)
			(layer "B.Fab")
		)
		(fp_line
			(start -0.12065 -0.2794)
			(end -0.12065 -0.3048)
			(stroke
				(width 0.1)
				(type default)
			)
			(layer "B.Fab")
		)
		(fp_line
			(start 0.12065 0.2794)
			(end 0.12065 0.3048)
			(stroke
				(width 0.1)
				(type default)
			)
			(layer "B.Fab")
		)
		(fp_line
			(start -0.120396 0.2794)
			(end 0.12065 0.2794)
			(stroke
				(width 0.1)
				(type default)
			)
			(layer "B.Fab")
		)
		(fp_line
			(start 0.67945 0.3048)
			(end 0.67945 -0.305054)
			(stroke
				(width 0.1)
				(type default)
			)
			(layer "B.Fab")
		)
		(fp_line
			(start 0.12065 0.3048)
			(end 0.67945 0.3048)
			(stroke
				(width 0.1)
				(type default)
			)
			(layer "B.Fab")
		)
		(fp_line
			(start -0.120396 0.3048)
			(end -0.120396 0.2794)
			(stroke
				(width 0.1)
				(type default)
			)
			(layer "B.Fab")
		)
		(fp_line
			(start -0.67945 0.3048)
			(end -0.120396 0.3048)
			(stroke
				(width 0.1)
				(type default)
			)
			(layer "B.Fab")
		)
		(pad "1" smd circle
			(at 0.40005 0 270)
			(size 0 0)
			(layers "B.Cu" "B.Mask" "B.Paste")
			(net "CRT_VCC5")
		)
		(pad "2" smd circle
			(at -0.40005 0 270)
			(size 0 0)
			(layers "B.Cu" "B.Mask" "B.Paste")
			(net "BMC_DDC_BUF_EN")
		)
	)
	(footprint ""
		(layer "B.Cu")
		(at 85.29955 -48.504094 180)
		(property "Reference" "R366"
			(at 0 0 0)
			(layer "B.SilkS")
			(hide yes)
			(effects
				(font
					(size 1.27 1.27)
				)
				(justify mirror)
			)
		)
		(property "Value" ""
			(at 0 0 0)
			(layer "B.Fab")
			(effects
				(font
					(size 1.27 1.27)
				)
				(justify mirror)
			)
		)
		(duplicate_pad_numbers_are_jumpers no)
		(fp_line
			(start 0.7874 0.4064)
			(end 0.7874 -0.4064)
			(stroke
				(width 0.1524)
				(type default)
			)
			(layer "B.SilkS")
		)
		(fp_line
			(start 0.7874 -0.4064)
			(end -0.7874 -0.4064)
			(stroke
				(width 0.1524)
				(type default)
			)
			(layer "B.SilkS")
		)
		(fp_line
			(start -0.7874 0.4064)
			(end 0.7874 0.4064)
			(stroke
				(width 0.1524)
				(type default)
			)
			(layer "B.SilkS")
		)
		(fp_line
			(start -0.7874 -0.4064)
			(end -0.7874 0.4064)
			(stroke
				(width 0.1524)
				(type default)
			)
			(layer "B.SilkS")
		)
		(fp_line
			(start 0.67945 0.3048)
			(end 0.67945 -0.305054)
			(stroke
				(width 0.1)
				(type default)
			)
			(layer "B.Fab")
		)
		(fp_line
			(start 0.67945 -0.305054)
			(end 0.12065 -0.305054)
			(stroke
				(width 0.1)
				(type default)
			)
			(layer "B.Fab")
		)
		(fp_line
			(start 0.12065 0.3048)
			(end 0.67945 0.3048)
			(stroke
				(width 0.1)
				(type default)
			)
			(layer "B.Fab")
		)
		(fp_line
			(start 0.12065 0.2794)
			(end 0.12065 0.3048)
			(stroke
				(width 0.1)
				(type default)
			)
			(layer "B.Fab")
		)
		(fp_line
			(start 0.12065 -0.2794)
			(end -0.12065 -0.2794)
			(stroke
				(width 0.1)
				(type default)
			)
			(layer "B.Fab")
		)
		(fp_line
			(start 0.12065 -0.305054)
			(end 0.12065 -0.2794)
			(stroke
				(width 0.1)
				(type default)
			)
			(layer "B.Fab")
		)
		(fp_line
			(start -0.120396 0.3048)
			(end -0.120396 0.2794)
			(stroke
				(width 0.1)
				(type default)
			)
			(layer "B.Fab")
		)
		(fp_line
			(start -0.120396 0.2794)
			(end 0.12065 0.2794)
			(stroke
				(width 0.1)
				(type default)
			)
			(layer "B.Fab")
		)
		(fp_line
			(start -0.12065 -0.2794)
			(end -0.12065 -0.3048)
			(stroke
				(width 0.1)
				(type default)
			)
			(layer "B.Fab")
		)
		(fp_line
			(start -0.12065 -0.3048)
			(end -0.67945 -0.3048)
			(stroke
				(width 0.1)
				(type default)
			)
			(layer "B.Fab")
		)
		(fp_line
			(start -0.67945 0.3048)
			(end -0.120396 0.3048)
			(stroke
				(width 0.1)
				(type default)
			)
			(layer "B.Fab")
		)
		(fp_line
			(start -0.67945 -0.3048)
			(end -0.67945 0.3048)
			(stroke
				(width 0.1)
				(type default)
			)
			(layer "B.Fab")
		)
		(pad "1" smd circle
			(at 0.40005 0)
			(size 0 0)
			(layers "B.Cu" "B.Mask" "B.Paste")
			(net "M_BMC_DDR4_MCAS_N")
		)
		(pad "2" smd circle
			(at -0.40005 0)
			(size 0 0)
			(layers "B.Cu" "B.Mask" "B.Paste")
			(net "P1V2_AUX")
		)
	)
	(footprint ""
		(layer "B.Cu")
		(at 66.513202 -37.038788 90)
		(property "Reference" "R206"
			(at 0 0 90)
			(layer "B.SilkS")
			(hide yes)
			(effects
				(font
					(size 1.27 1.27)
				)
				(justify mirror)
			)
		)
		(property "Value" ""
			(at 0 0 90)
			(layer "B.Fab")
			(effects
				(font
					(size 1.27 1.27)
				)
				(justify mirror)
			)
		)
		(duplicate_pad_numbers_are_jumpers no)
		(fp_line
			(start 0.7874 -0.4064)
			(end -0.7874 -0.4064)
			(stroke
				(width 0.1524)
				(type default)
			)
			(layer "B.SilkS")
		)
		(fp_line
			(start -0.7874 -0.4064)
			(end -0.7874 0.4064)
			(stroke
				(width 0.1524)
				(type default)
			)
			(layer "B.SilkS")
		)
		(fp_line
			(start 0.7874 0.4064)
			(end 0.7874 -0.4064)
			(stroke
				(width 0.1524)
				(type default)
			)
			(layer "B.SilkS")
		)
		(fp_line
			(start -0.7874 0.4064)
			(end 0.7874 0.4064)
			(stroke
				(width 0.1524)
				(type default)
			)
			(layer "B.SilkS")
		)
		(fp_line
			(start 0.67945 -0.305054)
			(end 0.12065 -0.305054)
			(stroke
				(width 0.1)
				(type default)
			)
			(layer "B.Fab")
		)
		(fp_line
			(start 0.12065 -0.305054)
			(end 0.12065 -0.2794)
			(stroke
				(width 0.1)
				(type default)
			)
			(layer "B.Fab")
		)
		(fp_line
			(start -0.12065 -0.3048)
			(end -0.67945 -0.3048)
			(stroke
				(width 0.1)
				(type default)
			)
			(layer "B.Fab")
		)
		(fp_line
			(start -0.67945 -0.3048)
			(end -0.67945 0.3048)
			(stroke
				(width 0.1)
				(type default)
			)
			(layer "B.Fab")
		)
		(fp_line
			(start 0.12065 -0.2794)
			(end -0.12065 -0.2794)
			(stroke
				(width 0.1)
				(type default)
			)
			(layer "B.Fab")
		)
		(fp_line
			(start -0.12065 -0.2794)
			(end -0.12065 -0.3048)
			(stroke
				(width 0.1)
				(type default)
			)
			(layer "B.Fab")
		)
		(fp_line
			(start 0.12065 0.2794)
			(end 0.12065 0.3048)
			(stroke
				(width 0.1)
				(type default)
			)
			(layer "B.Fab")
		)
		(fp_line
			(start -0.120396 0.2794)
			(end 0.12065 0.2794)
			(stroke
				(width 0.1)
				(type default)
			)
			(layer "B.Fab")
		)
		(fp_line
			(start 0.67945 0.3048)
			(end 0.67945 -0.305054)
			(stroke
				(width 0.1)
				(type default)
			)
			(layer "B.Fab")
		)
		(fp_line
			(start 0.12065 0.3048)
			(end 0.67945 0.3048)
			(stroke
				(width 0.1)
				(type default)
			)
			(layer "B.Fab")
		)
		(fp_line
			(start -0.120396 0.3048)
			(end -0.120396 0.2794)
			(stroke
				(width 0.1)
				(type default)
			)
			(layer "B.Fab")
		)
		(fp_line
			(start -0.67945 0.3048)
			(end -0.120396 0.3048)
			(stroke
				(width 0.1)
				(type default)
			)
			(layer "B.Fab")
		)
		(pad "1" smd circle
			(at 0.40005 0 270)
			(size 0 0)
			(layers "B.Cu" "B.Mask" "B.Paste")
			(net "GND")
		)
		(pad "2" smd circle
			(at -0.40005 0 270)
			(size 0 0)
			(layers "B.Cu" "B.Mask" "B.Paste")
			(net "JTAG_SCM_NTRST")
		)
	)
	(footprint ""
		(layer "B.Cu")
		(at 49.3014 -66.72072 90)
		(property "Reference" "C311"
			(at 0 0 90)
			(layer "B.SilkS")
			(hide yes)
			(effects
				(font
					(size 1.27 1.27)
				)
				(justify mirror)
			)
		)
		(property "Value" ""
			(at 0 0 90)
			(layer "B.Fab")
			(effects
				(font
					(size 1.27 1.27)
				)
				(justify mirror)
			)
		)
		(duplicate_pad_numbers_are_jumpers no)
		(fp_line
			(start 0.7874 -0.4064)
			(end -0.7874 -0.4064)
			(stroke
				(width 0.1524)
				(type default)
			)
			(layer "B.SilkS")
		)
		(fp_line
			(start -0.7874 -0.4064)
			(end -0.7874 0.4064)
			(stroke
				(width 0.1524)
				(type default)
			)
			(layer "B.SilkS")
		)
		(fp_line
			(start 0.7874 0.4064)
			(end 0.7874 -0.4064)
			(stroke
				(width 0.1524)
				(type default)
			)
			(layer "B.SilkS")
		)
		(fp_line
			(start -0.7874 0.4064)
			(end 0.7874 0.4064)
			(stroke
				(width 0.1524)
				(type default)
			)
			(layer "B.SilkS")
		)
		(fp_line
			(start 0.67945 -0.305054)
			(end 0.12065 -0.305054)
			(stroke
				(width 0.1)
				(type default)
			)
			(layer "B.Fab")
		)
		(fp_line
			(start 0.12065 -0.305054)
			(end 0.12065 -0.2794)
			(stroke
				(width 0.1)
				(type default)
			)
			(layer "B.Fab")
		)
		(fp_line
			(start -0.12065 -0.3048)
			(end -0.67945 -0.3048)
			(stroke
				(width 0.1)
				(type default)
			)
			(layer "B.Fab")
		)
		(fp_line
			(start -0.67945 -0.3048)
			(end -0.67945 0.3048)
			(stroke
				(width 0.1)
				(type default)
			)
			(layer "B.Fab")
		)
		(fp_line
			(start 0.12065 -0.2794)
			(end -0.12065 -0.2794)
			(stroke
				(width 0.1)
				(type default)
			)
			(layer "B.Fab")
		)
		(fp_line
			(start -0.12065 -0.2794)
			(end -0.12065 -0.3048)
			(stroke
				(width 0.1)
				(type default)
			)
			(layer "B.Fab")
		)
		(fp_line
			(start 0.12065 0.2794)
			(end 0.12065 0.3048)
			(stroke
				(width 0.1)
				(type default)
			)
			(layer "B.Fab")
		)
		(fp_line
			(start -0.120396 0.2794)
			(end 0.12065 0.2794)
			(stroke
				(width 0.1)
				(type default)
			)
			(layer "B.Fab")
		)
		(fp_line
			(start 0.67945 0.3048)
			(end 0.67945 -0.305054)
			(stroke
				(width 0.1)
				(type default)
			)
			(layer "B.Fab")
		)
		(fp_line
			(start 0.12065 0.3048)
			(end 0.67945 0.3048)
			(stroke
				(width 0.1)
				(type default)
			)
			(layer "B.Fab")
		)
		(fp_line
			(start -0.120396 0.3048)
			(end -0.120396 0.2794)
			(stroke
				(width 0.1)
				(type default)
			)
			(layer "B.Fab")
		)
		(fp_line
			(start -0.67945 0.3048)
			(end -0.120396 0.3048)
			(stroke
				(width 0.1)
				(type default)
			)
			(layer "B.Fab")
		)
		(pad "1" smd circle
			(at 0.40005 0 270)
			(size 0 0)
			(layers "B.Cu" "B.Mask" "B.Paste")
			(net "P1V0_SENSOR")
		)
		(pad "2" smd circle
			(at -0.40005 0 270)
			(size 0 0)
			(layers "B.Cu" "B.Mask" "B.Paste")
			(net "GND")
		)
	)
	(footprint ""
		(layer "B.Cu")
		(at 64.794384 -40.322754)
		(property "Reference" "R387"
			(at 0 0 0)
			(layer "B.SilkS")
			(hide yes)
			(effects
				(font
					(size 1.27 1.27)
				)
				(justify mirror)
			)
		)
		(property "Value" ""
			(at 0 0 0)
			(layer "B.Fab")
			(effects
				(font
					(size 1.27 1.27)
				)
				(justify mirror)
			)
		)
		(duplicate_pad_numbers_are_jumpers no)
		(fp_line
			(start -0.7874 -0.4064)
			(end -0.7874 0.4064)
			(stroke
				(width 0.1524)
				(type default)
			)
			(layer "B.SilkS")
		)
		(fp_line
			(start -0.7874 0.4064)
			(end 0.7874 0.4064)
			(stroke
				(width 0.1524)
				(type default)
			)
			(layer "B.SilkS")
		)
		(fp_line
			(start 0.7874 -0.4064)
			(end -0.7874 -0.4064)
			(stroke
				(width 0.1524)
				(type default)
			)
			(layer "B.SilkS")
		)
		(fp_line
			(start 0.7874 0.4064)
			(end 0.7874 -0.4064)
			(stroke
				(width 0.1524)
				(type default)
			)
			(layer "B.SilkS")
		)
		(fp_line
			(start -0.67945 -0.3048)
			(end -0.67945 0.3048)
			(stroke
				(width 0.1)
				(type default)
			)
			(layer "B.Fab")
		)
		(fp_line
			(start -0.67945 0.3048)
			(end -0.120396 0.3048)
			(stroke
				(width 0.1)
				(type default)
			)
			(layer "B.Fab")
		)
		(fp_line
			(start -0.12065 -0.3048)
			(end -0.67945 -0.3048)
			(stroke
				(width 0.1)
				(type default)
			)
			(layer "B.Fab")
		)
		(fp_line
			(start -0.12065 -0.2794)
			(end -0.12065 -0.3048)
			(stroke
				(width 0.1)
				(type default)
			)
			(layer "B.Fab")
		)
		(fp_line
			(start -0.120396 0.2794)
			(end 0.12065 0.2794)
			(stroke
				(width 0.1)
				(type default)
			)
			(layer "B.Fab")
		)
		(fp_line
			(start -0.120396 0.3048)
			(end -0.120396 0.2794)
			(stroke
				(width 0.1)
				(type default)
			)
			(layer "B.Fab")
		)
		(fp_line
			(start 0.12065 -0.305054)
			(end 0.12065 -0.2794)
			(stroke
				(width 0.1)
				(type default)
			)
			(layer "B.Fab")
		)
		(fp_line
			(start 0.12065 -0.2794)
			(end -0.12065 -0.2794)
			(stroke
				(width 0.1)
				(type default)
			)
			(layer "B.Fab")
		)
		(fp_line
			(start 0.12065 0.2794)
			(end 0.12065 0.3048)
			(stroke
				(width 0.1)
				(type default)
			)
			(layer "B.Fab")
		)
		(fp_line
			(start 0.12065 0.3048)
			(end 0.67945 0.3048)
			(stroke
				(width 0.1)
				(type default)
			)
			(layer "B.Fab")
		)
		(fp_line
			(start 0.67945 -0.305054)
			(end 0.12065 -0.305054)
			(stroke
				(width 0.1)
				(type default)
			)
			(layer "B.Fab")
		)
		(fp_line
			(start 0.67945 0.3048)
			(end 0.67945 -0.305054)
			(stroke
				(width 0.1)
				(type default)
			)
			(layer "B.Fab")
		)
		(pad "1" smd circle
			(at 0.40005 0 180)
			(size 0 0)
			(layers "B.Cu" "B.Mask" "B.Paste")
			(net "GND")
		)
		(pad "2" smd circle
			(at -0.40005 0 180)
			(size 0 0)
			(layers "B.Cu" "B.Mask" "B.Paste")
			(net "DP_BMC_HPD_3V3_BUF")
		)
	)
	(footprint ""
		(layer "B.Cu")
		(at 50.673 -30.861 -90)
		(property "Reference" "R264"
			(at 0 0 90)
			(layer "B.SilkS")
			(hide yes)
			(effects
				(font
					(size 1.27 1.27)
				)
				(justify mirror)
			)
		)
		(property "Value" ""
			(at 0 0 90)
			(layer "B.Fab")
			(effects
				(font
					(size 1.27 1.27)
				)
				(justify mirror)
			)
		)
		(duplicate_pad_numbers_are_jumpers no)
		(fp_line
			(start -0.7874 0.4064)
			(end 0.7874 0.4064)
			(stroke
				(width 0.1524)
				(type default)
			)
			(layer "B.SilkS")
		)
		(fp_line
			(start 0.7874 0.4064)
			(end 0.7874 -0.4064)
			(stroke
				(width 0.1524)
				(type default)
			)
			(layer "B.SilkS")
		)
		(fp_line
			(start -0.7874 -0.4064)
			(end -0.7874 0.4064)
			(stroke
				(width 0.1524)
				(type default)
			)
			(layer "B.SilkS")
		)
		(fp_line
			(start 0.7874 -0.4064)
			(end -0.7874 -0.4064)
			(stroke
				(width 0.1524)
				(type default)
			)
			(layer "B.SilkS")
		)
		(fp_line
			(start -0.67945 0.3048)
			(end -0.120396 0.3048)
			(stroke
				(width 0.1)
				(type default)
			)
			(layer "B.Fab")
		)
		(fp_line
			(start -0.120396 0.3048)
			(end -0.120396 0.2794)
			(stroke
				(width 0.1)
				(type default)
			)
			(layer "B.Fab")
		)
		(fp_line
			(start 0.12065 0.3048)
			(end 0.67945 0.3048)
			(stroke
				(width 0.1)
				(type default)
			)
			(layer "B.Fab")
		)
		(fp_line
			(start 0.67945 0.3048)
			(end 0.67945 -0.305054)
			(stroke
				(width 0.1)
				(type default)
			)
			(layer "B.Fab")
		)
		(fp_line
			(start -0.120396 0.2794)
			(end 0.12065 0.2794)
			(stroke
				(width 0.1)
				(type default)
			)
			(layer "B.Fab")
		)
		(fp_line
			(start 0.12065 0.2794)
			(end 0.12065 0.3048)
			(stroke
				(width 0.1)
				(type default)
			)
			(layer "B.Fab")
		)
		(fp_line
			(start -0.12065 -0.2794)
			(end -0.12065 -0.3048)
			(stroke
				(width 0.1)
				(type default)
			)
			(layer "B.Fab")
		)
		(fp_line
			(start 0.12065 -0.2794)
			(end -0.12065 -0.2794)
			(stroke
				(width 0.1)
				(type default)
			)
			(layer "B.Fab")
		)
		(fp_line
			(start -0.67945 -0.3048)
			(end -0.67945 0.3048)
			(stroke
				(width 0.1)
				(type default)
			)
			(layer "B.Fab")
		)
		(fp_line
			(start -0.12065 -0.3048)
			(end -0.67945 -0.3048)
			(stroke
				(width 0.1)
				(type default)
			)
			(layer "B.Fab")
		)
		(fp_line
			(start 0.12065 -0.305054)
			(end 0.12065 -0.2794)
			(stroke
				(width 0.1)
				(type default)
			)
			(layer "B.Fab")
		)
		(fp_line
			(start 0.67945 -0.305054)
			(end 0.12065 -0.305054)
			(stroke
				(width 0.1)
				(type default)
			)
			(layer "B.Fab")
		)
		(pad "1" smd circle
			(at 0.40005 0 90)
			(size 0 0)
			(layers "B.Cu" "B.Mask" "B.Paste")
			(net "P3V3_AUX")
		)
		(pad "2" smd circle
			(at -0.40005 0 90)
			(size 0 0)
			(layers "B.Cu" "B.Mask" "B.Paste")
			(net "SMB_BMC_MM16_SCL")
		)
	)
	(footprint ""
		(layer "B.Cu")
		(at 58.7375 -15.6337 -90)
		(property "Reference" "Q6"
			(at 2.52857 -1.4605 0)
			(unlocked yes)
			(layer "B.SilkS")
			(effects
				(font
					(size 0.7874 0.5842)
					(thickness 0.1524)
				)
				(justify left mirror)
			)
		)
		(property "Value" ""
			(at 0 0 90)
			(layer "B.Fab")
			(effects
				(font
					(size 1.27 1.27)
				)
				(justify mirror)
			)
		)
		(duplicate_pad_numbers_are_jumpers no)
		(fp_line
			(start -1.603248 1.500124)
			(end 1.603248 1.500124)
			(stroke
				(width 0.1524)
				(type default)
			)
			(layer "B.SilkS")
		)
		(fp_line
			(start 1.603248 1.500124)
			(end 1.603248 -1.500124)
			(stroke
				(width 0.1524)
				(type default)
			)
			(layer "B.SilkS")
		)
		(fp_line
			(start -1.603248 -1.500124)
			(end -1.603248 1.500124)
			(stroke
				(width 0.1524)
				(type default)
			)
			(layer "B.SilkS")
		)
		(fp_line
			(start 1.603248 -1.500124)
			(end -1.603248 -1.500124)
			(stroke
				(width 0.1524)
				(type default)
			)
			(layer "B.SilkS")
		)
		(fp_line
			(start -0.700024 1.500124)
			(end -0.700024 0.219964)
			(stroke
				(width 0.1)
				(type default)
			)
			(layer "B.Fab")
		)
		(fp_line
			(start 0.700024 1.500124)
			(end -0.700024 1.500124)
			(stroke
				(width 0.1)
				(type default)
			)
			(layer "B.Fab")
		)
		(fp_line
			(start 0.700024 1.169924)
			(end 0.700024 1.500124)
			(stroke
				(width 0.1)
				(type default)
			)
			(layer "B.Fab")
		)
		(fp_line
			(start 1.249934 1.169924)
			(end 0.700024 1.169924)
			(stroke
				(width 0.1)
				(type default)
			)
			(layer "B.Fab")
		)
		(fp_line
			(start 0.6985 0.729996)
			(end 1.249934 0.729996)
			(stroke
				(width 0.1)
				(type default)
			)
			(layer "B.Fab")
		)
		(fp_line
			(start 1.249934 0.729996)
			(end 1.249934 1.169924)
			(stroke
				(width 0.1)
				(type default)
			)
			(layer "B.Fab")
		)
		(fp_line
			(start -1.249934 0.219964)
			(end -1.249934 -0.219964)
			(stroke
				(width 0.1)
				(type default)
			)
			(layer "B.Fab")
		)
		(fp_line
			(start -0.700024 0.219964)
			(end -1.249934 0.219964)
			(stroke
				(width 0.1)
				(type default)
			)
			(layer "B.Fab")
		)
		(fp_line
			(start -1.249934 -0.219964)
			(end -0.700024 -0.219964)
			(stroke
				(width 0.1)
				(type default)
			)
			(layer "B.Fab")
		)
		(fp_line
			(start -0.700024 -0.219964)
			(end -0.700024 -1.500124)
			(stroke
				(width 0.1)
				(type default)
			)
			(layer "B.Fab")
		)
		(fp_line
			(start 0.6985 -0.729996)
			(end 0.6985 0.729996)
			(stroke
				(width 0.1)
				(type default)
			)
			(layer "B.Fab")
		)
		(fp_line
			(start 1.249934 -0.729996)
			(end 0.6985 -0.729996)
			(stroke
				(width 0.1)
				(type default)
			)
			(layer "B.Fab")
		)
		(fp_line
			(start 0.700024 -1.169924)
			(end 1.249934 -1.169924)
			(stroke
				(width 0.1)
				(type default)
			)
			(layer "B.Fab")
		)
		(fp_line
			(start 1.249934 -1.169924)
			(end 1.249934 -0.729996)
			(stroke
				(width 0.1)
				(type default)
			)
			(layer "B.Fab")
		)
		(fp_line
			(start -0.700024 -1.500124)
			(end 0.700024 -1.500124)
			(stroke
				(width 0.1)
				(type default)
			)
			(layer "B.Fab")
		)
		(fp_line
			(start 0.700024 -1.500124)
			(end 0.700024 -1.169924)
			(stroke
				(width 0.1)
				(type default)
			)
			(layer "B.Fab")
		)
		(fp_rect
			(start 0.700024 1.500124)
			(end -0.700024 -1.500124)
			(stroke
				(width 0)
				(type default)
			)
			(fill no)
			(layer "B.Fab")
		)
		(pad "D" smd rect
			(at -0.999998 0 180)
			(size 0.8128 0.9144)
			(layers "B.Cu" "B.Mask" "B.Paste")
			(net "FM_DEBUG_PORT_R_PRSNT_N")
		)
		(pad "G" smd rect
			(at 0.999998 -0.94996 180)
			(size 0.8128 0.9144)
			(layers "B.Cu" "B.Mask" "B.Paste")
			(net "DEBUG_PORT_PRSNT")
		)
		(pad "S" smd rect
			(at 0.999998 0.94996 180)
			(size 0.8128 0.9144)
			(layers "B.Cu" "B.Mask" "B.Paste")
			(net "GND")
		)
	)
	(footprint ""
		(layer "B.Cu")
		(at 63.129922 -49.472088 180)
		(property "Reference" "C73"
			(at 0 0 0)
			(layer "B.SilkS")
			(hide yes)
			(effects
				(font
					(size 1.27 1.27)
				)
				(justify mirror)
			)
		)
		(property "Value" ""
			(at 0 0 0)
			(layer "B.Fab")
			(effects
				(font
					(size 1.27 1.27)
				)
				(justify mirror)
			)
		)
		(duplicate_pad_numbers_are_jumpers no)
		(fp_line
			(start 0.7874 0.4064)
			(end 0.7874 -0.4064)
			(stroke
				(width 0.1524)
				(type default)
			)
			(layer "B.SilkS")
		)
		(fp_line
			(start 0.7874 -0.4064)
			(end -0.7874 -0.4064)
			(stroke
				(width 0.1524)
				(type default)
			)
			(layer "B.SilkS")
		)
		(fp_line
			(start -0.7874 0.4064)
			(end 0.7874 0.4064)
			(stroke
				(width 0.1524)
				(type default)
			)
			(layer "B.SilkS")
		)
		(fp_line
			(start -0.7874 -0.4064)
			(end -0.7874 0.4064)
			(stroke
				(width 0.1524)
				(type default)
			)
			(layer "B.SilkS")
		)
		(fp_line
			(start 0.67945 0.3048)
			(end 0.67945 -0.305054)
			(stroke
				(width 0.1)
				(type default)
			)
			(layer "B.Fab")
		)
		(fp_line
			(start 0.67945 -0.305054)
			(end 0.12065 -0.305054)
			(stroke
				(width 0.1)
				(type default)
			)
			(layer "B.Fab")
		)
		(fp_line
			(start 0.12065 0.3048)
			(end 0.67945 0.3048)
			(stroke
				(width 0.1)
				(type default)
			)
			(layer "B.Fab")
		)
		(fp_line
			(start 0.12065 0.2794)
			(end 0.12065 0.3048)
			(stroke
				(width 0.1)
				(type default)
			)
			(layer "B.Fab")
		)
		(fp_line
			(start 0.12065 -0.2794)
			(end -0.12065 -0.2794)
			(stroke
				(width 0.1)
				(type default)
			)
			(layer "B.Fab")
		)
		(fp_line
			(start 0.12065 -0.305054)
			(end 0.12065 -0.2794)
			(stroke
				(width 0.1)
				(type default)
			)
			(layer "B.Fab")
		)
		(fp_line
			(start -0.120396 0.3048)
			(end -0.120396 0.2794)
			(stroke
				(width 0.1)
				(type default)
			)
			(layer "B.Fab")
		)
		(fp_line
			(start -0.120396 0.2794)
			(end 0.12065 0.2794)
			(stroke
				(width 0.1)
				(type default)
			)
			(layer "B.Fab")
		)
		(fp_line
			(start -0.12065 -0.2794)
			(end -0.12065 -0.3048)
			(stroke
				(width 0.1)
				(type default)
			)
			(layer "B.Fab")
		)
		(fp_line
			(start -0.12065 -0.3048)
			(end -0.67945 -0.3048)
			(stroke
				(width 0.1)
				(type default)
			)
			(layer "B.Fab")
		)
		(fp_line
			(start -0.67945 0.3048)
			(end -0.120396 0.3048)
			(stroke
				(width 0.1)
				(type default)
			)
			(layer "B.Fab")
		)
		(fp_line
			(start -0.67945 -0.3048)
			(end -0.67945 0.3048)
			(stroke
				(width 0.1)
				(type default)
			)
			(layer "B.Fab")
		)
		(pad "1" smd circle
			(at 0.40005 0)
			(size 0 0)
			(layers "B.Cu" "B.Mask" "B.Paste")
			(net "P1V2_STBY_MVDD_CK")
		)
		(pad "2" smd circle
			(at -0.40005 0)
			(size 0 0)
			(layers "B.Cu" "B.Mask" "B.Paste")
			(net "GND")
		)
	)
	(footprint ""
		(layer "B.Cu")
		(at 60.556902 -61.858906 -90)
		(property "Reference" "R130"
			(at 0 0 90)
			(layer "B.SilkS")
			(hide yes)
			(effects
				(font
					(size 1.27 1.27)
				)
				(justify mirror)
			)
		)
		(property "Value" ""
			(at 0 0 90)
			(layer "B.Fab")
			(effects
				(font
					(size 1.27 1.27)
				)
				(justify mirror)
			)
		)
		(duplicate_pad_numbers_are_jumpers no)
		(fp_line
			(start -0.7874 0.4064)
			(end 0.7874 0.4064)
			(stroke
				(width 0.1524)
				(type default)
			)
			(layer "B.SilkS")
		)
		(fp_line
			(start 0.7874 0.4064)
			(end 0.7874 -0.4064)
			(stroke
				(width 0.1524)
				(type default)
			)
			(layer "B.SilkS")
		)
		(fp_line
			(start -0.7874 -0.4064)
			(end -0.7874 0.4064)
			(stroke
				(width 0.1524)
				(type default)
			)
			(layer "B.SilkS")
		)
		(fp_line
			(start 0.7874 -0.4064)
			(end -0.7874 -0.4064)
			(stroke
				(width 0.1524)
				(type default)
			)
			(layer "B.SilkS")
		)
		(fp_line
			(start -0.67945 0.3048)
			(end -0.120396 0.3048)
			(stroke
				(width 0.1)
				(type default)
			)
			(layer "B.Fab")
		)
		(fp_line
			(start -0.120396 0.3048)
			(end -0.120396 0.2794)
			(stroke
				(width 0.1)
				(type default)
			)
			(layer "B.Fab")
		)
		(fp_line
			(start 0.12065 0.3048)
			(end 0.67945 0.3048)
			(stroke
				(width 0.1)
				(type default)
			)
			(layer "B.Fab")
		)
		(fp_line
			(start 0.67945 0.3048)
			(end 0.67945 -0.305054)
			(stroke
				(width 0.1)
				(type default)
			)
			(layer "B.Fab")
		)
		(fp_line
			(start -0.120396 0.2794)
			(end 0.12065 0.2794)
			(stroke
				(width 0.1)
				(type default)
			)
			(layer "B.Fab")
		)
		(fp_line
			(start 0.12065 0.2794)
			(end 0.12065 0.3048)
			(stroke
				(width 0.1)
				(type default)
			)
			(layer "B.Fab")
		)
		(fp_line
			(start -0.12065 -0.2794)
			(end -0.12065 -0.3048)
			(stroke
				(width 0.1)
				(type default)
			)
			(layer "B.Fab")
		)
		(fp_line
			(start 0.12065 -0.2794)
			(end -0.12065 -0.2794)
			(stroke
				(width 0.1)
				(type default)
			)
			(layer "B.Fab")
		)
		(fp_line
			(start -0.67945 -0.3048)
			(end -0.67945 0.3048)
			(stroke
				(width 0.1)
				(type default)
			)
			(layer "B.Fab")
		)
		(fp_line
			(start -0.12065 -0.3048)
			(end -0.67945 -0.3048)
			(stroke
				(width 0.1)
				(type default)
			)
			(layer "B.Fab")
		)
		(fp_line
			(start 0.12065 -0.305054)
			(end 0.12065 -0.2794)
			(stroke
				(width 0.1)
				(type default)
			)
			(layer "B.Fab")
		)
		(fp_line
			(start 0.67945 -0.305054)
			(end 0.12065 -0.305054)
			(stroke
				(width 0.1)
				(type default)
			)
			(layer "B.Fab")
		)
		(pad "1" smd circle
			(at 0.40005 0 90)
			(size 0 0)
			(layers "B.Cu" "B.Mask" "B.Paste")
			(net "ESPI_LPC_D2_IO2")
		)
		(pad "2" smd circle
			(at -0.40005 0 90)
			(size 0 0)
			(layers "B.Cu" "B.Mask" "B.Paste")
			(net "ESPI_LPC_LAD2_IO2")
		)
	)
	(footprint ""
		(layer "B.Cu")
		(at 72.621394 -69.576188 -90)
		(property "Reference" "R686"
			(at 0 0 90)
			(layer "B.SilkS")
			(hide yes)
			(effects
				(font
					(size 1.27 1.27)
				)
				(justify mirror)
			)
		)
		(property "Value" ""
			(at 0 0 90)
			(layer "B.Fab")
			(effects
				(font
					(size 1.27 1.27)
				)
				(justify mirror)
			)
		)
		(duplicate_pad_numbers_are_jumpers no)
		(fp_line
			(start -0.7874 0.4064)
			(end 0.7874 0.4064)
			(stroke
				(width 0.1524)
				(type default)
			)
			(layer "B.SilkS")
		)
		(fp_line
			(start 0.7874 0.4064)
			(end 0.7874 -0.4064)
			(stroke
				(width 0.1524)
				(type default)
			)
			(layer "B.SilkS")
		)
		(fp_line
			(start -0.7874 -0.4064)
			(end -0.7874 0.4064)
			(stroke
				(width 0.1524)
				(type default)
			)
			(layer "B.SilkS")
		)
		(fp_line
			(start 0.7874 -0.4064)
			(end -0.7874 -0.4064)
			(stroke
				(width 0.1524)
				(type default)
			)
			(layer "B.SilkS")
		)
		(fp_line
			(start -0.67945 0.3048)
			(end -0.120396 0.3048)
			(stroke
				(width 0.1)
				(type default)
			)
			(layer "B.Fab")
		)
		(fp_line
			(start -0.120396 0.3048)
			(end -0.120396 0.2794)
			(stroke
				(width 0.1)
				(type default)
			)
			(layer "B.Fab")
		)
		(fp_line
			(start 0.12065 0.3048)
			(end 0.67945 0.3048)
			(stroke
				(width 0.1)
				(type default)
			)
			(layer "B.Fab")
		)
		(fp_line
			(start 0.67945 0.3048)
			(end 0.67945 -0.305054)
			(stroke
				(width 0.1)
				(type default)
			)
			(layer "B.Fab")
		)
		(fp_line
			(start -0.120396 0.2794)
			(end 0.12065 0.2794)
			(stroke
				(width 0.1)
				(type default)
			)
			(layer "B.Fab")
		)
		(fp_line
			(start 0.12065 0.2794)
			(end 0.12065 0.3048)
			(stroke
				(width 0.1)
				(type default)
			)
			(layer "B.Fab")
		)
		(fp_line
			(start -0.12065 -0.2794)
			(end -0.12065 -0.3048)
			(stroke
				(width 0.1)
				(type default)
			)
			(layer "B.Fab")
		)
		(fp_line
			(start 0.12065 -0.2794)
			(end -0.12065 -0.2794)
			(stroke
				(width 0.1)
				(type default)
			)
			(layer "B.Fab")
		)
		(fp_line
			(start -0.67945 -0.3048)
			(end -0.67945 0.3048)
			(stroke
				(width 0.1)
				(type default)
			)
			(layer "B.Fab")
		)
		(fp_line
			(start -0.12065 -0.3048)
			(end -0.67945 -0.3048)
			(stroke
				(width 0.1)
				(type default)
			)
			(layer "B.Fab")
		)
		(fp_line
			(start 0.12065 -0.305054)
			(end 0.12065 -0.2794)
			(stroke
				(width 0.1)
				(type default)
			)
			(layer "B.Fab")
		)
		(fp_line
			(start 0.67945 -0.305054)
			(end 0.12065 -0.305054)
			(stroke
				(width 0.1)
				(type default)
			)
			(layer "B.Fab")
		)
		(pad "1" smd circle
			(at 0.40005 0 90)
			(size 0 0)
			(layers "B.Cu" "B.Mask" "B.Paste")
			(net "P3V3_AUX")
		)
		(pad "2" smd circle
			(at -0.40005 0 90)
			(size 0 0)
			(layers "B.Cu" "B.Mask" "B.Paste")
			(net "BMC_EMMC_WP_N")
		)
	)
	(footprint ""
		(layer "B.Cu")
		(at 33.02 -101.854 -90)
		(property "Reference" "R282"
			(at 0 0 90)
			(layer "B.SilkS")
			(hide yes)
			(effects
				(font
					(size 1.27 1.27)
				)
				(justify mirror)
			)
		)
		(property "Value" ""
			(at 0 0 90)
			(layer "B.Fab")
			(effects
				(font
					(size 1.27 1.27)
				)
				(justify mirror)
			)
		)
		(duplicate_pad_numbers_are_jumpers no)
		(fp_line
			(start -0.7874 0.4064)
			(end 0.7874 0.4064)
			(stroke
				(width 0.1524)
				(type default)
			)
			(layer "B.SilkS")
		)
		(fp_line
			(start 0.7874 0.4064)
			(end 0.7874 -0.4064)
			(stroke
				(width 0.1524)
				(type default)
			)
			(layer "B.SilkS")
		)
		(fp_line
			(start -0.7874 -0.4064)
			(end -0.7874 0.4064)
			(stroke
				(width 0.1524)
				(type default)
			)
			(layer "B.SilkS")
		)
		(fp_line
			(start 0.7874 -0.4064)
			(end -0.7874 -0.4064)
			(stroke
				(width 0.1524)
				(type default)
			)
			(layer "B.SilkS")
		)
		(fp_line
			(start -0.67945 0.3048)
			(end -0.120396 0.3048)
			(stroke
				(width 0.1)
				(type default)
			)
			(layer "B.Fab")
		)
		(fp_line
			(start -0.120396 0.3048)
			(end -0.120396 0.2794)
			(stroke
				(width 0.1)
				(type default)
			)
			(layer "B.Fab")
		)
		(fp_line
			(start 0.12065 0.3048)
			(end 0.67945 0.3048)
			(stroke
				(width 0.1)
				(type default)
			)
			(layer "B.Fab")
		)
		(fp_line
			(start 0.67945 0.3048)
			(end 0.67945 -0.305054)
			(stroke
				(width 0.1)
				(type default)
			)
			(layer "B.Fab")
		)
		(fp_line
			(start -0.120396 0.2794)
			(end 0.12065 0.2794)
			(stroke
				(width 0.1)
				(type default)
			)
			(layer "B.Fab")
		)
		(fp_line
			(start 0.12065 0.2794)
			(end 0.12065 0.3048)
			(stroke
				(width 0.1)
				(type default)
			)
			(layer "B.Fab")
		)
		(fp_line
			(start -0.12065 -0.2794)
			(end -0.12065 -0.3048)
			(stroke
				(width 0.1)
				(type default)
			)
			(layer "B.Fab")
		)
		(fp_line
			(start 0.12065 -0.2794)
			(end -0.12065 -0.2794)
			(stroke
				(width 0.1)
				(type default)
			)
			(layer "B.Fab")
		)
		(fp_line
			(start -0.67945 -0.3048)
			(end -0.67945 0.3048)
			(stroke
				(width 0.1)
				(type default)
			)
			(layer "B.Fab")
		)
		(fp_line
			(start -0.12065 -0.3048)
			(end -0.67945 -0.3048)
			(stroke
				(width 0.1)
				(type default)
			)
			(layer "B.Fab")
		)
		(fp_line
			(start 0.12065 -0.305054)
			(end 0.12065 -0.2794)
			(stroke
				(width 0.1)
				(type default)
			)
			(layer "B.Fab")
		)
		(fp_line
			(start 0.67945 -0.305054)
			(end 0.12065 -0.305054)
			(stroke
				(width 0.1)
				(type default)
			)
			(layer "B.Fab")
		)
		(pad "1" smd circle
			(at 0.40005 0 90)
			(size 0 0)
			(layers "B.Cu" "B.Mask" "B.Paste")
			(net "RST_BMC_HW_R1")
		)
		(pad "2" smd circle
			(at -0.40005 0 90)
			(size 0 0)
			(layers "B.Cu" "B.Mask" "B.Paste")
			(net "RST_BMC_HW")
		)
	)
	(footprint ""
		(layer "B.Cu")
		(at 18.2118 -72.9234 180)
		(property "Reference" "R300"
			(at 0 0 0)
			(layer "B.SilkS")
			(hide yes)
			(effects
				(font
					(size 1.27 1.27)
				)
				(justify mirror)
			)
		)
		(property "Value" ""
			(at 0 0 0)
			(layer "B.Fab")
			(effects
				(font
					(size 1.27 1.27)
				)
				(justify mirror)
			)
		)
		(duplicate_pad_numbers_are_jumpers no)
		(fp_line
			(start 0.7874 0.4064)
			(end 0.7874 -0.4064)
			(stroke
				(width 0.1524)
				(type default)
			)
			(layer "B.SilkS")
		)
		(fp_line
			(start 0.7874 -0.4064)
			(end -0.7874 -0.4064)
			(stroke
				(width 0.1524)
				(type default)
			)
			(layer "B.SilkS")
		)
		(fp_line
			(start -0.7874 0.4064)
			(end 0.7874 0.4064)
			(stroke
				(width 0.1524)
				(type default)
			)
			(layer "B.SilkS")
		)
		(fp_line
			(start -0.7874 -0.4064)
			(end -0.7874 0.4064)
			(stroke
				(width 0.1524)
				(type default)
			)
			(layer "B.SilkS")
		)
		(fp_line
			(start 0.67945 0.3048)
			(end 0.67945 -0.305054)
			(stroke
				(width 0.1)
				(type default)
			)
			(layer "B.Fab")
		)
		(fp_line
			(start 0.67945 -0.305054)
			(end 0.12065 -0.305054)
			(stroke
				(width 0.1)
				(type default)
			)
			(layer "B.Fab")
		)
		(fp_line
			(start 0.12065 0.3048)
			(end 0.67945 0.3048)
			(stroke
				(width 0.1)
				(type default)
			)
			(layer "B.Fab")
		)
		(fp_line
			(start 0.12065 0.2794)
			(end 0.12065 0.3048)
			(stroke
				(width 0.1)
				(type default)
			)
			(layer "B.Fab")
		)
		(fp_line
			(start 0.12065 -0.2794)
			(end -0.12065 -0.2794)
			(stroke
				(width 0.1)
				(type default)
			)
			(layer "B.Fab")
		)
		(fp_line
			(start 0.12065 -0.305054)
			(end 0.12065 -0.2794)
			(stroke
				(width 0.1)
				(type default)
			)
			(layer "B.Fab")
		)
		(fp_line
			(start -0.120396 0.3048)
			(end -0.120396 0.2794)
			(stroke
				(width 0.1)
				(type default)
			)
			(layer "B.Fab")
		)
		(fp_line
			(start -0.120396 0.2794)
			(end 0.12065 0.2794)
			(stroke
				(width 0.1)
				(type default)
			)
			(layer "B.Fab")
		)
		(fp_line
			(start -0.12065 -0.2794)
			(end -0.12065 -0.3048)
			(stroke
				(width 0.1)
				(type default)
			)
			(layer "B.Fab")
		)
		(fp_line
			(start -0.12065 -0.3048)
			(end -0.67945 -0.3048)
			(stroke
				(width 0.1)
				(type default)
			)
			(layer "B.Fab")
		)
		(fp_line
			(start -0.67945 0.3048)
			(end -0.120396 0.3048)
			(stroke
				(width 0.1)
				(type default)
			)
			(layer "B.Fab")
		)
		(fp_line
			(start -0.67945 -0.3048)
			(end -0.67945 0.3048)
			(stroke
				(width 0.1)
				(type default)
			)
			(layer "B.Fab")
		)
		(pad "1" smd circle
			(at 0.40005 0)
			(size 0 0)
			(layers "B.Cu" "B.Mask" "B.Paste")
			(net "SMB_DEBUG_AUX_LVC3_USB_R1_SCL")
		)
		(pad "2" smd circle
			(at -0.40005 0)
			(size 0 0)
			(layers "B.Cu" "B.Mask" "B.Paste")
			(net "SMB_DEBUG_AUX_LVC3_USB_SCL")
		)
	)
	(footprint ""
		(layer "B.Cu")
		(at 68.58 -12.446 180)
		(property "Reference" "C335"
			(at 0 0 0)
			(layer "B.SilkS")
			(hide yes)
			(effects
				(font
					(size 1.27 1.27)
				)
				(justify mirror)
			)
		)
		(property "Value" ""
			(at 0 0 0)
			(layer "B.Fab")
			(effects
				(font
					(size 1.27 1.27)
				)
				(justify mirror)
			)
		)
		(duplicate_pad_numbers_are_jumpers no)
		(fp_line
			(start 0.7874 0.4064)
			(end 0.7874 -0.4064)
			(stroke
				(width 0.1524)
				(type default)
			)
			(layer "B.SilkS")
		)
		(fp_line
			(start 0.7874 -0.4064)
			(end -0.7874 -0.4064)
			(stroke
				(width 0.1524)
				(type default)
			)
			(layer "B.SilkS")
		)
		(fp_line
			(start -0.7874 0.4064)
			(end 0.7874 0.4064)
			(stroke
				(width 0.1524)
				(type default)
			)
			(layer "B.SilkS")
		)
		(fp_line
			(start -0.7874 -0.4064)
			(end -0.7874 0.4064)
			(stroke
				(width 0.1524)
				(type default)
			)
			(layer "B.SilkS")
		)
		(fp_line
			(start 0.67945 0.3048)
			(end 0.67945 -0.305054)
			(stroke
				(width 0.1)
				(type default)
			)
			(layer "B.Fab")
		)
		(fp_line
			(start 0.67945 -0.305054)
			(end 0.12065 -0.305054)
			(stroke
				(width 0.1)
				(type default)
			)
			(layer "B.Fab")
		)
		(fp_line
			(start 0.12065 0.3048)
			(end 0.67945 0.3048)
			(stroke
				(width 0.1)
				(type default)
			)
			(layer "B.Fab")
		)
		(fp_line
			(start 0.12065 0.2794)
			(end 0.12065 0.3048)
			(stroke
				(width 0.1)
				(type default)
			)
			(layer "B.Fab")
		)
		(fp_line
			(start 0.12065 -0.2794)
			(end -0.12065 -0.2794)
			(stroke
				(width 0.1)
				(type default)
			)
			(layer "B.Fab")
		)
		(fp_line
			(start 0.12065 -0.305054)
			(end 0.12065 -0.2794)
			(stroke
				(width 0.1)
				(type default)
			)
			(layer "B.Fab")
		)
		(fp_line
			(start -0.120396 0.3048)
			(end -0.120396 0.2794)
			(stroke
				(width 0.1)
				(type default)
			)
			(layer "B.Fab")
		)
		(fp_line
			(start -0.120396 0.2794)
			(end 0.12065 0.2794)
			(stroke
				(width 0.1)
				(type default)
			)
			(layer "B.Fab")
		)
		(fp_line
			(start -0.12065 -0.2794)
			(end -0.12065 -0.3048)
			(stroke
				(width 0.1)
				(type default)
			)
			(layer "B.Fab")
		)
		(fp_line
			(start -0.12065 -0.3048)
			(end -0.67945 -0.3048)
			(stroke
				(width 0.1)
				(type default)
			)
			(layer "B.Fab")
		)
		(fp_line
			(start -0.67945 0.3048)
			(end -0.120396 0.3048)
			(stroke
				(width 0.1)
				(type default)
			)
			(layer "B.Fab")
		)
		(fp_line
			(start -0.67945 -0.3048)
			(end -0.67945 0.3048)
			(stroke
				(width 0.1)
				(type default)
			)
			(layer "B.Fab")
		)
		(pad "1" smd circle
			(at 0.40005 0)
			(size 0 0)
			(layers "B.Cu" "B.Mask" "B.Paste")
			(net "REAR_AC_PWR_BMC_BTN_N")
		)
		(pad "2" smd circle
			(at -0.40005 0)
			(size 0 0)
			(layers "B.Cu" "B.Mask" "B.Paste")
			(net "GND")
		)
	)
	(footprint ""
		(layer "B.Cu")
		(at 30.5435 -41.4147 -90)
		(property "Reference" "C202"
			(at 0 0 90)
			(layer "B.SilkS")
			(hide yes)
			(effects
				(font
					(size 1.27 1.27)
				)
				(justify mirror)
			)
		)
		(property "Value" ""
			(at 0 0 90)
			(layer "B.Fab")
			(effects
				(font
					(size 1.27 1.27)
				)
				(justify mirror)
			)
		)
		(duplicate_pad_numbers_are_jumpers no)
		(fp_line
			(start -0.7874 0.4064)
			(end 0.7874 0.4064)
			(stroke
				(width 0.1524)
				(type default)
			)
			(layer "B.SilkS")
		)
		(fp_line
			(start 0.7874 0.4064)
			(end 0.7874 -0.4064)
			(stroke
				(width 0.1524)
				(type default)
			)
			(layer "B.SilkS")
		)
		(fp_line
			(start -0.7874 -0.4064)
			(end -0.7874 0.4064)
			(stroke
				(width 0.1524)
				(type default)
			)
			(layer "B.SilkS")
		)
		(fp_line
			(start 0.7874 -0.4064)
			(end -0.7874 -0.4064)
			(stroke
				(width 0.1524)
				(type default)
			)
			(layer "B.SilkS")
		)
		(fp_line
			(start -0.67945 0.3048)
			(end -0.120396 0.3048)
			(stroke
				(width 0.1)
				(type default)
			)
			(layer "B.Fab")
		)
		(fp_line
			(start -0.120396 0.3048)
			(end -0.120396 0.2794)
			(stroke
				(width 0.1)
				(type default)
			)
			(layer "B.Fab")
		)
		(fp_line
			(start 0.12065 0.3048)
			(end 0.67945 0.3048)
			(stroke
				(width 0.1)
				(type default)
			)
			(layer "B.Fab")
		)
		(fp_line
			(start 0.67945 0.3048)
			(end 0.67945 -0.305054)
			(stroke
				(width 0.1)
				(type default)
			)
			(layer "B.Fab")
		)
		(fp_line
			(start -0.120396 0.2794)
			(end 0.12065 0.2794)
			(stroke
				(width 0.1)
				(type default)
			)
			(layer "B.Fab")
		)
		(fp_line
			(start 0.12065 0.2794)
			(end 0.12065 0.3048)
			(stroke
				(width 0.1)
				(type default)
			)
			(layer "B.Fab")
		)
		(fp_line
			(start -0.12065 -0.2794)
			(end -0.12065 -0.3048)
			(stroke
				(width 0.1)
				(type default)
			)
			(layer "B.Fab")
		)
		(fp_line
			(start 0.12065 -0.2794)
			(end -0.12065 -0.2794)
			(stroke
				(width 0.1)
				(type default)
			)
			(layer "B.Fab")
		)
		(fp_line
			(start -0.67945 -0.3048)
			(end -0.67945 0.3048)
			(stroke
				(width 0.1)
				(type default)
			)
			(layer "B.Fab")
		)
		(fp_line
			(start -0.12065 -0.3048)
			(end -0.67945 -0.3048)
			(stroke
				(width 0.1)
				(type default)
			)
			(layer "B.Fab")
		)
		(fp_line
			(start 0.12065 -0.305054)
			(end 0.12065 -0.2794)
			(stroke
				(width 0.1)
				(type default)
			)
			(layer "B.Fab")
		)
		(fp_line
			(start 0.67945 -0.305054)
			(end 0.12065 -0.305054)
			(stroke
				(width 0.1)
				(type default)
			)
			(layer "B.Fab")
		)
		(pad "1" smd circle
			(at 0.40005 0 90)
			(size 0 0)
			(layers "B.Cu" "B.Mask" "B.Paste")
			(net "P5V_AUX")
		)
		(pad "2" smd circle
			(at -0.40005 0 90)
			(size 0 0)
			(layers "B.Cu" "B.Mask" "B.Paste")
			(net "GND")
		)
	)
	(footprint ""
		(layer "B.Cu")
		(at 33.001712 -36.076128 90)
		(property "Reference" "C204"
			(at 0 0 90)
			(layer "B.SilkS")
			(hide yes)
			(effects
				(font
					(size 1.27 1.27)
				)
				(justify mirror)
			)
		)
		(property "Value" ""
			(at 0 0 90)
			(layer "B.Fab")
			(effects
				(font
					(size 1.27 1.27)
				)
				(justify mirror)
			)
		)
		(duplicate_pad_numbers_are_jumpers no)
		(fp_line
			(start 1.2954 -0.5842)
			(end -1.2954 -0.5842)
			(stroke
				(width 0.1524)
				(type default)
			)
			(layer "B.SilkS")
		)
		(fp_line
			(start 0 -0.5842)
			(end 0 0.5842)
			(stroke
				(width 0.1524)
				(type default)
			)
			(layer "B.SilkS")
		)
		(fp_line
			(start -1.2954 -0.5842)
			(end -1.2954 0.5842)
			(stroke
				(width 0.1524)
				(type default)
			)
			(layer "B.SilkS")
		)
		(fp_line
			(start 1.2954 0.5842)
			(end 1.2954 -0.5842)
			(stroke
				(width 0.1524)
				(type default)
			)
			(layer "B.SilkS")
		)
		(fp_line
			(start -1.2954 0.5842)
			(end 1.2954 0.5842)
			(stroke
				(width 0.1524)
				(type default)
			)
			(layer "B.SilkS")
		)
		(fp_line
			(start 0.8636 -0.4572)
			(end -0.8636 -0.4572)
			(stroke
				(width 0.1)
				(type default)
			)
			(layer "B.Fab")
		)
		(fp_line
			(start -0.8636 -0.4572)
			(end -0.8636 -0.4064)
			(stroke
				(width 0.1)
				(type default)
			)
			(layer "B.Fab")
		)
		(fp_line
			(start 1.1938 -0.4064)
			(end 0.8636 -0.4064)
			(stroke
				(width 0.1)
				(type default)
			)
			(layer "B.Fab")
		)
		(fp_line
			(start 0.8636 -0.4064)
			(end 0.8636 -0.4572)
			(stroke
				(width 0.1)
				(type default)
			)
			(layer "B.Fab")
		)
		(fp_line
			(start -0.8636 -0.4064)
			(end -1.1938 -0.4064)
			(stroke
				(width 0.1)
				(type default)
			)
			(layer "B.Fab")
		)
		(fp_line
			(start -1.1938 -0.4064)
			(end -1.1938 0.4064)
			(stroke
				(width 0.1)
				(type default)
			)
			(layer "B.Fab")
		)
		(fp_line
			(start 1.1938 0.4064)
			(end 1.1938 -0.4064)
			(stroke
				(width 0.1)
				(type default)
			)
			(layer "B.Fab")
		)
		(fp_line
			(start 0.8636 0.4064)
			(end 1.1938 0.4064)
			(stroke
				(width 0.1)
				(type default)
			)
			(layer "B.Fab")
		)
		(fp_line
			(start -0.8636 0.4064)
			(end -0.8636 0.4572)
			(stroke
				(width 0.1)
				(type default)
			)
			(layer "B.Fab")
		)
		(fp_line
			(start -1.1938 0.4064)
			(end -0.8636 0.4064)
			(stroke
				(width 0.1)
				(type default)
			)
			(layer "B.Fab")
		)
		(fp_line
			(start 0.8636 0.4572)
			(end 0.8636 0.4064)
			(stroke
				(width 0.1)
				(type default)
			)
			(layer "B.Fab")
		)
		(fp_line
			(start -0.8636 0.4572)
			(end 0.8636 0.4572)
			(stroke
				(width 0.1)
				(type default)
			)
			(layer "B.Fab")
		)
		(pad "1" smd rect
			(at 0.7366 0)
			(size 0.7112 0.8128)
			(layers "B.Cu" "B.Mask" "B.Paste")
			(net "CRT_VCC5")
		)
		(pad "2" smd rect
			(at -0.7366 0)
			(size 0.7112 0.8128)
			(layers "B.Cu" "B.Mask" "B.Paste")
			(net "GND")
		)
	)
	(footprint ""
		(layer "B.Cu")
		(at 69.166994 -37.05479 90)
		(property "Reference" "L5"
			(at 0 0 90)
			(layer "B.SilkS")
			(hide yes)
			(effects
				(font
					(size 1.27 1.27)
				)
				(justify mirror)
			)
		)
		(property "Value" ""
			(at 0 0 90)
			(layer "B.Fab")
			(effects
				(font
					(size 1.27 1.27)
				)
				(justify mirror)
			)
		)
		(duplicate_pad_numbers_are_jumpers no)
		(fp_line
			(start 1.27 -0.5842)
			(end -1.27 -0.5842)
			(stroke
				(width 0.1524)
				(type default)
			)
			(layer "B.SilkS")
		)
		(fp_line
			(start 1.27 -0.5588)
			(end 1.27 -0.5842)
			(stroke
				(width 0.1524)
				(type default)
			)
			(layer "B.SilkS")
		)
		(fp_line
			(start 1.27 0.5842)
			(end 1.27 -0.5842)
			(stroke
				(width 0.1524)
				(type default)
			)
			(layer "B.SilkS")
		)
		(fp_line
			(start 0.127 0.5842)
			(end 0.127 -0.5842)
			(stroke
				(width 0.1524)
				(type default)
			)
			(layer "B.SilkS")
		)
		(fp_line
			(start -0.127 0.5842)
			(end -0.127 -0.5842)
			(stroke
				(width 0.1524)
				(type default)
			)
			(layer "B.SilkS")
		)
		(fp_line
			(start -1.27 0.5842)
			(end -1.27 -0.5842)
			(stroke
				(width 0.1524)
				(type default)
			)
			(layer "B.SilkS")
		)
		(fp_line
			(start -1.27 0.5842)
			(end 1.27 0.5842)
			(stroke
				(width 0.1524)
				(type default)
			)
			(layer "B.SilkS")
		)
		(fp_line
			(start 0.9144 -0.508)
			(end -0.9144 -0.508)
			(stroke
				(width 0.1)
				(type default)
			)
			(layer "B.Fab")
		)
		(fp_line
			(start -0.9144 -0.508)
			(end -0.9144 -0.406654)
			(stroke
				(width 0.1)
				(type default)
			)
			(layer "B.Fab")
		)
		(fp_line
			(start 1.194308 -0.406654)
			(end 0.9144 -0.406654)
			(stroke
				(width 0.1)
				(type default)
			)
			(layer "B.Fab")
		)
		(fp_line
			(start 0.9144 -0.406654)
			(end 0.9144 -0.508)
			(stroke
				(width 0.1)
				(type default)
			)
			(layer "B.Fab")
		)
		(fp_line
			(start -0.9144 -0.406654)
			(end -1.1938 -0.406654)
			(stroke
				(width 0.1)
				(type default)
			)
			(layer "B.Fab")
		)
		(fp_line
			(start -1.1938 -0.406654)
			(end -1.1938 0.4064)
			(stroke
				(width 0.1)
				(type default)
			)
			(layer "B.Fab")
		)
		(fp_line
			(start -0.9144 0.4064)
			(end -0.9144 0.508)
			(stroke
				(width 0.1)
				(type default)
			)
			(layer "B.Fab")
		)
		(fp_line
			(start -1.1938 0.4064)
			(end -0.9144 0.4064)
			(stroke
				(width 0.1)
				(type default)
			)
			(layer "B.Fab")
		)
		(fp_line
			(start 1.194308 0.406654)
			(end 1.194308 -0.406654)
			(stroke
				(width 0.1)
				(type default)
			)
			(layer "B.Fab")
		)
		(fp_line
			(start 0.9144 0.406654)
			(end 1.194308 0.406654)
			(stroke
				(width 0.1)
				(type default)
			)
			(layer "B.Fab")
		)
		(fp_line
			(start 0.9144 0.508)
			(end 0.9144 0.406654)
			(stroke
				(width 0.1)
				(type default)
			)
			(layer "B.Fab")
		)
		(fp_line
			(start -0.9144 0.508)
			(end 0.9144 0.508)
			(stroke
				(width 0.1)
				(type default)
			)
			(layer "B.Fab")
		)
		(pad "1" smd rect
			(at 0.7366 0)
			(size 0.7112 0.8128)
			(layers "B.Cu" "B.Mask" "B.Paste")
			(net "P1V8_AUX")
		)
		(pad "2" smd rect
			(at -0.7366 0)
			(size 0.7112 0.8128)
			(layers "B.Cu" "B.Mask" "B.Paste")
			(net "P1V8_STBY_AVDDPLL")
		)
	)
	(footprint ""
		(layer "B.Cu")
		(at 51.5366 -34.671 90)
		(property "Reference" "R221"
			(at 0 0 90)
			(layer "B.SilkS")
			(hide yes)
			(effects
				(font
					(size 1.27 1.27)
				)
				(justify mirror)
			)
		)
		(property "Value" ""
			(at 0 0 90)
			(layer "B.Fab")
			(effects
				(font
					(size 1.27 1.27)
				)
				(justify mirror)
			)
		)
		(duplicate_pad_numbers_are_jumpers no)
		(fp_line
			(start 0.7874 -0.4064)
			(end -0.7874 -0.4064)
			(stroke
				(width 0.1524)
				(type default)
			)
			(layer "B.SilkS")
		)
		(fp_line
			(start -0.7874 -0.4064)
			(end -0.7874 0.4064)
			(stroke
				(width 0.1524)
				(type default)
			)
			(layer "B.SilkS")
		)
		(fp_line
			(start 0.7874 0.4064)
			(end 0.7874 -0.4064)
			(stroke
				(width 0.1524)
				(type default)
			)
			(layer "B.SilkS")
		)
		(fp_line
			(start -0.7874 0.4064)
			(end 0.7874 0.4064)
			(stroke
				(width 0.1524)
				(type default)
			)
			(layer "B.SilkS")
		)
		(fp_line
			(start 0.67945 -0.305054)
			(end 0.12065 -0.305054)
			(stroke
				(width 0.1)
				(type default)
			)
			(layer "B.Fab")
		)
		(fp_line
			(start 0.12065 -0.305054)
			(end 0.12065 -0.2794)
			(stroke
				(width 0.1)
				(type default)
			)
			(layer "B.Fab")
		)
		(fp_line
			(start -0.12065 -0.3048)
			(end -0.67945 -0.3048)
			(stroke
				(width 0.1)
				(type default)
			)
			(layer "B.Fab")
		)
		(fp_line
			(start -0.67945 -0.3048)
			(end -0.67945 0.3048)
			(stroke
				(width 0.1)
				(type default)
			)
			(layer "B.Fab")
		)
		(fp_line
			(start 0.12065 -0.2794)
			(end -0.12065 -0.2794)
			(stroke
				(width 0.1)
				(type default)
			)
			(layer "B.Fab")
		)
		(fp_line
			(start -0.12065 -0.2794)
			(end -0.12065 -0.3048)
			(stroke
				(width 0.1)
				(type default)
			)
			(layer "B.Fab")
		)
		(fp_line
			(start 0.12065 0.2794)
			(end 0.12065 0.3048)
			(stroke
				(width 0.1)
				(type default)
			)
			(layer "B.Fab")
		)
		(fp_line
			(start -0.120396 0.2794)
			(end 0.12065 0.2794)
			(stroke
				(width 0.1)
				(type default)
			)
			(layer "B.Fab")
		)
		(fp_line
			(start 0.67945 0.3048)
			(end 0.67945 -0.305054)
			(stroke
				(width 0.1)
				(type default)
			)
			(layer "B.Fab")
		)
		(fp_line
			(start 0.12065 0.3048)
			(end 0.67945 0.3048)
			(stroke
				(width 0.1)
				(type default)
			)
			(layer "B.Fab")
		)
		(fp_line
			(start -0.120396 0.3048)
			(end -0.120396 0.2794)
			(stroke
				(width 0.1)
				(type default)
			)
			(layer "B.Fab")
		)
		(fp_line
			(start -0.67945 0.3048)
			(end -0.120396 0.3048)
			(stroke
				(width 0.1)
				(type default)
			)
			(layer "B.Fab")
		)
		(pad "1" smd circle
			(at 0.40005 0 270)
			(size 0 0)
			(layers "B.Cu" "B.Mask" "B.Paste")
			(net "JTAG_1_BMC_TRST_R")
		)
		(pad "2" smd circle
			(at -0.40005 0 270)
			(size 0 0)
			(layers "B.Cu" "B.Mask" "B.Paste")
			(net "JTAG_MB_TRST_N")
		)
	)
	(footprint ""
		(layer "B.Cu")
		(at 15.113 -20.447 90)
		(property "Reference" "C326"
			(at 0 0 90)
			(layer "B.SilkS")
			(hide yes)
			(effects
				(font
					(size 1.27 1.27)
				)
				(justify mirror)
			)
		)
		(property "Value" ""
			(at 0 0 90)
			(layer "B.Fab")
			(effects
				(font
					(size 1.27 1.27)
				)
				(justify mirror)
			)
		)
		(duplicate_pad_numbers_are_jumpers no)
		(fp_line
			(start 0.7874 -0.4064)
			(end -0.7874 -0.4064)
			(stroke
				(width 0.1524)
				(type default)
			)
			(layer "B.SilkS")
		)
		(fp_line
			(start -0.7874 -0.4064)
			(end -0.7874 0.4064)
			(stroke
				(width 0.1524)
				(type default)
			)
			(layer "B.SilkS")
		)
		(fp_line
			(start 0.7874 0.4064)
			(end 0.7874 -0.4064)
			(stroke
				(width 0.1524)
				(type default)
			)
			(layer "B.SilkS")
		)
		(fp_line
			(start -0.7874 0.4064)
			(end 0.7874 0.4064)
			(stroke
				(width 0.1524)
				(type default)
			)
			(layer "B.SilkS")
		)
		(fp_line
			(start 0.67945 -0.305054)
			(end 0.12065 -0.305054)
			(stroke
				(width 0.1)
				(type default)
			)
			(layer "B.Fab")
		)
		(fp_line
			(start 0.12065 -0.305054)
			(end 0.12065 -0.2794)
			(stroke
				(width 0.1)
				(type default)
			)
			(layer "B.Fab")
		)
		(fp_line
			(start -0.12065 -0.3048)
			(end -0.67945 -0.3048)
			(stroke
				(width 0.1)
				(type default)
			)
			(layer "B.Fab")
		)
		(fp_line
			(start -0.67945 -0.3048)
			(end -0.67945 0.3048)
			(stroke
				(width 0.1)
				(type default)
			)
			(layer "B.Fab")
		)
		(fp_line
			(start 0.12065 -0.2794)
			(end -0.12065 -0.2794)
			(stroke
				(width 0.1)
				(type default)
			)
			(layer "B.Fab")
		)
		(fp_line
			(start -0.12065 -0.2794)
			(end -0.12065 -0.3048)
			(stroke
				(width 0.1)
				(type default)
			)
			(layer "B.Fab")
		)
		(fp_line
			(start 0.12065 0.2794)
			(end 0.12065 0.3048)
			(stroke
				(width 0.1)
				(type default)
			)
			(layer "B.Fab")
		)
		(fp_line
			(start -0.120396 0.2794)
			(end 0.12065 0.2794)
			(stroke
				(width 0.1)
				(type default)
			)
			(layer "B.Fab")
		)
		(fp_line
			(start 0.67945 0.3048)
			(end 0.67945 -0.305054)
			(stroke
				(width 0.1)
				(type default)
			)
			(layer "B.Fab")
		)
		(fp_line
			(start 0.12065 0.3048)
			(end 0.67945 0.3048)
			(stroke
				(width 0.1)
				(type default)
			)
			(layer "B.Fab")
		)
		(fp_line
			(start -0.120396 0.3048)
			(end -0.120396 0.2794)
			(stroke
				(width 0.1)
				(type default)
			)
			(layer "B.Fab")
		)
		(fp_line
			(start -0.67945 0.3048)
			(end -0.120396 0.3048)
			(stroke
				(width 0.1)
				(type default)
			)
			(layer "B.Fab")
		)
		(pad "1" smd circle
			(at 0.40005 0 270)
			(size 0 0)
			(layers "B.Cu" "B.Mask" "B.Paste")
			(net "PWR_LED_BUF_N_R")
		)
		(pad "2" smd circle
			(at -0.40005 0 270)
			(size 0 0)
			(layers "B.Cu" "B.Mask" "B.Paste")
			(net "GND")
		)
	)
	(footprint ""
		(layer "B.Cu")
		(at 84.08924 -53.413152 180)
		(property "Reference" "R325"
			(at 0 0 0)
			(layer "B.SilkS")
			(hide yes)
			(effects
				(font
					(size 1.27 1.27)
				)
				(justify mirror)
			)
		)
		(property "Value" ""
			(at 0 0 0)
			(layer "B.Fab")
			(effects
				(font
					(size 1.27 1.27)
				)
				(justify mirror)
			)
		)
		(duplicate_pad_numbers_are_jumpers no)
		(fp_line
			(start 0.7874 0.4064)
			(end 0.7874 -0.4064)
			(stroke
				(width 0.1524)
				(type default)
			)
			(layer "B.SilkS")
		)
		(fp_line
			(start 0.7874 -0.4064)
			(end -0.7874 -0.4064)
			(stroke
				(width 0.1524)
				(type default)
			)
			(layer "B.SilkS")
		)
		(fp_line
			(start -0.7874 0.4064)
			(end 0.7874 0.4064)
			(stroke
				(width 0.1524)
				(type default)
			)
			(layer "B.SilkS")
		)
		(fp_line
			(start -0.7874 -0.4064)
			(end -0.7874 0.4064)
			(stroke
				(width 0.1524)
				(type default)
			)
			(layer "B.SilkS")
		)
		(fp_line
			(start 0.67945 0.3048)
			(end 0.67945 -0.305054)
			(stroke
				(width 0.1)
				(type default)
			)
			(layer "B.Fab")
		)
		(fp_line
			(start 0.67945 -0.305054)
			(end 0.12065 -0.305054)
			(stroke
				(width 0.1)
				(type default)
			)
			(layer "B.Fab")
		)
		(fp_line
			(start 0.12065 0.3048)
			(end 0.67945 0.3048)
			(stroke
				(width 0.1)
				(type default)
			)
			(layer "B.Fab")
		)
		(fp_line
			(start 0.12065 0.2794)
			(end 0.12065 0.3048)
			(stroke
				(width 0.1)
				(type default)
			)
			(layer "B.Fab")
		)
		(fp_line
			(start 0.12065 -0.2794)
			(end -0.12065 -0.2794)
			(stroke
				(width 0.1)
				(type default)
			)
			(layer "B.Fab")
		)
		(fp_line
			(start 0.12065 -0.305054)
			(end 0.12065 -0.2794)
			(stroke
				(width 0.1)
				(type default)
			)
			(layer "B.Fab")
		)
		(fp_line
			(start -0.120396 0.3048)
			(end -0.120396 0.2794)
			(stroke
				(width 0.1)
				(type default)
			)
			(layer "B.Fab")
		)
		(fp_line
			(start -0.120396 0.2794)
			(end 0.12065 0.2794)
			(stroke
				(width 0.1)
				(type default)
			)
			(layer "B.Fab")
		)
		(fp_line
			(start -0.12065 -0.2794)
			(end -0.12065 -0.3048)
			(stroke
				(width 0.1)
				(type default)
			)
			(layer "B.Fab")
		)
		(fp_line
			(start -0.12065 -0.3048)
			(end -0.67945 -0.3048)
			(stroke
				(width 0.1)
				(type default)
			)
			(layer "B.Fab")
		)
		(fp_line
			(start -0.67945 0.3048)
			(end -0.120396 0.3048)
			(stroke
				(width 0.1)
				(type default)
			)
			(layer "B.Fab")
		)
		(fp_line
			(start -0.67945 -0.3048)
			(end -0.67945 0.3048)
			(stroke
				(width 0.1)
				(type default)
			)
			(layer "B.Fab")
		)
		(pad "1" smd circle
			(at 0.40005 0)
			(size 0 0)
			(layers "B.Cu" "B.Mask" "B.Paste")
			(net "P0V6_DDR_VREF_AUX")
		)
		(pad "2" smd circle
			(at -0.40005 0)
			(size 0 0)
			(layers "B.Cu" "B.Mask" "B.Paste")
			(net "GND")
		)
	)
	(footprint ""
		(layer "B.Cu")
		(at 51.816 -30.861 -90)
		(property "Reference" "R229"
			(at 0 0 90)
			(layer "B.SilkS")
			(hide yes)
			(effects
				(font
					(size 1.27 1.27)
				)
				(justify mirror)
			)
		)
		(property "Value" ""
			(at 0 0 90)
			(layer "B.Fab")
			(effects
				(font
					(size 1.27 1.27)
				)
				(justify mirror)
			)
		)
		(duplicate_pad_numbers_are_jumpers no)
		(fp_line
			(start -0.7874 0.4064)
			(end 0.7874 0.4064)
			(stroke
				(width 0.1524)
				(type default)
			)
			(layer "B.SilkS")
		)
		(fp_line
			(start 0.7874 0.4064)
			(end 0.7874 -0.4064)
			(stroke
				(width 0.1524)
				(type default)
			)
			(layer "B.SilkS")
		)
		(fp_line
			(start -0.7874 -0.4064)
			(end -0.7874 0.4064)
			(stroke
				(width 0.1524)
				(type default)
			)
			(layer "B.SilkS")
		)
		(fp_line
			(start 0.7874 -0.4064)
			(end -0.7874 -0.4064)
			(stroke
				(width 0.1524)
				(type default)
			)
			(layer "B.SilkS")
		)
		(fp_line
			(start -0.67945 0.3048)
			(end -0.120396 0.3048)
			(stroke
				(width 0.1)
				(type default)
			)
			(layer "B.Fab")
		)
		(fp_line
			(start -0.120396 0.3048)
			(end -0.120396 0.2794)
			(stroke
				(width 0.1)
				(type default)
			)
			(layer "B.Fab")
		)
		(fp_line
			(start 0.12065 0.3048)
			(end 0.67945 0.3048)
			(stroke
				(width 0.1)
				(type default)
			)
			(layer "B.Fab")
		)
		(fp_line
			(start 0.67945 0.3048)
			(end 0.67945 -0.305054)
			(stroke
				(width 0.1)
				(type default)
			)
			(layer "B.Fab")
		)
		(fp_line
			(start -0.120396 0.2794)
			(end 0.12065 0.2794)
			(stroke
				(width 0.1)
				(type default)
			)
			(layer "B.Fab")
		)
		(fp_line
			(start 0.12065 0.2794)
			(end 0.12065 0.3048)
			(stroke
				(width 0.1)
				(type default)
			)
			(layer "B.Fab")
		)
		(fp_line
			(start -0.12065 -0.2794)
			(end -0.12065 -0.3048)
			(stroke
				(width 0.1)
				(type default)
			)
			(layer "B.Fab")
		)
		(fp_line
			(start 0.12065 -0.2794)
			(end -0.12065 -0.2794)
			(stroke
				(width 0.1)
				(type default)
			)
			(layer "B.Fab")
		)
		(fp_line
			(start -0.67945 -0.3048)
			(end -0.67945 0.3048)
			(stroke
				(width 0.1)
				(type default)
			)
			(layer "B.Fab")
		)
		(fp_line
			(start -0.12065 -0.3048)
			(end -0.67945 -0.3048)
			(stroke
				(width 0.1)
				(type default)
			)
			(layer "B.Fab")
		)
		(fp_line
			(start 0.12065 -0.305054)
			(end 0.12065 -0.2794)
			(stroke
				(width 0.1)
				(type default)
			)
			(layer "B.Fab")
		)
		(fp_line
			(start 0.67945 -0.305054)
			(end 0.12065 -0.305054)
			(stroke
				(width 0.1)
				(type default)
			)
			(layer "B.Fab")
		)
		(pad "1" smd circle
			(at 0.40005 0 90)
			(size 0 0)
			(layers "B.Cu" "B.Mask" "B.Paste")
			(net "GND")
		)
		(pad "2" smd circle
			(at -0.40005 0 90)
			(size 0 0)
			(layers "B.Cu" "B.Mask" "B.Paste")
			(net "JTAG_MB_TRST_N")
		)
	)
	(footprint ""
		(layer "B.Cu")
		(at 58.890662 -70.063614)
		(property "Reference" "R798"
			(at 0 0 0)
			(layer "B.SilkS")
			(hide yes)
			(effects
				(font
					(size 1.27 1.27)
				)
				(justify mirror)
			)
		)
		(property "Value" ""
			(at 0 0 0)
			(layer "B.Fab")
			(effects
				(font
					(size 1.27 1.27)
				)
				(justify mirror)
			)
		)
		(duplicate_pad_numbers_are_jumpers no)
		(fp_line
			(start -0.7874 -0.4064)
			(end -0.7874 0.4064)
			(stroke
				(width 0.1524)
				(type default)
			)
			(layer "B.SilkS")
		)
		(fp_line
			(start -0.7874 0.4064)
			(end 0.7874 0.4064)
			(stroke
				(width 0.1524)
				(type default)
			)
			(layer "B.SilkS")
		)
		(fp_line
			(start 0.7874 -0.4064)
			(end -0.7874 -0.4064)
			(stroke
				(width 0.1524)
				(type default)
			)
			(layer "B.SilkS")
		)
		(fp_line
			(start 0.7874 0.4064)
			(end 0.7874 -0.4064)
			(stroke
				(width 0.1524)
				(type default)
			)
			(layer "B.SilkS")
		)
		(fp_line
			(start -0.67945 -0.3048)
			(end -0.67945 0.3048)
			(stroke
				(width 0.1)
				(type default)
			)
			(layer "B.Fab")
		)
		(fp_line
			(start -0.67945 0.3048)
			(end -0.120396 0.3048)
			(stroke
				(width 0.1)
				(type default)
			)
			(layer "B.Fab")
		)
		(fp_line
			(start -0.12065 -0.3048)
			(end -0.67945 -0.3048)
			(stroke
				(width 0.1)
				(type default)
			)
			(layer "B.Fab")
		)
		(fp_line
			(start -0.12065 -0.2794)
			(end -0.12065 -0.3048)
			(stroke
				(width 0.1)
				(type default)
			)
			(layer "B.Fab")
		)
		(fp_line
			(start -0.120396 0.2794)
			(end 0.12065 0.2794)
			(stroke
				(width 0.1)
				(type default)
			)
			(layer "B.Fab")
		)
		(fp_line
			(start -0.120396 0.3048)
			(end -0.120396 0.2794)
			(stroke
				(width 0.1)
				(type default)
			)
			(layer "B.Fab")
		)
		(fp_line
			(start 0.12065 -0.305054)
			(end 0.12065 -0.2794)
			(stroke
				(width 0.1)
				(type default)
			)
			(layer "B.Fab")
		)
		(fp_line
			(start 0.12065 -0.2794)
			(end -0.12065 -0.2794)
			(stroke
				(width 0.1)
				(type default)
			)
			(layer "B.Fab")
		)
		(fp_line
			(start 0.12065 0.2794)
			(end 0.12065 0.3048)
			(stroke
				(width 0.1)
				(type default)
			)
			(layer "B.Fab")
		)
		(fp_line
			(start 0.12065 0.3048)
			(end 0.67945 0.3048)
			(stroke
				(width 0.1)
				(type default)
			)
			(layer "B.Fab")
		)
		(fp_line
			(start 0.67945 -0.305054)
			(end 0.12065 -0.305054)
			(stroke
				(width 0.1)
				(type default)
			)
			(layer "B.Fab")
		)
		(fp_line
			(start 0.67945 0.3048)
			(end 0.67945 -0.305054)
			(stroke
				(width 0.1)
				(type default)
			)
			(layer "B.Fab")
		)
		(pad "1" smd circle
			(at 0.40005 0 180)
			(size 0 0)
			(layers "B.Cu" "B.Mask" "B.Paste")
			(net "PGPPA_BMC_AUX_SENSOR")
		)
		(pad "2" smd circle
			(at -0.40005 0 180)
			(size 0 0)
			(layers "B.Cu" "B.Mask" "B.Paste")
			(net "GND")
		)
	)
	(footprint ""
		(layer "B.Cu")
		(at 81.129886 -40.990012)
		(property "Reference" "R344"
			(at 0 0 0)
			(layer "B.SilkS")
			(hide yes)
			(effects
				(font
					(size 1.27 1.27)
				)
				(justify mirror)
			)
		)
		(property "Value" ""
			(at 0 0 0)
			(layer "B.Fab")
			(effects
				(font
					(size 1.27 1.27)
				)
				(justify mirror)
			)
		)
		(duplicate_pad_numbers_are_jumpers no)
		(fp_line
			(start -0.7874 -0.4064)
			(end -0.7874 0.4064)
			(stroke
				(width 0.1524)
				(type default)
			)
			(layer "B.SilkS")
		)
		(fp_line
			(start -0.7874 0.4064)
			(end 0.7874 0.4064)
			(stroke
				(width 0.1524)
				(type default)
			)
			(layer "B.SilkS")
		)
		(fp_line
			(start 0.7874 -0.4064)
			(end -0.7874 -0.4064)
			(stroke
				(width 0.1524)
				(type default)
			)
			(layer "B.SilkS")
		)
		(fp_line
			(start 0.7874 0.4064)
			(end 0.7874 -0.4064)
			(stroke
				(width 0.1524)
				(type default)
			)
			(layer "B.SilkS")
		)
		(fp_line
			(start -0.67945 -0.3048)
			(end -0.67945 0.3048)
			(stroke
				(width 0.1)
				(type default)
			)
			(layer "B.Fab")
		)
		(fp_line
			(start -0.67945 0.3048)
			(end -0.120396 0.3048)
			(stroke
				(width 0.1)
				(type default)
			)
			(layer "B.Fab")
		)
		(fp_line
			(start -0.12065 -0.3048)
			(end -0.67945 -0.3048)
			(stroke
				(width 0.1)
				(type default)
			)
			(layer "B.Fab")
		)
		(fp_line
			(start -0.12065 -0.2794)
			(end -0.12065 -0.3048)
			(stroke
				(width 0.1)
				(type default)
			)
			(layer "B.Fab")
		)
		(fp_line
			(start -0.120396 0.2794)
			(end 0.12065 0.2794)
			(stroke
				(width 0.1)
				(type default)
			)
			(layer "B.Fab")
		)
		(fp_line
			(start -0.120396 0.3048)
			(end -0.120396 0.2794)
			(stroke
				(width 0.1)
				(type default)
			)
			(layer "B.Fab")
		)
		(fp_line
			(start 0.12065 -0.305054)
			(end 0.12065 -0.2794)
			(stroke
				(width 0.1)
				(type default)
			)
			(layer "B.Fab")
		)
		(fp_line
			(start 0.12065 -0.2794)
			(end -0.12065 -0.2794)
			(stroke
				(width 0.1)
				(type default)
			)
			(layer "B.Fab")
		)
		(fp_line
			(start 0.12065 0.2794)
			(end 0.12065 0.3048)
			(stroke
				(width 0.1)
				(type default)
			)
			(layer "B.Fab")
		)
		(fp_line
			(start 0.12065 0.3048)
			(end 0.67945 0.3048)
			(stroke
				(width 0.1)
				(type default)
			)
			(layer "B.Fab")
		)
		(fp_line
			(start 0.67945 -0.305054)
			(end 0.12065 -0.305054)
			(stroke
				(width 0.1)
				(type default)
			)
			(layer "B.Fab")
		)
		(fp_line
			(start 0.67945 0.3048)
			(end 0.67945 -0.305054)
			(stroke
				(width 0.1)
				(type default)
			)
			(layer "B.Fab")
		)
		(pad "1" smd circle
			(at 0.40005 0 180)
			(size 0 0)
			(layers "B.Cu" "B.Mask" "B.Paste")
			(net "GND")
		)
		(pad "2" smd circle
			(at -0.40005 0 180)
			(size 0 0)
			(layers "B.Cu" "B.Mask" "B.Paste")
			(net "M_BMC_DDR4_MACT_N")
		)
	)
	(footprint ""
		(layer "B.Cu")
		(at 60.099702 -43.630342 180)
		(property "Reference" "C59"
			(at 0 0 0)
			(layer "B.SilkS")
			(hide yes)
			(effects
				(font
					(size 1.27 1.27)
				)
				(justify mirror)
			)
		)
		(property "Value" ""
			(at 0 0 0)
			(layer "B.Fab")
			(effects
				(font
					(size 1.27 1.27)
				)
				(justify mirror)
			)
		)
		(duplicate_pad_numbers_are_jumpers no)
		(fp_line
			(start 0.7874 0.4064)
			(end 0.7874 -0.4064)
			(stroke
				(width 0.1524)
				(type default)
			)
			(layer "B.SilkS")
		)
		(fp_line
			(start 0.7874 -0.4064)
			(end -0.7874 -0.4064)
			(stroke
				(width 0.1524)
				(type default)
			)
			(layer "B.SilkS")
		)
		(fp_line
			(start -0.7874 0.4064)
			(end 0.7874 0.4064)
			(stroke
				(width 0.1524)
				(type default)
			)
			(layer "B.SilkS")
		)
		(fp_line
			(start -0.7874 -0.4064)
			(end -0.7874 0.4064)
			(stroke
				(width 0.1524)
				(type default)
			)
			(layer "B.SilkS")
		)
		(fp_line
			(start 0.67945 0.3048)
			(end 0.67945 -0.305054)
			(stroke
				(width 0.1)
				(type default)
			)
			(layer "B.Fab")
		)
		(fp_line
			(start 0.67945 -0.305054)
			(end 0.12065 -0.305054)
			(stroke
				(width 0.1)
				(type default)
			)
			(layer "B.Fab")
		)
		(fp_line
			(start 0.12065 0.3048)
			(end 0.67945 0.3048)
			(stroke
				(width 0.1)
				(type default)
			)
			(layer "B.Fab")
		)
		(fp_line
			(start 0.12065 0.2794)
			(end 0.12065 0.3048)
			(stroke
				(width 0.1)
				(type default)
			)
			(layer "B.Fab")
		)
		(fp_line
			(start 0.12065 -0.2794)
			(end -0.12065 -0.2794)
			(stroke
				(width 0.1)
				(type default)
			)
			(layer "B.Fab")
		)
		(fp_line
			(start 0.12065 -0.305054)
			(end 0.12065 -0.2794)
			(stroke
				(width 0.1)
				(type default)
			)
			(layer "B.Fab")
		)
		(fp_line
			(start -0.120396 0.3048)
			(end -0.120396 0.2794)
			(stroke
				(width 0.1)
				(type default)
			)
			(layer "B.Fab")
		)
		(fp_line
			(start -0.120396 0.2794)
			(end 0.12065 0.2794)
			(stroke
				(width 0.1)
				(type default)
			)
			(layer "B.Fab")
		)
		(fp_line
			(start -0.12065 -0.2794)
			(end -0.12065 -0.3048)
			(stroke
				(width 0.1)
				(type default)
			)
			(layer "B.Fab")
		)
		(fp_line
			(start -0.12065 -0.3048)
			(end -0.67945 -0.3048)
			(stroke
				(width 0.1)
				(type default)
			)
			(layer "B.Fab")
		)
		(fp_line
			(start -0.67945 0.3048)
			(end -0.120396 0.3048)
			(stroke
				(width 0.1)
				(type default)
			)
			(layer "B.Fab")
		)
		(fp_line
			(start -0.67945 -0.3048)
			(end -0.67945 0.3048)
			(stroke
				(width 0.1)
				(type default)
			)
			(layer "B.Fab")
		)
		(pad "1" smd circle
			(at 0.40005 0)
			(size 0 0)
			(layers "B.Cu" "B.Mask" "B.Paste")
			(net "P1V0_STBY_PLAVDD")
		)
		(pad "2" smd circle
			(at -0.40005 0)
			(size 0 0)
			(layers "B.Cu" "B.Mask" "B.Paste")
			(net "GND")
		)
	)
	(footprint ""
		(layer "B.Cu")
		(at 37.4015 -103.632)
		(property "Reference" "C146"
			(at 0 0 0)
			(layer "B.SilkS")
			(hide yes)
			(effects
				(font
					(size 1.27 1.27)
				)
				(justify mirror)
			)
		)
		(property "Value" ""
			(at 0 0 0)
			(layer "B.Fab")
			(effects
				(font
					(size 1.27 1.27)
				)
				(justify mirror)
			)
		)
		(duplicate_pad_numbers_are_jumpers no)
		(fp_line
			(start -0.7874 -0.4064)
			(end -0.7874 0.4064)
			(stroke
				(width 0.1524)
				(type default)
			)
			(layer "B.SilkS")
		)
		(fp_line
			(start -0.7874 0.4064)
			(end 0.7874 0.4064)
			(stroke
				(width 0.1524)
				(type default)
			)
			(layer "B.SilkS")
		)
		(fp_line
			(start 0.7874 -0.4064)
			(end -0.7874 -0.4064)
			(stroke
				(width 0.1524)
				(type default)
			)
			(layer "B.SilkS")
		)
		(fp_line
			(start 0.7874 0.4064)
			(end 0.7874 -0.4064)
			(stroke
				(width 0.1524)
				(type default)
			)
			(layer "B.SilkS")
		)
		(fp_line
			(start -0.67945 -0.3048)
			(end -0.67945 0.3048)
			(stroke
				(width 0.1)
				(type default)
			)
			(layer "B.Fab")
		)
		(fp_line
			(start -0.67945 0.3048)
			(end -0.120396 0.3048)
			(stroke
				(width 0.1)
				(type default)
			)
			(layer "B.Fab")
		)
		(fp_line
			(start -0.12065 -0.3048)
			(end -0.67945 -0.3048)
			(stroke
				(width 0.1)
				(type default)
			)
			(layer "B.Fab")
		)
		(fp_line
			(start -0.12065 -0.2794)
			(end -0.12065 -0.3048)
			(stroke
				(width 0.1)
				(type default)
			)
			(layer "B.Fab")
		)
		(fp_line
			(start -0.120396 0.2794)
			(end 0.12065 0.2794)
			(stroke
				(width 0.1)
				(type default)
			)
			(layer "B.Fab")
		)
		(fp_line
			(start -0.120396 0.3048)
			(end -0.120396 0.2794)
			(stroke
				(width 0.1)
				(type default)
			)
			(layer "B.Fab")
		)
		(fp_line
			(start 0.12065 -0.305054)
			(end 0.12065 -0.2794)
			(stroke
				(width 0.1)
				(type default)
			)
			(layer "B.Fab")
		)
		(fp_line
			(start 0.12065 -0.2794)
			(end -0.12065 -0.2794)
			(stroke
				(width 0.1)
				(type default)
			)
			(layer "B.Fab")
		)
		(fp_line
			(start 0.12065 0.2794)
			(end 0.12065 0.3048)
			(stroke
				(width 0.1)
				(type default)
			)
			(layer "B.Fab")
		)
		(fp_line
			(start 0.12065 0.3048)
			(end 0.67945 0.3048)
			(stroke
				(width 0.1)
				(type default)
			)
			(layer "B.Fab")
		)
		(fp_line
			(start 0.67945 -0.305054)
			(end 0.12065 -0.305054)
			(stroke
				(width 0.1)
				(type default)
			)
			(layer "B.Fab")
		)
		(fp_line
			(start 0.67945 0.3048)
			(end 0.67945 -0.305054)
			(stroke
				(width 0.1)
				(type default)
			)
			(layer "B.Fab")
		)
		(pad "1" smd circle
			(at 0.40005 0 180)
			(size 0 0)
			(layers "B.Cu" "B.Mask" "B.Paste")
			(net "P3V3_AUX")
		)
		(pad "2" smd circle
			(at -0.40005 0 180)
			(size 0 0)
			(layers "B.Cu" "B.Mask" "B.Paste")
			(net "GND")
		)
	)
	(footprint ""
		(layer "B.Cu")
		(at 57.673494 -44.412662 -90)
		(property "Reference" "C64"
			(at 0 0 90)
			(layer "B.SilkS")
			(hide yes)
			(effects
				(font
					(size 1.27 1.27)
				)
				(justify mirror)
			)
		)
		(property "Value" ""
			(at 0 0 90)
			(layer "B.Fab")
			(effects
				(font
					(size 1.27 1.27)
				)
				(justify mirror)
			)
		)
		(duplicate_pad_numbers_are_jumpers no)
		(fp_line
			(start -0.7874 0.4064)
			(end 0.7874 0.4064)
			(stroke
				(width 0.1524)
				(type default)
			)
			(layer "B.SilkS")
		)
		(fp_line
			(start 0.7874 0.4064)
			(end 0.7874 -0.4064)
			(stroke
				(width 0.1524)
				(type default)
			)
			(layer "B.SilkS")
		)
		(fp_line
			(start -0.7874 -0.4064)
			(end -0.7874 0.4064)
			(stroke
				(width 0.1524)
				(type default)
			)
			(layer "B.SilkS")
		)
		(fp_line
			(start 0.7874 -0.4064)
			(end -0.7874 -0.4064)
			(stroke
				(width 0.1524)
				(type default)
			)
			(layer "B.SilkS")
		)
		(fp_line
			(start -0.67945 0.3048)
			(end -0.120396 0.3048)
			(stroke
				(width 0.1)
				(type default)
			)
			(layer "B.Fab")
		)
		(fp_line
			(start -0.120396 0.3048)
			(end -0.120396 0.2794)
			(stroke
				(width 0.1)
				(type default)
			)
			(layer "B.Fab")
		)
		(fp_line
			(start 0.12065 0.3048)
			(end 0.67945 0.3048)
			(stroke
				(width 0.1)
				(type default)
			)
			(layer "B.Fab")
		)
		(fp_line
			(start 0.67945 0.3048)
			(end 0.67945 -0.305054)
			(stroke
				(width 0.1)
				(type default)
			)
			(layer "B.Fab")
		)
		(fp_line
			(start -0.120396 0.2794)
			(end 0.12065 0.2794)
			(stroke
				(width 0.1)
				(type default)
			)
			(layer "B.Fab")
		)
		(fp_line
			(start 0.12065 0.2794)
			(end 0.12065 0.3048)
			(stroke
				(width 0.1)
				(type default)
			)
			(layer "B.Fab")
		)
		(fp_line
			(start -0.12065 -0.2794)
			(end -0.12065 -0.3048)
			(stroke
				(width 0.1)
				(type default)
			)
			(layer "B.Fab")
		)
		(fp_line
			(start 0.12065 -0.2794)
			(end -0.12065 -0.2794)
			(stroke
				(width 0.1)
				(type default)
			)
			(layer "B.Fab")
		)
		(fp_line
			(start -0.67945 -0.3048)
			(end -0.67945 0.3048)
			(stroke
				(width 0.1)
				(type default)
			)
			(layer "B.Fab")
		)
		(fp_line
			(start -0.12065 -0.3048)
			(end -0.67945 -0.3048)
			(stroke
				(width 0.1)
				(type default)
			)
			(layer "B.Fab")
		)
		(fp_line
			(start 0.12065 -0.305054)
			(end 0.12065 -0.2794)
			(stroke
				(width 0.1)
				(type default)
			)
			(layer "B.Fab")
		)
		(fp_line
			(start 0.67945 -0.305054)
			(end 0.12065 -0.305054)
			(stroke
				(width 0.1)
				(type default)
			)
			(layer "B.Fab")
		)
		(pad "1" smd circle
			(at 0.40005 0 90)
			(size 0 0)
			(layers "B.Cu" "B.Mask" "B.Paste")
			(net "P1V0_STBY_PLAVDD")
		)
		(pad "2" smd circle
			(at -0.40005 0 90)
			(size 0 0)
			(layers "B.Cu" "B.Mask" "B.Paste")
			(net "GND")
		)
	)
	(footprint ""
		(layer "B.Cu")
		(at 31.877 -30.353 -90)
		(property "Reference" "C209"
			(at 0 0 90)
			(layer "B.SilkS")
			(hide yes)
			(effects
				(font
					(size 1.27 1.27)
				)
				(justify mirror)
			)
		)
		(property "Value" ""
			(at 0 0 90)
			(layer "B.Fab")
			(effects
				(font
					(size 1.27 1.27)
				)
				(justify mirror)
			)
		)
		(duplicate_pad_numbers_are_jumpers no)
		(fp_line
			(start -0.7874 0.4064)
			(end 0.7874 0.4064)
			(stroke
				(width 0.1524)
				(type default)
			)
			(layer "B.SilkS")
		)
		(fp_line
			(start 0.7874 0.4064)
			(end 0.7874 -0.4064)
			(stroke
				(width 0.1524)
				(type default)
			)
			(layer "B.SilkS")
		)
		(fp_line
			(start -0.7874 -0.4064)
			(end -0.7874 0.4064)
			(stroke
				(width 0.1524)
				(type default)
			)
			(layer "B.SilkS")
		)
		(fp_line
			(start 0.7874 -0.4064)
			(end -0.7874 -0.4064)
			(stroke
				(width 0.1524)
				(type default)
			)
			(layer "B.SilkS")
		)
		(fp_line
			(start -0.67945 0.3048)
			(end -0.120396 0.3048)
			(stroke
				(width 0.1)
				(type default)
			)
			(layer "B.Fab")
		)
		(fp_line
			(start -0.120396 0.3048)
			(end -0.120396 0.2794)
			(stroke
				(width 0.1)
				(type default)
			)
			(layer "B.Fab")
		)
		(fp_line
			(start 0.12065 0.3048)
			(end 0.67945 0.3048)
			(stroke
				(width 0.1)
				(type default)
			)
			(layer "B.Fab")
		)
		(fp_line
			(start 0.67945 0.3048)
			(end 0.67945 -0.305054)
			(stroke
				(width 0.1)
				(type default)
			)
			(layer "B.Fab")
		)
		(fp_line
			(start -0.120396 0.2794)
			(end 0.12065 0.2794)
			(stroke
				(width 0.1)
				(type default)
			)
			(layer "B.Fab")
		)
		(fp_line
			(start 0.12065 0.2794)
			(end 0.12065 0.3048)
			(stroke
				(width 0.1)
				(type default)
			)
			(layer "B.Fab")
		)
		(fp_line
			(start -0.12065 -0.2794)
			(end -0.12065 -0.3048)
			(stroke
				(width 0.1)
				(type default)
			)
			(layer "B.Fab")
		)
		(fp_line
			(start 0.12065 -0.2794)
			(end -0.12065 -0.2794)
			(stroke
				(width 0.1)
				(type default)
			)
			(layer "B.Fab")
		)
		(fp_line
			(start -0.67945 -0.3048)
			(end -0.67945 0.3048)
			(stroke
				(width 0.1)
				(type default)
			)
			(layer "B.Fab")
		)
		(fp_line
			(start -0.12065 -0.3048)
			(end -0.67945 -0.3048)
			(stroke
				(width 0.1)
				(type default)
			)
			(layer "B.Fab")
		)
		(fp_line
			(start 0.12065 -0.305054)
			(end 0.12065 -0.2794)
			(stroke
				(width 0.1)
				(type default)
			)
			(layer "B.Fab")
		)
		(fp_line
			(start 0.67945 -0.305054)
			(end 0.12065 -0.305054)
			(stroke
				(width 0.1)
				(type default)
			)
			(layer "B.Fab")
		)
		(pad "1" smd circle
			(at 0.40005 0 90)
			(size 0 0)
			(layers "B.Cu" "B.Mask" "B.Paste")
			(net "V_DACG_IO")
		)
		(pad "2" smd circle
			(at -0.40005 0 90)
			(size 0 0)
			(layers "B.Cu" "B.Mask" "B.Paste")
			(net "GND")
		)
	)
	(footprint ""
		(layer "B.Cu")
		(at 83.16722 -39.474394 180)
		(property "Reference" "R365"
			(at 0 0 0)
			(layer "B.SilkS")
			(hide yes)
			(effects
				(font
					(size 1.27 1.27)
				)
				(justify mirror)
			)
		)
		(property "Value" ""
			(at 0 0 0)
			(layer "B.Fab")
			(effects
				(font
					(size 1.27 1.27)
				)
				(justify mirror)
			)
		)
		(duplicate_pad_numbers_are_jumpers no)
		(fp_line
			(start 0.7874 0.4064)
			(end 0.7874 -0.4064)
			(stroke
				(width 0.1524)
				(type default)
			)
			(layer "B.SilkS")
		)
		(fp_line
			(start 0.7874 -0.4064)
			(end -0.7874 -0.4064)
			(stroke
				(width 0.1524)
				(type default)
			)
			(layer "B.SilkS")
		)
		(fp_line
			(start -0.7874 0.4064)
			(end 0.7874 0.4064)
			(stroke
				(width 0.1524)
				(type default)
			)
			(layer "B.SilkS")
		)
		(fp_line
			(start -0.7874 -0.4064)
			(end -0.7874 0.4064)
			(stroke
				(width 0.1524)
				(type default)
			)
			(layer "B.SilkS")
		)
		(fp_line
			(start 0.67945 0.3048)
			(end 0.67945 -0.305054)
			(stroke
				(width 0.1)
				(type default)
			)
			(layer "B.Fab")
		)
		(fp_line
			(start 0.67945 -0.305054)
			(end 0.12065 -0.305054)
			(stroke
				(width 0.1)
				(type default)
			)
			(layer "B.Fab")
		)
		(fp_line
			(start 0.12065 0.3048)
			(end 0.67945 0.3048)
			(stroke
				(width 0.1)
				(type default)
			)
			(layer "B.Fab")
		)
		(fp_line
			(start 0.12065 0.2794)
			(end 0.12065 0.3048)
			(stroke
				(width 0.1)
				(type default)
			)
			(layer "B.Fab")
		)
		(fp_line
			(start 0.12065 -0.2794)
			(end -0.12065 -0.2794)
			(stroke
				(width 0.1)
				(type default)
			)
			(layer "B.Fab")
		)
		(fp_line
			(start 0.12065 -0.305054)
			(end 0.12065 -0.2794)
			(stroke
				(width 0.1)
				(type default)
			)
			(layer "B.Fab")
		)
		(fp_line
			(start -0.120396 0.3048)
			(end -0.120396 0.2794)
			(stroke
				(width 0.1)
				(type default)
			)
			(layer "B.Fab")
		)
		(fp_line
			(start -0.120396 0.2794)
			(end 0.12065 0.2794)
			(stroke
				(width 0.1)
				(type default)
			)
			(layer "B.Fab")
		)
		(fp_line
			(start -0.12065 -0.2794)
			(end -0.12065 -0.3048)
			(stroke
				(width 0.1)
				(type default)
			)
			(layer "B.Fab")
		)
		(fp_line
			(start -0.12065 -0.3048)
			(end -0.67945 -0.3048)
			(stroke
				(width 0.1)
				(type default)
			)
			(layer "B.Fab")
		)
		(fp_line
			(start -0.67945 0.3048)
			(end -0.120396 0.3048)
			(stroke
				(width 0.1)
				(type default)
			)
			(layer "B.Fab")
		)
		(fp_line
			(start -0.67945 -0.3048)
			(end -0.67945 0.3048)
			(stroke
				(width 0.1)
				(type default)
			)
			(layer "B.Fab")
		)
		(pad "1" smd circle
			(at 0.40005 0)
			(size 0 0)
			(layers "B.Cu" "B.Mask" "B.Paste")
			(net "M_BMC_DDR4_MWE_N")
		)
		(pad "2" smd circle
			(at -0.40005 0)
			(size 0 0)
			(layers "B.Cu" "B.Mask" "B.Paste")
			(net "P1V2_AUX")
		)
	)
	(footprint ""
		(layer "B.Cu")
		(at 83.16722 -42.522394 180)
		(property "Reference" "R354"
			(at 0 0 0)
			(layer "B.SilkS")
			(hide yes)
			(effects
				(font
					(size 1.27 1.27)
				)
				(justify mirror)
			)
		)
		(property "Value" ""
			(at 0 0 0)
			(layer "B.Fab")
			(effects
				(font
					(size 1.27 1.27)
				)
				(justify mirror)
			)
		)
		(duplicate_pad_numbers_are_jumpers no)
		(fp_line
			(start 0.7874 0.4064)
			(end 0.7874 -0.4064)
			(stroke
				(width 0.1524)
				(type default)
			)
			(layer "B.SilkS")
		)
		(fp_line
			(start 0.7874 -0.4064)
			(end -0.7874 -0.4064)
			(stroke
				(width 0.1524)
				(type default)
			)
			(layer "B.SilkS")
		)
		(fp_line
			(start -0.7874 0.4064)
			(end 0.7874 0.4064)
			(stroke
				(width 0.1524)
				(type default)
			)
			(layer "B.SilkS")
		)
		(fp_line
			(start -0.7874 -0.4064)
			(end -0.7874 0.4064)
			(stroke
				(width 0.1524)
				(type default)
			)
			(layer "B.SilkS")
		)
		(fp_line
			(start 0.67945 0.3048)
			(end 0.67945 -0.305054)
			(stroke
				(width 0.1)
				(type default)
			)
			(layer "B.Fab")
		)
		(fp_line
			(start 0.67945 -0.305054)
			(end 0.12065 -0.305054)
			(stroke
				(width 0.1)
				(type default)
			)
			(layer "B.Fab")
		)
		(fp_line
			(start 0.12065 0.3048)
			(end 0.67945 0.3048)
			(stroke
				(width 0.1)
				(type default)
			)
			(layer "B.Fab")
		)
		(fp_line
			(start 0.12065 0.2794)
			(end 0.12065 0.3048)
			(stroke
				(width 0.1)
				(type default)
			)
			(layer "B.Fab")
		)
		(fp_line
			(start 0.12065 -0.2794)
			(end -0.12065 -0.2794)
			(stroke
				(width 0.1)
				(type default)
			)
			(layer "B.Fab")
		)
		(fp_line
			(start 0.12065 -0.305054)
			(end 0.12065 -0.2794)
			(stroke
				(width 0.1)
				(type default)
			)
			(layer "B.Fab")
		)
		(fp_line
			(start -0.120396 0.3048)
			(end -0.120396 0.2794)
			(stroke
				(width 0.1)
				(type default)
			)
			(layer "B.Fab")
		)
		(fp_line
			(start -0.120396 0.2794)
			(end 0.12065 0.2794)
			(stroke
				(width 0.1)
				(type default)
			)
			(layer "B.Fab")
		)
		(fp_line
			(start -0.12065 -0.2794)
			(end -0.12065 -0.3048)
			(stroke
				(width 0.1)
				(type default)
			)
			(layer "B.Fab")
		)
		(fp_line
			(start -0.12065 -0.3048)
			(end -0.67945 -0.3048)
			(stroke
				(width 0.1)
				(type default)
			)
			(layer "B.Fab")
		)
		(fp_line
			(start -0.67945 0.3048)
			(end -0.120396 0.3048)
			(stroke
				(width 0.1)
				(type default)
			)
			(layer "B.Fab")
		)
		(fp_line
			(start -0.67945 -0.3048)
			(end -0.67945 0.3048)
			(stroke
				(width 0.1)
				(type default)
			)
			(layer "B.Fab")
		)
		(pad "1" smd circle
			(at 0.40005 0)
			(size 0 0)
			(layers "B.Cu" "B.Mask" "B.Paste")
			(net "M_BMC_DDR4_MA<3>")
		)
		(pad "2" smd circle
			(at -0.40005 0)
			(size 0 0)
			(layers "B.Cu" "B.Mask" "B.Paste")
			(net "P1V2_AUX")
		)
	)
	(footprint ""
		(layer "B.Cu")
		(at 43.28922 -53.856382)
		(property "Reference" "C48"
			(at 0 0 0)
			(layer "B.SilkS")
			(hide yes)
			(effects
				(font
					(size 1.27 1.27)
				)
				(justify mirror)
			)
		)
		(property "Value" ""
			(at 0 0 0)
			(layer "B.Fab")
			(effects
				(font
					(size 1.27 1.27)
				)
				(justify mirror)
			)
		)
		(duplicate_pad_numbers_are_jumpers no)
		(fp_line
			(start -0.7874 -0.4064)
			(end -0.7874 0.4064)
			(stroke
				(width 0.1524)
				(type default)
			)
			(layer "B.SilkS")
		)
		(fp_line
			(start -0.7874 0.4064)
			(end 0.7874 0.4064)
			(stroke
				(width 0.1524)
				(type default)
			)
			(layer "B.SilkS")
		)
		(fp_line
			(start 0.7874 -0.4064)
			(end -0.7874 -0.4064)
			(stroke
				(width 0.1524)
				(type default)
			)
			(layer "B.SilkS")
		)
		(fp_line
			(start 0.7874 0.4064)
			(end 0.7874 -0.4064)
			(stroke
				(width 0.1524)
				(type default)
			)
			(layer "B.SilkS")
		)
		(fp_line
			(start -0.67945 -0.3048)
			(end -0.67945 0.3048)
			(stroke
				(width 0.1)
				(type default)
			)
			(layer "B.Fab")
		)
		(fp_line
			(start -0.67945 0.3048)
			(end -0.120396 0.3048)
			(stroke
				(width 0.1)
				(type default)
			)
			(layer "B.Fab")
		)
		(fp_line
			(start -0.12065 -0.3048)
			(end -0.67945 -0.3048)
			(stroke
				(width 0.1)
				(type default)
			)
			(layer "B.Fab")
		)
		(fp_line
			(start -0.12065 -0.2794)
			(end -0.12065 -0.3048)
			(stroke
				(width 0.1)
				(type default)
			)
			(layer "B.Fab")
		)
		(fp_line
			(start -0.120396 0.2794)
			(end 0.12065 0.2794)
			(stroke
				(width 0.1)
				(type default)
			)
			(layer "B.Fab")
		)
		(fp_line
			(start -0.120396 0.3048)
			(end -0.120396 0.2794)
			(stroke
				(width 0.1)
				(type default)
			)
			(layer "B.Fab")
		)
		(fp_line
			(start 0.12065 -0.305054)
			(end 0.12065 -0.2794)
			(stroke
				(width 0.1)
				(type default)
			)
			(layer "B.Fab")
		)
		(fp_line
			(start 0.12065 -0.2794)
			(end -0.12065 -0.2794)
			(stroke
				(width 0.1)
				(type default)
			)
			(layer "B.Fab")
		)
		(fp_line
			(start 0.12065 0.2794)
			(end 0.12065 0.3048)
			(stroke
				(width 0.1)
				(type default)
			)
			(layer "B.Fab")
		)
		(fp_line
			(start 0.12065 0.3048)
			(end 0.67945 0.3048)
			(stroke
				(width 0.1)
				(type default)
			)
			(layer "B.Fab")
		)
		(fp_line
			(start 0.67945 -0.305054)
			(end 0.12065 -0.305054)
			(stroke
				(width 0.1)
				(type default)
			)
			(layer "B.Fab")
		)
		(fp_line
			(start 0.67945 0.3048)
			(end 0.67945 -0.305054)
			(stroke
				(width 0.1)
				(type default)
			)
			(layer "B.Fab")
		)
		(pad "1" smd circle
			(at 0.40005 0 180)
			(size 0 0)
			(layers "B.Cu" "B.Mask" "B.Paste")
			(net "P3V3_STBY_DACAV33")
		)
		(pad "2" smd circle
			(at -0.40005 0 180)
			(size 0 0)
			(layers "B.Cu" "B.Mask" "B.Paste")
			(net "GND")
		)
	)
	(footprint ""
		(layer "B.Cu")
		(at 16.764 -72.771 -90)
		(property "Reference" "R302"
			(at 0 0 90)
			(layer "B.SilkS")
			(hide yes)
			(effects
				(font
					(size 1.27 1.27)
				)
				(justify mirror)
			)
		)
		(property "Value" ""
			(at 0 0 90)
			(layer "B.Fab")
			(effects
				(font
					(size 1.27 1.27)
				)
				(justify mirror)
			)
		)
		(duplicate_pad_numbers_are_jumpers no)
		(fp_line
			(start -0.7874 0.4064)
			(end 0.7874 0.4064)
			(stroke
				(width 0.1524)
				(type default)
			)
			(layer "B.SilkS")
		)
		(fp_line
			(start 0.7874 0.4064)
			(end 0.7874 -0.4064)
			(stroke
				(width 0.1524)
				(type default)
			)
			(layer "B.SilkS")
		)
		(fp_line
			(start -0.7874 -0.4064)
			(end -0.7874 0.4064)
			(stroke
				(width 0.1524)
				(type default)
			)
			(layer "B.SilkS")
		)
		(fp_line
			(start 0.7874 -0.4064)
			(end -0.7874 -0.4064)
			(stroke
				(width 0.1524)
				(type default)
			)
			(layer "B.SilkS")
		)
		(fp_line
			(start -0.67945 0.3048)
			(end -0.120396 0.3048)
			(stroke
				(width 0.1)
				(type default)
			)
			(layer "B.Fab")
		)
		(fp_line
			(start -0.120396 0.3048)
			(end -0.120396 0.2794)
			(stroke
				(width 0.1)
				(type default)
			)
			(layer "B.Fab")
		)
		(fp_line
			(start 0.12065 0.3048)
			(end 0.67945 0.3048)
			(stroke
				(width 0.1)
				(type default)
			)
			(layer "B.Fab")
		)
		(fp_line
			(start 0.67945 0.3048)
			(end 0.67945 -0.305054)
			(stroke
				(width 0.1)
				(type default)
			)
			(layer "B.Fab")
		)
		(fp_line
			(start -0.120396 0.2794)
			(end 0.12065 0.2794)
			(stroke
				(width 0.1)
				(type default)
			)
			(layer "B.Fab")
		)
		(fp_line
			(start 0.12065 0.2794)
			(end 0.12065 0.3048)
			(stroke
				(width 0.1)
				(type default)
			)
			(layer "B.Fab")
		)
		(fp_line
			(start -0.12065 -0.2794)
			(end -0.12065 -0.3048)
			(stroke
				(width 0.1)
				(type default)
			)
			(layer "B.Fab")
		)
		(fp_line
			(start 0.12065 -0.2794)
			(end -0.12065 -0.2794)
			(stroke
				(width 0.1)
				(type default)
			)
			(layer "B.Fab")
		)
		(fp_line
			(start -0.67945 -0.3048)
			(end -0.67945 0.3048)
			(stroke
				(width 0.1)
				(type default)
			)
			(layer "B.Fab")
		)
		(fp_line
			(start -0.12065 -0.3048)
			(end -0.67945 -0.3048)
			(stroke
				(width 0.1)
				(type default)
			)
			(layer "B.Fab")
		)
		(fp_line
			(start 0.12065 -0.305054)
			(end 0.12065 -0.2794)
			(stroke
				(width 0.1)
				(type default)
			)
			(layer "B.Fab")
		)
		(fp_line
			(start 0.67945 -0.305054)
			(end 0.12065 -0.305054)
			(stroke
				(width 0.1)
				(type default)
			)
			(layer "B.Fab")
		)
		(pad "1" smd circle
			(at 0.40005 0 90)
			(size 0 0)
			(layers "B.Cu" "B.Mask" "B.Paste")
			(net "SMB_DEBUG_AUX_LVC3_USB_R1_SDA")
		)
		(pad "2" smd circle
			(at -0.40005 0 90)
			(size 0 0)
			(layers "B.Cu" "B.Mask" "B.Paste")
			(net "SMB_DEBUG_AUX_LVC3_USB_SDA")
		)
	)
	(footprint ""
		(layer "B.Cu")
		(at 72.758808 -37.271706 -90)
		(property "Reference" "C62"
			(at 0 0 90)
			(layer "B.SilkS")
			(hide yes)
			(effects
				(font
					(size 1.27 1.27)
				)
				(justify mirror)
			)
		)
		(property "Value" ""
			(at 0 0 90)
			(layer "B.Fab")
			(effects
				(font
					(size 1.27 1.27)
				)
				(justify mirror)
			)
		)
		(duplicate_pad_numbers_are_jumpers no)
		(fp_line
			(start -0.7874 0.4064)
			(end 0.7874 0.4064)
			(stroke
				(width 0.1524)
				(type default)
			)
			(layer "B.SilkS")
		)
		(fp_line
			(start 0.7874 0.4064)
			(end 0.7874 -0.4064)
			(stroke
				(width 0.1524)
				(type default)
			)
			(layer "B.SilkS")
		)
		(fp_line
			(start -0.7874 -0.4064)
			(end -0.7874 0.4064)
			(stroke
				(width 0.1524)
				(type default)
			)
			(layer "B.SilkS")
		)
		(fp_line
			(start 0.7874 -0.4064)
			(end -0.7874 -0.4064)
			(stroke
				(width 0.1524)
				(type default)
			)
			(layer "B.SilkS")
		)
		(fp_line
			(start -0.67945 0.3048)
			(end -0.120396 0.3048)
			(stroke
				(width 0.1)
				(type default)
			)
			(layer "B.Fab")
		)
		(fp_line
			(start -0.120396 0.3048)
			(end -0.120396 0.2794)
			(stroke
				(width 0.1)
				(type default)
			)
			(layer "B.Fab")
		)
		(fp_line
			(start 0.12065 0.3048)
			(end 0.67945 0.3048)
			(stroke
				(width 0.1)
				(type default)
			)
			(layer "B.Fab")
		)
		(fp_line
			(start 0.67945 0.3048)
			(end 0.67945 -0.305054)
			(stroke
				(width 0.1)
				(type default)
			)
			(layer "B.Fab")
		)
		(fp_line
			(start -0.120396 0.2794)
			(end 0.12065 0.2794)
			(stroke
				(width 0.1)
				(type default)
			)
			(layer "B.Fab")
		)
		(fp_line
			(start 0.12065 0.2794)
			(end 0.12065 0.3048)
			(stroke
				(width 0.1)
				(type default)
			)
			(layer "B.Fab")
		)
		(fp_line
			(start -0.12065 -0.2794)
			(end -0.12065 -0.3048)
			(stroke
				(width 0.1)
				(type default)
			)
			(layer "B.Fab")
		)
		(fp_line
			(start 0.12065 -0.2794)
			(end -0.12065 -0.2794)
			(stroke
				(width 0.1)
				(type default)
			)
			(layer "B.Fab")
		)
		(fp_line
			(start -0.67945 -0.3048)
			(end -0.67945 0.3048)
			(stroke
				(width 0.1)
				(type default)
			)
			(layer "B.Fab")
		)
		(fp_line
			(start -0.12065 -0.3048)
			(end -0.67945 -0.3048)
			(stroke
				(width 0.1)
				(type default)
			)
			(layer "B.Fab")
		)
		(fp_line
			(start 0.12065 -0.305054)
			(end 0.12065 -0.2794)
			(stroke
				(width 0.1)
				(type default)
			)
			(layer "B.Fab")
		)
		(fp_line
			(start 0.67945 -0.305054)
			(end 0.12065 -0.305054)
			(stroke
				(width 0.1)
				(type default)
			)
			(layer "B.Fab")
		)
		(pad "1" smd circle
			(at 0.40005 0 90)
			(size 0 0)
			(layers "B.Cu" "B.Mask" "B.Paste")
			(net "P1V2_AUX")
		)
		(pad "2" smd circle
			(at -0.40005 0 90)
			(size 0 0)
			(layers "B.Cu" "B.Mask" "B.Paste")
			(net "GND")
		)
	)
	(footprint ""
		(layer "B.Cu")
		(at 32.396684 -58.349388 -90)
		(property "Reference" "R785"
			(at 0 0 90)
			(layer "B.SilkS")
			(hide yes)
			(effects
				(font
					(size 1.27 1.27)
				)
				(justify mirror)
			)
		)
		(property "Value" ""
			(at 0 0 90)
			(layer "B.Fab")
			(effects
				(font
					(size 1.27 1.27)
				)
				(justify mirror)
			)
		)
		(duplicate_pad_numbers_are_jumpers no)
		(fp_line
			(start -0.7874 0.4064)
			(end 0.7874 0.4064)
			(stroke
				(width 0.1524)
				(type default)
			)
			(layer "B.SilkS")
		)
		(fp_line
			(start 0.7874 0.4064)
			(end 0.7874 -0.4064)
			(stroke
				(width 0.1524)
				(type default)
			)
			(layer "B.SilkS")
		)
		(fp_line
			(start -0.7874 -0.4064)
			(end -0.7874 0.4064)
			(stroke
				(width 0.1524)
				(type default)
			)
			(layer "B.SilkS")
		)
		(fp_line
			(start 0.7874 -0.4064)
			(end -0.7874 -0.4064)
			(stroke
				(width 0.1524)
				(type default)
			)
			(layer "B.SilkS")
		)
		(fp_line
			(start -0.67945 0.3048)
			(end -0.120396 0.3048)
			(stroke
				(width 0.1)
				(type default)
			)
			(layer "B.Fab")
		)
		(fp_line
			(start -0.120396 0.3048)
			(end -0.120396 0.2794)
			(stroke
				(width 0.1)
				(type default)
			)
			(layer "B.Fab")
		)
		(fp_line
			(start 0.12065 0.3048)
			(end 0.67945 0.3048)
			(stroke
				(width 0.1)
				(type default)
			)
			(layer "B.Fab")
		)
		(fp_line
			(start 0.67945 0.3048)
			(end 0.67945 -0.305054)
			(stroke
				(width 0.1)
				(type default)
			)
			(layer "B.Fab")
		)
		(fp_line
			(start -0.120396 0.2794)
			(end 0.12065 0.2794)
			(stroke
				(width 0.1)
				(type default)
			)
			(layer "B.Fab")
		)
		(fp_line
			(start 0.12065 0.2794)
			(end 0.12065 0.3048)
			(stroke
				(width 0.1)
				(type default)
			)
			(layer "B.Fab")
		)
		(fp_line
			(start -0.12065 -0.2794)
			(end -0.12065 -0.3048)
			(stroke
				(width 0.1)
				(type default)
			)
			(layer "B.Fab")
		)
		(fp_line
			(start 0.12065 -0.2794)
			(end -0.12065 -0.2794)
			(stroke
				(width 0.1)
				(type default)
			)
			(layer "B.Fab")
		)
		(fp_line
			(start -0.67945 -0.3048)
			(end -0.67945 0.3048)
			(stroke
				(width 0.1)
				(type default)
			)
			(layer "B.Fab")
		)
		(fp_line
			(start -0.12065 -0.3048)
			(end -0.67945 -0.3048)
			(stroke
				(width 0.1)
				(type default)
			)
			(layer "B.Fab")
		)
		(fp_line
			(start 0.12065 -0.305054)
			(end 0.12065 -0.2794)
			(stroke
				(width 0.1)
				(type default)
			)
			(layer "B.Fab")
		)
		(fp_line
			(start 0.67945 -0.305054)
			(end 0.12065 -0.305054)
			(stroke
				(width 0.1)
				(type default)
			)
			(layer "B.Fab")
		)
		(pad "1" smd circle
			(at 0.40005 0 90)
			(size 0 0)
			(layers "B.Cu" "B.Mask" "B.Paste")
			(net "P12V_AUX")
		)
		(pad "2" smd circle
			(at -0.40005 0 90)
			(size 0 0)
			(layers "B.Cu" "B.Mask" "B.Paste")
			(net "P12V_SENSOR")
		)
	)
	(footprint ""
		(layer "B.Cu")
		(at 48.436022 -62.116462 90)
		(property "Reference" "R848"
			(at 0 0 90)
			(layer "B.SilkS")
			(hide yes)
			(effects
				(font
					(size 1.27 1.27)
				)
				(justify mirror)
			)
		)
		(property "Value" ""
			(at 0 0 90)
			(layer "B.Fab")
			(effects
				(font
					(size 1.27 1.27)
				)
				(justify mirror)
			)
		)
		(duplicate_pad_numbers_are_jumpers no)
		(fp_line
			(start 0.7874 -0.4064)
			(end -0.7874 -0.4064)
			(stroke
				(width 0.1524)
				(type default)
			)
			(layer "B.SilkS")
		)
		(fp_line
			(start -0.7874 -0.4064)
			(end -0.7874 0.4064)
			(stroke
				(width 0.1524)
				(type default)
			)
			(layer "B.SilkS")
		)
		(fp_line
			(start 0.7874 0.4064)
			(end 0.7874 -0.4064)
			(stroke
				(width 0.1524)
				(type default)
			)
			(layer "B.SilkS")
		)
		(fp_line
			(start -0.7874 0.4064)
			(end 0.7874 0.4064)
			(stroke
				(width 0.1524)
				(type default)
			)
			(layer "B.SilkS")
		)
		(fp_line
			(start 0.67945 -0.305054)
			(end 0.12065 -0.305054)
			(stroke
				(width 0.1)
				(type default)
			)
			(layer "B.Fab")
		)
		(fp_line
			(start 0.12065 -0.305054)
			(end 0.12065 -0.2794)
			(stroke
				(width 0.1)
				(type default)
			)
			(layer "B.Fab")
		)
		(fp_line
			(start -0.12065 -0.3048)
			(end -0.67945 -0.3048)
			(stroke
				(width 0.1)
				(type default)
			)
			(layer "B.Fab")
		)
		(fp_line
			(start -0.67945 -0.3048)
			(end -0.67945 0.3048)
			(stroke
				(width 0.1)
				(type default)
			)
			(layer "B.Fab")
		)
		(fp_line
			(start 0.12065 -0.2794)
			(end -0.12065 -0.2794)
			(stroke
				(width 0.1)
				(type default)
			)
			(layer "B.Fab")
		)
		(fp_line
			(start -0.12065 -0.2794)
			(end -0.12065 -0.3048)
			(stroke
				(width 0.1)
				(type default)
			)
			(layer "B.Fab")
		)
		(fp_line
			(start 0.12065 0.2794)
			(end 0.12065 0.3048)
			(stroke
				(width 0.1)
				(type default)
			)
			(layer "B.Fab")
		)
		(fp_line
			(start -0.120396 0.2794)
			(end 0.12065 0.2794)
			(stroke
				(width 0.1)
				(type default)
			)
			(layer "B.Fab")
		)
		(fp_line
			(start 0.67945 0.3048)
			(end 0.67945 -0.305054)
			(stroke
				(width 0.1)
				(type default)
			)
			(layer "B.Fab")
		)
		(fp_line
			(start 0.12065 0.3048)
			(end 0.67945 0.3048)
			(stroke
				(width 0.1)
				(type default)
			)
			(layer "B.Fab")
		)
		(fp_line
			(start -0.120396 0.3048)
			(end -0.120396 0.2794)
			(stroke
				(width 0.1)
				(type default)
			)
			(layer "B.Fab")
		)
		(fp_line
			(start -0.67945 0.3048)
			(end -0.120396 0.3048)
			(stroke
				(width 0.1)
				(type default)
			)
			(layer "B.Fab")
		)
		(pad "1" smd circle
			(at 0.40005 0 270)
			(size 0 0)
			(layers "B.Cu" "B.Mask" "B.Paste")
			(net "P3V3_AUX")
		)
		(pad "2" smd circle
			(at -0.40005 0 270)
			(size 0 0)
			(layers "B.Cu" "B.Mask" "B.Paste")
			(net "SMB_BMC_ALERT16_N")
		)
	)
	(footprint ""
		(layer "B.Cu")
		(at 85.29955 -42.395394 180)
		(property "Reference" "C14"
			(at 0 0 0)
			(layer "B.SilkS")
			(hide yes)
			(effects
				(font
					(size 1.27 1.27)
				)
				(justify mirror)
			)
		)
		(property "Value" ""
			(at 0 0 0)
			(layer "B.Fab")
			(effects
				(font
					(size 1.27 1.27)
				)
				(justify mirror)
			)
		)
		(duplicate_pad_numbers_are_jumpers no)
		(fp_line
			(start 0.7874 0.4064)
			(end 0.7874 -0.4064)
			(stroke
				(width 0.1524)
				(type default)
			)
			(layer "B.SilkS")
		)
		(fp_line
			(start 0.7874 -0.4064)
			(end -0.7874 -0.4064)
			(stroke
				(width 0.1524)
				(type default)
			)
			(layer "B.SilkS")
		)
		(fp_line
			(start -0.7874 0.4064)
			(end 0.7874 0.4064)
			(stroke
				(width 0.1524)
				(type default)
			)
			(layer "B.SilkS")
		)
		(fp_line
			(start -0.7874 -0.4064)
			(end -0.7874 0.4064)
			(stroke
				(width 0.1524)
				(type default)
			)
			(layer "B.SilkS")
		)
		(fp_line
			(start 0.67945 0.3048)
			(end 0.67945 -0.305054)
			(stroke
				(width 0.1)
				(type default)
			)
			(layer "B.Fab")
		)
		(fp_line
			(start 0.67945 -0.305054)
			(end 0.12065 -0.305054)
			(stroke
				(width 0.1)
				(type default)
			)
			(layer "B.Fab")
		)
		(fp_line
			(start 0.12065 0.3048)
			(end 0.67945 0.3048)
			(stroke
				(width 0.1)
				(type default)
			)
			(layer "B.Fab")
		)
		(fp_line
			(start 0.12065 0.2794)
			(end 0.12065 0.3048)
			(stroke
				(width 0.1)
				(type default)
			)
			(layer "B.Fab")
		)
		(fp_line
			(start 0.12065 -0.2794)
			(end -0.12065 -0.2794)
			(stroke
				(width 0.1)
				(type default)
			)
			(layer "B.Fab")
		)
		(fp_line
			(start 0.12065 -0.305054)
			(end 0.12065 -0.2794)
			(stroke
				(width 0.1)
				(type default)
			)
			(layer "B.Fab")
		)
		(fp_line
			(start -0.120396 0.3048)
			(end -0.120396 0.2794)
			(stroke
				(width 0.1)
				(type default)
			)
			(layer "B.Fab")
		)
		(fp_line
			(start -0.120396 0.2794)
			(end 0.12065 0.2794)
			(stroke
				(width 0.1)
				(type default)
			)
			(layer "B.Fab")
		)
		(fp_line
			(start -0.12065 -0.2794)
			(end -0.12065 -0.3048)
			(stroke
				(width 0.1)
				(type default)
			)
			(layer "B.Fab")
		)
		(fp_line
			(start -0.12065 -0.3048)
			(end -0.67945 -0.3048)
			(stroke
				(width 0.1)
				(type default)
			)
			(layer "B.Fab")
		)
		(fp_line
			(start -0.67945 0.3048)
			(end -0.120396 0.3048)
			(stroke
				(width 0.1)
				(type default)
			)
			(layer "B.Fab")
		)
		(fp_line
			(start -0.67945 -0.3048)
			(end -0.67945 0.3048)
			(stroke
				(width 0.1)
				(type default)
			)
			(layer "B.Fab")
		)
		(pad "1" smd circle
			(at 0.40005 0)
			(size 0 0)
			(layers "B.Cu" "B.Mask" "B.Paste")
			(net "P1V2_AUX")
		)
		(pad "2" smd circle
			(at -0.40005 0)
			(size 0 0)
			(layers "B.Cu" "B.Mask" "B.Paste")
			(net "GND")
		)
	)
	(footprint ""
		(layer "B.Cu")
		(at 24.3078 -24.003 -90)
		(property "Reference" "PC267"
			(at 0 0 90)
			(layer "B.SilkS")
			(hide yes)
			(effects
				(font
					(size 1.27 1.27)
				)
				(justify mirror)
			)
		)
		(property "Value" ""
			(at 0 0 90)
			(layer "B.Fab")
			(effects
				(font
					(size 1.27 1.27)
				)
				(justify mirror)
			)
		)
		(duplicate_pad_numbers_are_jumpers no)
		(fp_line
			(start -1.651 0.8382)
			(end 1.651 0.8382)
			(stroke
				(width 0.1524)
				(type default)
			)
			(layer "B.SilkS")
		)
		(fp_line
			(start 0 0.8382)
			(end 0 -0.8382)
			(stroke
				(width 0.1524)
				(type default)
			)
			(layer "B.SilkS")
		)
		(fp_line
			(start 1.651 0.8382)
			(end 1.651 -0.8382)
			(stroke
				(width 0.1524)
				(type default)
			)
			(layer "B.SilkS")
		)
		(fp_line
			(start -1.651 -0.8382)
			(end -1.651 0.8382)
			(stroke
				(width 0.1524)
				(type default)
			)
			(layer "B.SilkS")
		)
		(fp_line
			(start 1.651 -0.8382)
			(end -1.651 -0.8382)
			(stroke
				(width 0.1524)
				(type default)
			)
			(layer "B.SilkS")
		)
		(fp_line
			(start -1.55956 0.7366)
			(end -1.55956 -0.7366)
			(stroke
				(width 0.1)
				(type default)
			)
			(layer "B.Fab")
		)
		(fp_line
			(start -1.524 0.7366)
			(end -1.55956 0.7366)
			(stroke
				(width 0.1)
				(type default)
			)
			(layer "B.Fab")
		)
		(fp_line
			(start 1.524 0.7366)
			(end -1.524 0.7366)
			(stroke
				(width 0.1)
				(type default)
			)
			(layer "B.Fab")
		)
		(fp_line
			(start 1.55956 0.7366)
			(end 1.524 0.7366)
			(stroke
				(width 0.1)
				(type default)
			)
			(layer "B.Fab")
		)
		(fp_line
			(start -1.55956 -0.7366)
			(end -1.524 -0.7366)
			(stroke
				(width 0.1)
				(type default)
			)
			(layer "B.Fab")
		)
		(fp_line
			(start -1.524 -0.7366)
			(end 1.524 -0.7366)
			(stroke
				(width 0.1)
				(type default)
			)
			(layer "B.Fab")
		)
		(fp_line
			(start 1.524 -0.7366)
			(end 1.55956 -0.7366)
			(stroke
				(width 0.1)
				(type default)
			)
			(layer "B.Fab")
		)
		(fp_line
			(start 1.55956 -0.7366)
			(end 1.55956 0.7366)
			(stroke
				(width 0.1)
				(type default)
			)
			(layer "B.Fab")
		)
		(pad "1" smd rect
			(at 0.94996 0 270)
			(size 1.1176 1.3716)
			(layers "B.Cu" "B.Mask" "B.Paste")
			(net "P1V0_AUX")
		)
		(pad "2" smd rect
			(at -0.94996 0 270)
			(size 1.1176 1.3716)
			(layers "B.Cu" "B.Mask" "B.Paste")
			(net "GND")
		)
	)
	(footprint ""
		(layer "B.Cu")
		(at 56.43626 -47.606966 90)
		(property "Reference" "C99"
			(at 0 0 90)
			(layer "B.SilkS")
			(hide yes)
			(effects
				(font
					(size 1.27 1.27)
				)
				(justify mirror)
			)
		)
		(property "Value" ""
			(at 0 0 90)
			(layer "B.Fab")
			(effects
				(font
					(size 1.27 1.27)
				)
				(justify mirror)
			)
		)
		(duplicate_pad_numbers_are_jumpers no)
		(fp_line
			(start 0.7874 -0.4064)
			(end -0.7874 -0.4064)
			(stroke
				(width 0.1524)
				(type default)
			)
			(layer "B.SilkS")
		)
		(fp_line
			(start -0.7874 -0.4064)
			(end -0.7874 0.4064)
			(stroke
				(width 0.1524)
				(type default)
			)
			(layer "B.SilkS")
		)
		(fp_line
			(start 0.7874 0.4064)
			(end 0.7874 -0.4064)
			(stroke
				(width 0.1524)
				(type default)
			)
			(layer "B.SilkS")
		)
		(fp_line
			(start -0.7874 0.4064)
			(end 0.7874 0.4064)
			(stroke
				(width 0.1524)
				(type default)
			)
			(layer "B.SilkS")
		)
		(fp_line
			(start 0.67945 -0.305054)
			(end 0.12065 -0.305054)
			(stroke
				(width 0.1)
				(type default)
			)
			(layer "B.Fab")
		)
		(fp_line
			(start 0.12065 -0.305054)
			(end 0.12065 -0.2794)
			(stroke
				(width 0.1)
				(type default)
			)
			(layer "B.Fab")
		)
		(fp_line
			(start -0.12065 -0.3048)
			(end -0.67945 -0.3048)
			(stroke
				(width 0.1)
				(type default)
			)
			(layer "B.Fab")
		)
		(fp_line
			(start -0.67945 -0.3048)
			(end -0.67945 0.3048)
			(stroke
				(width 0.1)
				(type default)
			)
			(layer "B.Fab")
		)
		(fp_line
			(start 0.12065 -0.2794)
			(end -0.12065 -0.2794)
			(stroke
				(width 0.1)
				(type default)
			)
			(layer "B.Fab")
		)
		(fp_line
			(start -0.12065 -0.2794)
			(end -0.12065 -0.3048)
			(stroke
				(width 0.1)
				(type default)
			)
			(layer "B.Fab")
		)
		(fp_line
			(start 0.12065 0.2794)
			(end 0.12065 0.3048)
			(stroke
				(width 0.1)
				(type default)
			)
			(layer "B.Fab")
		)
		(fp_line
			(start -0.120396 0.2794)
			(end 0.12065 0.2794)
			(stroke
				(width 0.1)
				(type default)
			)
			(layer "B.Fab")
		)
		(fp_line
			(start 0.67945 0.3048)
			(end 0.67945 -0.305054)
			(stroke
				(width 0.1)
				(type default)
			)
			(layer "B.Fab")
		)
		(fp_line
			(start 0.12065 0.3048)
			(end 0.67945 0.3048)
			(stroke
				(width 0.1)
				(type default)
			)
			(layer "B.Fab")
		)
		(fp_line
			(start -0.120396 0.3048)
			(end -0.120396 0.2794)
			(stroke
				(width 0.1)
				(type default)
			)
			(layer "B.Fab")
		)
		(fp_line
			(start -0.67945 0.3048)
			(end -0.120396 0.3048)
			(stroke
				(width 0.1)
				(type default)
			)
			(layer "B.Fab")
		)
		(pad "1" smd circle
			(at 0.40005 0 270)
			(size 0 0)
			(layers "B.Cu" "B.Mask" "B.Paste")
			(net "P1V0_AUX")
		)
		(pad "2" smd circle
			(at -0.40005 0 270)
			(size 0 0)
			(layers "B.Cu" "B.Mask" "B.Paste")
			(net "GND")
		)
	)
	(footprint ""
		(layer "B.Cu")
		(at 50.155602 -43.303952 -90)
		(property "Reference" "C57"
			(at 0 0 90)
			(layer "B.SilkS")
			(hide yes)
			(effects
				(font
					(size 1.27 1.27)
				)
				(justify mirror)
			)
		)
		(property "Value" ""
			(at 0 0 90)
			(layer "B.Fab")
			(effects
				(font
					(size 1.27 1.27)
				)
				(justify mirror)
			)
		)
		(duplicate_pad_numbers_are_jumpers no)
		(fp_line
			(start -0.7874 0.4064)
			(end 0.7874 0.4064)
			(stroke
				(width 0.1524)
				(type default)
			)
			(layer "B.SilkS")
		)
		(fp_line
			(start 0.7874 0.4064)
			(end 0.7874 -0.4064)
			(stroke
				(width 0.1524)
				(type default)
			)
			(layer "B.SilkS")
		)
		(fp_line
			(start -0.7874 -0.4064)
			(end -0.7874 0.4064)
			(stroke
				(width 0.1524)
				(type default)
			)
			(layer "B.SilkS")
		)
		(fp_line
			(start 0.7874 -0.4064)
			(end -0.7874 -0.4064)
			(stroke
				(width 0.1524)
				(type default)
			)
			(layer "B.SilkS")
		)
		(fp_line
			(start -0.67945 0.3048)
			(end -0.120396 0.3048)
			(stroke
				(width 0.1)
				(type default)
			)
			(layer "B.Fab")
		)
		(fp_line
			(start -0.120396 0.3048)
			(end -0.120396 0.2794)
			(stroke
				(width 0.1)
				(type default)
			)
			(layer "B.Fab")
		)
		(fp_line
			(start 0.12065 0.3048)
			(end 0.67945 0.3048)
			(stroke
				(width 0.1)
				(type default)
			)
			(layer "B.Fab")
		)
		(fp_line
			(start 0.67945 0.3048)
			(end 0.67945 -0.305054)
			(stroke
				(width 0.1)
				(type default)
			)
			(layer "B.Fab")
		)
		(fp_line
			(start -0.120396 0.2794)
			(end 0.12065 0.2794)
			(stroke
				(width 0.1)
				(type default)
			)
			(layer "B.Fab")
		)
		(fp_line
			(start 0.12065 0.2794)
			(end 0.12065 0.3048)
			(stroke
				(width 0.1)
				(type default)
			)
			(layer "B.Fab")
		)
		(fp_line
			(start -0.12065 -0.2794)
			(end -0.12065 -0.3048)
			(stroke
				(width 0.1)
				(type default)
			)
			(layer "B.Fab")
		)
		(fp_line
			(start 0.12065 -0.2794)
			(end -0.12065 -0.2794)
			(stroke
				(width 0.1)
				(type default)
			)
			(layer "B.Fab")
		)
		(fp_line
			(start -0.67945 -0.3048)
			(end -0.67945 0.3048)
			(stroke
				(width 0.1)
				(type default)
			)
			(layer "B.Fab")
		)
		(fp_line
			(start -0.12065 -0.3048)
			(end -0.67945 -0.3048)
			(stroke
				(width 0.1)
				(type default)
			)
			(layer "B.Fab")
		)
		(fp_line
			(start 0.12065 -0.305054)
			(end 0.12065 -0.2794)
			(stroke
				(width 0.1)
				(type default)
			)
			(layer "B.Fab")
		)
		(fp_line
			(start 0.67945 -0.305054)
			(end 0.12065 -0.305054)
			(stroke
				(width 0.1)
				(type default)
			)
			(layer "B.Fab")
		)
		(pad "1" smd circle
			(at 0.40005 0 90)
			(size 0 0)
			(layers "B.Cu" "B.Mask" "B.Paste")
			(net "P3V3_P1V8_I2C_I3C")
		)
		(pad "2" smd circle
			(at -0.40005 0 90)
			(size 0 0)
			(layers "B.Cu" "B.Mask" "B.Paste")
			(net "GND")
		)
	)
	(footprint ""
		(layer "B.Cu")
		(at 17.78 -70.104 90)
		(property "Reference" "R298"
			(at 0 0 90)
			(layer "B.SilkS")
			(hide yes)
			(effects
				(font
					(size 1.27 1.27)
				)
				(justify mirror)
			)
		)
		(property "Value" ""
			(at 0 0 90)
			(layer "B.Fab")
			(effects
				(font
					(size 1.27 1.27)
				)
				(justify mirror)
			)
		)
		(duplicate_pad_numbers_are_jumpers no)
		(fp_line
			(start 0.7874 -0.4064)
			(end -0.7874 -0.4064)
			(stroke
				(width 0.1524)
				(type default)
			)
			(layer "B.SilkS")
		)
		(fp_line
			(start -0.7874 -0.4064)
			(end -0.7874 0.4064)
			(stroke
				(width 0.1524)
				(type default)
			)
			(layer "B.SilkS")
		)
		(fp_line
			(start 0.7874 0.4064)
			(end 0.7874 -0.4064)
			(stroke
				(width 0.1524)
				(type default)
			)
			(layer "B.SilkS")
		)
		(fp_line
			(start -0.7874 0.4064)
			(end 0.7874 0.4064)
			(stroke
				(width 0.1524)
				(type default)
			)
			(layer "B.SilkS")
		)
		(fp_line
			(start 0.67945 -0.305054)
			(end 0.12065 -0.305054)
			(stroke
				(width 0.1)
				(type default)
			)
			(layer "B.Fab")
		)
		(fp_line
			(start 0.12065 -0.305054)
			(end 0.12065 -0.2794)
			(stroke
				(width 0.1)
				(type default)
			)
			(layer "B.Fab")
		)
		(fp_line
			(start -0.12065 -0.3048)
			(end -0.67945 -0.3048)
			(stroke
				(width 0.1)
				(type default)
			)
			(layer "B.Fab")
		)
		(fp_line
			(start -0.67945 -0.3048)
			(end -0.67945 0.3048)
			(stroke
				(width 0.1)
				(type default)
			)
			(layer "B.Fab")
		)
		(fp_line
			(start 0.12065 -0.2794)
			(end -0.12065 -0.2794)
			(stroke
				(width 0.1)
				(type default)
			)
			(layer "B.Fab")
		)
		(fp_line
			(start -0.12065 -0.2794)
			(end -0.12065 -0.3048)
			(stroke
				(width 0.1)
				(type default)
			)
			(layer "B.Fab")
		)
		(fp_line
			(start 0.12065 0.2794)
			(end 0.12065 0.3048)
			(stroke
				(width 0.1)
				(type default)
			)
			(layer "B.Fab")
		)
		(fp_line
			(start -0.120396 0.2794)
			(end 0.12065 0.2794)
			(stroke
				(width 0.1)
				(type default)
			)
			(layer "B.Fab")
		)
		(fp_line
			(start 0.67945 0.3048)
			(end 0.67945 -0.305054)
			(stroke
				(width 0.1)
				(type default)
			)
			(layer "B.Fab")
		)
		(fp_line
			(start 0.12065 0.3048)
			(end 0.67945 0.3048)
			(stroke
				(width 0.1)
				(type default)
			)
			(layer "B.Fab")
		)
		(fp_line
			(start -0.120396 0.3048)
			(end -0.120396 0.2794)
			(stroke
				(width 0.1)
				(type default)
			)
			(layer "B.Fab")
		)
		(fp_line
			(start -0.67945 0.3048)
			(end -0.120396 0.3048)
			(stroke
				(width 0.1)
				(type default)
			)
			(layer "B.Fab")
		)
		(pad "1" smd circle
			(at 0.40005 0 270)
			(size 0 0)
			(layers "B.Cu" "B.Mask" "B.Paste")
			(net "P3V3_AUX")
		)
		(pad "2" smd circle
			(at -0.40005 0 270)
			(size 0 0)
			(layers "B.Cu" "B.Mask" "B.Paste")
			(net "SMB_DEBUG_AUX_LVC3_USB_R1_SCL")
		)
	)
	(footprint ""
		(layer "B.Cu")
		(at 17.526 -98.679 90)
		(property "Reference" "R525"
			(at 0 0 90)
			(layer "B.SilkS")
			(hide yes)
			(effects
				(font
					(size 1.27 1.27)
				)
				(justify mirror)
			)
		)
		(property "Value" ""
			(at 0 0 90)
			(layer "B.Fab")
			(effects
				(font
					(size 1.27 1.27)
				)
				(justify mirror)
			)
		)
		(duplicate_pad_numbers_are_jumpers no)
		(fp_line
			(start 0.7874 -0.4064)
			(end -0.7874 -0.4064)
			(stroke
				(width 0.1524)
				(type default)
			)
			(layer "B.SilkS")
		)
		(fp_line
			(start -0.7874 -0.4064)
			(end -0.7874 0.4064)
			(stroke
				(width 0.1524)
				(type default)
			)
			(layer "B.SilkS")
		)
		(fp_line
			(start 0.7874 0.4064)
			(end 0.7874 -0.4064)
			(stroke
				(width 0.1524)
				(type default)
			)
			(layer "B.SilkS")
		)
		(fp_line
			(start -0.7874 0.4064)
			(end 0.7874 0.4064)
			(stroke
				(width 0.1524)
				(type default)
			)
			(layer "B.SilkS")
		)
		(fp_line
			(start 0.67945 -0.305054)
			(end 0.12065 -0.305054)
			(stroke
				(width 0.1)
				(type default)
			)
			(layer "B.Fab")
		)
		(fp_line
			(start 0.12065 -0.305054)
			(end 0.12065 -0.2794)
			(stroke
				(width 0.1)
				(type default)
			)
			(layer "B.Fab")
		)
		(fp_line
			(start -0.12065 -0.3048)
			(end -0.67945 -0.3048)
			(stroke
				(width 0.1)
				(type default)
			)
			(layer "B.Fab")
		)
		(fp_line
			(start -0.67945 -0.3048)
			(end -0.67945 0.3048)
			(stroke
				(width 0.1)
				(type default)
			)
			(layer "B.Fab")
		)
		(fp_line
			(start 0.12065 -0.2794)
			(end -0.12065 -0.2794)
			(stroke
				(width 0.1)
				(type default)
			)
			(layer "B.Fab")
		)
		(fp_line
			(start -0.12065 -0.2794)
			(end -0.12065 -0.3048)
			(stroke
				(width 0.1)
				(type default)
			)
			(layer "B.Fab")
		)
		(fp_line
			(start 0.12065 0.2794)
			(end 0.12065 0.3048)
			(stroke
				(width 0.1)
				(type default)
			)
			(layer "B.Fab")
		)
		(fp_line
			(start -0.120396 0.2794)
			(end 0.12065 0.2794)
			(stroke
				(width 0.1)
				(type default)
			)
			(layer "B.Fab")
		)
		(fp_line
			(start 0.67945 0.3048)
			(end 0.67945 -0.305054)
			(stroke
				(width 0.1)
				(type default)
			)
			(layer "B.Fab")
		)
		(fp_line
			(start 0.12065 0.3048)
			(end 0.67945 0.3048)
			(stroke
				(width 0.1)
				(type default)
			)
			(layer "B.Fab")
		)
		(fp_line
			(start -0.120396 0.3048)
			(end -0.120396 0.2794)
			(stroke
				(width 0.1)
				(type default)
			)
			(layer "B.Fab")
		)
		(fp_line
			(start -0.67945 0.3048)
			(end -0.120396 0.3048)
			(stroke
				(width 0.1)
				(type default)
			)
			(layer "B.Fab")
		)
		(pad "1" smd circle
			(at 0.40005 0 270)
			(size 0 0)
			(layers "B.Cu" "B.Mask" "B.Paste")
			(net "P3V3_AUX")
		)
		(pad "2" smd circle
			(at -0.40005 0 270)
			(size 0 0)
			(layers "B.Cu" "B.Mask" "B.Paste")
			(net "VCCIO1")
		)
	)
	(footprint ""
		(layer "B.Cu")
		(at 82.108294 -51.730656 180)
		(property "Reference" "R324"
			(at 0 0 0)
			(layer "B.SilkS")
			(hide yes)
			(effects
				(font
					(size 1.27 1.27)
				)
				(justify mirror)
			)
		)
		(property "Value" ""
			(at 0 0 0)
			(layer "B.Fab")
			(effects
				(font
					(size 1.27 1.27)
				)
				(justify mirror)
			)
		)
		(duplicate_pad_numbers_are_jumpers no)
		(fp_line
			(start 0.7874 0.4064)
			(end 0.7874 -0.4064)
			(stroke
				(width 0.1524)
				(type default)
			)
			(layer "B.SilkS")
		)
		(fp_line
			(start 0.7874 -0.4064)
			(end -0.7874 -0.4064)
			(stroke
				(width 0.1524)
				(type default)
			)
			(layer "B.SilkS")
		)
		(fp_line
			(start -0.7874 0.4064)
			(end 0.7874 0.4064)
			(stroke
				(width 0.1524)
				(type default)
			)
			(layer "B.SilkS")
		)
		(fp_line
			(start -0.7874 -0.4064)
			(end -0.7874 0.4064)
			(stroke
				(width 0.1524)
				(type default)
			)
			(layer "B.SilkS")
		)
		(fp_line
			(start 0.67945 0.3048)
			(end 0.67945 -0.305054)
			(stroke
				(width 0.1)
				(type default)
			)
			(layer "B.Fab")
		)
		(fp_line
			(start 0.67945 -0.305054)
			(end 0.12065 -0.305054)
			(stroke
				(width 0.1)
				(type default)
			)
			(layer "B.Fab")
		)
		(fp_line
			(start 0.12065 0.3048)
			(end 0.67945 0.3048)
			(stroke
				(width 0.1)
				(type default)
			)
			(layer "B.Fab")
		)
		(fp_line
			(start 0.12065 0.2794)
			(end 0.12065 0.3048)
			(stroke
				(width 0.1)
				(type default)
			)
			(layer "B.Fab")
		)
		(fp_line
			(start 0.12065 -0.2794)
			(end -0.12065 -0.2794)
			(stroke
				(width 0.1)
				(type default)
			)
			(layer "B.Fab")
		)
		(fp_line
			(start 0.12065 -0.305054)
			(end 0.12065 -0.2794)
			(stroke
				(width 0.1)
				(type default)
			)
			(layer "B.Fab")
		)
		(fp_line
			(start -0.120396 0.3048)
			(end -0.120396 0.2794)
			(stroke
				(width 0.1)
				(type default)
			)
			(layer "B.Fab")
		)
		(fp_line
			(start -0.120396 0.2794)
			(end 0.12065 0.2794)
			(stroke
				(width 0.1)
				(type default)
			)
			(layer "B.Fab")
		)
		(fp_line
			(start -0.12065 -0.2794)
			(end -0.12065 -0.3048)
			(stroke
				(width 0.1)
				(type default)
			)
			(layer "B.Fab")
		)
		(fp_line
			(start -0.12065 -0.3048)
			(end -0.67945 -0.3048)
			(stroke
				(width 0.1)
				(type default)
			)
			(layer "B.Fab")
		)
		(fp_line
			(start -0.67945 0.3048)
			(end -0.120396 0.3048)
			(stroke
				(width 0.1)
				(type default)
			)
			(layer "B.Fab")
		)
		(fp_line
			(start -0.67945 -0.3048)
			(end -0.67945 0.3048)
			(stroke
				(width 0.1)
				(type default)
			)
			(layer "B.Fab")
		)
		(pad "1" smd circle
			(at 0.40005 0)
			(size 0 0)
			(layers "B.Cu" "B.Mask" "B.Paste")
			(net "P1V2_AUX")
		)
		(pad "2" smd circle
			(at -0.40005 0)
			(size 0 0)
			(layers "B.Cu" "B.Mask" "B.Paste")
			(net "P0V6_DDR_VREF_AUX")
		)
	)
	(footprint ""
		(layer "B.Cu")
		(at 19.431 -17.907 90)
		(property "Reference" "R53"
			(at 0 0 90)
			(layer "B.SilkS")
			(hide yes)
			(effects
				(font
					(size 1.27 1.27)
				)
				(justify mirror)
			)
		)
		(property "Value" ""
			(at 0 0 90)
			(layer "B.Fab")
			(effects
				(font
					(size 1.27 1.27)
				)
				(justify mirror)
			)
		)
		(duplicate_pad_numbers_are_jumpers no)
		(fp_line
			(start 0.7874 -0.4064)
			(end -0.7874 -0.4064)
			(stroke
				(width 0.1524)
				(type default)
			)
			(layer "B.SilkS")
		)
		(fp_line
			(start -0.7874 -0.4064)
			(end -0.7874 0.4064)
			(stroke
				(width 0.1524)
				(type default)
			)
			(layer "B.SilkS")
		)
		(fp_line
			(start 0.7874 0.4064)
			(end 0.7874 -0.4064)
			(stroke
				(width 0.1524)
				(type default)
			)
			(layer "B.SilkS")
		)
		(fp_line
			(start -0.7874 0.4064)
			(end 0.7874 0.4064)
			(stroke
				(width 0.1524)
				(type default)
			)
			(layer "B.SilkS")
		)
		(fp_line
			(start 0.67945 -0.305054)
			(end 0.12065 -0.305054)
			(stroke
				(width 0.1)
				(type default)
			)
			(layer "B.Fab")
		)
		(fp_line
			(start 0.12065 -0.305054)
			(end 0.12065 -0.2794)
			(stroke
				(width 0.1)
				(type default)
			)
			(layer "B.Fab")
		)
		(fp_line
			(start -0.12065 -0.3048)
			(end -0.67945 -0.3048)
			(stroke
				(width 0.1)
				(type default)
			)
			(layer "B.Fab")
		)
		(fp_line
			(start -0.67945 -0.3048)
			(end -0.67945 0.3048)
			(stroke
				(width 0.1)
				(type default)
			)
			(layer "B.Fab")
		)
		(fp_line
			(start 0.12065 -0.2794)
			(end -0.12065 -0.2794)
			(stroke
				(width 0.1)
				(type default)
			)
			(layer "B.Fab")
		)
		(fp_line
			(start -0.12065 -0.2794)
			(end -0.12065 -0.3048)
			(stroke
				(width 0.1)
				(type default)
			)
			(layer "B.Fab")
		)
		(fp_line
			(start 0.12065 0.2794)
			(end 0.12065 0.3048)
			(stroke
				(width 0.1)
				(type default)
			)
			(layer "B.Fab")
		)
		(fp_line
			(start -0.120396 0.2794)
			(end 0.12065 0.2794)
			(stroke
				(width 0.1)
				(type default)
			)
			(layer "B.Fab")
		)
		(fp_line
			(start 0.67945 0.3048)
			(end 0.67945 -0.305054)
			(stroke
				(width 0.1)
				(type default)
			)
			(layer "B.Fab")
		)
		(fp_line
			(start 0.12065 0.3048)
			(end 0.67945 0.3048)
			(stroke
				(width 0.1)
				(type default)
			)
			(layer "B.Fab")
		)
		(fp_line
			(start -0.120396 0.3048)
			(end -0.120396 0.2794)
			(stroke
				(width 0.1)
				(type default)
			)
			(layer "B.Fab")
		)
		(fp_line
			(start -0.67945 0.3048)
			(end -0.120396 0.3048)
			(stroke
				(width 0.1)
				(type default)
			)
			(layer "B.Fab")
		)
		(pad "1" smd circle
			(at 0.40005 0 270)
			(size 0 0)
			(layers "B.Cu" "B.Mask" "B.Paste")
			(net "TMC75_A1")
		)
		(pad "2" smd circle
			(at -0.40005 0 270)
			(size 0 0)
			(layers "B.Cu" "B.Mask" "B.Paste")
			(net "GND")
		)
	)
	(footprint ""
		(layer "B.Cu")
		(at 62.865 -31.369 -90)
		(property "Reference" "R491"
			(at 0 0 90)
			(layer "B.SilkS")
			(hide yes)
			(effects
				(font
					(size 1.27 1.27)
				)
				(justify mirror)
			)
		)
		(property "Value" ""
			(at 0 0 90)
			(layer "B.Fab")
			(effects
				(font
					(size 1.27 1.27)
				)
				(justify mirror)
			)
		)
		(duplicate_pad_numbers_are_jumpers no)
		(fp_line
			(start -0.7874 0.4064)
			(end 0.7874 0.4064)
			(stroke
				(width 0.1524)
				(type default)
			)
			(layer "B.SilkS")
		)
		(fp_line
			(start 0.7874 0.4064)
			(end 0.7874 -0.4064)
			(stroke
				(width 0.1524)
				(type default)
			)
			(layer "B.SilkS")
		)
		(fp_line
			(start -0.7874 -0.4064)
			(end -0.7874 0.4064)
			(stroke
				(width 0.1524)
				(type default)
			)
			(layer "B.SilkS")
		)
		(fp_line
			(start 0.7874 -0.4064)
			(end -0.7874 -0.4064)
			(stroke
				(width 0.1524)
				(type default)
			)
			(layer "B.SilkS")
		)
		(fp_line
			(start -0.67945 0.3048)
			(end -0.120396 0.3048)
			(stroke
				(width 0.1)
				(type default)
			)
			(layer "B.Fab")
		)
		(fp_line
			(start -0.120396 0.3048)
			(end -0.120396 0.2794)
			(stroke
				(width 0.1)
				(type default)
			)
			(layer "B.Fab")
		)
		(fp_line
			(start 0.12065 0.3048)
			(end 0.67945 0.3048)
			(stroke
				(width 0.1)
				(type default)
			)
			(layer "B.Fab")
		)
		(fp_line
			(start 0.67945 0.3048)
			(end 0.67945 -0.305054)
			(stroke
				(width 0.1)
				(type default)
			)
			(layer "B.Fab")
		)
		(fp_line
			(start -0.120396 0.2794)
			(end 0.12065 0.2794)
			(stroke
				(width 0.1)
				(type default)
			)
			(layer "B.Fab")
		)
		(fp_line
			(start 0.12065 0.2794)
			(end 0.12065 0.3048)
			(stroke
				(width 0.1)
				(type default)
			)
			(layer "B.Fab")
		)
		(fp_line
			(start -0.12065 -0.2794)
			(end -0.12065 -0.3048)
			(stroke
				(width 0.1)
				(type default)
			)
			(layer "B.Fab")
		)
		(fp_line
			(start 0.12065 -0.2794)
			(end -0.12065 -0.2794)
			(stroke
				(width 0.1)
				(type default)
			)
			(layer "B.Fab")
		)
		(fp_line
			(start -0.67945 -0.3048)
			(end -0.67945 0.3048)
			(stroke
				(width 0.1)
				(type default)
			)
			(layer "B.Fab")
		)
		(fp_line
			(start -0.12065 -0.3048)
			(end -0.67945 -0.3048)
			(stroke
				(width 0.1)
				(type default)
			)
			(layer "B.Fab")
		)
		(fp_line
			(start 0.12065 -0.305054)
			(end 0.12065 -0.2794)
			(stroke
				(width 0.1)
				(type default)
			)
			(layer "B.Fab")
		)
		(fp_line
			(start 0.67945 -0.305054)
			(end 0.12065 -0.305054)
			(stroke
				(width 0.1)
				(type default)
			)
			(layer "B.Fab")
		)
		(pad "1" smd circle
			(at 0.40005 0 90)
			(size 0 0)
			(layers "B.Cu" "B.Mask" "B.Paste")
			(net "P3V3_RGM")
		)
		(pad "2" smd circle
			(at -0.40005 0 90)
			(size 0 0)
			(layers "B.Cu" "B.Mask" "B.Paste")
			(net "RST_BMC_SRST_N")
		)
	)
	(footprint ""
		(layer "B.Cu")
		(at 73.516998 -47.730156)
		(property "Reference" "C16"
			(at 0 0 0)
			(layer "B.SilkS")
			(hide yes)
			(effects
				(font
					(size 1.27 1.27)
				)
				(justify mirror)
			)
		)
		(property "Value" ""
			(at 0 0 0)
			(layer "B.Fab")
			(effects
				(font
					(size 1.27 1.27)
				)
				(justify mirror)
			)
		)
		(duplicate_pad_numbers_are_jumpers no)
		(fp_line
			(start -0.7874 -0.4064)
			(end -0.7874 0.4064)
			(stroke
				(width 0.1524)
				(type default)
			)
			(layer "B.SilkS")
		)
		(fp_line
			(start -0.7874 0.4064)
			(end 0.7874 0.4064)
			(stroke
				(width 0.1524)
				(type default)
			)
			(layer "B.SilkS")
		)
		(fp_line
			(start 0.7874 -0.4064)
			(end -0.7874 -0.4064)
			(stroke
				(width 0.1524)
				(type default)
			)
			(layer "B.SilkS")
		)
		(fp_line
			(start 0.7874 0.4064)
			(end 0.7874 -0.4064)
			(stroke
				(width 0.1524)
				(type default)
			)
			(layer "B.SilkS")
		)
		(fp_line
			(start -0.67945 -0.3048)
			(end -0.67945 0.3048)
			(stroke
				(width 0.1)
				(type default)
			)
			(layer "B.Fab")
		)
		(fp_line
			(start -0.67945 0.3048)
			(end -0.120396 0.3048)
			(stroke
				(width 0.1)
				(type default)
			)
			(layer "B.Fab")
		)
		(fp_line
			(start -0.12065 -0.3048)
			(end -0.67945 -0.3048)
			(stroke
				(width 0.1)
				(type default)
			)
			(layer "B.Fab")
		)
		(fp_line
			(start -0.12065 -0.2794)
			(end -0.12065 -0.3048)
			(stroke
				(width 0.1)
				(type default)
			)
			(layer "B.Fab")
		)
		(fp_line
			(start -0.120396 0.2794)
			(end 0.12065 0.2794)
			(stroke
				(width 0.1)
				(type default)
			)
			(layer "B.Fab")
		)
		(fp_line
			(start -0.120396 0.3048)
			(end -0.120396 0.2794)
			(stroke
				(width 0.1)
				(type default)
			)
			(layer "B.Fab")
		)
		(fp_line
			(start 0.12065 -0.305054)
			(end 0.12065 -0.2794)
			(stroke
				(width 0.1)
				(type default)
			)
			(layer "B.Fab")
		)
		(fp_line
			(start 0.12065 -0.2794)
			(end -0.12065 -0.2794)
			(stroke
				(width 0.1)
				(type default)
			)
			(layer "B.Fab")
		)
		(fp_line
			(start 0.12065 0.2794)
			(end 0.12065 0.3048)
			(stroke
				(width 0.1)
				(type default)
			)
			(layer "B.Fab")
		)
		(fp_line
			(start 0.12065 0.3048)
			(end 0.67945 0.3048)
			(stroke
				(width 0.1)
				(type default)
			)
			(layer "B.Fab")
		)
		(fp_line
			(start 0.67945 -0.305054)
			(end 0.12065 -0.305054)
			(stroke
				(width 0.1)
				(type default)
			)
			(layer "B.Fab")
		)
		(fp_line
			(start 0.67945 0.3048)
			(end 0.67945 -0.305054)
			(stroke
				(width 0.1)
				(type default)
			)
			(layer "B.Fab")
		)
		(pad "1" smd circle
			(at 0.40005 0 180)
			(size 0 0)
			(layers "B.Cu" "B.Mask" "B.Paste")
			(net "P1V2_AUX")
		)
		(pad "2" smd circle
			(at -0.40005 0 180)
			(size 0 0)
			(layers "B.Cu" "B.Mask" "B.Paste")
			(net "GND")
		)
	)
	(footprint ""
		(layer "B.Cu")
		(at 84.452968 -98.20529 180)
		(property "Reference" "C249"
			(at 0 0 0)
			(layer "B.SilkS")
			(hide yes)
			(effects
				(font
					(size 1.27 1.27)
				)
				(justify mirror)
			)
		)
		(property "Value" ""
			(at 0 0 0)
			(layer "B.Fab")
			(effects
				(font
					(size 1.27 1.27)
				)
				(justify mirror)
			)
		)
		(duplicate_pad_numbers_are_jumpers no)
		(fp_line
			(start 0.7874 0.4064)
			(end 0.7874 -0.4064)
			(stroke
				(width 0.1524)
				(type default)
			)
			(layer "B.SilkS")
		)
		(fp_line
			(start 0.7874 -0.4064)
			(end -0.7874 -0.4064)
			(stroke
				(width 0.1524)
				(type default)
			)
			(layer "B.SilkS")
		)
		(fp_line
			(start -0.7874 0.4064)
			(end 0.7874 0.4064)
			(stroke
				(width 0.1524)
				(type default)
			)
			(layer "B.SilkS")
		)
		(fp_line
			(start -0.7874 -0.4064)
			(end -0.7874 0.4064)
			(stroke
				(width 0.1524)
				(type default)
			)
			(layer "B.SilkS")
		)
		(fp_line
			(start 0.67945 0.3048)
			(end 0.67945 -0.305054)
			(stroke
				(width 0.1)
				(type default)
			)
			(layer "B.Fab")
		)
		(fp_line
			(start 0.67945 -0.305054)
			(end 0.12065 -0.305054)
			(stroke
				(width 0.1)
				(type default)
			)
			(layer "B.Fab")
		)
		(fp_line
			(start 0.12065 0.3048)
			(end 0.67945 0.3048)
			(stroke
				(width 0.1)
				(type default)
			)
			(layer "B.Fab")
		)
		(fp_line
			(start 0.12065 0.2794)
			(end 0.12065 0.3048)
			(stroke
				(width 0.1)
				(type default)
			)
			(layer "B.Fab")
		)
		(fp_line
			(start 0.12065 -0.2794)
			(end -0.12065 -0.2794)
			(stroke
				(width 0.1)
				(type default)
			)
			(layer "B.Fab")
		)
		(fp_line
			(start 0.12065 -0.305054)
			(end 0.12065 -0.2794)
			(stroke
				(width 0.1)
				(type default)
			)
			(layer "B.Fab")
		)
		(fp_line
			(start -0.120396 0.3048)
			(end -0.120396 0.2794)
			(stroke
				(width 0.1)
				(type default)
			)
			(layer "B.Fab")
		)
		(fp_line
			(start -0.120396 0.2794)
			(end 0.12065 0.2794)
			(stroke
				(width 0.1)
				(type default)
			)
			(layer "B.Fab")
		)
		(fp_line
			(start -0.12065 -0.2794)
			(end -0.12065 -0.3048)
			(stroke
				(width 0.1)
				(type default)
			)
			(layer "B.Fab")
		)
		(fp_line
			(start -0.12065 -0.3048)
			(end -0.67945 -0.3048)
			(stroke
				(width 0.1)
				(type default)
			)
			(layer "B.Fab")
		)
		(fp_line
			(start -0.67945 0.3048)
			(end -0.120396 0.3048)
			(stroke
				(width 0.1)
				(type default)
			)
			(layer "B.Fab")
		)
		(fp_line
			(start -0.67945 -0.3048)
			(end -0.67945 0.3048)
			(stroke
				(width 0.1)
				(type default)
			)
			(layer "B.Fab")
		)
		(pad "1" smd circle
			(at 0.40005 0)
			(size 0 0)
			(layers "B.Cu" "B.Mask" "B.Paste")
			(net "P3V3_AUX")
		)
		(pad "2" smd circle
			(at -0.40005 0)
			(size 0 0)
			(layers "B.Cu" "B.Mask" "B.Paste")
			(net "GND")
		)
	)
	(footprint ""
		(layer "B.Cu")
		(at 45.260006 -114.324892 180)
		(property "Reference" "GF1"
			(at 30.591506 -4.763262 0)
			(unlocked yes)
			(layer "B.SilkS")
			(effects
				(font
					(size 0.7874 0.5842)
					(thickness 0.1524)
				)
				(justify left mirror)
			)
		)
		(property "Value" ""
			(at 0 0 0)
			(layer "B.Fab")
			(effects
				(font
					(size 1.27 1.27)
				)
				(justify mirror)
			)
		)
		(duplicate_pad_numbers_are_jumpers no)
		(fp_line
			(start 31.99511 5.32511)
			(end 31.245048 6.074918)
			(stroke
				(width 0.1524)
				(type default)
			)
			(layer "F.SilkS")
		)
		(fp_line
			(start 31.99511 0.07493)
			(end 31.99511 5.32511)
			(stroke
				(width 0.1524)
				(type default)
			)
			(layer "F.SilkS")
		)
		(fp_line
			(start 31.99511 -3.925062)
			(end 31.848806 -3.925062)
			(stroke
				(width 0.1524)
				(type default)
			)
			(layer "F.SilkS")
		)
		(fp_line
			(start 31.245048 6.074918)
			(end 14.385036 6.074918)
			(stroke
				(width 0.1524)
				(type default)
			)
			(layer "F.SilkS")
		)
		(fp_line
			(start 30.832806 -3.925062)
			(end 26.718006 -3.925062)
			(stroke
				(width 0.1524)
				(type default)
			)
			(layer "F.SilkS")
		)
		(fp_line
			(start 25.498806 -3.925062)
			(end 23.289006 -3.925062)
			(stroke
				(width 0.1524)
				(type default)
			)
			(layer "F.SilkS")
		)
		(fp_line
			(start 22.273006 -3.925062)
			(end 19.479006 -3.925062)
			(stroke
				(width 0.1524)
				(type default)
			)
			(layer "F.SilkS")
		)
		(fp_line
			(start 18.590006 -3.925062)
			(end 2.588006 -3.925062)
			(stroke
				(width 0.1524)
				(type default)
			)
			(layer "F.SilkS")
		)
		(fp_line
			(start 14.385036 6.074918)
			(end 13.634974 5.32511)
			(stroke
				(width 0.1524)
				(type default)
			)
			(layer "F.SilkS")
		)
		(fp_line
			(start 13.634974 5.32511)
			(end 13.634974 0.450088)
			(stroke
				(width 0.1524)
				(type default)
			)
			(layer "F.SilkS")
		)
		(fp_line
			(start 10.884916 5.32511)
			(end 10.135108 6.074918)
			(stroke
				(width 0.1524)
				(type default)
			)
			(layer "F.SilkS")
		)
		(fp_line
			(start 10.884916 0.450088)
			(end 10.884916 5.32511)
			(stroke
				(width 0.1524)
				(type default)
			)
			(layer "F.SilkS")
		)
		(fp_line
			(start 10.135108 6.074918)
			(end 1.674876 6.074918)
			(stroke
				(width 0.1524)
				(type default)
			)
			(layer "F.SilkS")
		)
		(fp_line
			(start 1.826006 -3.925062)
			(end -12.778994 -3.925062)
			(stroke
				(width 0.1524)
				(type default)
			)
			(layer "F.SilkS")
		)
		(fp_line
			(start 1.674876 6.074918)
			(end 0.925068 5.32511)
			(stroke
				(width 0.1524)
				(type default)
			)
			(layer "F.SilkS")
		)
		(fp_line
			(start 0.925068 5.32511)
			(end 0.925068 0)
			(stroke
				(width 0.1524)
				(type default)
			)
			(layer "F.SilkS")
		)
		(fp_line
			(start -0.925068 5.32511)
			(end -1.674876 6.074918)
			(stroke
				(width 0.1524)
				(type default)
			)
			(layer "F.SilkS")
		)
		(fp_line
			(start -0.925068 0)
			(end -0.925068 5.32511)
			(stroke
				(width 0.1524)
				(type default)
			)
			(layer "F.SilkS")
		)
		(fp_line
			(start -1.674876 6.074918)
			(end -18.524982 6.074918)
			(stroke
				(width 0.1524)
				(type default)
			)
			(layer "F.SilkS")
		)
		(fp_line
			(start -16.842994 -3.925062)
			(end -20.652994 -3.925062)
			(stroke
				(width 0.1524)
				(type default)
			)
			(layer "F.SilkS")
		)
		(fp_line
			(start -18.524982 6.074918)
			(end -19.275044 5.32511)
			(stroke
				(width 0.1524)
				(type default)
			)
			(layer "F.SilkS")
		)
		(fp_line
			(start -19.275044 5.32511)
			(end -19.275044 0.199898)
			(stroke
				(width 0.1524)
				(type default)
			)
			(layer "F.SilkS")
		)
		(fp_line
			(start -21.524976 5.32511)
			(end -22.275038 6.074918)
			(stroke
				(width 0.1524)
				(type default)
			)
			(layer "F.SilkS")
		)
		(fp_line
			(start -21.524976 0.199898)
			(end -21.524976 5.32511)
			(stroke
				(width 0.1524)
				(type default)
			)
			(layer "F.SilkS")
		)
		(fp_line
			(start -21.668994 -3.925062)
			(end -24.158194 -3.925062)
			(stroke
				(width 0.1524)
				(type default)
			)
			(layer "F.SilkS")
		)
		(fp_line
			(start -22.275038 6.074918)
			(end -30.729936 6.074918)
			(stroke
				(width 0.1524)
				(type default)
			)
			(layer "F.SilkS")
		)
		(fp_line
			(start -24.869394 -3.925062)
			(end -26.621994 -3.925062)
			(stroke
				(width 0.1524)
				(type default)
			)
			(layer "F.SilkS")
		)
		(fp_line
			(start -27.307794 -3.925062)
			(end -28.907994 -3.925062)
			(stroke
				(width 0.1524)
				(type default)
			)
			(layer "F.SilkS")
		)
		(fp_line
			(start -30.729936 6.074918)
			(end -31.479998 5.32511)
			(stroke
				(width 0.1524)
				(type default)
			)
			(layer "F.SilkS")
		)
		(fp_line
			(start -31.479998 5.32511)
			(end -31.479998 0.07493)
			(stroke
				(width 0.1524)
				(type default)
			)
			(layer "F.SilkS")
		)
		(fp_arc
			(start 12.260072 -0.925068)
			(mid 13.232377 -0.522289)
			(end 13.634974 0.450088)
			(stroke
				(width 0.1524)
				(type default)
			)
			(layer "F.SilkS")
		)
		(fp_arc
			(start 10.884916 0.450088)
			(mid 11.287695 -0.522293)
			(end 12.260072 -0.925068)
			(stroke
				(width 0.1524)
				(type default)
			)
			(layer "F.SilkS")
		)
		(fp_arc
			(start 0 -0.925068)
			(mid 0.654129 -0.654124)
			(end 0.925068 0)
			(stroke
				(width 0.1524)
				(type default)
			)
			(layer "F.SilkS")
		)
		(fp_arc
			(start -0.925068 0)
			(mid -0.654119 -0.654119)
			(end 0 -0.925068)
			(stroke
				(width 0.1524)
				(type default)
			)
			(layer "F.SilkS")
		)
		(fp_arc
			(start -20.40001 -0.925068)
			(mid -19.604525 -0.595579)
			(end -19.275044 0.199898)
			(stroke
				(width 0.1524)
				(type default)
			)
			(layer "F.SilkS")
		)
		(fp_arc
			(start -21.524976 0.199898)
			(mid -21.195479 -0.595572)
			(end -20.40001 -0.925068)
			(stroke
				(width 0.1524)
				(type default)
			)
			(layer "F.SilkS")
		)
		(fp_line
			(start 31.99511 5.32511)
			(end 31.245048 6.074918)
			(stroke
				(width 0.1524)
				(type default)
			)
			(layer "B.SilkS")
		)
		(fp_line
			(start 31.99511 0.07493)
			(end 31.99511 5.32511)
			(stroke
				(width 0.1524)
				(type default)
			)
			(layer "B.SilkS")
		)
		(fp_line
			(start 31.99511 -3.925062)
			(end 29.816806 -3.925062)
			(stroke
				(width 0.1524)
				(type default)
			)
			(layer "B.SilkS")
		)
		(fp_line
			(start 31.245048 6.074918)
			(end 14.385036 6.074918)
			(stroke
				(width 0.1524)
				(type default)
			)
			(layer "B.SilkS")
		)
		(fp_line
			(start 28.978606 -3.925062)
			(end 21.790406 -3.925062)
			(stroke
				(width 0.1524)
				(type default)
			)
			(layer "B.SilkS")
		)
		(fp_line
			(start 20.520406 -3.925062)
			(end 13.09116 -3.925062)
			(stroke
				(width 0.1524)
				(type default)
			)
			(layer "B.SilkS")
		)
		(fp_line
			(start 14.385036 6.074918)
			(end 13.634974 5.32511)
			(stroke
				(width 0.1524)
				(type default)
			)
			(layer "B.SilkS")
		)
		(fp_line
			(start 13.634974 5.32511)
			(end 13.634974 0.450088)
			(stroke
				(width 0.1524)
				(type default)
			)
			(layer "B.SilkS")
		)
		(fp_line
			(start 12.001246 -3.925062)
			(end 11.340084 -3.925062)
			(stroke
				(width 0.1524)
				(type default)
			)
			(layer "B.SilkS")
		)
		(fp_line
			(start 10.884916 5.32511)
			(end 10.135108 6.074918)
			(stroke
				(width 0.1524)
				(type default)
			)
			(layer "B.SilkS")
		)
		(fp_line
			(start 10.884916 0.450088)
			(end 10.884916 5.32511)
			(stroke
				(width 0.1524)
				(type default)
			)
			(layer "B.SilkS")
		)
		(fp_line
			(start 10.513568 -3.925062)
			(end 9.815576 -3.925062)
			(stroke
				(width 0.1524)
				(type default)
			)
			(layer "B.SilkS")
		)
		(fp_line
			(start 10.135108 6.074918)
			(end 1.674876 6.074918)
			(stroke
				(width 0.1524)
				(type default)
			)
			(layer "B.SilkS")
		)
		(fp_line
			(start 9.136126 -3.925062)
			(end 7.185406 -3.925062)
			(stroke
				(width 0.1524)
				(type default)
			)
			(layer "B.SilkS")
		)
		(fp_line
			(start 6.169406 -3.925062)
			(end 3.858006 -3.925062)
			(stroke
				(width 0.1524)
				(type default)
			)
			(layer "B.SilkS")
		)
		(fp_line
			(start 2.664206 -3.925062)
			(end 2.029206 -3.925062)
			(stroke
				(width 0.1524)
				(type default)
			)
			(layer "B.SilkS")
		)
		(fp_line
			(start 1.674876 6.074918)
			(end 0.925068 5.32511)
			(stroke
				(width 0.1524)
				(type default)
			)
			(layer "B.SilkS")
		)
		(fp_line
			(start 0.925068 5.32511)
			(end 0.925068 0)
			(stroke
				(width 0.1524)
				(type default)
			)
			(layer "B.SilkS")
		)
		(fp_line
			(start 0.860806 -3.925062)
			(end -7.063994 -3.925062)
			(stroke
				(width 0.1524)
				(type default)
			)
			(layer "B.SilkS")
		)
		(fp_line
			(start -0.925068 5.32511)
			(end -1.674876 6.074918)
			(stroke
				(width 0.1524)
				(type default)
			)
			(layer "B.SilkS")
		)
		(fp_line
			(start -0.925068 0)
			(end -0.925068 5.32511)
			(stroke
				(width 0.1524)
				(type default)
			)
			(layer "B.SilkS")
		)
		(fp_line
			(start -1.674876 6.074918)
			(end -18.524982 6.074918)
			(stroke
				(width 0.1524)
				(type default)
			)
			(layer "B.SilkS")
		)
		(fp_line
			(start -8.079994 -3.925062)
			(end -10.238994 -3.925062)
			(stroke
				(width 0.1524)
				(type default)
			)
			(layer "B.SilkS")
		)
		(fp_line
			(start -11.254994 -3.925062)
			(end -12.829794 -3.925062)
			(stroke
				(width 0.1524)
				(type default)
			)
			(layer "B.SilkS")
		)
		(fp_line
			(start -17.198594 -3.925062)
			(end -22.185376 -3.925062)
			(stroke
				(width 0.1524)
				(type default)
			)
			(layer "B.SilkS")
		)
		(fp_line
			(start -18.524982 6.074918)
			(end -19.275044 5.32511)
			(stroke
				(width 0.1524)
				(type default)
			)
			(layer "B.SilkS")
		)
		(fp_line
			(start -19.275044 5.32511)
			(end -19.275044 0.199898)
			(stroke
				(width 0.1524)
				(type default)
			)
			(layer "B.SilkS")
		)
		(fp_line
			(start -21.524976 5.32511)
			(end -22.275038 6.074918)
			(stroke
				(width 0.1524)
				(type default)
			)
			(layer "B.SilkS")
		)
		(fp_line
			(start -21.524976 0.199898)
			(end -21.524976 5.32511)
			(stroke
				(width 0.1524)
				(type default)
			)
			(layer "B.SilkS")
		)
		(fp_line
			(start -22.275038 6.074918)
			(end -30.729936 6.074918)
			(stroke
				(width 0.1524)
				(type default)
			)
			(layer "B.SilkS")
		)
		(fp_line
			(start -22.926294 -3.925062)
			(end -29.009594 -3.925062)
			(stroke
				(width 0.1524)
				(type default)
			)
			(layer "B.SilkS")
		)
		(fp_line
			(start -30.729936 6.074918)
			(end -31.479998 5.32511)
			(stroke
				(width 0.1524)
				(type default)
			)
			(layer "B.SilkS")
		)
		(fp_line
			(start -31.479998 5.32511)
			(end -31.479998 0.07493)
			(stroke
				(width 0.1524)
				(type default)
			)
			(layer "B.SilkS")
		)
		(fp_arc
			(start 12.260072 -0.925068)
			(mid 13.232377 -0.522289)
			(end 13.634974 0.450088)
			(stroke
				(width 0.1524)
				(type default)
			)
			(layer "B.SilkS")
		)
		(fp_arc
			(start 10.884916 0.450088)
			(mid 11.287695 -0.522293)
			(end 12.260072 -0.925068)
			(stroke
				(width 0.1524)
				(type default)
			)
			(layer "B.SilkS")
		)
		(fp_arc
			(start 0 -0.925068)
			(mid 0.654129 -0.654124)
			(end 0.925068 0)
			(stroke
				(width 0.1524)
				(type default)
			)
			(layer "B.SilkS")
		)
		(fp_arc
			(start -0.925068 0)
			(mid -0.654119 -0.654119)
			(end 0 -0.925068)
			(stroke
				(width 0.1524)
				(type default)
			)
			(layer "B.SilkS")
		)
		(fp_arc
			(start -20.40001 -0.925068)
			(mid -19.604525 -0.595579)
			(end -19.275044 0.199898)
			(stroke
				(width 0.1524)
				(type default)
			)
			(layer "B.SilkS")
		)
		(fp_arc
			(start -21.524976 0.199898)
			(mid -21.195479 -0.595572)
			(end -20.40001 -0.925068)
			(stroke
				(width 0.1524)
				(type default)
			)
			(layer "B.SilkS")
		)
		(fp_line
			(start 31.99511 5.32511)
			(end 31.245048 6.074918)
			(stroke
				(width 0.1)
				(type default)
			)
			(layer "B.Fab")
		)
		(fp_line
			(start 31.99511 0.07493)
			(end 31.99511 5.32511)
			(stroke
				(width 0.1)
				(type default)
			)
			(layer "B.Fab")
		)
		(fp_line
			(start 31.99511 -3.925062)
			(end -31.479998 -3.925062)
			(stroke
				(width 0.1)
				(type default)
			)
			(layer "B.Fab")
		)
		(fp_line
			(start 31.245048 6.074918)
			(end 14.385036 6.074918)
			(stroke
				(width 0.1)
				(type default)
			)
			(layer "B.Fab")
		)
		(fp_line
			(start 14.385036 6.074918)
			(end 13.634974 5.32511)
			(stroke
				(width 0.1)
				(type default)
			)
			(layer "B.Fab")
		)
		(fp_line
			(start 13.634974 5.32511)
			(end 13.634974 0.450088)
			(stroke
				(width 0.1)
				(type default)
			)
			(layer "B.Fab")
		)
		(fp_line
			(start 10.884916 5.32511)
			(end 10.135108 6.074918)
			(stroke
				(width 0.1)
				(type default)
			)
			(layer "B.Fab")
		)
		(fp_line
			(start 10.884916 0.450088)
			(end 10.884916 5.32511)
			(stroke
				(width 0.1)
				(type default)
			)
			(layer "B.Fab")
		)
		(fp_line
			(start 10.135108 6.074918)
			(end 1.674876 6.074918)
			(stroke
				(width 0.1)
				(type default)
			)
			(layer "B.Fab")
		)
		(fp_line
			(start 1.674876 6.074918)
			(end 0.925068 5.32511)
			(stroke
				(width 0.1)
				(type default)
			)
			(layer "B.Fab")
		)
		(fp_line
			(start 0.925068 5.32511)
			(end 0.925068 0)
			(stroke
				(width 0.1)
				(type default)
			)
			(layer "B.Fab")
		)
		(fp_line
			(start -0.925068 5.32511)
			(end -1.674876 6.074918)
			(stroke
				(width 0.1)
				(type default)
			)
			(layer "B.Fab")
		)
		(fp_line
			(start -0.925068 0)
			(end -0.925068 5.32511)
			(stroke
				(width 0.1)
				(type default)
			)
			(layer "B.Fab")
		)
		(fp_line
			(start -1.674876 6.074918)
			(end -18.524982 6.074918)
			(stroke
				(width 0.1)
				(type default)
			)
			(layer "B.Fab")
		)
		(fp_line
			(start -18.524982 6.074918)
			(end -19.275044 5.32511)
			(stroke
				(width 0.1)
				(type default)
			)
			(layer "B.Fab")
		)
		(fp_line
			(start -19.275044 5.32511)
			(end -19.275044 0.199898)
			(stroke
				(width 0.1)
				(type default)
			)
			(layer "B.Fab")
		)
		(fp_line
			(start -21.524976 5.32511)
			(end -22.275038 6.074918)
			(stroke
				(width 0.1)
				(type default)
			)
			(layer "B.Fab")
		)
		(fp_line
			(start -21.524976 0.199898)
			(end -21.524976 5.32511)
			(stroke
				(width 0.1)
				(type default)
			)
			(layer "B.Fab")
		)
		(fp_line
			(start -22.275038 6.074918)
			(end -30.729936 6.074918)
			(stroke
				(width 0.1)
				(type default)
			)
			(layer "B.Fab")
		)
		(fp_line
			(start -30.729936 6.074918)
			(end -31.479998 5.32511)
			(stroke
				(width 0.1)
				(type default)
			)
			(layer "B.Fab")
		)
		(fp_line
			(start -31.479998 5.32511)
			(end -31.479998 0.07493)
			(stroke
				(width 0.1)
				(type default)
			)
			(layer "B.Fab")
		)
		(fp_arc
			(start 12.260072 -0.925068)
			(mid 13.232377 -0.522289)
			(end 13.634974 0.450088)
			(stroke
				(width 0.1)
				(type default)
			)
			(layer "B.Fab")
		)
		(fp_arc
			(start 10.884916 0.450088)
			(mid 11.287695 -0.522293)
			(end 12.260072 -0.925068)
			(stroke
				(width 0.1)
				(type default)
			)
			(layer "B.Fab")
		)
		(fp_arc
			(start 0 -0.925068)
			(mid 0.654129 -0.654124)
			(end 0.925068 0)
			(stroke
				(width 0.1)
				(type default)
			)
			(layer "B.Fab")
		)
		(fp_arc
			(start -0.925068 0)
			(mid -0.654119 -0.654119)
			(end 0 -0.925068)
			(stroke
				(width 0.1)
				(type default)
			)
			(layer "B.Fab")
		)
		(fp_arc
			(start -20.40001 -0.925068)
			(mid -19.604525 -0.595579)
			(end -19.275044 0.199898)
			(stroke
				(width 0.1)
				(type default)
			)
			(layer "B.Fab")
		)
		(fp_arc
			(start -21.524976 0.199898)
			(mid -21.195479 -0.595572)
			(end -20.40001 -0.925068)
			(stroke
				(width 0.1)
				(type default)
			)
			(layer "B.Fab")
		)
		(fp_line
			(start 31.99511 5.32511)
			(end 31.245048 6.074918)
			(stroke
				(width 0.1)
				(type default)
			)
			(layer "F.Fab")
		)
		(fp_line
			(start 31.99511 0.07493)
			(end 31.99511 5.32511)
			(stroke
				(width 0.1)
				(type default)
			)
			(layer "F.Fab")
		)
		(fp_line
			(start 31.99511 -3.925062)
			(end -31.479998 -3.925062)
			(stroke
				(width 0.1)
				(type default)
			)
			(layer "F.Fab")
		)
		(fp_line
			(start 31.245048 6.074918)
			(end 14.385036 6.074918)
			(stroke
				(width 0.1)
				(type default)
			)
			(layer "F.Fab")
		)
		(fp_line
			(start 14.385036 6.074918)
			(end 13.634974 5.32511)
			(stroke
				(width 0.1)
				(type default)
			)
			(layer "F.Fab")
		)
		(fp_line
			(start 13.634974 5.32511)
			(end 13.634974 0.450088)
			(stroke
				(width 0.1)
				(type default)
			)
			(layer "F.Fab")
		)
		(fp_line
			(start 10.884916 5.32511)
			(end 10.135108 6.074918)
			(stroke
				(width 0.1)
				(type default)
			)
			(layer "F.Fab")
		)
		(fp_line
			(start 10.884916 0.450088)
			(end 10.884916 5.32511)
			(stroke
				(width 0.1)
				(type default)
			)
			(layer "F.Fab")
		)
		(fp_line
			(start 10.135108 6.074918)
			(end 1.674876 6.074918)
			(stroke
				(width 0.1)
				(type default)
			)
			(layer "F.Fab")
		)
		(fp_line
			(start 1.674876 6.074918)
			(end 0.925068 5.32511)
			(stroke
				(width 0.1)
				(type default)
			)
			(layer "F.Fab")
		)
		(fp_line
			(start 0.925068 5.32511)
			(end 0.925068 0)
			(stroke
				(width 0.1)
				(type default)
			)
			(layer "F.Fab")
		)
		(fp_line
			(start -0.925068 5.32511)
			(end -1.674876 6.074918)
			(stroke
				(width 0.1)
				(type default)
			)
			(layer "F.Fab")
		)
		(fp_line
			(start -0.925068 0)
			(end -0.925068 5.32511)
			(stroke
				(width 0.1)
				(type default)
			)
			(layer "F.Fab")
		)
		(fp_line
			(start -1.674876 6.074918)
			(end -18.524982 6.074918)
			(stroke
				(width 0.1)
				(type default)
			)
			(layer "F.Fab")
		)
		(fp_line
			(start -18.524982 6.074918)
			(end -19.275044 5.32511)
			(stroke
				(width 0.1)
				(type default)
			)
			(layer "F.Fab")
		)
		(fp_line
			(start -19.275044 5.32511)
			(end -19.275044 0.199898)
			(stroke
				(width 0.1)
				(type default)
			)
			(layer "F.Fab")
		)
		(fp_line
			(start -21.524976 5.32511)
			(end -22.275038 6.074918)
			(stroke
				(width 0.1)
				(type default)
			)
			(layer "F.Fab")
		)
		(fp_line
			(start -21.524976 0.199898)
			(end -21.524976 5.32511)
			(stroke
				(width 0.1)
				(type default)
			)
			(layer "F.Fab")
		)
		(fp_line
			(start -22.275038 6.074918)
			(end -30.729936 6.074918)
			(stroke
				(width 0.1)
				(type default)
			)
			(layer "F.Fab")
		)
		(fp_line
			(start -30.729936 6.074918)
			(end -31.479998 5.32511)
			(stroke
				(width 0.1)
				(type default)
			)
			(layer "F.Fab")
		)
		(fp_line
			(start -31.479998 5.32511)
			(end -31.479998 0.07493)
			(stroke
				(width 0.1)
				(type default)
			)
			(layer "F.Fab")
		)
		(fp_arc
			(start 12.260072 -0.925068)
			(mid 13.232377 -0.522289)
			(end 13.634974 0.450088)
			(stroke
				(width 0.1)
				(type default)
			)
			(layer "F.Fab")
		)
		(fp_arc
			(start 10.884916 0.450088)
			(mid 11.287695 -0.522293)
			(end 12.260072 -0.925068)
			(stroke
				(width 0.1)
				(type default)
			)
			(layer "F.Fab")
		)
		(fp_arc
			(start 0 -0.925068)
			(mid 0.654129 -0.654124)
			(end 0.925068 0)
			(stroke
				(width 0.1)
				(type default)
			)
			(layer "F.Fab")
		)
		(fp_arc
			(start -0.925068 0)
			(mid -0.654119 -0.654119)
			(end 0 -0.925068)
			(stroke
				(width 0.1)
				(type default)
			)
			(layer "F.Fab")
		)
		(fp_arc
			(start -20.40001 -0.925068)
			(mid -19.604525 -0.595579)
			(end -19.275044 0.199898)
			(stroke
				(width 0.1)
				(type default)
			)
			(layer "F.Fab")
		)
		(fp_arc
			(start -21.524976 0.199898)
			(mid -21.195479 -0.595572)
			(end -20.40001 -0.925068)
			(stroke
				(width 0.1)
				(type default)
			)
			(layer "F.Fab")
		)
		(fp_text user "B70"
			(at 29.337 -3.21183 180)
			(unlocked yes)
			(layer "F.SilkS")
			(effects
				(font
					(size 0.7874 0.5842)
					(thickness 0.1524)
				)
			)
		)
		(fp_text user "B43"
			(at 15.2146 -3.03403 180)
			(unlocked yes)
			(layer "F.SilkS")
			(effects
				(font
					(size 0.7874 0.5842)
					(thickness 0.1524)
				)
			)
		)
		(fp_text user "B42"
			(at 9.525 -3.03403 180)
			(unlocked yes)
			(layer "F.SilkS")
			(effects
				(font
					(size 0.7874 0.5842)
					(thickness 0.1524)
				)
			)
		)
		(fp_text user "B29"
			(at 2.1844 -3.03403 180)
			(unlocked yes)
			(layer "F.SilkS")
			(effects
				(font
					(size 0.7874 0.5842)
					(thickness 0.1524)
				)
			)
		)
		(fp_text user "B28"
			(at -2.4892 -3.03403 180)
			(unlocked yes)
			(layer "F.SilkS")
			(effects
				(font
					(size 0.7874 0.5842)
					(thickness 0.1524)
				)
			)
		)
		(fp_text user "B1"
			(at -18.2626 -3.03403 180)
			(unlocked yes)
			(layer "F.SilkS")
			(effects
				(font
					(size 0.7874 0.5842)
					(thickness 0.1524)
				)
			)
		)
		(fp_text user "OB14"
			(at -23.241 -3.03403 180)
			(unlocked yes)
			(layer "F.SilkS")
			(effects
				(font
					(size 0.7874 0.5842)
					(thickness 0.1524)
				)
			)
		)
		(fp_text user "OB1"
			(at -30.3784 -2.81559 180)
			(unlocked yes)
			(layer "F.SilkS")
			(effects
				(font
					(size 0.7874 0.5842)
					(thickness 0.1524)
				)
			)
		)
		(fp_text user "A70"
			(at 30.9118 -3.16103 180)
			(unlocked yes)
			(layer "B.SilkS")
			(effects
				(font
					(size 0.7874 0.5842)
					(thickness 0.1524)
				)
				(justify mirror)
			)
		)
		(fp_text user "A43"
			(at 15.2146 -3.03403 180)
			(unlocked yes)
			(layer "B.SilkS")
			(effects
				(font
					(size 0.7874 0.5842)
					(thickness 0.1524)
				)
				(justify mirror)
			)
		)
		(fp_text user "A42"
			(at 9.525 -3.03403 180)
			(unlocked yes)
			(layer "B.SilkS")
			(effects
				(font
					(size 0.7874 0.5842)
					(thickness 0.1524)
				)
				(justify mirror)
			)
		)
		(fp_text user "A29"
			(at 2.1844 -3.03403 180)
			(unlocked yes)
			(layer "B.SilkS")
			(effects
				(font
					(size 0.7874 0.5842)
					(thickness 0.1524)
				)
				(justify mirror)
			)
		)
		(fp_text user "A28"
			(at -2.4892 -3.03403 180)
			(unlocked yes)
			(layer "B.SilkS")
			(effects
				(font
					(size 0.7874 0.5842)
					(thickness 0.1524)
				)
				(justify mirror)
			)
		)
		(fp_text user "A1"
			(at -18.2626 -3.03403 180)
			(unlocked yes)
			(layer "B.SilkS")
			(effects
				(font
					(size 0.7874 0.5842)
					(thickness 0.1524)
				)
				(justify mirror)
			)
		)
		(fp_text user "OA14"
			(at -23.241 -3.03403 180)
			(unlocked yes)
			(layer "B.SilkS")
			(effects
				(font
					(size 0.7874 0.5842)
					(thickness 0.1524)
				)
				(justify mirror)
			)
		)
		(fp_text user "OA1"
			(at -30.3784 -3.03403 180)
			(unlocked yes)
			(layer "B.SilkS")
			(effects
				(font
					(size 0.7874 0.5842)
					(thickness 0.1524)
				)
				(justify mirror)
			)
		)
		(fp_text user "A70"
			(at 30.4546 -3.03403 180)
			(unlocked yes)
			(layer "B.Fab")
			(effects
				(font
					(size 0.7874 0.5842)
					(thickness 0.1524)
				)
				(justify mirror)
			)
		)
		(fp_text user "A43"
			(at 15.2146 -3.03403 180)
			(unlocked yes)
			(layer "B.Fab")
			(effects
				(font
					(size 0.7874 0.5842)
					(thickness 0.1524)
				)
				(justify mirror)
			)
		)
		(fp_text user "A42"
			(at 9.525 -3.03403 180)
			(unlocked yes)
			(layer "B.Fab")
			(effects
				(font
					(size 0.7874 0.5842)
					(thickness 0.1524)
				)
				(justify mirror)
			)
		)
		(fp_text user "A29"
			(at 2.1844 -3.03403 180)
			(unlocked yes)
			(layer "B.Fab")
			(effects
				(font
					(size 0.7874 0.5842)
					(thickness 0.1524)
				)
				(justify mirror)
			)
		)
		(fp_text user "A28"
			(at -2.4892 -3.03403 180)
			(unlocked yes)
			(layer "B.Fab")
			(effects
				(font
					(size 0.7874 0.5842)
					(thickness 0.1524)
				)
				(justify mirror)
			)
		)
		(fp_text user "A1"
			(at -18.2626 -3.03403 180)
			(unlocked yes)
			(layer "B.Fab")
			(effects
				(font
					(size 0.7874 0.5842)
					(thickness 0.1524)
				)
				(justify mirror)
			)
		)
		(fp_text user "OA14"
			(at -23.241 -3.03403 180)
			(unlocked yes)
			(layer "B.Fab")
			(effects
				(font
					(size 0.7874 0.5842)
					(thickness 0.1524)
				)
				(justify mirror)
			)
		)
		(fp_text user "OA1"
			(at -30.3784 -3.03403 180)
			(unlocked yes)
			(layer "B.Fab")
			(effects
				(font
					(size 0.7874 0.5842)
					(thickness 0.1524)
				)
				(justify mirror)
			)
		)
		(fp_text user "B70"
			(at 30.4546 -3.03403 180)
			(unlocked yes)
			(layer "F.Fab")
			(effects
				(font
					(size 0.7874 0.5842)
					(thickness 0.1524)
				)
			)
		)
		(fp_text user "B43"
			(at 15.2146 -3.03403 180)
			(unlocked yes)
			(layer "F.Fab")
			(effects
				(font
					(size 0.7874 0.5842)
					(thickness 0.1524)
				)
			)
		)
		(fp_text user "B42"
			(at 9.525 -3.03403 180)
			(unlocked yes)
			(layer "F.Fab")
			(effects
				(font
					(size 0.7874 0.5842)
					(thickness 0.1524)
				)
			)
		)
		(fp_text user "B29"
			(at 2.1844 -3.03403 180)
			(unlocked yes)
			(layer "F.Fab")
			(effects
				(font
					(size 0.7874 0.5842)
					(thickness 0.1524)
				)
			)
		)
		(fp_text user "B28"
			(at -2.4892 -3.03403 180)
			(unlocked yes)
			(layer "F.Fab")
			(effects
				(font
					(size 0.7874 0.5842)
					(thickness 0.1524)
				)
			)
		)
		(fp_text user "B1"
			(at -18.2626 -3.03403 180)
			(unlocked yes)
			(layer "F.Fab")
			(effects
				(font
					(size 0.7874 0.5842)
					(thickness 0.1524)
				)
			)
		)
		(fp_text user "OB14"
			(at -23.241 -3.03403 180)
			(unlocked yes)
			(layer "F.Fab")
			(effects
				(font
					(size 0.7874 0.5842)
					(thickness 0.1524)
				)
			)
		)
		(fp_text user "OB1"
			(at -30.3784 -3.03403 180)
			(unlocked yes)
			(layer "F.Fab")
			(effects
				(font
					(size 0.7874 0.5842)
					(thickness 0.1524)
				)
			)
		)
		(pad "A1" smd rect
			(at -18.204942 4.13512)
			(size 0.381 2.1336)
			(layers "B.Cu" "B.Mask" "B.Paste")
			(net "SMB_BMC_MM14_R1_SCL")
		)
		(pad "A2" smd rect
			(at -17.604994 4.13512)
			(size 0.381 2.1336)
			(layers "B.Cu" "B.Mask" "B.Paste")
			(net "SMB_BMC_MM14_R1_SDA")
		)
		(pad "A3" smd rect
			(at -17.005046 4.13512)
			(size 0.381 2.1336)
			(layers "B.Cu" "B.Mask" "B.Paste")
			(net "SMB_BMC_MM1_SCL")
		)
		(pad "A4" smd rect
			(at -16.405098 4.13512)
			(size 0.381 2.1336)
			(layers "B.Cu" "B.Mask" "B.Paste")
			(net "SMB_BMC_MM1_SDA")
		)
		(pad "A5" smd rect
			(at -15.804896 4.13512)
			(size 0.381 2.1336)
			(layers "B.Cu" "B.Mask" "B.Paste")
			(net "SMB_BMC_MM2_SCL_R1")
		)
		(pad "A6" smd rect
			(at -15.204948 4.13512)
			(size 0.381 2.1336)
			(layers "B.Cu" "B.Mask" "B.Paste")
			(net "SMB_BMC_MM2_SDA")
		)
		(pad "A7" smd rect
			(at -14.605 3.934968)
			(size 0.381 1.7272)
			(layers "B.Cu" "B.Mask" "B.Paste")
			(net "SMB_BMC_MM3_SCL")
		)
		(pad "A8" smd rect
			(at -14.005052 3.934968)
			(size 0.381 1.7272)
			(layers "B.Cu" "B.Mask" "B.Paste")
			(net "SMB_BMC_MM3_SDA")
		)
		(pad "A9" smd rect
			(at -13.405104 3.934968)
			(size 0.381 1.7272)
			(layers "B.Cu" "B.Mask" "B.Paste")
			(net "SMB_BMC_MM4_SCL")
		)
		(pad "A10" smd rect
			(at -12.804902 3.934968)
			(size 0.381 1.7272)
			(layers "B.Cu" "B.Mask" "B.Paste")
			(net "SMB_BMC_MM4_SDA")
		)
		(pad "A11" smd rect
			(at -12.204954 3.934968)
			(size 0.381 1.7272)
			(layers "B.Cu" "B.Mask" "B.Paste")
			(net "SMB_BMC_MM5_SCL")
		)
		(pad "A12" smd rect
			(at -11.605006 3.934968)
			(size 0.381 1.7272)
			(layers "B.Cu" "B.Mask" "B.Paste")
			(net "SMB_BMC_MM5_SDA")
		)
		(pad "A13" smd rect
			(at -11.005058 4.13512)
			(size 0.381 2.1336)
			(layers "B.Cu" "B.Mask" "B.Paste")
			(net "GND")
		)
		(pad "A14" smd rect
			(at -10.40511 3.934968)
			(size 0.381 1.7272)
			(layers "B.Cu" "B.Mask" "B.Paste")
			(net "CLK_100M_PCH_DP")
		)
		(pad "A15" smd rect
			(at -9.804908 3.934968)
			(size 0.381 1.7272)
			(layers "B.Cu" "B.Mask" "B.Paste")
			(net "CLK_100M_PCH_DN")
		)
		(pad "A16" smd rect
			(at -9.20496 4.13512)
			(size 0.381 2.1336)
			(layers "B.Cu" "B.Mask" "B.Paste")
			(net "GND")
		)
		(pad "A17" smd rect
			(at -8.605012 3.934968)
			(size 0.381 1.7272)
			(layers "B.Cu" "B.Mask" "B.Paste")
			(net "P2E_PCH_RX_DP")
		)
		(pad "A18" smd rect
			(at -8.005064 3.934968)
			(size 0.381 1.7272)
			(layers "B.Cu" "B.Mask" "B.Paste")
			(net "P2E_PCH_RX_DN")
		)
		(pad "A19" smd rect
			(at -7.405116 4.13512)
			(size 0.381 2.1336)
			(layers "B.Cu" "B.Mask" "B.Paste")
			(net "GND")
		)
		(pad "A20" smd rect
			(at -6.804914 3.934968)
			(size 0.381 1.7272)
			(layers "B.Cu" "B.Mask" "B.Paste")
			(net "P2E_PCH_TX_C_DP")
		)
		(pad "A21" smd rect
			(at -6.204966 3.934968)
			(size 0.381 1.7272)
			(layers "B.Cu" "B.Mask" "B.Paste")
			(net "P2E_PCH_TX_C_DN")
		)
		(pad "A22" smd rect
			(at -5.605018 4.13512)
			(size 0.381 2.1336)
			(layers "B.Cu" "B.Mask" "B.Paste")
			(net "GND")
		)
		(pad "A23" smd rect
			(at -5.00507 3.934968)
			(size 0.381 1.7272)
			(layers "B.Cu" "B.Mask" "B.Paste")
			(net "SMB_BMC_MM6_SCL")
		)
		(pad "A24" smd rect
			(at -4.405122 3.934968)
			(size 0.381 1.7272)
			(layers "B.Cu" "B.Mask" "B.Paste")
			(net "SMB_BMC_MM6_SDA")
		)
		(pad "A25" smd rect
			(at -3.80492 4.13512)
			(size 0.381 2.1336)
			(layers "B.Cu" "B.Mask" "B.Paste")
			(net "SMB_BMC_MM7_SCL")
		)
		(pad "A26" smd rect
			(at -3.204972 3.934968)
			(size 0.381 1.7272)
			(layers "B.Cu" "B.Mask" "B.Paste")
			(net "SMB_BMC_MM7_SDA")
		)
		(pad "A27" smd rect
			(at -2.605024 3.934968)
			(size 0.381 1.7272)
			(layers "B.Cu" "B.Mask" "B.Paste")
			(net "SMB_BMC_MM8_SCL")
		)
		(pad "A28" smd rect
			(at -2.005076 4.13512)
			(size 0.381 2.1336)
			(layers "B.Cu" "B.Mask" "B.Paste")
			(net "SMB_BMC_MM8_SDA")
		)
		(pad "A29" smd rect
			(at 2.005076 4.13512)
			(size 0.381 2.1336)
			(layers "B.Cu" "B.Mask" "B.Paste")
			(net "SMB_BMC_MM9_SCL")
		)
		(pad "A30" smd rect
			(at 2.605024 3.934968)
			(size 0.381 1.7272)
			(layers "B.Cu" "B.Mask" "B.Paste")
			(net "SMB_BMC_MM9_SDA")
		)
		(pad "A31" smd rect
			(at 3.204972 3.934968)
			(size 0.381 1.7272)
			(layers "B.Cu" "B.Mask" "B.Paste")
			(net "SMB_BMC_MM10_SCL")
		)
		(pad "A32" smd rect
			(at 3.80492 4.13512)
			(size 0.381 2.1336)
			(layers "B.Cu" "B.Mask" "B.Paste")
			(net "SMB_BMC_MM10_SDA")
		)
		(pad "A33" smd rect
			(at 4.405122 3.934968)
			(size 0.381 1.7272)
			(layers "B.Cu" "B.Mask" "B.Paste")
			(net "GND")
		)
		(pad "A34" smd rect
			(at 5.00507 3.934968)
			(size 0.381 1.7272)
			(layers "B.Cu" "B.Mask" "B.Paste")
			(net "JTAG_MB_TCK")
		)
		(pad "A35" smd rect
			(at 5.605018 4.13512)
			(size 0.381 2.1336)
			(layers "B.Cu" "B.Mask" "B.Paste")
			(net "JTAG_MB_TMS")
		)
		(pad "A36" smd rect
			(at 6.204966 3.934968)
			(size 0.381 1.7272)
			(layers "B.Cu" "B.Mask" "B.Paste")
			(net "JTAG_MB_TDI")
		)
		(pad "A37" smd rect
			(at 6.804914 3.934968)
			(size 0.381 1.7272)
			(layers "B.Cu" "B.Mask" "B.Paste")
			(net "JTAG_MB_TDO")
		)
		(pad "A38" smd rect
			(at 7.405116 4.13512)
			(size 0.381 2.1336)
			(layers "B.Cu" "B.Mask" "B.Paste")
			(net "SMB_BMC_MM12_SCL")
		)
		(pad "A39" smd rect
			(at 8.005064 3.934968)
			(size 0.381 1.7272)
			(layers "B.Cu" "B.Mask" "B.Paste")
			(net "SMB_BMC_MM12_SDA")
		)
		(pad "A40" smd rect
			(at 8.605012 3.934968)
			(size 0.381 1.7272)
			(layers "B.Cu" "B.Mask" "B.Paste")
			(net "SMB_BMC_MM13_SCL")
		)
		(pad "A41" smd rect
			(at 9.20496 4.13512)
			(size 0.381 2.1336)
			(layers "B.Cu" "B.Mask" "B.Paste")
			(net "SMB_BMC_MM13_SDA")
		)
		(pad "A42" smd rect
			(at 9.804908 4.13512)
			(size 0.381 2.1336)
			(layers "B.Cu" "B.Mask" "B.Paste")
			(net "GND")
		)
		(pad "A43" smd rect
			(at 14.714982 4.13512)
			(size 0.381 2.1336)
			(layers "B.Cu" "B.Mask" "B.Paste")
			(net "FM_JTAG_SEL")
		)
		(pad "A44" smd rect
			(at 15.31493 3.934968)
			(size 0.381 1.7272)
			(layers "B.Cu" "B.Mask" "B.Paste")
			(net "PWRGD_PSU_AC_PWROK_R")
		)
		(pad "A45" smd rect
			(at 15.914878 3.934968)
			(size 0.381 1.7272)
			(layers "B.Cu" "B.Mask" "B.Paste")
			(net "TP_GF_A45")
		)
		(pad "A46" smd rect
			(at 16.51508 4.13512)
			(size 0.381 2.1336)
			(layers "B.Cu" "B.Mask" "B.Paste")
			(net "RST_MB_STBY_N")
		)
		(pad "A47" smd rect
			(at 17.115028 3.934968)
			(size 0.381 1.7272)
			(layers "B.Cu" "B.Mask" "B.Paste")
			(net "SYS_PWRBTN_N")
		)
		(pad "A48" smd rect
			(at 17.714976 3.934968)
			(size 0.381 1.7272)
			(layers "B.Cu" "B.Mask" "B.Paste")
			(net "PWRGD_SYS_PWROK")
		)
		(pad "A49" smd rect
			(at 18.314924 4.13512)
			(size 0.381 2.1336)
			(layers "B.Cu" "B.Mask" "B.Paste")
			(net "FM_DBP_CPU_PREQ_GF_R_N")
		)
		(pad "A50" smd rect
			(at 18.914872 3.934968)
			(size 0.381 1.7272)
			(layers "B.Cu" "B.Mask" "B.Paste")
			(net "FM_DBP_BMC_PRDY_N")
		)
		(pad "A51" smd rect
			(at 19.515074 3.934968)
			(size 0.381 1.7272)
			(layers "B.Cu" "B.Mask" "B.Paste")
			(net "RST_PLTRST_N")
		)
		(pad "A52" smd rect
			(at 20.115022 4.13512)
			(size 0.381 2.1336)
			(layers "B.Cu" "B.Mask" "B.Paste")
			(net "FM_BMC_UARTSW_MSB_N")
		)
		(pad "A53" smd rect
			(at 20.71497 3.934968)
			(size 0.381 1.7272)
			(layers "B.Cu" "B.Mask" "B.Paste")
			(net "RST_ROT_CPU_N")
		)
		(pad "A54" smd rect
			(at 21.314918 3.934968)
			(size 0.381 1.7272)
			(layers "B.Cu" "B.Mask" "B.Paste")
			(net "FM_INTRUDER_N")
		)
		(pad "A55" smd rect
			(at 21.91512 4.13512)
			(size 0.381 2.1336)
			(layers "B.Cu" "B.Mask" "B.Paste")
			(net "FM_BMC_UARTSW_LSB_N")
		)
		(pad "A56" smd rect
			(at 22.515068 3.934968)
			(size 0.381 1.7272)
			(layers "B.Cu" "B.Mask" "B.Paste")
			(net "IRQ_SMI_ACTIVE_GF_N")
		)
		(pad "A57" smd rect
			(at 23.115016 3.934968)
			(size 0.381 1.7272)
			(layers "B.Cu" "B.Mask" "B.Paste")
			(net "FM_PRSNT_1_N")
		)
		(pad "A58" smd rect
			(at 23.714964 4.13512)
			(size 0.381 2.1336)
			(layers "B.Cu" "B.Mask" "B.Paste")
			(net "GND")
		)
		(pad "A59" smd rect
			(at 24.314912 3.934968)
			(size 0.381 1.7272)
			(layers "B.Cu" "B.Mask" "B.Paste")
			(net "USB3_FPNL_RXP")
		)
		(pad "A60" smd rect
			(at 24.915114 3.934968)
			(size 0.381 1.7272)
			(layers "B.Cu" "B.Mask" "B.Paste")
			(net "USB3_FPNL_RXN")
		)
		(pad "A61" smd rect
			(at 25.515062 4.13512)
			(size 0.381 2.1336)
			(layers "B.Cu" "B.Mask" "B.Paste")
			(net "GND")
		)
		(pad "A62" smd rect
			(at 26.11501 3.934968)
			(size 0.381 1.7272)
			(layers "B.Cu" "B.Mask" "B.Paste")
			(net "TP_GF_A62")
		)
		(pad "A63" smd rect
			(at 26.714958 3.934968)
			(size 0.381 1.7272)
			(layers "B.Cu" "B.Mask" "B.Paste")
			(net "TP_GF_A63")
		)
		(pad "A64" smd rect
			(at 27.314906 4.13512)
			(size 0.381 2.1336)
			(layers "B.Cu" "B.Mask" "B.Paste")
			(net "GND")
		)
		(pad "A65" smd rect
			(at 27.915108 3.934968)
			(size 0.381 1.7272)
			(layers "B.Cu" "B.Mask" "B.Paste")
			(net "P2E_GPU_RX_DP")
		)
		(pad "A66" smd rect
			(at 28.515056 3.934968)
			(size 0.381 1.7272)
			(layers "B.Cu" "B.Mask" "B.Paste")
			(net "P2E_GPU_RX_DN")
		)
		(pad "A67" smd rect
			(at 29.115004 4.13512)
			(size 0.381 2.1336)
			(layers "B.Cu" "B.Mask" "B.Paste")
			(net "GND")
		)
		(pad "A68" smd rect
			(at 29.714952 3.934968)
			(size 0.381 1.7272)
			(layers "B.Cu" "B.Mask" "B.Paste")
			(net "CLK_100M_GPU_DP")
		)
		(pad "A69" smd rect
			(at 30.3149 3.934968)
			(size 0.381 1.7272)
			(layers "B.Cu" "B.Mask" "B.Paste")
			(net "CLK_100M_GPU_DN")
		)
		(pad "A70" smd rect
			(at 30.915102 4.13512)
			(size 0.381 2.1336)
			(layers "B.Cu" "B.Mask" "B.Paste")
			(net "GND")
		)
		(pad "B1" smd rect
			(at -18.204942 3.934968)
			(size 0.381 1.7272)
			(layers "B.Cu" "B.Mask" "B.Paste")
			(net "ESPI_HOST_LPC_BMC_CLK")
		)
		(pad "B2" smd rect
			(at -17.604994 3.934968)
			(size 0.381 1.7272)
			(layers "B.Cu" "B.Mask" "B.Paste")
			(net "ESPI_HOST_LPC_BMC_LFRAME_N")
		)
		(pad "B3" smd rect
			(at -17.005046 3.934968)
			(size 0.381 1.7272)
			(layers "B.Cu" "B.Mask" "B.Paste")
			(net "IRQ_BMC_LPC_SERIRQ_ESPI_GF")
		)
		(pad "B4" smd rect
			(at -16.405098 3.934968)
			(size 0.381 1.7272)
			(layers "B.Cu" "B.Mask" "B.Paste")
			(net "RST_BMC_LPC_ESPI_N")
		)
		(pad "B5" smd rect
			(at -15.804896 3.934968)
			(size 0.381 1.7272)
			(layers "B.Cu" "B.Mask" "B.Paste")
			(net "ESPI_LPC_LAD0_IO0")
		)
		(pad "B6" smd rect
			(at -15.204948 3.934968)
			(size 0.381 1.7272)
			(layers "B.Cu" "B.Mask" "B.Paste")
			(net "ESPI_LPC_LAD1_IO1")
		)
		(pad "B7" smd rect
			(at -14.605 3.934968)
			(size 0.381 1.7272)
			(layers "B.Cu" "B.Mask" "B.Paste")
			(net "ESPI_LPC_LAD2_IO2")
		)
		(pad "B8" smd rect
			(at -14.005052 3.934968)
			(size 0.381 1.7272)
			(layers "B.Cu" "B.Mask" "B.Paste")
			(net "ESPI_LPC_LAD3_IO3")
		)
		(pad "B9" smd rect
			(at -13.405104 3.934968)
			(size 0.381 1.7272)
			(layers "B.Cu" "B.Mask" "B.Paste")
			(net "LPC_ESPI_SEL")
		)
		(pad "B10" smd rect
			(at -12.804902 3.934968)
			(size 0.381 1.7272)
			(layers "B.Cu" "B.Mask" "B.Paste")
			(net "GND")
		)
		(pad "B11" smd rect
			(at -12.204954 3.934968)
			(size 0.381 1.7272)
			(layers "B.Cu" "B.Mask" "B.Paste")
			(net "SPI_SYS_R_CLK")
		)
		(pad "B12" smd rect
			(at -11.605006 3.934968)
			(size 0.381 1.7272)
			(layers "B.Cu" "B.Mask" "B.Paste")
			(net "SPI_SYS_CS0_N")
		)
		(pad "B13" smd rect
			(at -11.005058 4.13512)
			(size 0.381 2.1336)
			(layers "B.Cu" "B.Mask" "B.Paste")
			(net "SPI_SYS_R_MOSI")
		)
		(pad "B14" smd rect
			(at -10.40511 3.934968)
			(size 0.381 1.7272)
			(layers "B.Cu" "B.Mask" "B.Paste")
			(net "SPI_SYS_R_MISO")
		)
		(pad "B15" smd rect
			(at -9.804908 3.934968)
			(size 0.381 1.7272)
			(layers "B.Cu" "B.Mask" "B.Paste")
			(net "SPI_SYS_WP_R_IO2")
		)
		(pad "B16" smd rect
			(at -9.20496 4.13512)
			(size 0.381 2.1336)
			(layers "B.Cu" "B.Mask" "B.Paste")
			(net "SPI_SYS_HOLD_R_IO3")
		)
		(pad "B17" smd rect
			(at -8.605012 3.934968)
			(size 0.381 1.7272)
			(layers "B.Cu" "B.Mask" "B.Paste")
			(net "GND")
		)
		(pad "B18" smd rect
			(at -8.005064 3.934968)
			(size 0.381 1.7272)
			(layers "B.Cu" "B.Mask" "B.Paste")
			(net "RMII_OCP_RCLKI")
		)
		(pad "B19" smd rect
			(at -7.405116 4.13512)
			(size 0.381 2.1336)
			(layers "B.Cu" "B.Mask" "B.Paste")
			(net "RMII_CSRDV")
		)
		(pad "B20" smd rect
			(at -6.804914 3.934968)
			(size 0.381 1.7272)
			(layers "B.Cu" "B.Mask" "B.Paste")
			(net "RMII_TXEN")
		)
		(pad "B21" smd rect
			(at -6.204966 3.934968)
			(size 0.381 1.7272)
			(layers "B.Cu" "B.Mask" "B.Paste")
			(net "RMII_TXD0")
		)
		(pad "B22" smd rect
			(at -5.605018 4.13512)
			(size 0.381 2.1336)
			(layers "B.Cu" "B.Mask" "B.Paste")
			(net "RMII_TXD1")
		)
		(pad "B23" smd rect
			(at -5.00507 3.934968)
			(size 0.381 1.7272)
			(layers "B.Cu" "B.Mask" "B.Paste")
			(net "RMII_RXER")
		)
		(pad "B24" smd rect
			(at -4.405122 3.934968)
			(size 0.381 1.7272)
			(layers "B.Cu" "B.Mask" "B.Paste")
			(net "RMII_RXD0")
		)
		(pad "B25" smd rect
			(at -3.80492 4.13512)
			(size 0.381 2.1336)
			(layers "B.Cu" "B.Mask" "B.Paste")
			(net "RMII_RXD1")
		)
		(pad "B26" smd rect
			(at -3.204972 3.934968)
			(size 0.381 1.7272)
			(layers "B.Cu" "B.Mask" "B.Paste")
			(net "GND")
		)
		(pad "B27" smd rect
			(at -2.605024 3.934968)
			(size 0.381 1.7272)
			(layers "B.Cu" "B.Mask" "B.Paste")
			(net "PECI_BMC")
		)
		(pad "B28" smd rect
			(at -2.005076 4.13512)
			(size 0.381 2.1336)
			(layers "B.Cu" "B.Mask" "B.Paste")
			(net "PVCCIO_PECI_BMC")
		)
		(pad "B29" smd rect
			(at 2.005076 4.13512)
			(size 0.381 2.1336)
			(layers "B.Cu" "B.Mask" "B.Paste")
			(net "SGPIO_DO_0")
		)
		(pad "B30" smd rect
			(at 2.605024 3.934968)
			(size 0.381 1.7272)
			(layers "B.Cu" "B.Mask" "B.Paste")
			(net "SGPIO_CLK_0")
		)
		(pad "B31" smd rect
			(at 3.204972 3.934968)
			(size 0.381 1.7272)
			(layers "B.Cu" "B.Mask" "B.Paste")
			(net "SGPIO_DI_0")
		)
		(pad "B32" smd rect
			(at 3.80492 4.13512)
			(size 0.381 2.1336)
			(layers "B.Cu" "B.Mask" "B.Paste")
			(net "SGPIO_LD_0")
		)
		(pad "B33" smd rect
			(at 4.405122 3.934968)
			(size 0.381 1.7272)
			(layers "B.Cu" "B.Mask" "B.Paste")
			(net "GND")
		)
		(pad "B34" smd rect
			(at 5.00507 3.934968)
			(size 0.381 1.7272)
			(layers "B.Cu" "B.Mask" "B.Paste")
			(net "SGPIO_DO_1")
		)
		(pad "B35" smd rect
			(at 5.605018 4.13512)
			(size 0.381 2.1336)
			(layers "B.Cu" "B.Mask" "B.Paste")
			(net "SGPIO_CLK_1")
		)
		(pad "B36" smd rect
			(at 6.204966 3.934968)
			(size 0.381 1.7272)
			(layers "B.Cu" "B.Mask" "B.Paste")
			(net "SGPIO_DI_1")
		)
		(pad "B37" smd rect
			(at 6.804914 3.934968)
			(size 0.381 1.7272)
			(layers "B.Cu" "B.Mask" "B.Paste")
			(net "SGPIO_LD_1")
		)
		(pad "B38" smd rect
			(at 7.405116 4.13512)
			(size 0.381 2.1336)
			(layers "B.Cu" "B.Mask" "B.Paste")
			(net "GND")
		)
		(pad "B39" smd rect
			(at 8.005064 3.934968)
			(size 0.381 1.7272)
			(layers "B.Cu" "B.Mask" "B.Paste")
			(net "RST_SGPIO_RESET_N")
		)
		(pad "B40" smd rect
			(at 8.605012 3.934968)
			(size 0.381 1.7272)
			(layers "B.Cu" "B.Mask" "B.Paste")
			(net "IRQ_SGPIO_N")
		)
		(pad "B41" smd rect
			(at 9.20496 4.13512)
			(size 0.381 2.1336)
			(layers "B.Cu" "B.Mask" "B.Paste")
			(net "P3V_BAT_R")
		)
		(pad "B42" smd rect
			(at 9.804908 4.13512)
			(size 0.381 2.1336)
			(layers "B.Cu" "B.Mask" "B.Paste")
			(net "AC_PWR_BTN_N")
		)
		(pad "B43" smd rect
			(at 14.714982 4.13512)
			(size 0.381 2.1336)
			(layers "B.Cu" "B.Mask" "B.Paste")
			(net "QSPI_2_PLD_CLK")
		)
		(pad "B44" smd rect
			(at 15.31493 3.934968)
			(size 0.381 1.7272)
			(layers "B.Cu" "B.Mask" "B.Paste")
			(net "TP_GF1_B44")
		)
		(pad "B45" smd rect
			(at 15.914878 3.934968)
			(size 0.381 1.7272)
			(layers "B.Cu" "B.Mask" "B.Paste")
			(net "QSPI_2_PLD_IO0")
		)
		(pad "B46" smd rect
			(at 16.51508 4.13512)
			(size 0.381 2.1336)
			(layers "B.Cu" "B.Mask" "B.Paste")
			(net "QSPI_2_PLD_IO1")
		)
		(pad "B47" smd rect
			(at 17.115028 3.934968)
			(size 0.381 1.7272)
			(layers "B.Cu" "B.Mask" "B.Paste")
			(net "QSPI_2_PLD_IO2")
		)
		(pad "B48" smd rect
			(at 17.714976 3.934968)
			(size 0.381 1.7272)
			(layers "B.Cu" "B.Mask" "B.Paste")
			(net "QSPI_2_PLD_IO3")
		)
		(pad "B49" smd rect
			(at 18.314924 4.13512)
			(size 0.381 2.1336)
			(layers "B.Cu" "B.Mask" "B.Paste")
			(net "GND")
		)
		(pad "B50" smd rect
			(at 18.914872 3.934968)
			(size 0.381 1.7272)
			(layers "B.Cu" "B.Mask" "B.Paste")
			(net "USB_HOST_BMC_B_DP")
		)
		(pad "B51" smd rect
			(at 19.515074 3.934968)
			(size 0.381 1.7272)
			(layers "B.Cu" "B.Mask" "B.Paste")
			(net "USB_HOST_BMC_B_DN")
		)
		(pad "B52" smd rect
			(at 20.115022 4.13512)
			(size 0.381 2.1336)
			(layers "B.Cu" "B.Mask" "B.Paste")
			(net "GND")
		)
		(pad "B53" smd rect
			(at 20.71497 3.934968)
			(size 0.381 1.7272)
			(layers "B.Cu" "B.Mask" "B.Paste")
			(net "USB_HOST_BMC_A_DP")
		)
		(pad "B54" smd rect
			(at 21.314918 3.934968)
			(size 0.381 1.7272)
			(layers "B.Cu" "B.Mask" "B.Paste")
			(net "USB_HOST_BMC_A_DN")
		)
		(pad "B55" smd rect
			(at 21.91512 4.13512)
			(size 0.381 2.1336)
			(layers "B.Cu" "B.Mask" "B.Paste")
			(net "GND")
		)
		(pad "B56" smd rect
			(at 22.515068 3.934968)
			(size 0.381 1.7272)
			(layers "B.Cu" "B.Mask" "B.Paste")
			(net "USB_FPNL_DP")
		)
		(pad "B57" smd rect
			(at 23.115016 3.934968)
			(size 0.381 1.7272)
			(layers "B.Cu" "B.Mask" "B.Paste")
			(net "USB_FPNL_DN")
		)
		(pad "B58" smd rect
			(at 23.714964 4.13512)
			(size 0.381 2.1336)
			(layers "B.Cu" "B.Mask" "B.Paste")
			(net "GND")
		)
		(pad "B59" smd rect
			(at 24.314912 3.934968)
			(size 0.381 1.7272)
			(layers "B.Cu" "B.Mask" "B.Paste")
			(net "USB3_FPNL_TXP")
		)
		(pad "B60" smd rect
			(at 24.915114 3.934968)
			(size 0.381 1.7272)
			(layers "B.Cu" "B.Mask" "B.Paste")
			(net "USB3_FPNL_TXN")
		)
		(pad "B61" smd rect
			(at 25.515062 4.13512)
			(size 0.381 2.1336)
			(layers "B.Cu" "B.Mask" "B.Paste")
			(net "GND")
		)
		(pad "B62" smd rect
			(at 26.11501 3.934968)
			(size 0.381 1.7272)
			(layers "B.Cu" "B.Mask" "B.Paste")
			(net "TP_GF_B62")
		)
		(pad "B63" smd rect
			(at 26.714958 3.934968)
			(size 0.381 1.7272)
			(layers "B.Cu" "B.Mask" "B.Paste")
			(net "TP_GF_B63")
		)
		(pad "B64" smd rect
			(at 27.314906 4.13512)
			(size 0.381 2.1336)
			(layers "B.Cu" "B.Mask" "B.Paste")
			(net "GND")
		)
		(pad "B65" smd rect
			(at 27.915108 3.934968)
			(size 0.381 1.7272)
			(layers "B.Cu" "B.Mask" "B.Paste")
			(net "P2E_GPU_TX_C_DP")
		)
		(pad "B66" smd rect
			(at 28.515056 3.934968)
			(size 0.381 1.7272)
			(layers "B.Cu" "B.Mask" "B.Paste")
			(net "P2E_GPU_TX_C_DN")
		)
		(pad "B67" smd rect
			(at 29.115004 4.13512)
			(size 0.381 2.1336)
			(layers "B.Cu" "B.Mask" "B.Paste")
			(net "GND")
		)
		(pad "B68" smd rect
			(at 29.714952 3.934968)
			(size 0.381 1.7272)
			(layers "B.Cu" "B.Mask" "B.Paste")
			(net "HDD_LED_R_N")
		)
		(pad "B69" smd rect
			(at 30.3149 3.934968)
			(size 0.381 1.7272)
			(layers "B.Cu" "B.Mask" "B.Paste")
			(net "PCH_BEEP_R_LED")
		)
		(pad "B70" smd rect
			(at 30.915102 4.13512)
			(size 0.381 2.1336)
			(layers "B.Cu" "B.Mask" "B.Paste")
			(net "GND")
		)
		(pad "OA1" smd rect
			(at -30.39999 4.13512)
			(size 0.381 2.1336)
			(layers "B.Cu" "B.Mask" "B.Paste")
			(net "P12V_AUX")
		)
		(pad "OA2" smd rect
			(at -29.800042 3.934968)
			(size 0.381 1.7272)
			(layers "B.Cu" "B.Mask" "B.Paste")
			(net "P12V_AUX")
		)
		(pad "OA3" smd rect
			(at -29.200094 4.13512)
			(size 0.381 2.1336)
			(layers "B.Cu" "B.Mask" "B.Paste")
			(net "GND")
		)
		(pad "OA4" smd rect
			(at -28.599892 4.13512)
			(size 0.381 2.1336)
			(layers "B.Cu" "B.Mask" "B.Paste")
			(net "GND")
		)
		(pad "OA5" smd rect
			(at -27.999944 4.13512)
			(size 0.381 2.1336)
			(layers "B.Cu" "B.Mask" "B.Paste")
			(net "I3C1_SPD_SCL")
		)
		(pad "OA6" smd rect
			(at -27.399996 4.13512)
			(size 0.381 2.1336)
			(layers "B.Cu" "B.Mask" "B.Paste")
			(net "I3C1_SPD_SDA")
		)
		(pad "OA7" smd rect
			(at -26.800048 4.13512)
			(size 0.381 2.1336)
			(layers "B.Cu" "B.Mask" "B.Paste")
			(net "I3C2_SPD_SCL")
		)
		(pad "OA8" smd rect
			(at -26.2001 4.13512)
			(size 0.381 2.1336)
			(layers "B.Cu" "B.Mask" "B.Paste")
			(net "I3C2_SPD_SDA")
		)
		(pad "OA9" smd rect
			(at -25.599898 4.13512)
			(size 0.381 2.1336)
			(layers "B.Cu" "B.Mask" "B.Paste")
			(net "I3C3_SPD_SCL")
		)
		(pad "OA10" smd rect
			(at -24.99995 4.13512)
			(size 0.381 2.1336)
			(layers "B.Cu" "B.Mask" "B.Paste")
			(net "I3C3_SPD_SDA")
		)
		(pad "OA11" smd rect
			(at -24.400002 3.934968)
			(size 0.381 1.7272)
			(layers "B.Cu" "B.Mask" "B.Paste")
			(net "I3C4_SPD_SCL")
		)
		(pad "OA12" smd rect
			(at -23.800054 3.934968)
			(size 0.381 1.7272)
			(layers "B.Cu" "B.Mask" "B.Paste")
			(net "I3C4_SPD_SDA")
		)
		(pad "OA13" smd rect
			(at -23.200106 4.13512)
			(size 0.381 2.1336)
			(layers "B.Cu" "B.Mask" "B.Paste")
			(net "GND")
		)
		(pad "OA14" smd rect
			(at -22.599904 4.13512)
			(size 0.381 2.1336)
			(layers "B.Cu" "B.Mask" "B.Paste")
			(net "FM_VIRTUAL_RESEAT")
		)
		(pad "OB1" smd rect
			(at -30.39999 4.13512)
			(size 0.381 2.1336)
			(layers "B.Cu" "B.Mask" "B.Paste")
			(net "P12V_AUX")
		)
		(pad "OB2" smd rect
			(at -29.800042 4.13512)
			(size 0.381 2.1336)
			(layers "B.Cu" "B.Mask" "B.Paste")
			(net "P12V_AUX")
		)
		(pad "OB3" smd rect
			(at -29.200094 4.13512)
			(size 0.381 2.1336)
			(layers "B.Cu" "B.Mask" "B.Paste")
			(net "FM_PRSNT_0_R_N")
		)
		(pad "OB4" smd rect
			(at -28.599892 4.13512)
			(size 0.381 2.1336)
			(layers "B.Cu" "B.Mask" "B.Paste")
			(net "GND")
		)
		(pad "OB5" smd rect
			(at -27.999944 4.13512)
			(size 0.381 2.1336)
			(layers "B.Cu" "B.Mask" "B.Paste")
			(net "UART_BIC_GF_TXD")
		)
		(pad "OB6" smd rect
			(at -27.399996 4.13512)
			(size 0.381 2.1336)
			(layers "B.Cu" "B.Mask" "B.Paste")
			(net "UART_BIC_GF_RXD")
		)
		(pad "OB7" smd rect
			(at -26.800048 4.13512)
			(size 0.381 2.1336)
			(layers "B.Cu" "B.Mask" "B.Paste")
			(net "GND")
		)
		(pad "OB8" smd rect
			(at -26.2001 4.13512)
			(size 0.381 2.1336)
			(layers "B.Cu" "B.Mask" "B.Paste")
			(net "UART_SYS_DBG_TX")
		)
		(pad "OB9" smd rect
			(at -25.599898 4.13512)
			(size 0.381 2.1336)
			(layers "B.Cu" "B.Mask" "B.Paste")
			(net "UART_SYS_DBG_RX")
		)
		(pad "OB10" smd rect
			(at -24.99995 4.13512)
			(size 0.381 2.1336)
			(layers "B.Cu" "B.Mask" "B.Paste")
			(net "GND")
		)
		(pad "OB11" smd rect
			(at -24.400002 3.934968)
			(size 0.381 1.7272)
			(layers "B.Cu" "B.Mask" "B.Paste")
			(net "RST_SRST_PLD_BMC_R_N")
		)
		(pad "OB12" smd rect
			(at -23.800054 3.934968)
			(size 0.381 1.7272)
			(layers "B.Cu" "B.Mask" "B.Paste")
			(net "SPI_TPM_CS_N")
		)
		(pad "OB13" smd rect
			(at -23.200106 4.13512)
			(size 0.381 2.1336)
			(layers "B.Cu" "B.Mask" "B.Paste")
			(net "H_CPU_CATERR_LVC2_R2_N")
		)
		(pad "OB14" smd rect
			(at -22.599904 4.13512)
			(size 0.381 2.1336)
			(layers "B.Cu" "B.Mask" "B.Paste")
			(net "FM_SOL_UART_CH_SEL")
		)
		(zone
			(layer "F.Cu")
			(hatch none 0.5)
			(connect_pads
				(clearance 0)
			)
			(min_thickness 0.25)
			(keepout
				(tracks not_allowed)
				(vias allowed)
				(pads allowed)
				(copperpour not_allowed)
				(footprints allowed)
			)
			(placement
				(enabled no)
				(sheetname "")
			)
			(fill
				(thermal_gap 0.5)
				(thermal_bridge_width 0.5)
				(island_removal_mode 0)
			)
			(polygon
				(pts
					(xy 35.124898 -120.39981) (xy 34.37509 -119.650002) (xy 34.37509 -117.342412) (xy 35.264598 -117.342412)
					(xy 35.264598 -119.526812) (xy 35.645598 -119.526812) (xy 35.645598 -117.342412) (xy 35.864546 -117.342412)
					(xy 35.864546 -119.526812) (xy 36.245546 -119.526812) (xy 36.245546 -117.342412) (xy 36.464494 -117.342412)
					(xy 36.464494 -119.12346) (xy 36.845494 -119.12346) (xy 36.845494 -117.342412) (xy 37.064442 -117.342412)
					(xy 37.064442 -119.12346) (xy 37.445442 -119.12346) (xy 37.445442 -117.342412) (xy 37.66439 -117.342412)
					(xy 37.66439 -119.526812) (xy 38.04539 -119.526812) (xy 38.04539 -117.342412) (xy 38.264592 -117.342412)
					(xy 38.264592 -119.12346) (xy 38.645592 -119.12346) (xy 38.645592 -117.342412) (xy 38.86454 -117.342412)
					(xy 38.86454 -119.12346) (xy 39.24554 -119.12346) (xy 39.24554 -117.342412) (xy 39.464488 -117.342412)
					(xy 39.464488 -119.526812) (xy 39.845488 -119.526812) (xy 39.845488 -117.342412) (xy 40.064436 -117.342412)
					(xy 40.064436 -119.12346) (xy 40.445436 -119.12346) (xy 40.445436 -117.342412) (xy 40.664384 -117.342412)
					(xy 40.664384 -119.12346) (xy 41.045384 -119.12346) (xy 41.045384 -117.342412) (xy 41.264586 -117.342412)
					(xy 41.264586 -119.526812) (xy 41.645586 -119.526812) (xy 41.645586 -117.342412) (xy 41.864534 -117.342412)
					(xy 41.864534 -119.12346) (xy 42.245534 -119.12346) (xy 42.245534 -117.342412) (xy 42.464482 -117.342412)
					(xy 42.464482 -119.12346) (xy 42.845482 -119.12346) (xy 42.845482 -117.342412) (xy 43.06443 -117.342412)
					(xy 43.06443 -119.526812) (xy 43.44543 -119.526812) (xy 43.44543 -117.342412) (xy 44.334938 -117.342412)
					(xy 44.334938 -119.650002) (xy 43.58513 -120.39981)
				)
			)
		)
		(zone
			(layer "F.Cu")
			(hatch none 0.5)
			(connect_pads
				(clearance 0)
			)
			(min_thickness 0.25)
			(keepout
				(tracks not_allowed)
				(vias allowed)
				(pads allowed)
				(copperpour not_allowed)
				(footprints allowed)
			)
			(placement
				(enabled no)
				(sheetname "")
			)
			(fill
				(thermal_gap 0.5)
				(thermal_bridge_width 0.5)
				(island_removal_mode 0)
			)
			(polygon
				(pts
					(xy 67.535044 -120.39981) (xy 66.784982 -119.650002) (xy 66.784982 -117.342412) (xy 67.66941 -117.342412)
					(xy 67.66941 -119.526812) (xy 68.05041 -119.526812) (xy 68.05041 -117.342412) (xy 68.269612 -117.342412)
					(xy 68.269612 -119.526812) (xy 68.650612 -119.526812) (xy 68.650612 -117.342412) (xy 68.86956 -117.342412)
					(xy 68.86956 -119.12346) (xy 69.25056 -119.12346) (xy 69.25056 -117.342412) (xy 69.469508 -117.342412)
					(xy 69.469508 -119.12346) (xy 69.850508 -119.12346) (xy 69.850508 -117.342412) (xy 70.069456 -117.342412)
					(xy 70.069456 -119.526812) (xy 70.450456 -119.526812) (xy 70.450456 -117.342412) (xy 70.669404 -117.342412)
					(xy 70.669404 -119.526812) (xy 71.050404 -119.526812) (xy 71.050404 -117.342412) (xy 71.269606 -117.342412)
					(xy 71.269606 -119.526812) (xy 71.650606 -119.526812) (xy 71.650606 -117.342412) (xy 71.869554 -117.342412)
					(xy 71.869554 -119.526812) (xy 72.250554 -119.526812) (xy 72.250554 -117.342412) (xy 72.469502 -117.342412)
					(xy 72.469502 -119.526812) (xy 72.850502 -119.526812) (xy 72.850502 -117.342412) (xy 73.06945 -117.342412)
					(xy 73.06945 -119.526812) (xy 73.45045 -119.526812) (xy 73.45045 -117.342412) (xy 73.669398 -117.342412)
					(xy 73.669398 -119.526812) (xy 74.050398 -119.526812) (xy 74.050398 -117.342412) (xy 74.2696 -117.342412)
					(xy 74.2696 -119.526812) (xy 74.6506 -119.526812) (xy 74.6506 -117.342412) (xy 74.869548 -117.342412)
					(xy 74.869548 -119.526812) (xy 75.250548 -119.526812) (xy 75.250548 -117.342412) (xy 75.469496 -117.342412)
					(xy 75.469496 -119.526812) (xy 75.850496 -119.526812) (xy 75.850496 -117.342412) (xy 76.740004 -117.342412)
					(xy 76.740004 -119.650002) (xy 75.989942 -120.39981)
				)
			)
		)
		(zone
			(layer "F.Cu")
			(hatch none 0.5)
			(connect_pads
				(clearance 0)
			)
			(min_thickness 0.25)
			(keepout
				(tracks not_allowed)
				(vias allowed)
				(pads allowed)
				(copperpour not_allowed)
				(footprints allowed)
			)
			(placement
				(enabled no)
				(sheetname "")
			)
			(fill
				(thermal_gap 0.5)
				(thermal_bridge_width 0.5)
				(island_removal_mode 0)
			)
			(polygon
				(pts
					(xy 14.014958 -120.39981) (xy 13.264896 -119.650002) (xy 13.264896 -117.342412) (xy 14.154404 -117.342412)
					(xy 14.154404 -119.526812) (xy 14.535404 -119.526812) (xy 14.535404 -117.342412) (xy 14.754606 -117.342412)
					(xy 14.754606 -119.12346) (xy 15.135606 -119.12346) (xy 15.135606 -117.342412) (xy 15.354554 -117.342412)
					(xy 15.354554 -119.12346) (xy 15.735554 -119.12346) (xy 15.735554 -117.342412) (xy 15.954502 -117.342412)
					(xy 15.954502 -119.526812) (xy 16.335502 -119.526812) (xy 16.335502 -117.342412) (xy 16.55445 -117.342412)
					(xy 16.55445 -119.12346) (xy 16.93545 -119.12346) (xy 16.93545 -117.342412) (xy 17.154398 -117.342412)
					(xy 17.154398 -119.12346) (xy 17.535398 -119.12346) (xy 17.535398 -117.342412) (xy 17.7546 -117.342412)
					(xy 17.7546 -119.526812) (xy 18.1356 -119.526812) (xy 18.1356 -117.342412) (xy 18.354548 -117.342412)
					(xy 18.354548 -119.12346) (xy 18.735548 -119.12346) (xy 18.735548 -117.342412) (xy 18.954496 -117.342412)
					(xy 18.954496 -119.12346) (xy 19.335496 -119.12346) (xy 19.335496 -117.342412) (xy 19.554444 -117.342412)
					(xy 19.554444 -119.526812) (xy 19.935444 -119.526812) (xy 19.935444 -117.342412) (xy 20.154392 -117.342412)
					(xy 20.154392 -119.12346) (xy 20.535392 -119.12346) (xy 20.535392 -117.342412) (xy 20.754594 -117.342412)
					(xy 20.754594 -119.12346) (xy 21.135594 -119.12346) (xy 21.135594 -117.342412) (xy 21.354542 -117.342412)
					(xy 21.354542 -119.526812) (xy 21.735542 -119.526812) (xy 21.735542 -117.342412) (xy 21.95449 -117.342412)
					(xy 21.95449 -119.12346) (xy 22.33549 -119.12346) (xy 22.33549 -117.342412) (xy 22.554438 -117.342412)
					(xy 22.554438 -119.12346) (xy 22.935438 -119.12346) (xy 22.935438 -117.342412) (xy 23.154386 -117.342412)
					(xy 23.154386 -119.526812) (xy 23.535386 -119.526812) (xy 23.535386 -117.342412) (xy 23.754588 -117.342412)
					(xy 23.754588 -119.12346) (xy 24.135588 -119.12346) (xy 24.135588 -117.342412) (xy 24.354536 -117.342412)
					(xy 24.354536 -119.12346) (xy 24.735536 -119.12346) (xy 24.735536 -117.342412) (xy 24.954484 -117.342412)
					(xy 24.954484 -119.526812) (xy 25.335484 -119.526812) (xy 25.335484 -117.342412) (xy 25.554432 -117.342412)
					(xy 25.554432 -119.12346) (xy 25.935432 -119.12346) (xy 25.935432 -117.342412) (xy 26.154634 -117.342412)
					(xy 26.154634 -119.12346) (xy 26.535634 -119.12346) (xy 26.535634 -117.342412) (xy 26.754582 -117.342412)
					(xy 26.754582 -119.526812) (xy 27.135582 -119.526812) (xy 27.135582 -117.342412) (xy 27.35453 -117.342412)
					(xy 27.35453 -119.12346) (xy 27.73553 -119.12346) (xy 27.73553 -117.342412) (xy 27.954478 -117.342412)
					(xy 27.954478 -119.12346) (xy 28.335478 -119.12346) (xy 28.335478 -117.342412) (xy 28.554426 -117.342412)
					(xy 28.554426 -119.526812) (xy 28.935426 -119.526812) (xy 28.935426 -117.342412) (xy 29.154628 -117.342412)
					(xy 29.154628 -119.12346) (xy 29.535628 -119.12346) (xy 29.535628 -117.342412) (xy 29.754576 -117.342412)
					(xy 29.754576 -119.12346) (xy 30.135576 -119.12346) (xy 30.135576 -117.342412) (xy 30.354524 -117.342412)
					(xy 30.354524 -119.526812) (xy 30.735524 -119.526812) (xy 30.735524 -117.342412) (xy 31.625032 -117.342412)
					(xy 31.625032 -119.650002) (xy 30.87497 -120.39981)
				)
			)
		)
		(zone
			(layer "F.Cu")
			(hatch none 0.5)
			(connect_pads
				(clearance 0)
			)
			(min_thickness 0.25)
			(keepout
				(tracks not_allowed)
				(vias allowed)
				(pads allowed)
				(copperpour not_allowed)
				(footprints allowed)
			)
			(placement
				(enabled no)
				(sheetname "")
			)
			(fill
				(thermal_gap 0.5)
				(thermal_bridge_width 0.5)
				(island_removal_mode 0)
			)
			(polygon
				(pts
					(xy 46.934882 -120.39981) (xy 46.185074 -119.650002) (xy 46.185074 -117.342412) (xy 47.074582 -117.342412)
					(xy 47.074582 -119.526812) (xy 47.455582 -119.526812) (xy 47.455582 -117.342412) (xy 47.67453 -117.342412)
					(xy 47.67453 -119.12346) (xy 48.05553 -119.12346) (xy 48.05553 -117.342412) (xy 48.274478 -117.342412)
					(xy 48.274478 -119.12346) (xy 48.655478 -119.12346) (xy 48.655478 -117.342412) (xy 48.874426 -117.342412)
					(xy 48.874426 -119.526812) (xy 49.255426 -119.526812) (xy 49.255426 -117.342412) (xy 49.474628 -117.342412)
					(xy 49.474628 -119.12346) (xy 49.855628 -119.12346) (xy 49.855628 -117.342412) (xy 50.074576 -117.342412)
					(xy 50.074576 -119.12346) (xy 50.455576 -119.12346) (xy 50.455576 -117.342412) (xy 50.674524 -117.342412)
					(xy 50.674524 -119.526812) (xy 51.055524 -119.526812) (xy 51.055524 -117.342412) (xy 51.274472 -117.342412)
					(xy 51.274472 -119.12346) (xy 51.655472 -119.12346) (xy 51.655472 -117.342412) (xy 51.87442 -117.342412)
					(xy 51.87442 -119.12346) (xy 52.25542 -119.12346) (xy 52.25542 -117.342412) (xy 52.474622 -117.342412)
					(xy 52.474622 -119.526812) (xy 52.855622 -119.526812) (xy 52.855622 -117.342412) (xy 53.07457 -117.342412)
					(xy 53.07457 -119.12346) (xy 53.45557 -119.12346) (xy 53.45557 -117.342412) (xy 53.674518 -117.342412)
					(xy 53.674518 -119.12346) (xy 54.055518 -119.12346) (xy 54.055518 -117.342412) (xy 54.274466 -117.342412)
					(xy 54.274466 -119.526812) (xy 54.655466 -119.526812) (xy 54.655466 -117.342412) (xy 54.874414 -117.342412)
					(xy 54.874414 -119.12346) (xy 55.255414 -119.12346) (xy 55.255414 -117.342412) (xy 55.474616 -117.342412)
					(xy 55.474616 -119.12346) (xy 55.855616 -119.12346) (xy 55.855616 -117.342412) (xy 56.074564 -117.342412)
					(xy 56.074564 -119.526812) (xy 56.455564 -119.526812) (xy 56.455564 -117.342412) (xy 56.674512 -117.342412)
					(xy 56.674512 -119.12346) (xy 57.055512 -119.12346) (xy 57.055512 -117.342412) (xy 57.27446 -117.342412)
					(xy 57.27446 -119.12346) (xy 57.65546 -119.12346) (xy 57.65546 -117.342412) (xy 57.874408 -117.342412)
					(xy 57.874408 -119.12346) (xy 58.255408 -119.12346) (xy 58.255408 -117.342412) (xy 58.47461 -117.342412)
					(xy 58.47461 -119.12346) (xy 58.85561 -119.12346) (xy 58.85561 -117.342412) (xy 59.074558 -117.342412)
					(xy 59.074558 -119.12346) (xy 59.455558 -119.12346) (xy 59.455558 -117.342412) (xy 59.674506 -117.342412)
					(xy 59.674506 -119.12346) (xy 60.055506 -119.12346) (xy 60.055506 -117.342412) (xy 60.274454 -117.342412)
					(xy 60.274454 -119.12346) (xy 60.655454 -119.12346) (xy 60.655454 -117.342412) (xy 60.874402 -117.342412)
					(xy 60.874402 -119.12346) (xy 61.255402 -119.12346) (xy 61.255402 -117.342412) (xy 61.474604 -117.342412)
					(xy 61.474604 -119.12346) (xy 61.855604 -119.12346) (xy 61.855604 -117.342412) (xy 62.074552 -117.342412)
					(xy 62.074552 -119.12346) (xy 62.455552 -119.12346) (xy 62.455552 -117.342412) (xy 62.6745 -117.342412)
					(xy 62.6745 -119.12346) (xy 63.0555 -119.12346) (xy 63.0555 -117.342412) (xy 63.274448 -117.342412)
					(xy 63.274448 -119.12346) (xy 63.655448 -119.12346) (xy 63.655448 -117.342412) (xy 64.53505 -117.342412)
					(xy 64.53505 -119.650002) (xy 63.784988 -120.39981)
				)
			)
		)
		(zone
			(layers "F.Cu" "B.Cu" "In1.Cu" "In2.Cu" "In3.Cu" "In4.Cu" "In5.Cu" "In6.Cu"
				"In7.Cu" "In8.Cu" "In9.Cu" "In10.Cu"
			)
			(hatch none 0.5)
			(connect_pads
				(clearance 0)
			)
			(min_thickness 0.25)
			(keepout
				(tracks allowed)
				(vias not_allowed)
				(pads allowed)
				(copperpour not_allowed)
				(footprints allowed)
			)
			(placement
				(enabled no)
				(sheetname "")
			)
			(fill
				(thermal_gap 0.5)
				(thermal_bridge_width 0.5)
				(island_removal_mode 0)
			)
			(polygon
				(pts
					(xy 14.103604 -119.577612) (xy 30.786324 -119.577612) (xy 30.786324 -117.139212) (xy 14.103604 -117.139212)
				)
			)
		)
		(zone
			(layers "F.Cu" "B.Cu" "In1.Cu" "In2.Cu" "In3.Cu" "In4.Cu" "In5.Cu" "In6.Cu"
				"In7.Cu" "In8.Cu" "In9.Cu" "In10.Cu"
			)
			(hatch none 0.5)
			(connect_pads
				(clearance 0)
			)
			(min_thickness 0.25)
			(keepout
				(tracks allowed)
				(vias not_allowed)
				(pads allowed)
				(copperpour not_allowed)
				(footprints allowed)
			)
			(placement
				(enabled no)
				(sheetname "")
			)
			(fill
				(thermal_gap 0.5)
				(thermal_bridge_width 0.5)
				(island_removal_mode 0)
			)
			(polygon
				(pts
					(xy 35.213798 -119.577612) (xy 43.49623 -119.577612) (xy 43.49623 -117.139212) (xy 35.213798 -117.139212)
				)
			)
		)
		(zone
			(layers "F.Cu" "B.Cu" "In1.Cu" "In2.Cu" "In3.Cu" "In4.Cu" "In5.Cu" "In6.Cu"
				"In7.Cu" "In8.Cu" "In9.Cu" "In10.Cu"
			)
			(hatch none 0.5)
			(connect_pads
				(clearance 0)
			)
			(min_thickness 0.25)
			(keepout
				(tracks allowed)
				(vias not_allowed)
				(pads allowed)
				(copperpour not_allowed)
				(footprints allowed)
			)
			(placement
				(enabled no)
				(sheetname "")
			)
			(fill
				(thermal_gap 0.5)
				(thermal_bridge_width 0.5)
				(island_removal_mode 0)
			)
			(polygon
				(pts
					(xy 47.023782 -119.577612) (xy 63.706248 -119.577612) (xy 63.706248 -117.139212) (xy 47.023782 -117.139212)
				)
			)
		)
		(zone
			(layers "F.Cu" "B.Cu" "In1.Cu" "In2.Cu" "In3.Cu" "In4.Cu" "In5.Cu" "In6.Cu"
				"In7.Cu" "In8.Cu" "In9.Cu" "In10.Cu"
			)
			(hatch none 0.5)
			(connect_pads
				(clearance 0)
			)
			(min_thickness 0.25)
			(keepout
				(tracks allowed)
				(vias not_allowed)
				(pads allowed)
				(copperpour not_allowed)
				(footprints allowed)
			)
			(placement
				(enabled no)
				(sheetname "")
			)
			(fill
				(thermal_gap 0.5)
				(thermal_bridge_width 0.5)
				(island_removal_mode 0)
			)
			(polygon
				(pts
					(xy 67.61861 -119.577612) (xy 75.901296 -119.577612) (xy 75.901296 -117.139212) (xy 67.61861 -117.139212)
				)
			)
		)
		(zone
			(layer "B.Cu")
			(hatch none 0.5)
			(connect_pads
				(clearance 0)
			)
			(min_thickness 0.25)
			(keepout
				(tracks not_allowed)
				(vias allowed)
				(pads allowed)
				(copperpour not_allowed)
				(footprints allowed)
			)
			(placement
				(enabled no)
				(sheetname "")
			)
			(fill
				(thermal_gap 0.5)
				(thermal_bridge_width 0.5)
				(island_removal_mode 0)
			)
			(polygon
				(pts
					(xy 35.124898 -120.39981) (xy 34.37509 -119.650002) (xy 34.37509 -117.342412) (xy 35.264598 -117.342412)
					(xy 35.264598 -119.526812) (xy 35.645598 -119.526812) (xy 35.645598 -117.342412) (xy 35.864546 -117.342412)
					(xy 35.864546 -119.526812) (xy 36.245546 -119.526812) (xy 36.245546 -117.342412) (xy 36.464494 -117.342412)
					(xy 36.464494 -119.12346) (xy 36.845494 -119.12346) (xy 36.845494 -117.342412) (xy 37.064442 -117.342412)
					(xy 37.064442 -119.12346) (xy 37.445442 -119.12346) (xy 37.445442 -117.342412) (xy 37.66439 -117.342412)
					(xy 37.66439 -119.526812) (xy 38.04539 -119.526812) (xy 38.04539 -117.342412) (xy 38.264592 -117.342412)
					(xy 38.264592 -119.12346) (xy 38.645592 -119.12346) (xy 38.645592 -117.342412) (xy 38.86454 -117.342412)
					(xy 38.86454 -119.12346) (xy 39.24554 -119.12346) (xy 39.24554 -117.342412) (xy 39.464488 -117.342412)
					(xy 39.464488 -119.526812) (xy 39.845488 -119.526812) (xy 39.845488 -117.342412) (xy 40.064436 -117.342412)
					(xy 40.064436 -119.12346) (xy 40.445436 -119.12346) (xy 40.445436 -117.342412) (xy 40.664384 -117.342412)
					(xy 40.664384 -119.12346) (xy 41.045384 -119.12346) (xy 41.045384 -117.342412) (xy 41.264586 -117.342412)
					(xy 41.264586 -119.526812) (xy 41.645586 -119.526812) (xy 41.645586 -117.342412) (xy 41.864534 -117.342412)
					(xy 41.864534 -119.12346) (xy 42.245534 -119.12346) (xy 42.245534 -117.342412) (xy 42.464482 -117.342412)
					(xy 42.464482 -119.12346) (xy 42.845482 -119.12346) (xy 42.845482 -117.342412) (xy 43.06443 -117.342412)
					(xy 43.06443 -119.526812) (xy 43.44543 -119.526812) (xy 43.44543 -117.342412) (xy 44.334938 -117.342412)
					(xy 44.334938 -119.650002) (xy 43.58513 -120.39981)
				)
			)
		)
		(zone
			(layer "B.Cu")
			(hatch none 0.5)
			(connect_pads
				(clearance 0)
			)
			(min_thickness 0.25)
			(keepout
				(tracks not_allowed)
				(vias allowed)
				(pads allowed)
				(copperpour not_allowed)
				(footprints allowed)
			)
			(placement
				(enabled no)
				(sheetname "")
			)
			(fill
				(thermal_gap 0.5)
				(thermal_bridge_width 0.5)
				(island_removal_mode 0)
			)
			(polygon
				(pts
					(xy 67.535044 -120.39981) (xy 66.784982 -119.650002) (xy 66.784982 -117.342412) (xy 67.66941 -117.342412)
					(xy 67.66941 -119.526812) (xy 68.05041 -119.526812) (xy 68.05041 -117.342412) (xy 68.269612 -117.342412)
					(xy 68.269612 -119.526812) (xy 68.650612 -119.526812) (xy 68.650612 -117.342412) (xy 68.86956 -117.342412)
					(xy 68.86956 -119.12346) (xy 69.25056 -119.12346) (xy 69.25056 -117.342412) (xy 69.469508 -117.342412)
					(xy 69.469508 -119.12346) (xy 69.850508 -119.12346) (xy 69.850508 -117.342412) (xy 70.069456 -117.342412)
					(xy 70.069456 -119.526812) (xy 70.450456 -119.526812) (xy 70.450456 -117.342412) (xy 70.669404 -117.342412)
					(xy 70.669404 -119.526812) (xy 71.050404 -119.526812) (xy 71.050404 -117.342412) (xy 71.269606 -117.342412)
					(xy 71.269606 -119.526812) (xy 71.650606 -119.526812) (xy 71.650606 -117.342412) (xy 71.869554 -117.342412)
					(xy 71.869554 -119.526812) (xy 72.250554 -119.526812) (xy 72.250554 -117.342412) (xy 72.469502 -117.342412)
					(xy 72.469502 -119.526812) (xy 72.850502 -119.526812) (xy 72.850502 -117.342412) (xy 73.06945 -117.342412)
					(xy 73.06945 -119.526812) (xy 73.45045 -119.526812) (xy 73.45045 -117.342412) (xy 73.669398 -117.342412)
					(xy 73.669398 -119.526812) (xy 74.050398 -119.526812) (xy 74.050398 -117.342412) (xy 74.2696 -117.342412)
					(xy 74.2696 -119.526812) (xy 74.6506 -119.526812) (xy 74.6506 -117.342412) (xy 74.869548 -117.342412)
					(xy 74.869548 -119.12346) (xy 75.250548 -119.12346) (xy 75.250548 -117.342412) (xy 75.469496 -117.342412)
					(xy 75.469496 -119.526812) (xy 75.850496 -119.526812) (xy 75.850496 -117.342412) (xy 76.740004 -117.342412)
					(xy 76.740004 -119.650002) (xy 75.989942 -120.39981)
				)
			)
		)
		(zone
			(layer "B.Cu")
			(hatch none 0.5)
			(connect_pads
				(clearance 0)
			)
			(min_thickness 0.25)
			(keepout
				(tracks not_allowed)
				(vias allowed)
				(pads allowed)
				(copperpour not_allowed)
				(footprints allowed)
			)
			(placement
				(enabled no)
				(sheetname "")
			)
			(fill
				(thermal_gap 0.5)
				(thermal_bridge_width 0.5)
				(island_removal_mode 0)
			)
			(polygon
				(pts
					(xy 14.014958 -120.39981) (xy 13.264896 -119.650002) (xy 13.264896 -117.342412) (xy 14.154404 -117.342412)
					(xy 14.154404 -119.526812) (xy 14.535404 -119.526812) (xy 14.535404 -117.342412) (xy 14.754606 -117.342412)
					(xy 14.754606 -119.12346) (xy 15.135606 -119.12346) (xy 15.135606 -117.342412) (xy 15.354554 -117.342412)
					(xy 15.354554 -119.12346) (xy 15.735554 -119.12346) (xy 15.735554 -117.342412) (xy 15.954502 -117.342412)
					(xy 15.954502 -119.526812) (xy 16.335502 -119.526812) (xy 16.335502 -117.342412) (xy 16.55445 -117.342412)
					(xy 16.55445 -119.12346) (xy 16.93545 -119.12346) (xy 16.93545 -117.342412) (xy 17.154398 -117.342412)
					(xy 17.154398 -119.12346) (xy 17.535398 -119.12346) (xy 17.535398 -117.342412) (xy 17.7546 -117.342412)
					(xy 17.7546 -119.526812) (xy 18.1356 -119.526812) (xy 18.1356 -117.342412) (xy 18.354548 -117.342412)
					(xy 18.354548 -119.12346) (xy 18.735548 -119.12346) (xy 18.735548 -117.342412) (xy 18.954496 -117.342412)
					(xy 18.954496 -119.12346) (xy 19.335496 -119.12346) (xy 19.335496 -117.342412) (xy 19.554444 -117.342412)
					(xy 19.554444 -119.526812) (xy 19.935444 -119.526812) (xy 19.935444 -117.342412) (xy 20.154392 -117.342412)
					(xy 20.154392 -119.12346) (xy 20.535392 -119.12346) (xy 20.535392 -117.342412) (xy 20.754594 -117.342412)
					(xy 20.754594 -119.12346) (xy 21.135594 -119.12346) (xy 21.135594 -117.342412) (xy 21.354542 -117.342412)
					(xy 21.354542 -119.526812) (xy 21.735542 -119.526812) (xy 21.735542 -117.342412) (xy 21.95449 -117.342412)
					(xy 21.95449 -119.12346) (xy 22.33549 -119.12346) (xy 22.33549 -117.342412) (xy 22.554438 -117.342412)
					(xy 22.554438 -119.12346) (xy 22.935438 -119.12346) (xy 22.935438 -117.342412) (xy 23.154386 -117.342412)
					(xy 23.154386 -119.526812) (xy 23.535386 -119.526812) (xy 23.535386 -117.342412) (xy 23.754588 -117.342412)
					(xy 23.754588 -119.12346) (xy 24.135588 -119.12346) (xy 24.135588 -117.342412) (xy 24.354536 -117.342412)
					(xy 24.354536 -119.12346) (xy 24.735536 -119.12346) (xy 24.735536 -117.342412) (xy 24.954484 -117.342412)
					(xy 24.954484 -119.526812) (xy 25.335484 -119.526812) (xy 25.335484 -117.342412) (xy 25.554432 -117.342412)
					(xy 25.554432 -119.12346) (xy 25.935432 -119.12346) (xy 25.935432 -117.342412) (xy 26.154634 -117.342412)
					(xy 26.154634 -119.12346) (xy 26.535634 -119.12346) (xy 26.535634 -117.342412) (xy 26.754582 -117.342412)
					(xy 26.754582 -119.526812) (xy 27.135582 -119.526812) (xy 27.135582 -117.342412) (xy 27.35453 -117.342412)
					(xy 27.35453 -119.12346) (xy 27.73553 -119.12346) (xy 27.73553 -117.342412) (xy 27.954478 -117.342412)
					(xy 27.954478 -119.12346) (xy 28.335478 -119.12346) (xy 28.335478 -117.342412) (xy 28.554426 -117.342412)
					(xy 28.554426 -119.526812) (xy 28.935426 -119.526812) (xy 28.935426 -117.342412) (xy 29.154628 -117.342412)
					(xy 29.154628 -119.12346) (xy 29.535628 -119.12346) (xy 29.535628 -117.342412) (xy 29.754576 -117.342412)
					(xy 29.754576 -119.12346) (xy 30.135576 -119.12346) (xy 30.135576 -117.342412) (xy 30.354524 -117.342412)
					(xy 30.354524 -119.526812) (xy 30.735524 -119.526812) (xy 30.735524 -117.342412) (xy 31.625032 -117.342412)
					(xy 31.625032 -119.650002) (xy 30.87497 -120.39981)
				)
			)
		)
		(zone
			(layer "B.Cu")
			(hatch none 0.5)
			(connect_pads
				(clearance 0)
			)
			(min_thickness 0.25)
			(keepout
				(tracks not_allowed)
				(vias allowed)
				(pads allowed)
				(copperpour not_allowed)
				(footprints allowed)
			)
			(placement
				(enabled no)
				(sheetname "")
			)
			(fill
				(thermal_gap 0.5)
				(thermal_bridge_width 0.5)
				(island_removal_mode 0)
			)
			(polygon
				(pts
					(xy 46.934882 -120.39981) (xy 46.185074 -119.650002) (xy 46.185074 -117.342412) (xy 47.074582 -117.342412)
					(xy 47.074582 -119.526812) (xy 47.455582 -119.526812) (xy 47.455582 -117.342412) (xy 47.67453 -117.342412)
					(xy 47.67453 -119.12346) (xy 48.05553 -119.12346) (xy 48.05553 -117.342412) (xy 48.274478 -117.342412)
					(xy 48.274478 -119.12346) (xy 48.655478 -119.12346) (xy 48.655478 -117.342412) (xy 48.874426 -117.342412)
					(xy 48.874426 -119.526812) (xy 49.255426 -119.526812) (xy 49.255426 -117.342412) (xy 49.474628 -117.342412)
					(xy 49.474628 -119.12346) (xy 49.855628 -119.12346) (xy 49.855628 -117.342412) (xy 50.074576 -117.342412)
					(xy 50.074576 -119.12346) (xy 50.455576 -119.12346) (xy 50.455576 -117.342412) (xy 50.674524 -117.342412)
					(xy 50.674524 -119.526812) (xy 51.055524 -119.526812) (xy 51.055524 -117.342412) (xy 51.274472 -117.342412)
					(xy 51.274472 -119.12346) (xy 51.655472 -119.12346) (xy 51.655472 -117.342412) (xy 51.87442 -117.342412)
					(xy 51.87442 -119.12346) (xy 52.25542 -119.12346) (xy 52.25542 -117.342412) (xy 52.474622 -117.342412)
					(xy 52.474622 -119.526812) (xy 52.855622 -119.526812) (xy 52.855622 -117.342412) (xy 53.07457 -117.342412)
					(xy 53.07457 -119.12346) (xy 53.45557 -119.12346) (xy 53.45557 -117.342412) (xy 53.674518 -117.342412)
					(xy 53.674518 -119.12346) (xy 54.055518 -119.12346) (xy 54.055518 -117.342412) (xy 54.274466 -117.342412)
					(xy 54.274466 -119.526812) (xy 54.655466 -119.526812) (xy 54.655466 -117.342412) (xy 54.874414 -117.342412)
					(xy 54.874414 -119.12346) (xy 55.255414 -119.12346) (xy 55.255414 -117.342412) (xy 55.474616 -117.342412)
					(xy 55.474616 -119.12346) (xy 55.855616 -119.12346) (xy 55.855616 -117.342412) (xy 56.074564 -117.342412)
					(xy 56.074564 -119.526812) (xy 56.455564 -119.526812) (xy 56.455564 -117.342412) (xy 56.674512 -117.342412)
					(xy 56.674512 -119.12346) (xy 57.055512 -119.12346) (xy 57.055512 -117.342412) (xy 57.27446 -117.342412)
					(xy 57.27446 -119.12346) (xy 57.65546 -119.12346) (xy 57.65546 -117.342412) (xy 57.874408 -117.342412)
					(xy 57.874408 -119.12346) (xy 58.255408 -119.12346) (xy 58.255408 -117.342412) (xy 58.47461 -117.342412)
					(xy 58.47461 -119.12346) (xy 58.85561 -119.12346) (xy 58.85561 -117.342412) (xy 59.074558 -117.342412)
					(xy 59.074558 -119.12346) (xy 59.455558 -119.12346) (xy 59.455558 -117.342412) (xy 59.674506 -117.342412)
					(xy 59.674506 -119.12346) (xy 60.055506 -119.12346) (xy 60.055506 -117.342412) (xy 60.274454 -117.342412)
					(xy 60.274454 -119.526812) (xy 60.655454 -119.526812) (xy 60.655454 -117.342412) (xy 60.874402 -117.342412)
					(xy 60.874402 -119.526812) (xy 61.255402 -119.526812) (xy 61.255402 -117.342412) (xy 61.474604 -117.342412)
					(xy 61.474604 -119.526812) (xy 61.855604 -119.526812) (xy 61.855604 -117.342412) (xy 62.074552 -117.342412)
					(xy 62.074552 -119.526812) (xy 62.455552 -119.526812) (xy 62.455552 -117.342412) (xy 62.6745 -117.342412)
					(xy 62.6745 -119.526812) (xy 63.0555 -119.526812) (xy 63.0555 -117.342412) (xy 63.274448 -117.342412)
					(xy 63.274448 -119.526812) (xy 63.655448 -119.526812) (xy 63.655448 -117.342412) (xy 64.53505 -117.342412)
					(xy 64.53505 -119.650002) (xy 63.784988 -120.39981)
				)
			)
		)
	)
	(footprint ""
		(layer "B.Cu")
		(at 54.675024 -71.820024)
		(property "Reference" "R779"
			(at 0 0 0)
			(layer "B.SilkS")
			(hide yes)
			(effects
				(font
					(size 1.27 1.27)
				)
				(justify mirror)
			)
		)
		(property "Value" ""
			(at 0 0 0)
			(layer "B.Fab")
			(effects
				(font
					(size 1.27 1.27)
				)
				(justify mirror)
			)
		)
		(duplicate_pad_numbers_are_jumpers no)
		(fp_line
			(start -0.7874 -0.4064)
			(end -0.7874 0.4064)
			(stroke
				(width 0.1524)
				(type default)
			)
			(layer "B.SilkS")
		)
		(fp_line
			(start -0.7874 0.4064)
			(end 0.7874 0.4064)
			(stroke
				(width 0.1524)
				(type default)
			)
			(layer "B.SilkS")
		)
		(fp_line
			(start 0.7874 -0.4064)
			(end -0.7874 -0.4064)
			(stroke
				(width 0.1524)
				(type default)
			)
			(layer "B.SilkS")
		)
		(fp_line
			(start 0.7874 0.4064)
			(end 0.7874 -0.4064)
			(stroke
				(width 0.1524)
				(type default)
			)
			(layer "B.SilkS")
		)
		(fp_line
			(start -0.67945 -0.3048)
			(end -0.67945 0.3048)
			(stroke
				(width 0.1)
				(type default)
			)
			(layer "B.Fab")
		)
		(fp_line
			(start -0.67945 0.3048)
			(end -0.120396 0.3048)
			(stroke
				(width 0.1)
				(type default)
			)
			(layer "B.Fab")
		)
		(fp_line
			(start -0.12065 -0.3048)
			(end -0.67945 -0.3048)
			(stroke
				(width 0.1)
				(type default)
			)
			(layer "B.Fab")
		)
		(fp_line
			(start -0.12065 -0.2794)
			(end -0.12065 -0.3048)
			(stroke
				(width 0.1)
				(type default)
			)
			(layer "B.Fab")
		)
		(fp_line
			(start -0.120396 0.2794)
			(end 0.12065 0.2794)
			(stroke
				(width 0.1)
				(type default)
			)
			(layer "B.Fab")
		)
		(fp_line
			(start -0.120396 0.3048)
			(end -0.120396 0.2794)
			(stroke
				(width 0.1)
				(type default)
			)
			(layer "B.Fab")
		)
		(fp_line
			(start 0.12065 -0.305054)
			(end 0.12065 -0.2794)
			(stroke
				(width 0.1)
				(type default)
			)
			(layer "B.Fab")
		)
		(fp_line
			(start 0.12065 -0.2794)
			(end -0.12065 -0.2794)
			(stroke
				(width 0.1)
				(type default)
			)
			(layer "B.Fab")
		)
		(fp_line
			(start 0.12065 0.2794)
			(end 0.12065 0.3048)
			(stroke
				(width 0.1)
				(type default)
			)
			(layer "B.Fab")
		)
		(fp_line
			(start 0.12065 0.3048)
			(end 0.67945 0.3048)
			(stroke
				(width 0.1)
				(type default)
			)
			(layer "B.Fab")
		)
		(fp_line
			(start 0.67945 -0.305054)
			(end 0.12065 -0.305054)
			(stroke
				(width 0.1)
				(type default)
			)
			(layer "B.Fab")
		)
		(fp_line
			(start 0.67945 0.3048)
			(end 0.67945 -0.305054)
			(stroke
				(width 0.1)
				(type default)
			)
			(layer "B.Fab")
		)
		(pad "1" smd circle
			(at 0.40005 0 180)
			(size 0 0)
			(layers "B.Cu" "B.Mask" "B.Paste")
			(net "P2V5_AUX")
		)
		(pad "2" smd circle
			(at -0.40005 0 180)
			(size 0 0)
			(layers "B.Cu" "B.Mask" "B.Paste")
			(net "ADCVREFEXT1")
		)
	)
	(footprint ""
		(layer "B.Cu")
		(at 51.816 -66.7004 90)
		(property "Reference" "R407"
			(at 0 0 90)
			(layer "B.SilkS")
			(hide yes)
			(effects
				(font
					(size 1.27 1.27)
				)
				(justify mirror)
			)
		)
		(property "Value" ""
			(at 0 0 90)
			(layer "B.Fab")
			(effects
				(font
					(size 1.27 1.27)
				)
				(justify mirror)
			)
		)
		(duplicate_pad_numbers_are_jumpers no)
		(fp_line
			(start 0.7874 -0.4064)
			(end -0.7874 -0.4064)
			(stroke
				(width 0.1524)
				(type default)
			)
			(layer "B.SilkS")
		)
		(fp_line
			(start -0.7874 -0.4064)
			(end -0.7874 0.4064)
			(stroke
				(width 0.1524)
				(type default)
			)
			(layer "B.SilkS")
		)
		(fp_line
			(start 0.7874 0.4064)
			(end 0.7874 -0.4064)
			(stroke
				(width 0.1524)
				(type default)
			)
			(layer "B.SilkS")
		)
		(fp_line
			(start -0.7874 0.4064)
			(end 0.7874 0.4064)
			(stroke
				(width 0.1524)
				(type default)
			)
			(layer "B.SilkS")
		)
		(fp_line
			(start 0.67945 -0.305054)
			(end 0.12065 -0.305054)
			(stroke
				(width 0.1)
				(type default)
			)
			(layer "B.Fab")
		)
		(fp_line
			(start 0.12065 -0.305054)
			(end 0.12065 -0.2794)
			(stroke
				(width 0.1)
				(type default)
			)
			(layer "B.Fab")
		)
		(fp_line
			(start -0.12065 -0.3048)
			(end -0.67945 -0.3048)
			(stroke
				(width 0.1)
				(type default)
			)
			(layer "B.Fab")
		)
		(fp_line
			(start -0.67945 -0.3048)
			(end -0.67945 0.3048)
			(stroke
				(width 0.1)
				(type default)
			)
			(layer "B.Fab")
		)
		(fp_line
			(start 0.12065 -0.2794)
			(end -0.12065 -0.2794)
			(stroke
				(width 0.1)
				(type default)
			)
			(layer "B.Fab")
		)
		(fp_line
			(start -0.12065 -0.2794)
			(end -0.12065 -0.3048)
			(stroke
				(width 0.1)
				(type default)
			)
			(layer "B.Fab")
		)
		(fp_line
			(start 0.12065 0.2794)
			(end 0.12065 0.3048)
			(stroke
				(width 0.1)
				(type default)
			)
			(layer "B.Fab")
		)
		(fp_line
			(start -0.120396 0.2794)
			(end 0.12065 0.2794)
			(stroke
				(width 0.1)
				(type default)
			)
			(layer "B.Fab")
		)
		(fp_line
			(start 0.67945 0.3048)
			(end 0.67945 -0.305054)
			(stroke
				(width 0.1)
				(type default)
			)
			(layer "B.Fab")
		)
		(fp_line
			(start 0.12065 0.3048)
			(end 0.67945 0.3048)
			(stroke
				(width 0.1)
				(type default)
			)
			(layer "B.Fab")
		)
		(fp_line
			(start -0.120396 0.3048)
			(end -0.120396 0.2794)
			(stroke
				(width 0.1)
				(type default)
			)
			(layer "B.Fab")
		)
		(fp_line
			(start -0.67945 0.3048)
			(end -0.120396 0.3048)
			(stroke
				(width 0.1)
				(type default)
			)
			(layer "B.Fab")
		)
		(pad "1" smd circle
			(at 0.40005 0 270)
			(size 0 0)
			(layers "B.Cu" "B.Mask" "B.Paste")
			(net "FM_BMC_SUSACK_R1_N")
		)
		(pad "2" smd circle
			(at -0.40005 0 270)
			(size 0 0)
			(layers "B.Cu" "B.Mask" "B.Paste")
			(net "FM_BMC_SUSACK_N")
		)
	)
	(footprint ""
		(layer "B.Cu")
		(at 15.113 -18.161 -90)
		(property "Reference" "C321"
			(at 0 0 90)
			(layer "B.SilkS")
			(hide yes)
			(effects
				(font
					(size 1.27 1.27)
				)
				(justify mirror)
			)
		)
		(property "Value" ""
			(at 0 0 90)
			(layer "B.Fab")
			(effects
				(font
					(size 1.27 1.27)
				)
				(justify mirror)
			)
		)
		(duplicate_pad_numbers_are_jumpers no)
		(fp_line
			(start -0.7874 0.4064)
			(end 0.7874 0.4064)
			(stroke
				(width 0.1524)
				(type default)
			)
			(layer "B.SilkS")
		)
		(fp_line
			(start 0.7874 0.4064)
			(end 0.7874 -0.4064)
			(stroke
				(width 0.1524)
				(type default)
			)
			(layer "B.SilkS")
		)
		(fp_line
			(start -0.7874 -0.4064)
			(end -0.7874 0.4064)
			(stroke
				(width 0.1524)
				(type default)
			)
			(layer "B.SilkS")
		)
		(fp_line
			(start 0.7874 -0.4064)
			(end -0.7874 -0.4064)
			(stroke
				(width 0.1524)
				(type default)
			)
			(layer "B.SilkS")
		)
		(fp_line
			(start -0.67945 0.3048)
			(end -0.120396 0.3048)
			(stroke
				(width 0.1)
				(type default)
			)
			(layer "B.Fab")
		)
		(fp_line
			(start -0.120396 0.3048)
			(end -0.120396 0.2794)
			(stroke
				(width 0.1)
				(type default)
			)
			(layer "B.Fab")
		)
		(fp_line
			(start 0.12065 0.3048)
			(end 0.67945 0.3048)
			(stroke
				(width 0.1)
				(type default)
			)
			(layer "B.Fab")
		)
		(fp_line
			(start 0.67945 0.3048)
			(end 0.67945 -0.305054)
			(stroke
				(width 0.1)
				(type default)
			)
			(layer "B.Fab")
		)
		(fp_line
			(start -0.120396 0.2794)
			(end 0.12065 0.2794)
			(stroke
				(width 0.1)
				(type default)
			)
			(layer "B.Fab")
		)
		(fp_line
			(start 0.12065 0.2794)
			(end 0.12065 0.3048)
			(stroke
				(width 0.1)
				(type default)
			)
			(layer "B.Fab")
		)
		(fp_line
			(start -0.12065 -0.2794)
			(end -0.12065 -0.3048)
			(stroke
				(width 0.1)
				(type default)
			)
			(layer "B.Fab")
		)
		(fp_line
			(start 0.12065 -0.2794)
			(end -0.12065 -0.2794)
			(stroke
				(width 0.1)
				(type default)
			)
			(layer "B.Fab")
		)
		(fp_line
			(start -0.67945 -0.3048)
			(end -0.67945 0.3048)
			(stroke
				(width 0.1)
				(type default)
			)
			(layer "B.Fab")
		)
		(fp_line
			(start -0.12065 -0.3048)
			(end -0.67945 -0.3048)
			(stroke
				(width 0.1)
				(type default)
			)
			(layer "B.Fab")
		)
		(fp_line
			(start 0.12065 -0.305054)
			(end 0.12065 -0.2794)
			(stroke
				(width 0.1)
				(type default)
			)
			(layer "B.Fab")
		)
		(fp_line
			(start 0.67945 -0.305054)
			(end 0.12065 -0.305054)
			(stroke
				(width 0.1)
				(type default)
			)
			(layer "B.Fab")
		)
		(pad "1" smd circle
			(at 0.40005 0 90)
			(size 0 0)
			(layers "B.Cu" "B.Mask" "B.Paste")
			(net "PWR_LED_P5V_AUX")
		)
		(pad "2" smd circle
			(at -0.40005 0 90)
			(size 0 0)
			(layers "B.Cu" "B.Mask" "B.Paste")
			(net "GND")
		)
	)
	(footprint ""
		(layer "B.Cu")
		(at 103.8225 -65.6336 -90)
		(property "Reference" "J20"
			(at 0.8636 -2.95783 270)
			(unlocked yes)
			(layer "B.SilkS")
			(effects
				(font
					(size 0.7874 0.5842)
					(thickness 0.1524)
				)
				(justify left mirror)
			)
		)
		(property "Value" ""
			(at 0 0 90)
			(layer "B.Fab")
			(effects
				(font
					(size 1.27 1.27)
				)
				(justify mirror)
			)
		)
		(duplicate_pad_numbers_are_jumpers no)
		(fp_line
			(start -1.2192 2.1082)
			(end 1.2192 2.1082)
			(stroke
				(width 0.1524)
				(type default)
			)
			(layer "B.SilkS")
		)
		(fp_line
			(start 1.2192 2.1082)
			(end 1.2192 -2.1082)
			(stroke
				(width 0.1524)
				(type default)
			)
			(layer "B.SilkS")
		)
		(fp_line
			(start -1.2192 0.450088)
			(end -1.2192 2.1082)
			(stroke
				(width 0.1524)
				(type default)
			)
			(layer "B.SilkS")
		)
		(fp_line
			(start -1.2192 -2.1082)
			(end -1.2192 -0.466344)
			(stroke
				(width 0.1524)
				(type default)
			)
			(layer "B.SilkS")
		)
		(fp_line
			(start 1.2192 -2.1082)
			(end -1.2192 -2.1082)
			(stroke
				(width 0.1524)
				(type default)
			)
			(layer "B.SilkS")
		)
		(pad "" np_thru_hole circle
			(at -3.4671 -1.27 180)
			(size 1.0414 1.0414)
			(drill 1.0414)
			(layers "*.Cu" "*.Mask")
			(clearance 0.381)
			(thermal_gap 0.381)
		)
		(pad "" np_thru_hole circle
			(at -3.4671 1.27 180)
			(size 1.0414 1.0414)
			(drill 1.0414)
			(layers "*.Cu" "*.Mask")
			(clearance 0.381)
			(thermal_gap 0.381)
		)
		(pad "" np_thru_hole circle
			(at 2.8829 -1.27 180)
			(size 1.0414 1.0414)
			(drill 1.0414)
			(layers "*.Cu" "*.Mask")
			(clearance 0.381)
			(thermal_gap 0.381)
		)
		(pad "" np_thru_hole circle
			(at 2.8829 1.27 180)
			(size 1.0414 1.0414)
			(drill 1.0414)
			(layers "*.Cu" "*.Mask")
			(clearance 0.381)
			(thermal_gap 0.381)
		)
		(pad "1" smd rect
			(at -0.8255 -0.249936 180)
			(size 0.3048 0.508)
			(layers "B.Cu" "B.Mask" "B.Paste")
			(net "85_5INCH_BOT_DP")
		)
		(pad "2" smd rect
			(at -0.8255 0.249936 180)
			(size 0.3048 0.508)
			(layers "B.Cu" "B.Mask" "B.Paste")
			(net "85_5INCH_BOT_DN")
		)
		(pad "3" smd circle
			(at 0 0 90)
			(size 0 0)
			(layers "B.Cu" "B.Mask" "B.Paste")
			(net "GND_P1")
		)
		(zone
			(layers "F.Cu" "B.Cu" "In1.Cu" "In2.Cu" "In3.Cu" "In4.Cu" "In5.Cu" "In6.Cu"
				"In7.Cu" "In8.Cu" "In9.Cu" "In10.Cu"
			)
			(hatch none 0.5)
			(connect_pads
				(clearance 0)
			)
			(min_thickness 0.25)
			(keepout
				(tracks not_allowed)
				(vias allowed)
				(pads allowed)
				(copperpour not_allowed)
				(footprints allowed)
			)
			(placement
				(enabled no)
				(sheetname "")
			)
			(fill
				(thermal_gap 0.5)
				(thermal_bridge_width 0.5)
				(island_removal_mode 0)
			)
			(polygon
				(pts
					(arc
						(start 103.4796 -69.1007)
						(mid 101.6254 -69.1007)
						(end 103.4796 -69.1007)
					)
				)
			)
		)
		(zone
			(layers "F.Cu" "B.Cu" "In1.Cu" "In2.Cu" "In3.Cu" "In4.Cu" "In5.Cu" "In6.Cu"
				"In7.Cu" "In8.Cu" "In9.Cu" "In10.Cu"
			)
			(hatch none 0.5)
			(connect_pads
				(clearance 0)
			)
			(min_thickness 0.25)
			(keepout
				(tracks not_allowed)
				(vias allowed)
				(pads allowed)
				(copperpour not_allowed)
				(footprints allowed)
			)
			(placement
				(enabled no)
				(sheetname "")
			)
			(fill
				(thermal_gap 0.5)
				(thermal_bridge_width 0.5)
				(island_removal_mode 0)
			)
			(polygon
				(pts
					(arc
						(start 103.4796 -62.7507)
						(mid 101.6254 -62.7507)
						(end 103.4796 -62.7507)
					)
				)
			)
		)
		(zone
			(layers "F.Cu" "B.Cu" "In1.Cu" "In2.Cu" "In3.Cu" "In4.Cu" "In5.Cu" "In6.Cu"
				"In7.Cu" "In8.Cu" "In9.Cu" "In10.Cu"
			)
			(hatch none 0.5)
			(connect_pads
				(clearance 0)
			)
			(min_thickness 0.25)
			(keepout
				(tracks not_allowed)
				(vias allowed)
				(pads allowed)
				(copperpour not_allowed)
				(footprints allowed)
			)
			(placement
				(enabled no)
				(sheetname "")
			)
			(fill
				(thermal_gap 0.5)
				(thermal_bridge_width 0.5)
				(island_removal_mode 0)
			)
			(polygon
				(pts
					(arc
						(start 106.0196 -69.1007)
						(mid 104.1654 -69.1007)
						(end 106.0196 -69.1007)
					)
				)
			)
		)
		(zone
			(layers "F.Cu" "B.Cu" "In1.Cu" "In2.Cu" "In3.Cu" "In4.Cu" "In5.Cu" "In6.Cu"
				"In7.Cu" "In8.Cu" "In9.Cu" "In10.Cu"
			)
			(hatch none 0.5)
			(connect_pads
				(clearance 0)
			)
			(min_thickness 0.25)
			(keepout
				(tracks not_allowed)
				(vias allowed)
				(pads allowed)
				(copperpour not_allowed)
				(footprints allowed)
			)
			(placement
				(enabled no)
				(sheetname "")
			)
			(fill
				(thermal_gap 0.5)
				(thermal_bridge_width 0.5)
				(island_removal_mode 0)
			)
			(polygon
				(pts
					(arc
						(start 106.0196 -62.7507)
						(mid 104.1654 -62.7507)
						(end 106.0196 -62.7507)
					)
				)
			)
		)
		(zone
			(layer "B.Cu")
			(hatch none 0.5)
			(connect_pads
				(clearance 0)
			)
			(min_thickness 0.25)
			(keepout
				(tracks not_allowed)
				(vias allowed)
				(pads allowed)
				(copperpour not_allowed)
				(footprints allowed)
			)
			(placement
				(enabled no)
				(sheetname "")
			)
			(fill
				(thermal_gap 0.5)
				(thermal_bridge_width 0.5)
				(island_removal_mode 0)
			)
			(polygon
				(pts
					(xy 104.37114 -66.7512) (xy 104.275636 -66.7512) (xy 104.275636 -66.1543) (xy 103.869236 -66.1543)
					(xy 103.869236 -66.7512) (xy 103.775764 -66.7512) (xy 103.775764 -66.1543) (xy 103.369364 -66.1543)
					(xy 103.369364 -66.7512) (xy 103.27386 -66.7512) (xy 103.27386 -66.0527) (xy 104.37114 -66.0527)
				)
			)
		)
	)
	(footprint ""
		(layer "B.Cu")
		(at 14.2494 -83.693 90)
		(property "Reference" "R808"
			(at 0 0 90)
			(layer "B.SilkS")
			(hide yes)
			(effects
				(font
					(size 1.27 1.27)
				)
				(justify mirror)
			)
		)
		(property "Value" ""
			(at 0 0 90)
			(layer "B.Fab")
			(effects
				(font
					(size 1.27 1.27)
				)
				(justify mirror)
			)
		)
		(duplicate_pad_numbers_are_jumpers no)
		(fp_line
			(start 0.7874 -0.4064)
			(end -0.7874 -0.4064)
			(stroke
				(width 0.1524)
				(type default)
			)
			(layer "B.SilkS")
		)
		(fp_line
			(start -0.7874 -0.4064)
			(end -0.7874 0.4064)
			(stroke
				(width 0.1524)
				(type default)
			)
			(layer "B.SilkS")
		)
		(fp_line
			(start 0.7874 0.4064)
			(end 0.7874 -0.4064)
			(stroke
				(width 0.1524)
				(type default)
			)
			(layer "B.SilkS")
		)
		(fp_line
			(start -0.7874 0.4064)
			(end 0.7874 0.4064)
			(stroke
				(width 0.1524)
				(type default)
			)
			(layer "B.SilkS")
		)
		(fp_line
			(start 0.67945 -0.305054)
			(end 0.12065 -0.305054)
			(stroke
				(width 0.1)
				(type default)
			)
			(layer "B.Fab")
		)
		(fp_line
			(start 0.12065 -0.305054)
			(end 0.12065 -0.2794)
			(stroke
				(width 0.1)
				(type default)
			)
			(layer "B.Fab")
		)
		(fp_line
			(start -0.12065 -0.3048)
			(end -0.67945 -0.3048)
			(stroke
				(width 0.1)
				(type default)
			)
			(layer "B.Fab")
		)
		(fp_line
			(start -0.67945 -0.3048)
			(end -0.67945 0.3048)
			(stroke
				(width 0.1)
				(type default)
			)
			(layer "B.Fab")
		)
		(fp_line
			(start 0.12065 -0.2794)
			(end -0.12065 -0.2794)
			(stroke
				(width 0.1)
				(type default)
			)
			(layer "B.Fab")
		)
		(fp_line
			(start -0.12065 -0.2794)
			(end -0.12065 -0.3048)
			(stroke
				(width 0.1)
				(type default)
			)
			(layer "B.Fab")
		)
		(fp_line
			(start 0.12065 0.2794)
			(end 0.12065 0.3048)
			(stroke
				(width 0.1)
				(type default)
			)
			(layer "B.Fab")
		)
		(fp_line
			(start -0.120396 0.2794)
			(end 0.12065 0.2794)
			(stroke
				(width 0.1)
				(type default)
			)
			(layer "B.Fab")
		)
		(fp_line
			(start 0.67945 0.3048)
			(end 0.67945 -0.305054)
			(stroke
				(width 0.1)
				(type default)
			)
			(layer "B.Fab")
		)
		(fp_line
			(start 0.12065 0.3048)
			(end 0.67945 0.3048)
			(stroke
				(width 0.1)
				(type default)
			)
			(layer "B.Fab")
		)
		(fp_line
			(start -0.120396 0.3048)
			(end -0.120396 0.2794)
			(stroke
				(width 0.1)
				(type default)
			)
			(layer "B.Fab")
		)
		(fp_line
			(start -0.67945 0.3048)
			(end -0.120396 0.3048)
			(stroke
				(width 0.1)
				(type default)
			)
			(layer "B.Fab")
		)
		(pad "1" smd circle
			(at 0.40005 0 270)
			(size 0 0)
			(layers "B.Cu" "B.Mask" "B.Paste")
			(net "PU_FPGA_CONFIG_DONE")
		)
		(pad "2" smd circle
			(at -0.40005 0 270)
			(size 0 0)
			(layers "B.Cu" "B.Mask" "B.Paste")
			(net "PVCCIO_AUX_PLD")
		)
	)
	(footprint ""
		(layer "B.Cu")
		(at 50.240692 -55.170832)
		(property "Reference" "C115"
			(at 0 0 0)
			(layer "B.SilkS")
			(hide yes)
			(effects
				(font
					(size 1.27 1.27)
				)
				(justify mirror)
			)
		)
		(property "Value" ""
			(at 0 0 0)
			(layer "B.Fab")
			(effects
				(font
					(size 1.27 1.27)
				)
				(justify mirror)
			)
		)
		(duplicate_pad_numbers_are_jumpers no)
		(fp_line
			(start -0.7874 -0.4064)
			(end -0.7874 0.4064)
			(stroke
				(width 0.1524)
				(type default)
			)
			(layer "B.SilkS")
		)
		(fp_line
			(start -0.7874 0.4064)
			(end 0.7874 0.4064)
			(stroke
				(width 0.1524)
				(type default)
			)
			(layer "B.SilkS")
		)
		(fp_line
			(start 0.7874 -0.4064)
			(end -0.7874 -0.4064)
			(stroke
				(width 0.1524)
				(type default)
			)
			(layer "B.SilkS")
		)
		(fp_line
			(start 0.7874 0.4064)
			(end 0.7874 -0.4064)
			(stroke
				(width 0.1524)
				(type default)
			)
			(layer "B.SilkS")
		)
		(fp_line
			(start -0.67945 -0.3048)
			(end -0.67945 0.3048)
			(stroke
				(width 0.1)
				(type default)
			)
			(layer "B.Fab")
		)
		(fp_line
			(start -0.67945 0.3048)
			(end -0.120396 0.3048)
			(stroke
				(width 0.1)
				(type default)
			)
			(layer "B.Fab")
		)
		(fp_line
			(start -0.12065 -0.3048)
			(end -0.67945 -0.3048)
			(stroke
				(width 0.1)
				(type default)
			)
			(layer "B.Fab")
		)
		(fp_line
			(start -0.12065 -0.2794)
			(end -0.12065 -0.3048)
			(stroke
				(width 0.1)
				(type default)
			)
			(layer "B.Fab")
		)
		(fp_line
			(start -0.120396 0.2794)
			(end 0.12065 0.2794)
			(stroke
				(width 0.1)
				(type default)
			)
			(layer "B.Fab")
		)
		(fp_line
			(start -0.120396 0.3048)
			(end -0.120396 0.2794)
			(stroke
				(width 0.1)
				(type default)
			)
			(layer "B.Fab")
		)
		(fp_line
			(start 0.12065 -0.305054)
			(end 0.12065 -0.2794)
			(stroke
				(width 0.1)
				(type default)
			)
			(layer "B.Fab")
		)
		(fp_line
			(start 0.12065 -0.2794)
			(end -0.12065 -0.2794)
			(stroke
				(width 0.1)
				(type default)
			)
			(layer "B.Fab")
		)
		(fp_line
			(start 0.12065 0.2794)
			(end 0.12065 0.3048)
			(stroke
				(width 0.1)
				(type default)
			)
			(layer "B.Fab")
		)
		(fp_line
			(start 0.12065 0.3048)
			(end 0.67945 0.3048)
			(stroke
				(width 0.1)
				(type default)
			)
			(layer "B.Fab")
		)
		(fp_line
			(start 0.67945 -0.305054)
			(end 0.12065 -0.305054)
			(stroke
				(width 0.1)
				(type default)
			)
			(layer "B.Fab")
		)
		(fp_line
			(start 0.67945 0.3048)
			(end 0.67945 -0.305054)
			(stroke
				(width 0.1)
				(type default)
			)
			(layer "B.Fab")
		)
		(pad "1" smd circle
			(at 0.40005 0 180)
			(size 0 0)
			(layers "B.Cu" "B.Mask" "B.Paste")
			(net "P3V3_AUX")
		)
		(pad "2" smd circle
			(at -0.40005 0 180)
			(size 0 0)
			(layers "B.Cu" "B.Mask" "B.Paste")
			(net "GND")
		)
	)
	(footprint ""
		(layer "B.Cu")
		(at 47.846742 -73.957688 180)
		(property "Reference" "R776"
			(at 0 0 0)
			(layer "B.SilkS")
			(hide yes)
			(effects
				(font
					(size 1.27 1.27)
				)
				(justify mirror)
			)
		)
		(property "Value" ""
			(at 0 0 0)
			(layer "B.Fab")
			(effects
				(font
					(size 1.27 1.27)
				)
				(justify mirror)
			)
		)
		(duplicate_pad_numbers_are_jumpers no)
		(fp_line
			(start 0.7874 0.4064)
			(end 0.7874 -0.4064)
			(stroke
				(width 0.1524)
				(type default)
			)
			(layer "B.SilkS")
		)
		(fp_line
			(start 0.7874 -0.4064)
			(end -0.7874 -0.4064)
			(stroke
				(width 0.1524)
				(type default)
			)
			(layer "B.SilkS")
		)
		(fp_line
			(start -0.7874 0.4064)
			(end 0.7874 0.4064)
			(stroke
				(width 0.1524)
				(type default)
			)
			(layer "B.SilkS")
		)
		(fp_line
			(start -0.7874 -0.4064)
			(end -0.7874 0.4064)
			(stroke
				(width 0.1524)
				(type default)
			)
			(layer "B.SilkS")
		)
		(fp_line
			(start 0.67945 0.3048)
			(end 0.67945 -0.305054)
			(stroke
				(width 0.1)
				(type default)
			)
			(layer "B.Fab")
		)
		(fp_line
			(start 0.67945 -0.305054)
			(end 0.12065 -0.305054)
			(stroke
				(width 0.1)
				(type default)
			)
			(layer "B.Fab")
		)
		(fp_line
			(start 0.12065 0.3048)
			(end 0.67945 0.3048)
			(stroke
				(width 0.1)
				(type default)
			)
			(layer "B.Fab")
		)
		(fp_line
			(start 0.12065 0.2794)
			(end 0.12065 0.3048)
			(stroke
				(width 0.1)
				(type default)
			)
			(layer "B.Fab")
		)
		(fp_line
			(start 0.12065 -0.2794)
			(end -0.12065 -0.2794)
			(stroke
				(width 0.1)
				(type default)
			)
			(layer "B.Fab")
		)
		(fp_line
			(start 0.12065 -0.305054)
			(end 0.12065 -0.2794)
			(stroke
				(width 0.1)
				(type default)
			)
			(layer "B.Fab")
		)
		(fp_line
			(start -0.120396 0.3048)
			(end -0.120396 0.2794)
			(stroke
				(width 0.1)
				(type default)
			)
			(layer "B.Fab")
		)
		(fp_line
			(start -0.120396 0.2794)
			(end 0.12065 0.2794)
			(stroke
				(width 0.1)
				(type default)
			)
			(layer "B.Fab")
		)
		(fp_line
			(start -0.12065 -0.2794)
			(end -0.12065 -0.3048)
			(stroke
				(width 0.1)
				(type default)
			)
			(layer "B.Fab")
		)
		(fp_line
			(start -0.12065 -0.3048)
			(end -0.67945 -0.3048)
			(stroke
				(width 0.1)
				(type default)
			)
			(layer "B.Fab")
		)
		(fp_line
			(start -0.67945 0.3048)
			(end -0.120396 0.3048)
			(stroke
				(width 0.1)
				(type default)
			)
			(layer "B.Fab")
		)
		(fp_line
			(start -0.67945 -0.3048)
			(end -0.67945 0.3048)
			(stroke
				(width 0.1)
				(type default)
			)
			(layer "B.Fab")
		)
		(pad "1" smd circle
			(at 0.40005 0)
			(size 0 0)
			(layers "B.Cu" "B.Mask" "B.Paste")
			(net "BATTERY_DETECT_R")
		)
		(pad "2" smd circle
			(at -0.40005 0)
			(size 0 0)
			(layers "B.Cu" "B.Mask" "B.Paste")
			(net "GND")
		)
	)
	(footprint ""
		(layer "B.Cu")
		(at 53.337968 -43.761406 180)
		(property "Reference" "C110"
			(at 0 0 0)
			(layer "B.SilkS")
			(hide yes)
			(effects
				(font
					(size 1.27 1.27)
				)
				(justify mirror)
			)
		)
		(property "Value" ""
			(at 0 0 0)
			(layer "B.Fab")
			(effects
				(font
					(size 1.27 1.27)
				)
				(justify mirror)
			)
		)
		(duplicate_pad_numbers_are_jumpers no)
		(fp_line
			(start 0.7874 0.4064)
			(end 0.7874 -0.4064)
			(stroke
				(width 0.1524)
				(type default)
			)
			(layer "B.SilkS")
		)
		(fp_line
			(start 0.7874 -0.4064)
			(end -0.7874 -0.4064)
			(stroke
				(width 0.1524)
				(type default)
			)
			(layer "B.SilkS")
		)
		(fp_line
			(start -0.7874 0.4064)
			(end 0.7874 0.4064)
			(stroke
				(width 0.1524)
				(type default)
			)
			(layer "B.SilkS")
		)
		(fp_line
			(start -0.7874 -0.4064)
			(end -0.7874 0.4064)
			(stroke
				(width 0.1524)
				(type default)
			)
			(layer "B.SilkS")
		)
		(fp_line
			(start 0.67945 0.3048)
			(end 0.67945 -0.305054)
			(stroke
				(width 0.1)
				(type default)
			)
			(layer "B.Fab")
		)
		(fp_line
			(start 0.67945 -0.305054)
			(end 0.12065 -0.305054)
			(stroke
				(width 0.1)
				(type default)
			)
			(layer "B.Fab")
		)
		(fp_line
			(start 0.12065 0.3048)
			(end 0.67945 0.3048)
			(stroke
				(width 0.1)
				(type default)
			)
			(layer "B.Fab")
		)
		(fp_line
			(start 0.12065 0.2794)
			(end 0.12065 0.3048)
			(stroke
				(width 0.1)
				(type default)
			)
			(layer "B.Fab")
		)
		(fp_line
			(start 0.12065 -0.2794)
			(end -0.12065 -0.2794)
			(stroke
				(width 0.1)
				(type default)
			)
			(layer "B.Fab")
		)
		(fp_line
			(start 0.12065 -0.305054)
			(end 0.12065 -0.2794)
			(stroke
				(width 0.1)
				(type default)
			)
			(layer "B.Fab")
		)
		(fp_line
			(start -0.120396 0.3048)
			(end -0.120396 0.2794)
			(stroke
				(width 0.1)
				(type default)
			)
			(layer "B.Fab")
		)
		(fp_line
			(start -0.120396 0.2794)
			(end 0.12065 0.2794)
			(stroke
				(width 0.1)
				(type default)
			)
			(layer "B.Fab")
		)
		(fp_line
			(start -0.12065 -0.2794)
			(end -0.12065 -0.3048)
			(stroke
				(width 0.1)
				(type default)
			)
			(layer "B.Fab")
		)
		(fp_line
			(start -0.12065 -0.3048)
			(end -0.67945 -0.3048)
			(stroke
				(width 0.1)
				(type default)
			)
			(layer "B.Fab")
		)
		(fp_line
			(start -0.67945 0.3048)
			(end -0.120396 0.3048)
			(stroke
				(width 0.1)
				(type default)
			)
			(layer "B.Fab")
		)
		(fp_line
			(start -0.67945 -0.3048)
			(end -0.67945 0.3048)
			(stroke
				(width 0.1)
				(type default)
			)
			(layer "B.Fab")
		)
		(pad "1" smd circle
			(at 0.40005 0)
			(size 0 0)
			(layers "B.Cu" "B.Mask" "B.Paste")
			(net "P3V3_AUX")
		)
		(pad "2" smd circle
			(at -0.40005 0)
			(size 0 0)
			(layers "B.Cu" "B.Mask" "B.Paste")
			(net "GND")
		)
	)
	(footprint ""
		(layer "B.Cu")
		(at 26.259536 -89.98712 180)
		(property "Reference" "C218"
			(at 0 0 0)
			(layer "B.SilkS")
			(hide yes)
			(effects
				(font
					(size 1.27 1.27)
				)
				(justify mirror)
			)
		)
		(property "Value" ""
			(at 0 0 0)
			(layer "B.Fab")
			(effects
				(font
					(size 1.27 1.27)
				)
				(justify mirror)
			)
		)
		(duplicate_pad_numbers_are_jumpers no)
		(fp_line
			(start 0.69215 0.2921)
			(end 0.69215 -0.2921)
			(stroke
				(width 0.1524)
				(type default)
			)
			(layer "B.SilkS")
		)
		(fp_line
			(start 0.69215 -0.2921)
			(end -0.69215 -0.2921)
			(stroke
				(width 0.1524)
				(type default)
			)
			(layer "B.SilkS")
		)
		(fp_line
			(start -0.69215 0.2921)
			(end 0.69215 0.2921)
			(stroke
				(width 0.1524)
				(type default)
			)
			(layer "B.SilkS")
		)
		(fp_line
			(start -0.69215 -0.2921)
			(end -0.69215 0.2921)
			(stroke
				(width 0.1524)
				(type default)
			)
			(layer "B.SilkS")
		)
		(fp_line
			(start 0.51435 0.2794)
			(end 0.51435 -0.2794)
			(stroke
				(width 0.1)
				(type default)
			)
			(layer "B.Fab")
		)
		(fp_line
			(start 0.51435 -0.2794)
			(end -0.51435 -0.2794)
			(stroke
				(width 0.1)
				(type default)
			)
			(layer "B.Fab")
		)
		(fp_line
			(start -0.51435 0.2794)
			(end 0.51435 0.2794)
			(stroke
				(width 0.1)
				(type default)
			)
			(layer "B.Fab")
		)
		(fp_line
			(start -0.51435 -0.2794)
			(end -0.51435 0.2794)
			(stroke
				(width 0.1)
				(type default)
			)
			(layer "B.Fab")
		)
		(pad "1" smd circle
			(at 0.40005 0)
			(size 0 0)
			(layers "B.Cu" "B.Mask" "B.Paste")
			(net "VCCIO5")
		)
		(pad "2" smd circle
			(at -0.40005 0)
			(size 0 0)
			(layers "B.Cu" "B.Mask" "B.Paste")
			(net "GND")
		)
		(zone
			(layer "B.Cu")
			(hatch none 0.5)
			(connect_pads
				(clearance 0)
			)
			(min_thickness 0.25)
			(keepout
				(tracks not_allowed)
				(vias allowed)
				(pads allowed)
				(copperpour not_allowed)
				(footprints allowed)
			)
			(placement
				(enabled no)
				(sheetname "")
			)
			(fill
				(thermal_gap 0.5)
				(thermal_bridge_width 0.5)
				(island_removal_mode 0)
			)
			(polygon
				(pts
					(xy 26.069036 -90.07475) (xy 26.160476 -90.132916) (xy 26.359866 -90.132916) (xy 26.450036 -90.07475)
					(xy 26.450036 -89.89949) (xy 26.359866 -89.84107) (xy 26.160476 -89.84107) (xy 26.069036 -89.899236)
				)
			)
		)
	)
	(footprint ""
		(layer "B.Cu")
		(at 71.599806 -72.047608 -90)
		(property "Reference" "R685"
			(at 0 0 90)
			(layer "B.SilkS")
			(hide yes)
			(effects
				(font
					(size 1.27 1.27)
				)
				(justify mirror)
			)
		)
		(property "Value" ""
			(at 0 0 90)
			(layer "B.Fab")
			(effects
				(font
					(size 1.27 1.27)
				)
				(justify mirror)
			)
		)
		(duplicate_pad_numbers_are_jumpers no)
		(fp_line
			(start -0.7874 0.4064)
			(end 0.7874 0.4064)
			(stroke
				(width 0.1524)
				(type default)
			)
			(layer "B.SilkS")
		)
		(fp_line
			(start 0.7874 0.4064)
			(end 0.7874 -0.4064)
			(stroke
				(width 0.1524)
				(type default)
			)
			(layer "B.SilkS")
		)
		(fp_line
			(start -0.7874 -0.4064)
			(end -0.7874 0.4064)
			(stroke
				(width 0.1524)
				(type default)
			)
			(layer "B.SilkS")
		)
		(fp_line
			(start 0.7874 -0.4064)
			(end -0.7874 -0.4064)
			(stroke
				(width 0.1524)
				(type default)
			)
			(layer "B.SilkS")
		)
		(fp_line
			(start -0.67945 0.3048)
			(end -0.120396 0.3048)
			(stroke
				(width 0.1)
				(type default)
			)
			(layer "B.Fab")
		)
		(fp_line
			(start -0.120396 0.3048)
			(end -0.120396 0.2794)
			(stroke
				(width 0.1)
				(type default)
			)
			(layer "B.Fab")
		)
		(fp_line
			(start 0.12065 0.3048)
			(end 0.67945 0.3048)
			(stroke
				(width 0.1)
				(type default)
			)
			(layer "B.Fab")
		)
		(fp_line
			(start 0.67945 0.3048)
			(end 0.67945 -0.305054)
			(stroke
				(width 0.1)
				(type default)
			)
			(layer "B.Fab")
		)
		(fp_line
			(start -0.120396 0.2794)
			(end 0.12065 0.2794)
			(stroke
				(width 0.1)
				(type default)
			)
			(layer "B.Fab")
		)
		(fp_line
			(start 0.12065 0.2794)
			(end 0.12065 0.3048)
			(stroke
				(width 0.1)
				(type default)
			)
			(layer "B.Fab")
		)
		(fp_line
			(start -0.12065 -0.2794)
			(end -0.12065 -0.3048)
			(stroke
				(width 0.1)
				(type default)
			)
			(layer "B.Fab")
		)
		(fp_line
			(start 0.12065 -0.2794)
			(end -0.12065 -0.2794)
			(stroke
				(width 0.1)
				(type default)
			)
			(layer "B.Fab")
		)
		(fp_line
			(start -0.67945 -0.3048)
			(end -0.67945 0.3048)
			(stroke
				(width 0.1)
				(type default)
			)
			(layer "B.Fab")
		)
		(fp_line
			(start -0.12065 -0.3048)
			(end -0.67945 -0.3048)
			(stroke
				(width 0.1)
				(type default)
			)
			(layer "B.Fab")
		)
		(fp_line
			(start 0.12065 -0.305054)
			(end 0.12065 -0.2794)
			(stroke
				(width 0.1)
				(type default)
			)
			(layer "B.Fab")
		)
		(fp_line
			(start 0.67945 -0.305054)
			(end 0.12065 -0.305054)
			(stroke
				(width 0.1)
				(type default)
			)
			(layer "B.Fab")
		)
		(pad "1" smd circle
			(at 0.40005 0 90)
			(size 0 0)
			(layers "B.Cu" "B.Mask" "B.Paste")
			(net "BMC_EMMC_CD_N")
		)
		(pad "2" smd circle
			(at -0.40005 0 90)
			(size 0 0)
			(layers "B.Cu" "B.Mask" "B.Paste")
			(net "GND")
		)
	)
	(footprint ""
		(layer "B.Cu")
		(at 19.6342 -75.3618 180)
		(property "Reference" "C318"
			(at 0 0 0)
			(layer "B.SilkS")
			(hide yes)
			(effects
				(font
					(size 1.27 1.27)
				)
				(justify mirror)
			)
		)
		(property "Value" ""
			(at 0 0 0)
			(layer "B.Fab")
			(effects
				(font
					(size 1.27 1.27)
				)
				(justify mirror)
			)
		)
		(duplicate_pad_numbers_are_jumpers no)
		(fp_line
			(start 0.7874 0.4064)
			(end 0.7874 -0.4064)
			(stroke
				(width 0.1524)
				(type default)
			)
			(layer "B.SilkS")
		)
		(fp_line
			(start 0.7874 -0.4064)
			(end -0.7874 -0.4064)
			(stroke
				(width 0.1524)
				(type default)
			)
			(layer "B.SilkS")
		)
		(fp_line
			(start -0.7874 0.4064)
			(end 0.7874 0.4064)
			(stroke
				(width 0.1524)
				(type default)
			)
			(layer "B.SilkS")
		)
		(fp_line
			(start -0.7874 -0.4064)
			(end -0.7874 0.4064)
			(stroke
				(width 0.1524)
				(type default)
			)
			(layer "B.SilkS")
		)
		(fp_line
			(start 0.67945 0.3048)
			(end 0.67945 -0.305054)
			(stroke
				(width 0.1)
				(type default)
			)
			(layer "B.Fab")
		)
		(fp_line
			(start 0.67945 -0.305054)
			(end 0.12065 -0.305054)
			(stroke
				(width 0.1)
				(type default)
			)
			(layer "B.Fab")
		)
		(fp_line
			(start 0.12065 0.3048)
			(end 0.67945 0.3048)
			(stroke
				(width 0.1)
				(type default)
			)
			(layer "B.Fab")
		)
		(fp_line
			(start 0.12065 0.2794)
			(end 0.12065 0.3048)
			(stroke
				(width 0.1)
				(type default)
			)
			(layer "B.Fab")
		)
		(fp_line
			(start 0.12065 -0.2794)
			(end -0.12065 -0.2794)
			(stroke
				(width 0.1)
				(type default)
			)
			(layer "B.Fab")
		)
		(fp_line
			(start 0.12065 -0.305054)
			(end 0.12065 -0.2794)
			(stroke
				(width 0.1)
				(type default)
			)
			(layer "B.Fab")
		)
		(fp_line
			(start -0.120396 0.3048)
			(end -0.120396 0.2794)
			(stroke
				(width 0.1)
				(type default)
			)
			(layer "B.Fab")
		)
		(fp_line
			(start -0.120396 0.2794)
			(end 0.12065 0.2794)
			(stroke
				(width 0.1)
				(type default)
			)
			(layer "B.Fab")
		)
		(fp_line
			(start -0.12065 -0.2794)
			(end -0.12065 -0.3048)
			(stroke
				(width 0.1)
				(type default)
			)
			(layer "B.Fab")
		)
		(fp_line
			(start -0.12065 -0.3048)
			(end -0.67945 -0.3048)
			(stroke
				(width 0.1)
				(type default)
			)
			(layer "B.Fab")
		)
		(fp_line
			(start -0.67945 0.3048)
			(end -0.120396 0.3048)
			(stroke
				(width 0.1)
				(type default)
			)
			(layer "B.Fab")
		)
		(fp_line
			(start -0.67945 -0.3048)
			(end -0.67945 0.3048)
			(stroke
				(width 0.1)
				(type default)
			)
			(layer "B.Fab")
		)
		(pad "1" smd circle
			(at 0.40005 0)
			(size 0 0)
			(layers "B.Cu" "B.Mask" "B.Paste")
			(net "P3V3_AUX")
		)
		(pad "2" smd circle
			(at -0.40005 0)
			(size 0 0)
			(layers "B.Cu" "B.Mask" "B.Paste")
			(net "GND")
		)
	)
	(footprint ""
		(layer "B.Cu")
		(at -7.874 -109.728 180)
		(property "Reference" "DB1"
			(at 1.7526 -5.76707 0)
			(unlocked yes)
			(layer "B.SilkS")
			(effects
				(font
					(size 0.7874 0.5842)
					(thickness 0.1524)
				)
				(justify left mirror)
			)
		)
		(property "Value" ""
			(at 0 0 0)
			(layer "B.Fab")
			(effects
				(font
					(size 1.27 1.27)
				)
				(justify mirror)
			)
		)
		(duplicate_pad_numbers_are_jumpers no)
		(fp_line
			(start 3.330702 -4.771136)
			(end -3.330702 -4.771136)
			(stroke
				(width 0.1524)
				(type default)
			)
			(layer "B.SilkS")
		)
		(fp_line
			(start 0 4.011168)
			(end 3.330702 -4.771136)
			(stroke
				(width 0.1524)
				(type default)
			)
			(layer "B.SilkS")
		)
		(fp_line
			(start -3.330702 -4.771136)
			(end 0 4.011168)
			(stroke
				(width 0.1524)
				(type default)
			)
			(layer "B.SilkS")
		)
		(fp_line
			(start 3.330702 -4.771136)
			(end -3.330702 -4.771136)
			(stroke
				(width 0.1)
				(type default)
			)
			(layer "B.Fab")
		)
		(fp_line
			(start 0 4.011168)
			(end 3.330702 -4.771136)
			(stroke
				(width 0.1)
				(type default)
			)
			(layer "B.Fab")
		)
		(fp_line
			(start -3.330702 -4.771136)
			(end 0 4.011168)
			(stroke
				(width 0.1)
				(type default)
			)
			(layer "B.Fab")
		)
		(pad "1" thru_hole circle
			(at 0 0)
			(size 2.159 2.159)
			(drill 1.7018)
			(layers "*.Cu" "*.Mask")
			(remove_unused_layers no)
			(net "T_GND")
			(clearance 0.0254)
			(thermal_gap 0.0254)
		)
		(pad "2" thru_hole circle
			(at 1.27 -3.348736)
			(size 2.159 2.159)
			(drill 1.7018)
			(layers "*.Cu" "*.Mask")
			(remove_unused_layers no)
			(net "TDR_SE_50_OHM_TOP")
			(clearance 0.0254)
			(thermal_gap 0.0254)
		)
		(pad "3" thru_hole circle
			(at -1.27 -3.348736)
			(size 2.159 2.159)
			(drill 1.7018)
			(layers "*.Cu" "*.Mask")
			(remove_unused_layers no)
			(net "TDR_SE_50_OHM_TOP")
			(clearance 0.0254)
			(thermal_gap 0.0254)
		)
	)
	(footprint ""
		(layer "B.Cu")
		(at 53.719476 -47.913036 90)
		(property "Reference" "C107"
			(at 0 0 90)
			(layer "B.SilkS")
			(hide yes)
			(effects
				(font
					(size 1.27 1.27)
				)
				(justify mirror)
			)
		)
		(property "Value" ""
			(at 0 0 90)
			(layer "B.Fab")
			(effects
				(font
					(size 1.27 1.27)
				)
				(justify mirror)
			)
		)
		(duplicate_pad_numbers_are_jumpers no)
		(fp_line
			(start 0.7874 -0.4064)
			(end -0.7874 -0.4064)
			(stroke
				(width 0.1524)
				(type default)
			)
			(layer "B.SilkS")
		)
		(fp_line
			(start -0.7874 -0.4064)
			(end -0.7874 0.4064)
			(stroke
				(width 0.1524)
				(type default)
			)
			(layer "B.SilkS")
		)
		(fp_line
			(start 0.7874 0.4064)
			(end 0.7874 -0.4064)
			(stroke
				(width 0.1524)
				(type default)
			)
			(layer "B.SilkS")
		)
		(fp_line
			(start -0.7874 0.4064)
			(end 0.7874 0.4064)
			(stroke
				(width 0.1524)
				(type default)
			)
			(layer "B.SilkS")
		)
		(fp_line
			(start 0.67945 -0.305054)
			(end 0.12065 -0.305054)
			(stroke
				(width 0.1)
				(type default)
			)
			(layer "B.Fab")
		)
		(fp_line
			(start 0.12065 -0.305054)
			(end 0.12065 -0.2794)
			(stroke
				(width 0.1)
				(type default)
			)
			(layer "B.Fab")
		)
		(fp_line
			(start -0.12065 -0.3048)
			(end -0.67945 -0.3048)
			(stroke
				(width 0.1)
				(type default)
			)
			(layer "B.Fab")
		)
		(fp_line
			(start -0.67945 -0.3048)
			(end -0.67945 0.3048)
			(stroke
				(width 0.1)
				(type default)
			)
			(layer "B.Fab")
		)
		(fp_line
			(start 0.12065 -0.2794)
			(end -0.12065 -0.2794)
			(stroke
				(width 0.1)
				(type default)
			)
			(layer "B.Fab")
		)
		(fp_line
			(start -0.12065 -0.2794)
			(end -0.12065 -0.3048)
			(stroke
				(width 0.1)
				(type default)
			)
			(layer "B.Fab")
		)
		(fp_line
			(start 0.12065 0.2794)
			(end 0.12065 0.3048)
			(stroke
				(width 0.1)
				(type default)
			)
			(layer "B.Fab")
		)
		(fp_line
			(start -0.120396 0.2794)
			(end 0.12065 0.2794)
			(stroke
				(width 0.1)
				(type default)
			)
			(layer "B.Fab")
		)
		(fp_line
			(start 0.67945 0.3048)
			(end 0.67945 -0.305054)
			(stroke
				(width 0.1)
				(type default)
			)
			(layer "B.Fab")
		)
		(fp_line
			(start 0.12065 0.3048)
			(end 0.67945 0.3048)
			(stroke
				(width 0.1)
				(type default)
			)
			(layer "B.Fab")
		)
		(fp_line
			(start -0.120396 0.3048)
			(end -0.120396 0.2794)
			(stroke
				(width 0.1)
				(type default)
			)
			(layer "B.Fab")
		)
		(fp_line
			(start -0.67945 0.3048)
			(end -0.120396 0.3048)
			(stroke
				(width 0.1)
				(type default)
			)
			(layer "B.Fab")
		)
		(pad "1" smd circle
			(at 0.40005 0 270)
			(size 0 0)
			(layers "B.Cu" "B.Mask" "B.Paste")
			(net "P1V2_AUX")
		)
		(pad "2" smd circle
			(at -0.40005 0 270)
			(size 0 0)
			(layers "B.Cu" "B.Mask" "B.Paste")
			(net "GND")
		)
	)
	(footprint ""
		(layer "B.Cu")
		(at 71.676768 -51.63185 90)
		(property "Reference" "C5"
			(at 0 0 90)
			(layer "B.SilkS")
			(hide yes)
			(effects
				(font
					(size 1.27 1.27)
				)
				(justify mirror)
			)
		)
		(property "Value" ""
			(at 0 0 90)
			(layer "B.Fab")
			(effects
				(font
					(size 1.27 1.27)
				)
				(justify mirror)
			)
		)
		(duplicate_pad_numbers_are_jumpers no)
		(fp_line
			(start 0.7874 -0.4064)
			(end -0.7874 -0.4064)
			(stroke
				(width 0.1524)
				(type default)
			)
			(layer "B.SilkS")
		)
		(fp_line
			(start -0.7874 -0.4064)
			(end -0.7874 0.4064)
			(stroke
				(width 0.1524)
				(type default)
			)
			(layer "B.SilkS")
		)
		(fp_line
			(start 0.7874 0.4064)
			(end 0.7874 -0.4064)
			(stroke
				(width 0.1524)
				(type default)
			)
			(layer "B.SilkS")
		)
		(fp_line
			(start -0.7874 0.4064)
			(end 0.7874 0.4064)
			(stroke
				(width 0.1524)
				(type default)
			)
			(layer "B.SilkS")
		)
		(fp_line
			(start 0.67945 -0.305054)
			(end 0.12065 -0.305054)
			(stroke
				(width 0.1)
				(type default)
			)
			(layer "B.Fab")
		)
		(fp_line
			(start 0.12065 -0.305054)
			(end 0.12065 -0.2794)
			(stroke
				(width 0.1)
				(type default)
			)
			(layer "B.Fab")
		)
		(fp_line
			(start -0.12065 -0.3048)
			(end -0.67945 -0.3048)
			(stroke
				(width 0.1)
				(type default)
			)
			(layer "B.Fab")
		)
		(fp_line
			(start -0.67945 -0.3048)
			(end -0.67945 0.3048)
			(stroke
				(width 0.1)
				(type default)
			)
			(layer "B.Fab")
		)
		(fp_line
			(start 0.12065 -0.2794)
			(end -0.12065 -0.2794)
			(stroke
				(width 0.1)
				(type default)
			)
			(layer "B.Fab")
		)
		(fp_line
			(start -0.12065 -0.2794)
			(end -0.12065 -0.3048)
			(stroke
				(width 0.1)
				(type default)
			)
			(layer "B.Fab")
		)
		(fp_line
			(start 0.12065 0.2794)
			(end 0.12065 0.3048)
			(stroke
				(width 0.1)
				(type default)
			)
			(layer "B.Fab")
		)
		(fp_line
			(start -0.120396 0.2794)
			(end 0.12065 0.2794)
			(stroke
				(width 0.1)
				(type default)
			)
			(layer "B.Fab")
		)
		(fp_line
			(start 0.67945 0.3048)
			(end 0.67945 -0.305054)
			(stroke
				(width 0.1)
				(type default)
			)
			(layer "B.Fab")
		)
		(fp_line
			(start 0.12065 0.3048)
			(end 0.67945 0.3048)
			(stroke
				(width 0.1)
				(type default)
			)
			(layer "B.Fab")
		)
		(fp_line
			(start -0.120396 0.3048)
			(end -0.120396 0.2794)
			(stroke
				(width 0.1)
				(type default)
			)
			(layer "B.Fab")
		)
		(fp_line
			(start -0.67945 0.3048)
			(end -0.120396 0.3048)
			(stroke
				(width 0.1)
				(type default)
			)
			(layer "B.Fab")
		)
		(pad "1" smd circle
			(at 0.40005 0 270)
			(size 0 0)
			(layers "B.Cu" "B.Mask" "B.Paste")
			(net "P1V2_AUX")
		)
		(pad "2" smd circle
			(at -0.40005 0 270)
			(size 0 0)
			(layers "B.Cu" "B.Mask" "B.Paste")
			(net "GND")
		)
	)
	(footprint ""
		(layer "B.Cu")
		(at 79.7814 -68.6562 90)
		(property "Reference" "U52"
			(at -0.2794 1.97993 270)
			(unlocked yes)
			(layer "B.SilkS")
			(effects
				(font
					(size 0.7874 0.5842)
					(thickness 0.1524)
				)
				(justify mirror)
			)
		)
		(property "Value" ""
			(at 0 0 90)
			(layer "B.Fab")
			(effects
				(font
					(size 1.27 1.27)
				)
				(justify mirror)
			)
		)
		(duplicate_pad_numbers_are_jumpers no)
		(fp_line
			(start 0.254 -1.1176)
			(end 1.7018 -1.1176)
			(stroke
				(width 0.1524)
				(type default)
			)
			(layer "B.SilkS")
		)
		(fp_line
			(start -0.254 -1.1176)
			(end 0 -0.7112)
			(stroke
				(width 0.1524)
				(type default)
			)
			(layer "B.SilkS")
		)
		(fp_line
			(start -1.7018 -1.1176)
			(end -0.254 -1.1176)
			(stroke
				(width 0.1524)
				(type default)
			)
			(layer "B.SilkS")
		)
		(fp_line
			(start -1.7018 -1.1176)
			(end -1.7018 1.1176)
			(stroke
				(width 0.1524)
				(type default)
			)
			(layer "B.SilkS")
		)
		(fp_line
			(start 0 -0.7112)
			(end 0.254 -1.1176)
			(stroke
				(width 0.1524)
				(type default)
			)
			(layer "B.SilkS")
		)
		(fp_line
			(start 1.7018 1.1176)
			(end 1.7018 -1.1176)
			(stroke
				(width 0.1524)
				(type default)
			)
			(layer "B.SilkS")
		)
		(fp_line
			(start -1.7018 1.1176)
			(end 1.7018 1.1176)
			(stroke
				(width 0.1524)
				(type default)
			)
			(layer "B.SilkS")
		)
		(fp_poly
			(pts
				(xy 1.8161 -0.675386) (xy 2.4003 -0.446786) (xy 2.4003 -0.878586)
			)
			(stroke
				(width 0)
				(type default)
			)
			(fill yes)
			(layer "B.SilkS")
		)
		(fp_line
			(start 0.254 -1.1176)
			(end 1.5494 -1.1176)
			(stroke
				(width 0.1)
				(type default)
			)
			(layer "B.Fab")
		)
		(fp_line
			(start -0.254 -1.1176)
			(end 0.254 -1.1176)
			(stroke
				(width 0.1)
				(type default)
			)
			(layer "B.Fab")
		)
		(fp_line
			(start -1.5494 -1.1176)
			(end -0.254 -1.1176)
			(stroke
				(width 0.1)
				(type default)
			)
			(layer "B.Fab")
		)
		(fp_line
			(start -1.5494 -1.1176)
			(end -1.5494 1.1176)
			(stroke
				(width 0.1)
				(type default)
			)
			(layer "B.Fab")
		)
		(fp_line
			(start 1.5494 1.1176)
			(end 1.5494 -1.1176)
			(stroke
				(width 0.1)
				(type default)
			)
			(layer "B.Fab")
		)
		(fp_line
			(start -1.5494 1.1176)
			(end 1.5494 1.1176)
			(stroke
				(width 0.1)
				(type default)
			)
			(layer "B.Fab")
		)
		(fp_poly
			(pts
				(xy 1.8161 -0.675386) (xy 2.4003 -0.446786) (xy 2.4003 -0.878586)
			)
			(stroke
				(width 0)
				(type default)
			)
			(fill yes)
			(layer "B.Fab")
		)
		(pad "1" smd rect
			(at 0.962406 -0.649986)
			(size 0.3302 1.1684)
			(layers "B.Cu" "B.Mask" "B.Paste")
			(net "PWRGD_P5V_AUX")
		)
		(pad "2" smd rect
			(at 0.962406 0)
			(size 0.3302 1.1684)
			(layers "B.Cu" "B.Mask" "B.Paste")
			(net "PWRGD_P3V3_RGM")
		)
		(pad "3" smd rect
			(at 0.962406 0.649986)
			(size 0.3302 1.1684)
			(layers "B.Cu" "B.Mask" "B.Paste")
			(net "GND")
		)
		(pad "4" smd rect
			(at -0.962406 0.649986)
			(size 0.3302 1.1684)
			(layers "B.Cu" "B.Mask" "B.Paste")
			(net "EN_P1V2_AUX")
		)
		(pad "5" smd rect
			(at -0.962406 -0.649986)
			(size 0.3302 1.1684)
			(layers "B.Cu" "B.Mask" "B.Paste")
			(net "P3V3_LDO")
		)
	)
	(footprint ""
		(layer "B.Cu")
		(at 112.014 -58.42 90)
		(property "Reference" "X2"
			(at 1.99263 2.8448 0)
			(unlocked yes)
			(layer "B.SilkS")
			(effects
				(font
					(size 0.7874 0.5842)
					(thickness 0.1524)
				)
				(justify left mirror)
			)
		)
		(property "Value" ""
			(at 0 0 90)
			(layer "B.Fab")
			(effects
				(font
					(size 1.27 1.27)
				)
				(justify mirror)
			)
		)
		(property "Device Type" "TP_TDR_4P_FTS_TH-TP_TDR_4P_DIPA"
			(at -1.30175 1.27 0)
			(unlocked yes)
			(layer "B.Fab")
			(hide yes)
			(effects
				(font
					(size 0.635 0.4064)
					(thickness 0.1524)
				)
				(justify mirror)
			)
		)
		(property "User Part Number" "N_A"
			(at -1.30175 1.27 0)
			(unlocked yes)
			(layer "Cmts.User")
			(hide yes)
			(effects
				(font
					(size 0.635 0.4064)
					(thickness 0.1524)
				)
				(justify mirror)
			)
		)
		(duplicate_pad_numbers_are_jumpers no)
		(fp_line
			(start 0 -1.27)
			(end 0 -0.635)
			(stroke
				(width 0.1524)
				(type default)
			)
			(layer "B.SilkS")
		)
		(fp_line
			(start -2.54 -1.27)
			(end 0 -1.27)
			(stroke
				(width 0.1524)
				(type default)
			)
			(layer "B.SilkS")
		)
		(fp_line
			(start -2.54 -1.1303)
			(end -2.54 -1.27)
			(stroke
				(width 0.1524)
				(type default)
			)
			(layer "B.SilkS")
		)
		(fp_line
			(start 0 0.635)
			(end 0 1.905)
			(stroke
				(width 0.1524)
				(type default)
			)
			(layer "B.SilkS")
		)
		(fp_line
			(start -2.54 1.4097)
			(end -2.54 1.1303)
			(stroke
				(width 0.1524)
				(type default)
			)
			(layer "B.SilkS")
		)
		(fp_line
			(start 0 3.175)
			(end 0 3.81)
			(stroke
				(width 0.1524)
				(type default)
			)
			(layer "B.SilkS")
		)
		(fp_line
			(start 0 3.81)
			(end -2.54 3.81)
			(stroke
				(width 0.1524)
				(type default)
			)
			(layer "B.SilkS")
		)
		(fp_line
			(start -2.54 3.81)
			(end -2.54 3.6703)
			(stroke
				(width 0.1524)
				(type default)
			)
			(layer "B.SilkS")
		)
		(fp_poly
			(pts
				(xy 0.761746 0) (xy 2.285746 -0.762) (xy 2.285746 0.762)
			)
			(stroke
				(width 0)
				(type default)
			)
			(fill yes)
			(layer "B.SilkS")
		)
		(fp_line
			(start 0 -1.27)
			(end 0 3.81)
			(stroke
				(width 0.1)
				(type default)
			)
			(layer "B.Fab")
		)
		(fp_line
			(start -2.54 -1.27)
			(end 0 -1.27)
			(stroke
				(width 0.1)
				(type default)
			)
			(layer "B.Fab")
		)
		(fp_line
			(start 0 3.81)
			(end -2.54 3.81)
			(stroke
				(width 0.1)
				(type default)
			)
			(layer "B.Fab")
		)
		(fp_line
			(start -2.54 3.81)
			(end -2.54 -1.27)
			(stroke
				(width 0.1)
				(type default)
			)
			(layer "B.Fab")
		)
		(fp_poly
			(pts
				(xy 0.761746 0) (xy 2.285746 -0.762) (xy 2.285746 0.762)
			)
			(stroke
				(width 0)
				(type default)
			)
			(fill yes)
			(layer "B.Fab")
		)
		(pad "1" thru_hole circle
			(at 0 0 270)
			(size 1.0033 1.0033)
			(drill 0.249936)
			(layers "*.Cu" "*.Mask")
			(remove_unused_layers no)
			(net "TDR_DIFF_85_IN1_DP")
			(clearance 0.10795)
			(padstack
				(mode front_inner_back)
				(layer "Inner"
					(shape circle)
					(size 0.8001 0.8001)
					(clearance 0.1524)
				)
				(layer "B.Cu"
					(shape circle)
					(size 1.0033 1.0033)
					(thermal_gap 0.10795)
					(clearance 0.10795)
				)
			)
		)
		(pad "2" thru_hole circle
			(at -2.54 0 270)
			(size 1.9939 1.9939)
			(drill 0.249936)
			(layers "*.Cu" "*.Mask")
			(remove_unused_layers no)
			(net "GND_P1")
			(clearance 0.10795)
			(padstack
				(mode front_inner_back)
				(layer "Inner"
					(shape circle)
					(size 0.8001 0.8001)
					(clearance 0.1524)
				)
				(layer "B.Cu"
					(shape circle)
					(size 1.9939 1.9939)
					(thermal_gap 0.10795)
					(clearance 0.10795)
				)
			)
		)
		(pad "3" thru_hole circle
			(at -2.54 2.54 270)
			(size 1.9939 1.9939)
			(drill 0.249936)
			(layers "*.Cu" "*.Mask")
			(remove_unused_layers no)
			(net "GND_P1")
			(clearance 0.10795)
			(padstack
				(mode front_inner_back)
				(layer "Inner"
					(shape circle)
					(size 0.8001 0.8001)
					(clearance 0.1524)
				)
				(layer "B.Cu"
					(shape circle)
					(size 1.9939 1.9939)
					(thermal_gap 0.10795)
					(clearance 0.10795)
				)
			)
		)
		(pad "4" thru_hole circle
			(at 0 2.54 270)
			(size 1.0033 1.0033)
			(drill 0.249936)
			(layers "*.Cu" "*.Mask")
			(remove_unused_layers no)
			(net "TDR_DIFF_85_IN1_DN")
			(clearance 0.10795)
			(padstack
				(mode front_inner_back)
				(layer "Inner"
					(shape circle)
					(size 0.8001 0.8001)
					(clearance 0.1524)
				)
				(layer "B.Cu"
					(shape circle)
					(size 1.0033 1.0033)
					(thermal_gap 0.10795)
					(clearance 0.10795)
				)
			)
		)
	)
	(footprint ""
		(layer "B.Cu")
		(at 31.9532 -59.6392)
		(property "Reference" "R786"
			(at 0 0 0)
			(layer "B.SilkS")
			(hide yes)
			(effects
				(font
					(size 1.27 1.27)
				)
				(justify mirror)
			)
		)
		(property "Value" ""
			(at 0 0 0)
			(layer "B.Fab")
			(effects
				(font
					(size 1.27 1.27)
				)
				(justify mirror)
			)
		)
		(duplicate_pad_numbers_are_jumpers no)
		(fp_line
			(start -0.7874 -0.4064)
			(end -0.7874 0.4064)
			(stroke
				(width 0.1524)
				(type default)
			)
			(layer "B.SilkS")
		)
		(fp_line
			(start -0.7874 0.4064)
			(end 0.7874 0.4064)
			(stroke
				(width 0.1524)
				(type default)
			)
			(layer "B.SilkS")
		)
		(fp_line
			(start 0.7874 -0.4064)
			(end -0.7874 -0.4064)
			(stroke
				(width 0.1524)
				(type default)
			)
			(layer "B.SilkS")
		)
		(fp_line
			(start 0.7874 0.4064)
			(end 0.7874 -0.4064)
			(stroke
				(width 0.1524)
				(type default)
			)
			(layer "B.SilkS")
		)
		(fp_line
			(start -0.67945 -0.3048)
			(end -0.67945 0.3048)
			(stroke
				(width 0.1)
				(type default)
			)
			(layer "B.Fab")
		)
		(fp_line
			(start -0.67945 0.3048)
			(end -0.120396 0.3048)
			(stroke
				(width 0.1)
				(type default)
			)
			(layer "B.Fab")
		)
		(fp_line
			(start -0.12065 -0.3048)
			(end -0.67945 -0.3048)
			(stroke
				(width 0.1)
				(type default)
			)
			(layer "B.Fab")
		)
		(fp_line
			(start -0.12065 -0.2794)
			(end -0.12065 -0.3048)
			(stroke
				(width 0.1)
				(type default)
			)
			(layer "B.Fab")
		)
		(fp_line
			(start -0.120396 0.2794)
			(end 0.12065 0.2794)
			(stroke
				(width 0.1)
				(type default)
			)
			(layer "B.Fab")
		)
		(fp_line
			(start -0.120396 0.3048)
			(end -0.120396 0.2794)
			(stroke
				(width 0.1)
				(type default)
			)
			(layer "B.Fab")
		)
		(fp_line
			(start 0.12065 -0.305054)
			(end 0.12065 -0.2794)
			(stroke
				(width 0.1)
				(type default)
			)
			(layer "B.Fab")
		)
		(fp_line
			(start 0.12065 -0.2794)
			(end -0.12065 -0.2794)
			(stroke
				(width 0.1)
				(type default)
			)
			(layer "B.Fab")
		)
		(fp_line
			(start 0.12065 0.2794)
			(end 0.12065 0.3048)
			(stroke
				(width 0.1)
				(type default)
			)
			(layer "B.Fab")
		)
		(fp_line
			(start 0.12065 0.3048)
			(end 0.67945 0.3048)
			(stroke
				(width 0.1)
				(type default)
			)
			(layer "B.Fab")
		)
		(fp_line
			(start 0.67945 -0.305054)
			(end 0.12065 -0.305054)
			(stroke
				(width 0.1)
				(type default)
			)
			(layer "B.Fab")
		)
		(fp_line
			(start 0.67945 0.3048)
			(end 0.67945 -0.305054)
			(stroke
				(width 0.1)
				(type default)
			)
			(layer "B.Fab")
		)
		(pad "1" smd circle
			(at 0.40005 0 180)
			(size 0 0)
			(layers "B.Cu" "B.Mask" "B.Paste")
			(net "P12V_SENSOR")
		)
		(pad "2" smd circle
			(at -0.40005 0 180)
			(size 0 0)
			(layers "B.Cu" "B.Mask" "B.Paste")
			(net "GND")
		)
	)
	(footprint ""
		(layer "B.Cu")
		(at 79.57947 -54.898798)
		(property "Reference" "C221"
			(at 0 0 0)
			(layer "B.SilkS")
			(hide yes)
			(effects
				(font
					(size 1.27 1.27)
				)
				(justify mirror)
			)
		)
		(property "Value" ""
			(at 0 0 0)
			(layer "B.Fab")
			(effects
				(font
					(size 1.27 1.27)
				)
				(justify mirror)
			)
		)
		(duplicate_pad_numbers_are_jumpers no)
		(fp_line
			(start -0.7874 -0.4064)
			(end -0.7874 0.4064)
			(stroke
				(width 0.1524)
				(type default)
			)
			(layer "B.SilkS")
		)
		(fp_line
			(start -0.7874 0.4064)
			(end 0.7874 0.4064)
			(stroke
				(width 0.1524)
				(type default)
			)
			(layer "B.SilkS")
		)
		(fp_line
			(start 0.7874 -0.4064)
			(end -0.7874 -0.4064)
			(stroke
				(width 0.1524)
				(type default)
			)
			(layer "B.SilkS")
		)
		(fp_line
			(start 0.7874 0.4064)
			(end 0.7874 -0.4064)
			(stroke
				(width 0.1524)
				(type default)
			)
			(layer "B.SilkS")
		)
		(fp_line
			(start -0.67945 -0.3048)
			(end -0.67945 0.3048)
			(stroke
				(width 0.1)
				(type default)
			)
			(layer "B.Fab")
		)
		(fp_line
			(start -0.67945 0.3048)
			(end -0.120396 0.3048)
			(stroke
				(width 0.1)
				(type default)
			)
			(layer "B.Fab")
		)
		(fp_line
			(start -0.12065 -0.3048)
			(end -0.67945 -0.3048)
			(stroke
				(width 0.1)
				(type default)
			)
			(layer "B.Fab")
		)
		(fp_line
			(start -0.12065 -0.2794)
			(end -0.12065 -0.3048)
			(stroke
				(width 0.1)
				(type default)
			)
			(layer "B.Fab")
		)
		(fp_line
			(start -0.120396 0.2794)
			(end 0.12065 0.2794)
			(stroke
				(width 0.1)
				(type default)
			)
			(layer "B.Fab")
		)
		(fp_line
			(start -0.120396 0.3048)
			(end -0.120396 0.2794)
			(stroke
				(width 0.1)
				(type default)
			)
			(layer "B.Fab")
		)
		(fp_line
			(start 0.12065 -0.305054)
			(end 0.12065 -0.2794)
			(stroke
				(width 0.1)
				(type default)
			)
			(layer "B.Fab")
		)
		(fp_line
			(start 0.12065 -0.2794)
			(end -0.12065 -0.2794)
			(stroke
				(width 0.1)
				(type default)
			)
			(layer "B.Fab")
		)
		(fp_line
			(start 0.12065 0.2794)
			(end 0.12065 0.3048)
			(stroke
				(width 0.1)
				(type default)
			)
			(layer "B.Fab")
		)
		(fp_line
			(start 0.12065 0.3048)
			(end 0.67945 0.3048)
			(stroke
				(width 0.1)
				(type default)
			)
			(layer "B.Fab")
		)
		(fp_line
			(start 0.67945 -0.305054)
			(end 0.12065 -0.305054)
			(stroke
				(width 0.1)
				(type default)
			)
			(layer "B.Fab")
		)
		(fp_line
			(start 0.67945 0.3048)
			(end 0.67945 -0.305054)
			(stroke
				(width 0.1)
				(type default)
			)
			(layer "B.Fab")
		)
		(pad "1" smd circle
			(at 0.40005 0 180)
			(size 0 0)
			(layers "B.Cu" "B.Mask" "B.Paste")
			(net "P1V2_AUX")
		)
		(pad "2" smd circle
			(at -0.40005 0 180)
			(size 0 0)
			(layers "B.Cu" "B.Mask" "B.Paste")
			(net "GND")
		)
	)
	(footprint ""
		(layer "B.Cu")
		(at 76.239878 -55.895748 -90)
		(property "Reference" "C123"
			(at 0 0 90)
			(layer "B.SilkS")
			(hide yes)
			(effects
				(font
					(size 1.27 1.27)
				)
				(justify mirror)
			)
		)
		(property "Value" ""
			(at 0 0 90)
			(layer "B.Fab")
			(effects
				(font
					(size 1.27 1.27)
				)
				(justify mirror)
			)
		)
		(duplicate_pad_numbers_are_jumpers no)
		(fp_line
			(start -1.2954 0.5842)
			(end 1.2954 0.5842)
			(stroke
				(width 0.1524)
				(type default)
			)
			(layer "B.SilkS")
		)
		(fp_line
			(start 1.2954 0.5842)
			(end 1.2954 -0.5842)
			(stroke
				(width 0.1524)
				(type default)
			)
			(layer "B.SilkS")
		)
		(fp_line
			(start -1.2954 -0.5842)
			(end -1.2954 0.5842)
			(stroke
				(width 0.1524)
				(type default)
			)
			(layer "B.SilkS")
		)
		(fp_line
			(start 0 -0.5842)
			(end 0 0.5842)
			(stroke
				(width 0.1524)
				(type default)
			)
			(layer "B.SilkS")
		)
		(fp_line
			(start 1.2954 -0.5842)
			(end -1.2954 -0.5842)
			(stroke
				(width 0.1524)
				(type default)
			)
			(layer "B.SilkS")
		)
		(fp_line
			(start -0.8636 0.4572)
			(end 0.8636 0.4572)
			(stroke
				(width 0.1)
				(type default)
			)
			(layer "B.Fab")
		)
		(fp_line
			(start 0.8636 0.4572)
			(end 0.8636 0.4064)
			(stroke
				(width 0.1)
				(type default)
			)
			(layer "B.Fab")
		)
		(fp_line
			(start -1.1938 0.4064)
			(end -0.8636 0.4064)
			(stroke
				(width 0.1)
				(type default)
			)
			(layer "B.Fab")
		)
		(fp_line
			(start -0.8636 0.4064)
			(end -0.8636 0.4572)
			(stroke
				(width 0.1)
				(type default)
			)
			(layer "B.Fab")
		)
		(fp_line
			(start 0.8636 0.4064)
			(end 1.1938 0.4064)
			(stroke
				(width 0.1)
				(type default)
			)
			(layer "B.Fab")
		)
		(fp_line
			(start 1.1938 0.4064)
			(end 1.1938 -0.4064)
			(stroke
				(width 0.1)
				(type default)
			)
			(layer "B.Fab")
		)
		(fp_line
			(start -1.1938 -0.4064)
			(end -1.1938 0.4064)
			(stroke
				(width 0.1)
				(type default)
			)
			(layer "B.Fab")
		)
		(fp_line
			(start -0.8636 -0.4064)
			(end -1.1938 -0.4064)
			(stroke
				(width 0.1)
				(type default)
			)
			(layer "B.Fab")
		)
		(fp_line
			(start 0.8636 -0.4064)
			(end 0.8636 -0.4572)
			(stroke
				(width 0.1)
				(type default)
			)
			(layer "B.Fab")
		)
		(fp_line
			(start 1.1938 -0.4064)
			(end 0.8636 -0.4064)
			(stroke
				(width 0.1)
				(type default)
			)
			(layer "B.Fab")
		)
		(fp_line
			(start -0.8636 -0.4572)
			(end -0.8636 -0.4064)
			(stroke
				(width 0.1)
				(type default)
			)
			(layer "B.Fab")
		)
		(fp_line
			(start 0.8636 -0.4572)
			(end -0.8636 -0.4572)
			(stroke
				(width 0.1)
				(type default)
			)
			(layer "B.Fab")
		)
		(pad "1" smd rect
			(at 0.7366 0 180)
			(size 0.7112 0.8128)
			(layers "B.Cu" "B.Mask" "B.Paste")
			(net "P1V0_AUX")
		)
		(pad "2" smd rect
			(at -0.7366 0 180)
			(size 0.7112 0.8128)
			(layers "B.Cu" "B.Mask" "B.Paste")
			(net "GND")
		)
	)
	(footprint ""
		(layer "B.Cu")
		(at 59.309 -24.257 -90)
		(property "Reference" "C148"
			(at 0 0 90)
			(layer "B.SilkS")
			(hide yes)
			(effects
				(font
					(size 1.27 1.27)
				)
				(justify mirror)
			)
		)
		(property "Value" ""
			(at 0 0 90)
			(layer "B.Fab")
			(effects
				(font
					(size 1.27 1.27)
				)
				(justify mirror)
			)
		)
		(duplicate_pad_numbers_are_jumpers no)
		(fp_line
			(start -0.7874 0.4064)
			(end 0.7874 0.4064)
			(stroke
				(width 0.1524)
				(type default)
			)
			(layer "B.SilkS")
		)
		(fp_line
			(start 0.7874 0.4064)
			(end 0.7874 -0.4064)
			(stroke
				(width 0.1524)
				(type default)
			)
			(layer "B.SilkS")
		)
		(fp_line
			(start -0.7874 -0.4064)
			(end -0.7874 0.4064)
			(stroke
				(width 0.1524)
				(type default)
			)
			(layer "B.SilkS")
		)
		(fp_line
			(start 0.7874 -0.4064)
			(end -0.7874 -0.4064)
			(stroke
				(width 0.1524)
				(type default)
			)
			(layer "B.SilkS")
		)
		(fp_line
			(start -0.67945 0.3048)
			(end -0.120396 0.3048)
			(stroke
				(width 0.1)
				(type default)
			)
			(layer "B.Fab")
		)
		(fp_line
			(start -0.120396 0.3048)
			(end -0.120396 0.2794)
			(stroke
				(width 0.1)
				(type default)
			)
			(layer "B.Fab")
		)
		(fp_line
			(start 0.12065 0.3048)
			(end 0.67945 0.3048)
			(stroke
				(width 0.1)
				(type default)
			)
			(layer "B.Fab")
		)
		(fp_line
			(start 0.67945 0.3048)
			(end 0.67945 -0.305054)
			(stroke
				(width 0.1)
				(type default)
			)
			(layer "B.Fab")
		)
		(fp_line
			(start -0.120396 0.2794)
			(end 0.12065 0.2794)
			(stroke
				(width 0.1)
				(type default)
			)
			(layer "B.Fab")
		)
		(fp_line
			(start 0.12065 0.2794)
			(end 0.12065 0.3048)
			(stroke
				(width 0.1)
				(type default)
			)
			(layer "B.Fab")
		)
		(fp_line
			(start -0.12065 -0.2794)
			(end -0.12065 -0.3048)
			(stroke
				(width 0.1)
				(type default)
			)
			(layer "B.Fab")
		)
		(fp_line
			(start 0.12065 -0.2794)
			(end -0.12065 -0.2794)
			(stroke
				(width 0.1)
				(type default)
			)
			(layer "B.Fab")
		)
		(fp_line
			(start -0.67945 -0.3048)
			(end -0.67945 0.3048)
			(stroke
				(width 0.1)
				(type default)
			)
			(layer "B.Fab")
		)
		(fp_line
			(start -0.12065 -0.3048)
			(end -0.67945 -0.3048)
			(stroke
				(width 0.1)
				(type default)
			)
			(layer "B.Fab")
		)
		(fp_line
			(start 0.12065 -0.305054)
			(end 0.12065 -0.2794)
			(stroke
				(width 0.1)
				(type default)
			)
			(layer "B.Fab")
		)
		(fp_line
			(start 0.67945 -0.305054)
			(end 0.12065 -0.305054)
			(stroke
				(width 0.1)
				(type default)
			)
			(layer "B.Fab")
		)
		(pad "1" smd circle
			(at 0.40005 0 90)
			(size 0 0)
			(layers "B.Cu" "B.Mask" "B.Paste")
			(net "P3V3_AUX")
		)
		(pad "2" smd circle
			(at -0.40005 0 90)
			(size 0 0)
			(layers "B.Cu" "B.Mask" "B.Paste")
			(net "GND")
		)
	)
	(footprint ""
		(layer "B.Cu")
		(at 64.102996 -34.637726 -90)
		(property "Reference" "R210"
			(at 0 0 90)
			(layer "B.SilkS")
			(hide yes)
			(effects
				(font
					(size 1.27 1.27)
				)
				(justify mirror)
			)
		)
		(property "Value" ""
			(at 0 0 90)
			(layer "B.Fab")
			(effects
				(font
					(size 1.27 1.27)
				)
				(justify mirror)
			)
		)
		(duplicate_pad_numbers_are_jumpers no)
		(fp_line
			(start -0.7874 0.4064)
			(end 0.7874 0.4064)
			(stroke
				(width 0.1524)
				(type default)
			)
			(layer "B.SilkS")
		)
		(fp_line
			(start 0.7874 0.4064)
			(end 0.7874 -0.4064)
			(stroke
				(width 0.1524)
				(type default)
			)
			(layer "B.SilkS")
		)
		(fp_line
			(start -0.7874 -0.4064)
			(end -0.7874 0.4064)
			(stroke
				(width 0.1524)
				(type default)
			)
			(layer "B.SilkS")
		)
		(fp_line
			(start 0.7874 -0.4064)
			(end -0.7874 -0.4064)
			(stroke
				(width 0.1524)
				(type default)
			)
			(layer "B.SilkS")
		)
		(fp_line
			(start -0.67945 0.3048)
			(end -0.120396 0.3048)
			(stroke
				(width 0.1)
				(type default)
			)
			(layer "B.Fab")
		)
		(fp_line
			(start -0.120396 0.3048)
			(end -0.120396 0.2794)
			(stroke
				(width 0.1)
				(type default)
			)
			(layer "B.Fab")
		)
		(fp_line
			(start 0.12065 0.3048)
			(end 0.67945 0.3048)
			(stroke
				(width 0.1)
				(type default)
			)
			(layer "B.Fab")
		)
		(fp_line
			(start 0.67945 0.3048)
			(end 0.67945 -0.305054)
			(stroke
				(width 0.1)
				(type default)
			)
			(layer "B.Fab")
		)
		(fp_line
			(start -0.120396 0.2794)
			(end 0.12065 0.2794)
			(stroke
				(width 0.1)
				(type default)
			)
			(layer "B.Fab")
		)
		(fp_line
			(start 0.12065 0.2794)
			(end 0.12065 0.3048)
			(stroke
				(width 0.1)
				(type default)
			)
			(layer "B.Fab")
		)
		(fp_line
			(start -0.12065 -0.2794)
			(end -0.12065 -0.3048)
			(stroke
				(width 0.1)
				(type default)
			)
			(layer "B.Fab")
		)
		(fp_line
			(start 0.12065 -0.2794)
			(end -0.12065 -0.2794)
			(stroke
				(width 0.1)
				(type default)
			)
			(layer "B.Fab")
		)
		(fp_line
			(start -0.67945 -0.3048)
			(end -0.67945 0.3048)
			(stroke
				(width 0.1)
				(type default)
			)
			(layer "B.Fab")
		)
		(fp_line
			(start -0.12065 -0.3048)
			(end -0.67945 -0.3048)
			(stroke
				(width 0.1)
				(type default)
			)
			(layer "B.Fab")
		)
		(fp_line
			(start 0.12065 -0.305054)
			(end 0.12065 -0.2794)
			(stroke
				(width 0.1)
				(type default)
			)
			(layer "B.Fab")
		)
		(fp_line
			(start 0.67945 -0.305054)
			(end 0.12065 -0.305054)
			(stroke
				(width 0.1)
				(type default)
			)
			(layer "B.Fab")
		)
		(pad "1" smd circle
			(at 0.40005 0 90)
			(size 0 0)
			(layers "B.Cu" "B.Mask" "B.Paste")
			(net "GND")
		)
		(pad "2" smd circle
			(at -0.40005 0 90)
			(size 0 0)
			(layers "B.Cu" "B.Mask" "B.Paste")
			(net "PD_SP_ENTEST")
		)
	)
	(footprint ""
		(layer "B.Cu")
		(at 84.9122 -67.691)
		(property "Reference" "DM7"
			(at 0 0 0)
			(layer "B.SilkS")
			(hide yes)
			(effects
				(font
					(size 1.27 1.27)
				)
				(justify mirror)
			)
		)
		(property "Value" ""
			(at 0 0 0)
			(layer "B.Fab")
			(effects
				(font
					(size 1.27 1.27)
				)
				(justify mirror)
			)
		)
		(duplicate_pad_numbers_are_jumpers no)
		(fp_line
			(start -2.9337 2.4511)
			(end -2.9337 3.0861)
			(stroke
				(width 0.1524)
				(type default)
			)
			(layer "B.SilkS")
		)
		(fp_line
			(start -2.9337 3.0861)
			(end -3.1115 3.0734)
			(stroke
				(width 0.1524)
				(type default)
			)
			(layer "B.SilkS")
		)
		(fp_line
			(start -2.8194 2.667)
			(end -3.048 2.667)
			(stroke
				(width 0.1524)
				(type default)
			)
			(layer "B.SilkS")
		)
		(fp_line
			(start -2.5019 2.6797)
			(end -2.4638 2.667)
			(stroke
				(width 0.1524)
				(type default)
			)
			(layer "B.SilkS")
		)
		(fp_line
			(start -2.4638 2.667)
			(end -2.413 2.6543)
			(stroke
				(width 0.1524)
				(type default)
			)
			(layer "B.SilkS")
		)
		(fp_line
			(start -2.4384 3.0861)
			(end -2.5019 3.0607)
			(stroke
				(width 0.1524)
				(type default)
			)
			(layer "B.SilkS")
		)
		(fp_line
			(start -2.413 2.6543)
			(end -2.3749 2.6543)
			(stroke
				(width 0.1524)
				(type default)
			)
			(layer "B.SilkS")
		)
		(fp_line
			(start -2.3876 3.0861)
			(end -2.4384 3.0861)
			(stroke
				(width 0.1524)
				(type default)
			)
			(layer "B.SilkS")
		)
		(fp_line
			(start -2.3749 2.6543)
			(end -2.3241 2.667)
			(stroke
				(width 0.1524)
				(type default)
			)
			(layer "B.SilkS")
		)
		(fp_line
			(start -2.3241 2.667)
			(end -2.2987 2.6797)
			(stroke
				(width 0.1524)
				(type default)
			)
			(layer "B.SilkS")
		)
		(fp_line
			(start -2.3241 3.0734)
			(end -2.3876 3.0861)
			(stroke
				(width 0.1524)
				(type default)
			)
			(layer "B.SilkS")
		)
		(fp_line
			(start -2.2987 2.6797)
			(end -2.2606 2.7051)
			(stroke
				(width 0.1524)
				(type default)
			)
			(layer "B.SilkS")
		)
		(fp_line
			(start -2.2987 3.0607)
			(end -2.3241 3.0734)
			(stroke
				(width 0.1524)
				(type default)
			)
			(layer "B.SilkS")
		)
		(fp_line
			(start -2.2606 2.7051)
			(end -2.2352 2.7305)
			(stroke
				(width 0.1524)
				(type default)
			)
			(layer "B.SilkS")
		)
		(fp_line
			(start -2.2606 3.0353)
			(end -2.2987 3.0607)
			(stroke
				(width 0.1524)
				(type default)
			)
			(layer "B.SilkS")
		)
		(fp_line
			(start -2.2352 2.7305)
			(end -2.2098 2.7686)
			(stroke
				(width 0.1524)
				(type default)
			)
			(layer "B.SilkS")
		)
		(fp_line
			(start -2.2352 3.0099)
			(end -2.2606 3.0353)
			(stroke
				(width 0.1524)
				(type default)
			)
			(layer "B.SilkS")
		)
		(fp_line
			(start -2.2098 2.7686)
			(end -2.1971 2.794)
			(stroke
				(width 0.1524)
				(type default)
			)
			(layer "B.SilkS")
		)
		(fp_line
			(start -2.2098 2.9718)
			(end -2.2352 3.0099)
			(stroke
				(width 0.1524)
				(type default)
			)
			(layer "B.SilkS")
		)
		(fp_line
			(start -2.1971 2.794)
			(end -2.1844 2.8575)
			(stroke
				(width 0.1524)
				(type default)
			)
			(layer "B.SilkS")
		)
		(fp_line
			(start -2.1971 2.9464)
			(end -2.2098 2.9718)
			(stroke
				(width 0.1524)
				(type default)
			)
			(layer "B.SilkS")
		)
		(fp_line
			(start -2.1844 2.8575)
			(end -2.1844 2.8956)
			(stroke
				(width 0.1524)
				(type default)
			)
			(layer "B.SilkS")
		)
		(fp_line
			(start -2.1844 2.8956)
			(end -2.1971 2.9464)
			(stroke
				(width 0.1524)
				(type default)
			)
			(layer "B.SilkS")
		)
		(fp_line
			(start -1.8161 2.4511)
			(end -1.8161 3.0861)
			(stroke
				(width 0.1524)
				(type default)
			)
			(layer "B.SilkS")
		)
		(fp_line
			(start -1.8161 3.0861)
			(end -1.9939 3.0734)
			(stroke
				(width 0.1524)
				(type default)
			)
			(layer "B.SilkS")
		)
		(fp_line
			(start -1.7018 2.667)
			(end -1.9304 2.667)
			(stroke
				(width 0.1524)
				(type default)
			)
			(layer "B.SilkS")
		)
		(fp_line
			(start -1.4224 2.7686)
			(end -1.4224 3.0861)
			(stroke
				(width 0.1524)
				(type default)
			)
			(layer "B.SilkS")
		)
		(fp_line
			(start -1.397 2.7178)
			(end -1.4224 2.7686)
			(stroke
				(width 0.1524)
				(type default)
			)
			(layer "B.SilkS")
		)
		(fp_line
			(start -1.3589 2.667)
			(end -1.397 2.7178)
			(stroke
				(width 0.1524)
				(type default)
			)
			(layer "B.SilkS")
		)
		(fp_line
			(start -1.3081 2.6543)
			(end -1.3589 2.667)
			(stroke
				(width 0.1524)
				(type default)
			)
			(layer "B.SilkS")
		)
		(fp_line
			(start -1.27 2.6543)
			(end -1.3081 2.6543)
			(stroke
				(width 0.1524)
				(type default)
			)
			(layer "B.SilkS")
		)
		(fp_line
			(start -1.2192 2.667)
			(end -1.27 2.6543)
			(stroke
				(width 0.1524)
				(type default)
			)
			(layer "B.SilkS")
		)
		(fp_line
			(start -1.1938 2.6924)
			(end -1.2192 2.667)
			(stroke
				(width 0.1524)
				(type default)
			)
			(layer "B.SilkS")
		)
		(fp_line
			(start -1.1684 2.7305)
			(end -1.1938 2.6924)
			(stroke
				(width 0.1524)
				(type default)
			)
			(layer "B.SilkS")
		)
		(fp_line
			(start -1.143 2.6543)
			(end -1.143 3.0861)
			(stroke
				(width 0.1524)
				(type default)
			)
			(layer "B.SilkS")
		)
		(fp_line
			(start -1.143 2.7813)
			(end -1.1684 2.7305)
			(stroke
				(width 0.1524)
				(type default)
			)
			(layer "B.SilkS")
		)
		(fp_line
			(start -0.9144 4.191)
			(end -0.9144 5.461)
			(stroke
				(width 0.254)
				(type default)
			)
			(layer "B.SilkS")
		)
		(fp_line
			(start -0.7239 2.3495)
			(end -0.6985 2.3241)
			(stroke
				(width 0.1524)
				(type default)
			)
			(layer "B.SilkS")
		)
		(fp_line
			(start -0.7239 2.3749)
			(end -0.7239 2.3495)
			(stroke
				(width 0.1524)
				(type default)
			)
			(layer "B.SilkS")
		)
		(fp_line
			(start -0.6985 2.3241)
			(end -0.6731 2.3495)
			(stroke
				(width 0.1524)
				(type default)
			)
			(layer "B.SilkS")
		)
		(fp_line
			(start -0.6985 2.4003)
			(end -0.7239 2.3749)
			(stroke
				(width 0.1524)
				(type default)
			)
			(layer "B.SilkS")
		)
		(fp_line
			(start -0.6985 2.6416)
			(end -0.6985 3.0861)
			(stroke
				(width 0.1524)
				(type default)
			)
			(layer "B.SilkS")
		)
		(fp_line
			(start -0.6731 2.3495)
			(end -0.6731 2.3749)
			(stroke
				(width 0.1524)
				(type default)
			)
			(layer "B.SilkS")
		)
		(fp_line
			(start -0.6731 2.3749)
			(end -0.6985 2.4003)
			(stroke
				(width 0.1524)
				(type default)
			)
			(layer "B.SilkS")
		)
		(fp_line
			(start -0.635 4.3434)
			(end -0.9144 4.191)
			(stroke
				(width 0.254)
				(type default)
			)
			(layer "B.SilkS")
		)
		(fp_line
			(start -0.3556 -1.27)
			(end -0.3556 1.2954)
			(stroke
				(width 0.254)
				(type default)
			)
			(layer "B.SilkS")
		)
		(fp_line
			(start -0.3048 4.7752)
			(end -0.2794 4.5974)
			(stroke
				(width 0.254)
				(type default)
			)
			(layer "B.SilkS")
		)
		(fp_line
			(start -0.2794 4.5974)
			(end -0.254 4.5212)
			(stroke
				(width 0.254)
				(type default)
			)
			(layer "B.SilkS")
		)
		(fp_line
			(start -0.254 4.5212)
			(end -0.2032 4.4196)
			(stroke
				(width 0.254)
				(type default)
			)
			(layer "B.SilkS")
		)
		(fp_line
			(start -0.2032 4.4196)
			(end -0.127 4.318)
			(stroke
				(width 0.254)
				(type default)
			)
			(layer "B.SilkS")
		)
		(fp_line
			(start -0.127 4.318)
			(end 0 4.2164)
			(stroke
				(width 0.254)
				(type default)
			)
			(layer "B.SilkS")
		)
		(fp_line
			(start -0.1016 5.2578)
			(end -0.2032 5.1308)
			(stroke
				(width 0.254)
				(type default)
			)
			(layer "B.SilkS")
		)
		(fp_line
			(start 0 4.2164)
			(end 0.1016 4.1656)
			(stroke
				(width 0.254)
				(type default)
			)
			(layer "B.SilkS")
		)
		(fp_line
			(start 0.0381 2.4257)
			(end 0.0381 3.0861)
			(stroke
				(width 0.1524)
				(type default)
			)
			(layer "B.SilkS")
		)
		(fp_line
			(start 0.0508 5.3594)
			(end -0.1016 5.2578)
			(stroke
				(width 0.254)
				(type default)
			)
			(layer "B.SilkS")
		)
		(fp_line
			(start 0.1016 4.1656)
			(end 0.1778 4.1402)
			(stroke
				(width 0.254)
				(type default)
			)
			(layer "B.SilkS")
		)
		(fp_line
			(start 0.1016 5.3848)
			(end 0.0508 5.3594)
			(stroke
				(width 0.254)
				(type default)
			)
			(layer "B.SilkS")
		)
		(fp_line
			(start 0.1778 4.1402)
			(end 0.3048 4.1148)
			(stroke
				(width 0.254)
				(type default)
			)
			(layer "B.SilkS")
		)
		(fp_line
			(start 0.1778 5.4102)
			(end 0.1016 5.3848)
			(stroke
				(width 0.254)
				(type default)
			)
			(layer "B.SilkS")
		)
		(fp_line
			(start 0.3048 4.1148)
			(end 0.4064 4.1148)
			(stroke
				(width 0.254)
				(type default)
			)
			(layer "B.SilkS")
		)
		(fp_line
			(start 0.3556 5.4356)
			(end 0.1778 5.4102)
			(stroke
				(width 0.254)
				(type default)
			)
			(layer "B.SilkS")
		)
		(fp_line
			(start 0.381 5.4356)
			(end 0.3556 5.4356)
			(stroke
				(width 0.254)
				(type default)
			)
			(layer "B.SilkS")
		)
		(fp_line
			(start 0.4064 4.1148)
			(end 0.5334 4.1402)
			(stroke
				(width 0.254)
				(type default)
			)
			(layer "B.SilkS")
		)
		(fp_line
			(start 0.5334 4.1402)
			(end 0.6096 4.1656)
			(stroke
				(width 0.254)
				(type default)
			)
			(layer "B.SilkS")
		)
		(fp_line
			(start 0.5334 5.4102)
			(end 0.381 5.4356)
			(stroke
				(width 0.254)
				(type default)
			)
			(layer "B.SilkS")
		)
		(fp_line
			(start 0.5588 0)
			(end 1.1938 0)
			(stroke
				(width 0.254)
				(type default)
			)
			(layer "B.SilkS")
		)
		(fp_line
			(start 0.5969 3.0861)
			(end 0.4191 2.6543)
			(stroke
				(width 0.1524)
				(type default)
			)
			(layer "B.SilkS")
		)
		(fp_line
			(start 0.6096 4.1656)
			(end 0.7112 4.2164)
			(stroke
				(width 0.254)
				(type default)
			)
			(layer "B.SilkS")
		)
		(fp_line
			(start 0.6096 5.3848)
			(end 0.5334 5.4102)
			(stroke
				(width 0.254)
				(type default)
			)
			(layer "B.SilkS")
		)
		(fp_line
			(start 0.7112 4.2164)
			(end 0.8128 4.2926)
			(stroke
				(width 0.254)
				(type default)
			)
			(layer "B.SilkS")
		)
		(fp_line
			(start 0.7112 5.334)
			(end 0.6096 5.3848)
			(stroke
				(width 0.254)
				(type default)
			)
			(layer "B.SilkS")
		)
		(fp_line
			(start 0.7747 2.6543)
			(end 0.5969 3.0861)
			(stroke
				(width 0.1524)
				(type default)
			)
			(layer "B.SilkS")
		)
		(fp_line
			(start 0.8128 4.2926)
			(end 0.8382 4.318)
			(stroke
				(width 0.254)
				(type default)
			)
			(layer "B.SilkS")
		)
		(fp_line
			(start 0.8382 4.318)
			(end 0.9144 4.4196)
			(stroke
				(width 0.254)
				(type default)
			)
			(layer "B.SilkS")
		)
		(fp_line
			(start 0.8382 5.2324)
			(end 0.7112 5.334)
			(stroke
				(width 0.254)
				(type default)
			)
			(layer "B.SilkS")
		)
		(fp_line
			(start 0.9144 4.4196)
			(end 0.9652 4.5212)
			(stroke
				(width 0.254)
				(type default)
			)
			(layer "B.SilkS")
		)
		(fp_line
			(start 0.9144 5.1308)
			(end 0.8382 5.2324)
			(stroke
				(width 0.254)
				(type default)
			)
			(layer "B.SilkS")
		)
		(fp_line
			(start 0.9652 4.5212)
			(end 0.9906 4.5974)
			(stroke
				(width 0.254)
				(type default)
			)
			(layer "B.SilkS")
		)
		(fp_line
			(start 0.9652 5.0292)
			(end 0.9144 5.1308)
			(stroke
				(width 0.254)
				(type default)
			)
			(layer "B.SilkS")
		)
		(fp_line
			(start 0.9906 4.5974)
			(end 1.016 4.7498)
			(stroke
				(width 0.254)
				(type default)
			)
			(layer "B.SilkS")
		)
		(fp_line
			(start 0.9906 4.953)
			(end 0.9652 5.0292)
			(stroke
				(width 0.254)
				(type default)
			)
			(layer "B.SilkS")
		)
		(fp_line
			(start 1.016 4.7498)
			(end 1.016 4.826)
			(stroke
				(width 0.254)
				(type default)
			)
			(layer "B.SilkS")
		)
		(fp_line
			(start 1.016 4.7752)
			(end -0.3048 4.7752)
			(stroke
				(width 0.254)
				(type default)
			)
			(layer "B.SilkS")
		)
		(fp_line
			(start 1.016 4.826)
			(end 0.9906 4.953)
			(stroke
				(width 0.254)
				(type default)
			)
			(layer "B.SilkS")
		)
		(fp_line
			(start 1.1557 2.4257)
			(end 1.1557 3.0861)
			(stroke
				(width 0.1524)
				(type default)
			)
			(layer "B.SilkS")
		)
		(fp_line
			(start 1.1938 -1.27)
			(end 0.5588 -1.27)
			(stroke
				(width 0.254)
				(type default)
			)
			(layer "B.SilkS")
		)
		(fp_line
			(start 1.1938 -1.27)
			(end 1.1938 1.2954)
			(stroke
				(width 0.254)
				(type default)
			)
			(layer "B.SilkS")
		)
		(fp_line
			(start 1.3208 -1.524)
			(end -1.4732 1.397)
			(stroke
				(width 0.1524)
				(type default)
			)
			(layer "B.SilkS")
		)
		(fp_line
			(start 1.7526 2.4384)
			(end 1.7526 3.0861)
			(stroke
				(width 0.1524)
				(type default)
			)
			(layer "B.SilkS")
		)
		(fp_line
			(start 1.7526 2.7813)
			(end 1.778 2.7559)
			(stroke
				(width 0.1524)
				(type default)
			)
			(layer "B.SilkS")
		)
		(fp_line
			(start 1.778 2.7559)
			(end 1.8161 2.7305)
			(stroke
				(width 0.1524)
				(type default)
			)
			(layer "B.SilkS")
		)
		(fp_line
			(start 1.778 3.0353)
			(end 1.7526 3.0099)
			(stroke
				(width 0.1524)
				(type default)
			)
			(layer "B.SilkS")
		)
		(fp_line
			(start 1.8161 2.7305)
			(end 1.8542 2.7178)
			(stroke
				(width 0.1524)
				(type default)
			)
			(layer "B.SilkS")
		)
		(fp_line
			(start 1.8161 3.0607)
			(end 1.778 3.0353)
			(stroke
				(width 0.1524)
				(type default)
			)
			(layer "B.SilkS")
		)
		(fp_line
			(start 1.8542 2.7178)
			(end 1.9177 2.7178)
			(stroke
				(width 0.1524)
				(type default)
			)
			(layer "B.SilkS")
		)
		(fp_line
			(start 1.8796 3.0734)
			(end 1.8161 3.0607)
			(stroke
				(width 0.1524)
				(type default)
			)
			(layer "B.SilkS")
		)
		(fp_line
			(start 1.9177 2.7178)
			(end 1.9685 2.7305)
			(stroke
				(width 0.1524)
				(type default)
			)
			(layer "B.SilkS")
		)
		(fp_line
			(start 1.9304 3.0734)
			(end 1.8796 3.0734)
			(stroke
				(width 0.1524)
				(type default)
			)
			(layer "B.SilkS")
		)
		(fp_line
			(start 1.9685 2.7305)
			(end 2.0066 2.7559)
			(stroke
				(width 0.1524)
				(type default)
			)
			(layer "B.SilkS")
		)
		(fp_line
			(start 1.9685 3.0607)
			(end 1.9304 3.0734)
			(stroke
				(width 0.1524)
				(type default)
			)
			(layer "B.SilkS")
		)
		(fp_line
			(start 2.0066 2.7559)
			(end 2.0447 2.794)
			(stroke
				(width 0.1524)
				(type default)
			)
			(layer "B.SilkS")
		)
		(fp_line
			(start 2.0066 3.0353)
			(end 1.9685 3.0607)
			(stroke
				(width 0.1524)
				(type default)
			)
			(layer "B.SilkS")
		)
		(fp_line
			(start 2.032 3.0099)
			(end 2.0066 3.0353)
			(stroke
				(width 0.1524)
				(type default)
			)
			(layer "B.SilkS")
		)
		(fp_line
			(start 2.0447 2.794)
			(end 2.0574 2.8194)
			(stroke
				(width 0.1524)
				(type default)
			)
			(layer "B.SilkS")
		)
		(fp_line
			(start 2.0574 2.8194)
			(end 2.0701 2.8575)
			(stroke
				(width 0.1524)
				(type default)
			)
			(layer "B.SilkS")
		)
		(fp_line
			(start 2.0574 2.9718)
			(end 2.032 3.0099)
			(stroke
				(width 0.1524)
				(type default)
			)
			(layer "B.SilkS")
		)
		(fp_line
			(start 2.0701 2.8575)
			(end 2.0701 2.9083)
			(stroke
				(width 0.1524)
				(type default)
			)
			(layer "B.SilkS")
		)
		(fp_line
			(start 2.0701 2.9083)
			(end 2.0574 2.9718)
			(stroke
				(width 0.1524)
				(type default)
			)
			(layer "B.SilkS")
		)
		(fp_line
			(start 2.3114 2.7686)
			(end 2.3114 3.0861)
			(stroke
				(width 0.1524)
				(type default)
			)
			(layer "B.SilkS")
		)
		(fp_line
			(start 2.3368 2.7178)
			(end 2.3114 2.7686)
			(stroke
				(width 0.1524)
				(type default)
			)
			(layer "B.SilkS")
		)
		(fp_line
			(start 2.3749 2.667)
			(end 2.3368 2.7178)
			(stroke
				(width 0.1524)
				(type default)
			)
			(layer "B.SilkS")
		)
		(fp_line
			(start 2.4257 2.6543)
			(end 2.3749 2.667)
			(stroke
				(width 0.1524)
				(type default)
			)
			(layer "B.SilkS")
		)
		(fp_line
			(start 2.4638 2.6543)
			(end 2.4257 2.6543)
			(stroke
				(width 0.1524)
				(type default)
			)
			(layer "B.SilkS")
		)
		(fp_line
			(start 2.5146 2.667)
			(end 2.4638 2.6543)
			(stroke
				(width 0.1524)
				(type default)
			)
			(layer "B.SilkS")
		)
		(fp_line
			(start 2.54 2.6924)
			(end 2.5146 2.667)
			(stroke
				(width 0.1524)
				(type default)
			)
			(layer "B.SilkS")
		)
		(fp_line
			(start 2.5654 2.7305)
			(end 2.54 2.6924)
			(stroke
				(width 0.1524)
				(type default)
			)
			(layer "B.SilkS")
		)
		(fp_line
			(start 2.5908 2.6543)
			(end 2.5908 3.0861)
			(stroke
				(width 0.1524)
				(type default)
			)
			(layer "B.SilkS")
		)
		(fp_line
			(start 2.5908 2.7813)
			(end 2.5654 2.7305)
			(stroke
				(width 0.1524)
				(type default)
			)
			(layer "B.SilkS")
		)
		(fp_line
			(start 2.8575 2.5527)
			(end 2.8575 2.6416)
			(stroke
				(width 0.1524)
				(type default)
			)
			(layer "B.SilkS")
		)
		(fp_line
			(start 2.8575 2.6416)
			(end 2.8702 2.6797)
			(stroke
				(width 0.1524)
				(type default)
			)
			(layer "B.SilkS")
		)
		(fp_line
			(start 2.8702 2.5146)
			(end 2.8575 2.5527)
			(stroke
				(width 0.1524)
				(type default)
			)
			(layer "B.SilkS")
		)
		(fp_line
			(start 2.8702 2.6797)
			(end 2.8956 2.7178)
			(stroke
				(width 0.1524)
				(type default)
			)
			(layer "B.SilkS")
		)
		(fp_line
			(start 2.8956 2.7178)
			(end 2.921 2.7432)
			(stroke
				(width 0.1524)
				(type default)
			)
			(layer "B.SilkS")
		)
		(fp_line
			(start 2.921 2.7432)
			(end 2.9591 2.7686)
			(stroke
				(width 0.1524)
				(type default)
			)
			(layer "B.SilkS")
		)
		(fp_line
			(start 2.9337 2.4511)
			(end 2.8702 2.5146)
			(stroke
				(width 0.1524)
				(type default)
			)
			(layer "B.SilkS")
		)
		(fp_line
			(start 2.9591 2.7686)
			(end 3.0099 2.8067)
			(stroke
				(width 0.1524)
				(type default)
			)
			(layer "B.SilkS")
		)
		(fp_line
			(start 2.9972 2.4384)
			(end 2.9337 2.4511)
			(stroke
				(width 0.1524)
				(type default)
			)
			(layer "B.SilkS")
		)
		(fp_line
			(start 3.0099 2.8067)
			(end 3.048 2.8575)
			(stroke
				(width 0.1524)
				(type default)
			)
			(layer "B.SilkS")
		)
		(fp_line
			(start 3.048 2.4511)
			(end 2.9972 2.4384)
			(stroke
				(width 0.1524)
				(type default)
			)
			(layer "B.SilkS")
		)
		(fp_line
			(start 3.048 2.8575)
			(end 3.0734 2.8829)
			(stroke
				(width 0.1524)
				(type default)
			)
			(layer "B.SilkS")
		)
		(fp_line
			(start 3.0734 2.8829)
			(end 3.0988 2.921)
			(stroke
				(width 0.1524)
				(type default)
			)
			(layer "B.SilkS")
		)
		(fp_line
			(start 3.0861 2.4765)
			(end 3.048 2.4511)
			(stroke
				(width 0.1524)
				(type default)
			)
			(layer "B.SilkS")
		)
		(fp_line
			(start 3.0988 2.921)
			(end 3.1242 2.9972)
			(stroke
				(width 0.1524)
				(type default)
			)
			(layer "B.SilkS")
		)
		(fp_line
			(start 3.1115 2.5019)
			(end 3.0861 2.4765)
			(stroke
				(width 0.1524)
				(type default)
			)
			(layer "B.SilkS")
		)
		(fp_line
			(start 3.1242 2.9972)
			(end 3.1369 3.0861)
			(stroke
				(width 0.1524)
				(type default)
			)
			(layer "B.SilkS")
		)
		(fp_line
			(start 3.1369 2.5527)
			(end 3.1115 2.5019)
			(stroke
				(width 0.1524)
				(type default)
			)
			(layer "B.SilkS")
		)
		(fp_line
			(start 3.1369 3.0861)
			(end 2.8321 3.0861)
			(stroke
				(width 0.1524)
				(type default)
			)
			(layer "B.SilkS")
		)
		(fp_arc
			(start -1.5748 4.826)
			(mid -0.985652 3.828319)
			(end 0.127 3.5052)
			(stroke
				(width 0.1524)
				(type default)
			)
			(layer "B.SilkS")
		)
		(fp_arc
			(start -0.127 3.5052)
			(mid 0.985608 3.828376)
			(end 1.5748 4.826)
			(stroke
				(width 0.1524)
				(type default)
			)
			(layer "B.SilkS")
		)
		(fp_arc
			(start 0.1524 6.096)
			(mid -0.964559 5.805562)
			(end -1.5748 4.826)
			(stroke
				(width 0.1524)
				(type default)
			)
			(layer "B.SilkS")
		)
		(fp_arc
			(start 0.5588 0)
			(mid -0.0762 -0.635)
			(end 0.5588 -1.27)
			(stroke
				(width 0.254)
				(type default)
			)
			(layer "B.SilkS")
		)
		(fp_arc
			(start 1.5748 4.826)
			(mid 0.964547 5.805546)
			(end -0.1524 6.096)
			(stroke
				(width 0.1524)
				(type default)
			)
			(layer "B.SilkS")
		)
		(fp_circle
			(center -0.9652 0.6858)
			(end -0.35306 0.6858)
			(stroke
				(width 0.254)
				(type default)
			)
			(fill no)
			(layer "B.SilkS")
		)
		(fp_circle
			(center 0 0)
			(end 2.03454 0)
			(stroke
				(width 0.1524)
				(type default)
			)
			(fill no)
			(layer "B.SilkS")
		)
		(fp_circle
			(center 1.8923 2.8956)
			(end 2.07264 2.8956)
			(stroke
				(width 0.1524)
				(type default)
			)
			(fill no)
			(layer "B.SilkS")
		)
	)
	(footprint ""
		(layer "B.Cu")
		(at 21.859494 -95.187008 90)
		(property "Reference" "C187"
			(at 0 0 90)
			(layer "B.SilkS")
			(hide yes)
			(effects
				(font
					(size 1.27 1.27)
				)
				(justify mirror)
			)
		)
		(property "Value" ""
			(at 0 0 90)
			(layer "B.Fab")
			(effects
				(font
					(size 1.27 1.27)
				)
				(justify mirror)
			)
		)
		(duplicate_pad_numbers_are_jumpers no)
		(fp_line
			(start 0.69215 -0.2921)
			(end -0.69215 -0.2921)
			(stroke
				(width 0.1524)
				(type default)
			)
			(layer "B.SilkS")
		)
		(fp_line
			(start -0.69215 -0.2921)
			(end -0.69215 0.2921)
			(stroke
				(width 0.1524)
				(type default)
			)
			(layer "B.SilkS")
		)
		(fp_line
			(start 0.69215 0.2921)
			(end 0.69215 -0.2921)
			(stroke
				(width 0.1524)
				(type default)
			)
			(layer "B.SilkS")
		)
		(fp_line
			(start -0.69215 0.2921)
			(end 0.69215 0.2921)
			(stroke
				(width 0.1524)
				(type default)
			)
			(layer "B.SilkS")
		)
		(fp_line
			(start 0.51435 -0.2794)
			(end -0.51435 -0.2794)
			(stroke
				(width 0.1)
				(type default)
			)
			(layer "B.Fab")
		)
		(fp_line
			(start -0.51435 -0.2794)
			(end -0.51435 0.2794)
			(stroke
				(width 0.1)
				(type default)
			)
			(layer "B.Fab")
		)
		(fp_line
			(start 0.51435 0.2794)
			(end 0.51435 -0.2794)
			(stroke
				(width 0.1)
				(type default)
			)
			(layer "B.Fab")
		)
		(fp_line
			(start -0.51435 0.2794)
			(end 0.51435 0.2794)
			(stroke
				(width 0.1)
				(type default)
			)
			(layer "B.Fab")
		)
		(pad "1" smd circle
			(at 0.40005 0 270)
			(size 0 0)
			(layers "B.Cu" "B.Mask" "B.Paste")
			(net "VCCIO2")
		)
		(pad "2" smd circle
			(at -0.40005 0 270)
			(size 0 0)
			(layers "B.Cu" "B.Mask" "B.Paste")
			(net "GND")
		)
		(zone
			(layer "B.Cu")
			(hatch none 0.5)
			(connect_pads
				(clearance 0)
			)
			(min_thickness 0.25)
			(keepout
				(tracks not_allowed)
				(vias allowed)
				(pads allowed)
				(copperpour not_allowed)
				(footprints allowed)
			)
			(placement
				(enabled no)
				(sheetname "")
			)
			(fill
				(thermal_gap 0.5)
				(thermal_bridge_width 0.5)
				(island_removal_mode 0)
			)
			(polygon
				(pts
					(xy 21.947124 -95.377508) (xy 22.00529 -95.286068) (xy 22.00529 -95.086678) (xy 21.947124 -94.996508)
					(xy 21.771864 -94.996508) (xy 21.713444 -95.086678) (xy 21.713444 -95.286068) (xy 21.77161 -95.377508)
				)
			)
		)
	)
	(footprint ""
		(layer "B.Cu")
		(at 12.319 -94.488 180)
		(property "Reference" "R457"
			(at 0 0 0)
			(layer "B.SilkS")
			(hide yes)
			(effects
				(font
					(size 1.27 1.27)
				)
				(justify mirror)
			)
		)
		(property "Value" ""
			(at 0 0 0)
			(layer "B.Fab")
			(effects
				(font
					(size 1.27 1.27)
				)
				(justify mirror)
			)
		)
		(duplicate_pad_numbers_are_jumpers no)
		(fp_line
			(start 0.7874 0.4064)
			(end 0.7874 -0.4064)
			(stroke
				(width 0.1524)
				(type default)
			)
			(layer "B.SilkS")
		)
		(fp_line
			(start 0.7874 -0.4064)
			(end -0.7874 -0.4064)
			(stroke
				(width 0.1524)
				(type default)
			)
			(layer "B.SilkS")
		)
		(fp_line
			(start -0.7874 0.4064)
			(end 0.7874 0.4064)
			(stroke
				(width 0.1524)
				(type default)
			)
			(layer "B.SilkS")
		)
		(fp_line
			(start -0.7874 -0.4064)
			(end -0.7874 0.4064)
			(stroke
				(width 0.1524)
				(type default)
			)
			(layer "B.SilkS")
		)
		(fp_line
			(start 0.67945 0.3048)
			(end 0.67945 -0.305054)
			(stroke
				(width 0.1)
				(type default)
			)
			(layer "B.Fab")
		)
		(fp_line
			(start 0.67945 -0.305054)
			(end 0.12065 -0.305054)
			(stroke
				(width 0.1)
				(type default)
			)
			(layer "B.Fab")
		)
		(fp_line
			(start 0.12065 0.3048)
			(end 0.67945 0.3048)
			(stroke
				(width 0.1)
				(type default)
			)
			(layer "B.Fab")
		)
		(fp_line
			(start 0.12065 0.2794)
			(end 0.12065 0.3048)
			(stroke
				(width 0.1)
				(type default)
			)
			(layer "B.Fab")
		)
		(fp_line
			(start 0.12065 -0.2794)
			(end -0.12065 -0.2794)
			(stroke
				(width 0.1)
				(type default)
			)
			(layer "B.Fab")
		)
		(fp_line
			(start 0.12065 -0.305054)
			(end 0.12065 -0.2794)
			(stroke
				(width 0.1)
				(type default)
			)
			(layer "B.Fab")
		)
		(fp_line
			(start -0.120396 0.3048)
			(end -0.120396 0.2794)
			(stroke
				(width 0.1)
				(type default)
			)
			(layer "B.Fab")
		)
		(fp_line
			(start -0.120396 0.2794)
			(end 0.12065 0.2794)
			(stroke
				(width 0.1)
				(type default)
			)
			(layer "B.Fab")
		)
		(fp_line
			(start -0.12065 -0.2794)
			(end -0.12065 -0.3048)
			(stroke
				(width 0.1)
				(type default)
			)
			(layer "B.Fab")
		)
		(fp_line
			(start -0.12065 -0.3048)
			(end -0.67945 -0.3048)
			(stroke
				(width 0.1)
				(type default)
			)
			(layer "B.Fab")
		)
		(fp_line
			(start -0.67945 0.3048)
			(end -0.120396 0.3048)
			(stroke
				(width 0.1)
				(type default)
			)
			(layer "B.Fab")
		)
		(fp_line
			(start -0.67945 -0.3048)
			(end -0.67945 0.3048)
			(stroke
				(width 0.1)
				(type default)
			)
			(layer "B.Fab")
		)
		(pad "1" smd circle
			(at 0.40005 0)
			(size 0 0)
			(layers "B.Cu" "B.Mask" "B.Paste")
			(net "SMB_BMC_ALERT10_N")
		)
		(pad "2" smd circle
			(at -0.40005 0)
			(size 0 0)
			(layers "B.Cu" "B.Mask" "B.Paste")
			(net "SMB_BMC_ALERT10_R1_N")
		)
	)
	(footprint ""
		(layer "B.Cu")
		(at 18.923 -101.981 -90)
		(property "Reference" "R322"
			(at 0 0 90)
			(layer "B.SilkS")
			(hide yes)
			(effects
				(font
					(size 1.27 1.27)
				)
				(justify mirror)
			)
		)
		(property "Value" ""
			(at 0 0 90)
			(layer "B.Fab")
			(effects
				(font
					(size 1.27 1.27)
				)
				(justify mirror)
			)
		)
		(duplicate_pad_numbers_are_jumpers no)
		(fp_line
			(start -0.7874 0.4064)
			(end 0.7874 0.4064)
			(stroke
				(width 0.1524)
				(type default)
			)
			(layer "B.SilkS")
		)
		(fp_line
			(start 0.7874 0.4064)
			(end 0.7874 -0.4064)
			(stroke
				(width 0.1524)
				(type default)
			)
			(layer "B.SilkS")
		)
		(fp_line
			(start -0.7874 -0.4064)
			(end -0.7874 0.4064)
			(stroke
				(width 0.1524)
				(type default)
			)
			(layer "B.SilkS")
		)
		(fp_line
			(start 0.7874 -0.4064)
			(end -0.7874 -0.4064)
			(stroke
				(width 0.1524)
				(type default)
			)
			(layer "B.SilkS")
		)
		(fp_line
			(start -0.67945 0.3048)
			(end -0.120396 0.3048)
			(stroke
				(width 0.1)
				(type default)
			)
			(layer "B.Fab")
		)
		(fp_line
			(start -0.120396 0.3048)
			(end -0.120396 0.2794)
			(stroke
				(width 0.1)
				(type default)
			)
			(layer "B.Fab")
		)
		(fp_line
			(start 0.12065 0.3048)
			(end 0.67945 0.3048)
			(stroke
				(width 0.1)
				(type default)
			)
			(layer "B.Fab")
		)
		(fp_line
			(start 0.67945 0.3048)
			(end 0.67945 -0.305054)
			(stroke
				(width 0.1)
				(type default)
			)
			(layer "B.Fab")
		)
		(fp_line
			(start -0.120396 0.2794)
			(end 0.12065 0.2794)
			(stroke
				(width 0.1)
				(type default)
			)
			(layer "B.Fab")
		)
		(fp_line
			(start 0.12065 0.2794)
			(end 0.12065 0.3048)
			(stroke
				(width 0.1)
				(type default)
			)
			(layer "B.Fab")
		)
		(fp_line
			(start -0.12065 -0.2794)
			(end -0.12065 -0.3048)
			(stroke
				(width 0.1)
				(type default)
			)
			(layer "B.Fab")
		)
		(fp_line
			(start 0.12065 -0.2794)
			(end -0.12065 -0.2794)
			(stroke
				(width 0.1)
				(type default)
			)
			(layer "B.Fab")
		)
		(fp_line
			(start -0.67945 -0.3048)
			(end -0.67945 0.3048)
			(stroke
				(width 0.1)
				(type default)
			)
			(layer "B.Fab")
		)
		(fp_line
			(start -0.12065 -0.3048)
			(end -0.67945 -0.3048)
			(stroke
				(width 0.1)
				(type default)
			)
			(layer "B.Fab")
		)
		(fp_line
			(start 0.12065 -0.305054)
			(end 0.12065 -0.2794)
			(stroke
				(width 0.1)
				(type default)
			)
			(layer "B.Fab")
		)
		(fp_line
			(start 0.67945 -0.305054)
			(end 0.12065 -0.305054)
			(stroke
				(width 0.1)
				(type default)
			)
			(layer "B.Fab")
		)
		(pad "1" smd circle
			(at 0.40005 0 90)
			(size 0 0)
			(layers "B.Cu" "B.Mask" "B.Paste")
			(net "PWRGD_P3V3_RGM_R1")
		)
		(pad "2" smd circle
			(at -0.40005 0 90)
			(size 0 0)
			(layers "B.Cu" "B.Mask" "B.Paste")
			(net "PWRGD_P3V3_RGM")
		)
	)
	(footprint ""
		(layer "B.Cu")
		(at 71.069708 -29.817314)
		(property "Reference" "C192"
			(at 0 0 0)
			(layer "B.SilkS")
			(hide yes)
			(effects
				(font
					(size 1.27 1.27)
				)
				(justify mirror)
			)
		)
		(property "Value" ""
			(at 0 0 0)
			(layer "B.Fab")
			(effects
				(font
					(size 1.27 1.27)
				)
				(justify mirror)
			)
		)
		(duplicate_pad_numbers_are_jumpers no)
		(fp_line
			(start -0.7874 -0.4064)
			(end -0.7874 0.4064)
			(stroke
				(width 0.1524)
				(type default)
			)
			(layer "B.SilkS")
		)
		(fp_line
			(start -0.7874 0.4064)
			(end 0.7874 0.4064)
			(stroke
				(width 0.1524)
				(type default)
			)
			(layer "B.SilkS")
		)
		(fp_line
			(start 0.7874 -0.4064)
			(end -0.7874 -0.4064)
			(stroke
				(width 0.1524)
				(type default)
			)
			(layer "B.SilkS")
		)
		(fp_line
			(start 0.7874 0.4064)
			(end 0.7874 -0.4064)
			(stroke
				(width 0.1524)
				(type default)
			)
			(layer "B.SilkS")
		)
		(fp_line
			(start -0.67945 -0.3048)
			(end -0.67945 0.3048)
			(stroke
				(width 0.1)
				(type default)
			)
			(layer "B.Fab")
		)
		(fp_line
			(start -0.67945 0.3048)
			(end -0.120396 0.3048)
			(stroke
				(width 0.1)
				(type default)
			)
			(layer "B.Fab")
		)
		(fp_line
			(start -0.12065 -0.3048)
			(end -0.67945 -0.3048)
			(stroke
				(width 0.1)
				(type default)
			)
			(layer "B.Fab")
		)
		(fp_line
			(start -0.12065 -0.2794)
			(end -0.12065 -0.3048)
			(stroke
				(width 0.1)
				(type default)
			)
			(layer "B.Fab")
		)
		(fp_line
			(start -0.120396 0.2794)
			(end 0.12065 0.2794)
			(stroke
				(width 0.1)
				(type default)
			)
			(layer "B.Fab")
		)
		(fp_line
			(start -0.120396 0.3048)
			(end -0.120396 0.2794)
			(stroke
				(width 0.1)
				(type default)
			)
			(layer "B.Fab")
		)
		(fp_line
			(start 0.12065 -0.305054)
			(end 0.12065 -0.2794)
			(stroke
				(width 0.1)
				(type default)
			)
			(layer "B.Fab")
		)
		(fp_line
			(start 0.12065 -0.2794)
			(end -0.12065 -0.2794)
			(stroke
				(width 0.1)
				(type default)
			)
			(layer "B.Fab")
		)
		(fp_line
			(start 0.12065 0.2794)
			(end 0.12065 0.3048)
			(stroke
				(width 0.1)
				(type default)
			)
			(layer "B.Fab")
		)
		(fp_line
			(start 0.12065 0.3048)
			(end 0.67945 0.3048)
			(stroke
				(width 0.1)
				(type default)
			)
			(layer "B.Fab")
		)
		(fp_line
			(start 0.67945 -0.305054)
			(end 0.12065 -0.305054)
			(stroke
				(width 0.1)
				(type default)
			)
			(layer "B.Fab")
		)
		(fp_line
			(start 0.67945 0.3048)
			(end 0.67945 -0.305054)
			(stroke
				(width 0.1)
				(type default)
			)
			(layer "B.Fab")
		)
		(pad "1" smd circle
			(at 0.40005 0 180)
			(size 0 0)
			(layers "B.Cu" "B.Mask" "B.Paste")
			(net "P3V3_AUX")
		)
		(pad "2" smd circle
			(at -0.40005 0 180)
			(size 0 0)
			(layers "B.Cu" "B.Mask" "B.Paste")
			(net "GND")
		)
	)
	(footprint ""
		(layer "B.Cu")
		(at 39.930832 -48.026828)
		(property "Reference" "R424"
			(at 0 0 0)
			(layer "B.SilkS")
			(hide yes)
			(effects
				(font
					(size 1.27 1.27)
				)
				(justify mirror)
			)
		)
		(property "Value" ""
			(at 0 0 0)
			(layer "B.Fab")
			(effects
				(font
					(size 1.27 1.27)
				)
				(justify mirror)
			)
		)
		(duplicate_pad_numbers_are_jumpers no)
		(fp_line
			(start -0.7874 -0.4064)
			(end -0.7874 0.4064)
			(stroke
				(width 0.1524)
				(type default)
			)
			(layer "B.SilkS")
		)
		(fp_line
			(start -0.7874 0.4064)
			(end 0.7874 0.4064)
			(stroke
				(width 0.1524)
				(type default)
			)
			(layer "B.SilkS")
		)
		(fp_line
			(start 0.7874 -0.4064)
			(end -0.7874 -0.4064)
			(stroke
				(width 0.1524)
				(type default)
			)
			(layer "B.SilkS")
		)
		(fp_line
			(start 0.7874 0.4064)
			(end 0.7874 -0.4064)
			(stroke
				(width 0.1524)
				(type default)
			)
			(layer "B.SilkS")
		)
		(fp_line
			(start -0.67945 -0.3048)
			(end -0.67945 0.3048)
			(stroke
				(width 0.1)
				(type default)
			)
			(layer "B.Fab")
		)
		(fp_line
			(start -0.67945 0.3048)
			(end -0.120396 0.3048)
			(stroke
				(width 0.1)
				(type default)
			)
			(layer "B.Fab")
		)
		(fp_line
			(start -0.12065 -0.3048)
			(end -0.67945 -0.3048)
			(stroke
				(width 0.1)
				(type default)
			)
			(layer "B.Fab")
		)
		(fp_line
			(start -0.12065 -0.2794)
			(end -0.12065 -0.3048)
			(stroke
				(width 0.1)
				(type default)
			)
			(layer "B.Fab")
		)
		(fp_line
			(start -0.120396 0.2794)
			(end 0.12065 0.2794)
			(stroke
				(width 0.1)
				(type default)
			)
			(layer "B.Fab")
		)
		(fp_line
			(start -0.120396 0.3048)
			(end -0.120396 0.2794)
			(stroke
				(width 0.1)
				(type default)
			)
			(layer "B.Fab")
		)
		(fp_line
			(start 0.12065 -0.305054)
			(end 0.12065 -0.2794)
			(stroke
				(width 0.1)
				(type default)
			)
			(layer "B.Fab")
		)
		(fp_line
			(start 0.12065 -0.2794)
			(end -0.12065 -0.2794)
			(stroke
				(width 0.1)
				(type default)
			)
			(layer "B.Fab")
		)
		(fp_line
			(start 0.12065 0.2794)
			(end 0.12065 0.3048)
			(stroke
				(width 0.1)
				(type default)
			)
			(layer "B.Fab")
		)
		(fp_line
			(start 0.12065 0.3048)
			(end 0.67945 0.3048)
			(stroke
				(width 0.1)
				(type default)
			)
			(layer "B.Fab")
		)
		(fp_line
			(start 0.67945 -0.305054)
			(end 0.12065 -0.305054)
			(stroke
				(width 0.1)
				(type default)
			)
			(layer "B.Fab")
		)
		(fp_line
			(start 0.67945 0.3048)
			(end 0.67945 -0.305054)
			(stroke
				(width 0.1)
				(type default)
			)
			(layer "B.Fab")
		)
		(pad "1" smd circle
			(at 0.40005 0 180)
			(size 0 0)
			(layers "B.Cu" "B.Mask" "B.Paste")
			(net "SMB_BMC_MM13_R_SDA")
		)
		(pad "2" smd circle
			(at -0.40005 0 180)
			(size 0 0)
			(layers "B.Cu" "B.Mask" "B.Paste")
			(net "SMB_BMC_MM13_SDA")
		)
	)
	(footprint ""
		(layer "B.Cu")
		(at 70.358 -19.685 90)
		(property "Reference" "R865"
			(at 0 0 90)
			(layer "B.SilkS")
			(hide yes)
			(effects
				(font
					(size 1.27 1.27)
				)
				(justify mirror)
			)
		)
		(property "Value" ""
			(at 0 0 90)
			(layer "B.Fab")
			(effects
				(font
					(size 1.27 1.27)
				)
				(justify mirror)
			)
		)
		(duplicate_pad_numbers_are_jumpers no)
		(fp_line
			(start 0.7874 -0.4064)
			(end -0.7874 -0.4064)
			(stroke
				(width 0.1524)
				(type default)
			)
			(layer "B.SilkS")
		)
		(fp_line
			(start -0.7874 -0.4064)
			(end -0.7874 0.4064)
			(stroke
				(width 0.1524)
				(type default)
			)
			(layer "B.SilkS")
		)
		(fp_line
			(start 0.7874 0.4064)
			(end 0.7874 -0.4064)
			(stroke
				(width 0.1524)
				(type default)
			)
			(layer "B.SilkS")
		)
		(fp_line
			(start -0.7874 0.4064)
			(end 0.7874 0.4064)
			(stroke
				(width 0.1524)
				(type default)
			)
			(layer "B.SilkS")
		)
		(fp_line
			(start 0.67945 -0.305054)
			(end 0.12065 -0.305054)
			(stroke
				(width 0.1)
				(type default)
			)
			(layer "B.Fab")
		)
		(fp_line
			(start 0.12065 -0.305054)
			(end 0.12065 -0.2794)
			(stroke
				(width 0.1)
				(type default)
			)
			(layer "B.Fab")
		)
		(fp_line
			(start -0.12065 -0.3048)
			(end -0.67945 -0.3048)
			(stroke
				(width 0.1)
				(type default)
			)
			(layer "B.Fab")
		)
		(fp_line
			(start -0.67945 -0.3048)
			(end -0.67945 0.3048)
			(stroke
				(width 0.1)
				(type default)
			)
			(layer "B.Fab")
		)
		(fp_line
			(start 0.12065 -0.2794)
			(end -0.12065 -0.2794)
			(stroke
				(width 0.1)
				(type default)
			)
			(layer "B.Fab")
		)
		(fp_line
			(start -0.12065 -0.2794)
			(end -0.12065 -0.3048)
			(stroke
				(width 0.1)
				(type default)
			)
			(layer "B.Fab")
		)
		(fp_line
			(start 0.12065 0.2794)
			(end 0.12065 0.3048)
			(stroke
				(width 0.1)
				(type default)
			)
			(layer "B.Fab")
		)
		(fp_line
			(start -0.120396 0.2794)
			(end 0.12065 0.2794)
			(stroke
				(width 0.1)
				(type default)
			)
			(layer "B.Fab")
		)
		(fp_line
			(start 0.67945 0.3048)
			(end 0.67945 -0.305054)
			(stroke
				(width 0.1)
				(type default)
			)
			(layer "B.Fab")
		)
		(fp_line
			(start 0.12065 0.3048)
			(end 0.67945 0.3048)
			(stroke
				(width 0.1)
				(type default)
			)
			(layer "B.Fab")
		)
		(fp_line
			(start -0.120396 0.3048)
			(end -0.120396 0.2794)
			(stroke
				(width 0.1)
				(type default)
			)
			(layer "B.Fab")
		)
		(fp_line
			(start -0.67945 0.3048)
			(end -0.120396 0.3048)
			(stroke
				(width 0.1)
				(type default)
			)
			(layer "B.Fab")
		)
		(pad "1" smd circle
			(at 0.40005 0 270)
			(size 0 0)
			(layers "B.Cu" "B.Mask" "B.Paste")
			(net "FM_BOARD_BMC_REV_ID0")
		)
		(pad "2" smd circle
			(at -0.40005 0 270)
			(size 0 0)
			(layers "B.Cu" "B.Mask" "B.Paste")
			(net "GND")
		)
	)
	(footprint ""
		(layer "B.Cu")
		(at 61.330586 -49.314354)
		(property "Reference" "C49"
			(at 0 0 0)
			(layer "B.SilkS")
			(hide yes)
			(effects
				(font
					(size 1.27 1.27)
				)
				(justify mirror)
			)
		)
		(property "Value" ""
			(at 0 0 0)
			(layer "B.Fab")
			(effects
				(font
					(size 1.27 1.27)
				)
				(justify mirror)
			)
		)
		(duplicate_pad_numbers_are_jumpers no)
		(fp_line
			(start -0.7874 -0.4064)
			(end -0.7874 0.4064)
			(stroke
				(width 0.1524)
				(type default)
			)
			(layer "B.SilkS")
		)
		(fp_line
			(start -0.7874 0.4064)
			(end 0.7874 0.4064)
			(stroke
				(width 0.1524)
				(type default)
			)
			(layer "B.SilkS")
		)
		(fp_line
			(start 0.7874 -0.4064)
			(end -0.7874 -0.4064)
			(stroke
				(width 0.1524)
				(type default)
			)
			(layer "B.SilkS")
		)
		(fp_line
			(start 0.7874 0.4064)
			(end 0.7874 -0.4064)
			(stroke
				(width 0.1524)
				(type default)
			)
			(layer "B.SilkS")
		)
		(fp_line
			(start -0.67945 -0.3048)
			(end -0.67945 0.3048)
			(stroke
				(width 0.1)
				(type default)
			)
			(layer "B.Fab")
		)
		(fp_line
			(start -0.67945 0.3048)
			(end -0.120396 0.3048)
			(stroke
				(width 0.1)
				(type default)
			)
			(layer "B.Fab")
		)
		(fp_line
			(start -0.12065 -0.3048)
			(end -0.67945 -0.3048)
			(stroke
				(width 0.1)
				(type default)
			)
			(layer "B.Fab")
		)
		(fp_line
			(start -0.12065 -0.2794)
			(end -0.12065 -0.3048)
			(stroke
				(width 0.1)
				(type default)
			)
			(layer "B.Fab")
		)
		(fp_line
			(start -0.120396 0.2794)
			(end 0.12065 0.2794)
			(stroke
				(width 0.1)
				(type default)
			)
			(layer "B.Fab")
		)
		(fp_line
			(start -0.120396 0.3048)
			(end -0.120396 0.2794)
			(stroke
				(width 0.1)
				(type default)
			)
			(layer "B.Fab")
		)
		(fp_line
			(start 0.12065 -0.305054)
			(end 0.12065 -0.2794)
			(stroke
				(width 0.1)
				(type default)
			)
			(layer "B.Fab")
		)
		(fp_line
			(start 0.12065 -0.2794)
			(end -0.12065 -0.2794)
			(stroke
				(width 0.1)
				(type default)
			)
			(layer "B.Fab")
		)
		(fp_line
			(start 0.12065 0.2794)
			(end 0.12065 0.3048)
			(stroke
				(width 0.1)
				(type default)
			)
			(layer "B.Fab")
		)
		(fp_line
			(start 0.12065 0.3048)
			(end 0.67945 0.3048)
			(stroke
				(width 0.1)
				(type default)
			)
			(layer "B.Fab")
		)
		(fp_line
			(start 0.67945 -0.305054)
			(end 0.12065 -0.305054)
			(stroke
				(width 0.1)
				(type default)
			)
			(layer "B.Fab")
		)
		(fp_line
			(start 0.67945 0.3048)
			(end 0.67945 -0.305054)
			(stroke
				(width 0.1)
				(type default)
			)
			(layer "B.Fab")
		)
		(pad "1" smd circle
			(at 0.40005 0 180)
			(size 0 0)
			(layers "B.Cu" "B.Mask" "B.Paste")
			(net "P1V8_STBY_AVDDPLL")
		)
		(pad "2" smd circle
			(at -0.40005 0 180)
			(size 0 0)
			(layers "B.Cu" "B.Mask" "B.Paste")
			(net "GND")
		)
	)
	(footprint ""
		(layer "B.Cu")
		(at 7.239 -61.087)
		(property "Reference" "C265"
			(at 0 0 0)
			(layer "B.SilkS")
			(hide yes)
			(effects
				(font
					(size 1.27 1.27)
				)
				(justify mirror)
			)
		)
		(property "Value" ""
			(at 0 0 0)
			(layer "B.Fab")
			(effects
				(font
					(size 1.27 1.27)
				)
				(justify mirror)
			)
		)
		(duplicate_pad_numbers_are_jumpers no)
		(fp_line
			(start -1.524 -0.762)
			(end -1.524 0.762)
			(stroke
				(width 0.1524)
				(type default)
			)
			(layer "B.SilkS")
		)
		(fp_line
			(start -1.524 0.762)
			(end 1.524 0.762)
			(stroke
				(width 0.1524)
				(type default)
			)
			(layer "B.SilkS")
		)
		(fp_line
			(start 1.524 -0.762)
			(end -1.524 -0.762)
			(stroke
				(width 0.1524)
				(type default)
			)
			(layer "B.SilkS")
		)
		(fp_line
			(start 1.524 0.762)
			(end 1.524 -0.762)
			(stroke
				(width 0.1524)
				(type default)
			)
			(layer "B.SilkS")
		)
		(fp_line
			(start -1.1049 -0.724916)
			(end 1.1049 -0.724916)
			(stroke
				(width 0.1)
				(type default)
			)
			(layer "B.Fab")
		)
		(fp_line
			(start -1.1049 0.724916)
			(end -1.1049 -0.724916)
			(stroke
				(width 0.1)
				(type default)
			)
			(layer "B.Fab")
		)
		(fp_line
			(start 1.1049 -0.724916)
			(end 1.1049 0.724916)
			(stroke
				(width 0.1)
				(type default)
			)
			(layer "B.Fab")
		)
		(fp_line
			(start 1.1049 0.724916)
			(end -1.1049 0.724916)
			(stroke
				(width 0.1)
				(type default)
			)
			(layer "B.Fab")
		)
		(pad "1" smd rect
			(at 0.889 0)
			(size 1.016 1.27)
			(layers "B.Cu" "B.Mask" "B.Paste")
			(net "SW_P3V3_AUX_FLT")
		)
		(pad "2" smd rect
			(at -0.889 0)
			(size 1.016 1.27)
			(layers "B.Cu" "B.Mask" "B.Paste")
			(net "GND")
		)
	)
	(footprint ""
		(layer "B.Cu")
		(at 46.502066 -21.26234 180)
		(property "Reference" "U23"
			(at -1.453134 -2.41681 0)
			(unlocked yes)
			(layer "B.SilkS")
			(effects
				(font
					(size 0.7874 0.5842)
					(thickness 0.1524)
				)
				(justify left mirror)
			)
		)
		(property "Value" ""
			(at 0 0 0)
			(layer "B.Fab")
			(effects
				(font
					(size 1.27 1.27)
				)
				(justify mirror)
			)
		)
		(duplicate_pad_numbers_are_jumpers no)
		(fp_line
			(start 1.733296 1.549908)
			(end -1.733296 1.549908)
			(stroke
				(width 0.1524)
				(type default)
			)
			(layer "B.SilkS")
		)
		(fp_line
			(start 1.733296 -1.549908)
			(end 1.733296 1.549908)
			(stroke
				(width 0.1524)
				(type default)
			)
			(layer "B.SilkS")
		)
		(fp_line
			(start 0.660908 -1.549908)
			(end 1.733296 -1.549908)
			(stroke
				(width 0.1524)
				(type default)
			)
			(layer "B.SilkS")
		)
		(fp_line
			(start 0 -0.889)
			(end 0.660908 -1.549908)
			(stroke
				(width 0.1524)
				(type default)
			)
			(layer "B.SilkS")
		)
		(fp_line
			(start -0.660908 -1.549908)
			(end 0 -0.889)
			(stroke
				(width 0.1524)
				(type default)
			)
			(layer "B.SilkS")
		)
		(fp_line
			(start -1.733296 1.549908)
			(end -1.733296 -1.549908)
			(stroke
				(width 0.1524)
				(type default)
			)
			(layer "B.SilkS")
		)
		(fp_line
			(start -1.733296 -1.549908)
			(end -0.660908 -1.549908)
			(stroke
				(width 0.1524)
				(type default)
			)
			(layer "B.SilkS")
		)
		(fp_poly
			(pts
				(xy 0.977646 -2.547874) (xy 1.485646 -2.547874) (xy 1.231646 -2.039874)
			)
			(stroke
				(width 0)
				(type default)
			)
			(fill yes)
			(layer "B.SilkS")
		)
		(fp_line
			(start 0.849884 1.549908)
			(end -0.849884 1.549908)
			(stroke
				(width 0.1)
				(type default)
			)
			(layer "B.Fab")
		)
		(fp_line
			(start 0.849884 -1.549908)
			(end 0.849884 1.549908)
			(stroke
				(width 0.1)
				(type default)
			)
			(layer "B.Fab")
		)
		(fp_line
			(start -0.849884 1.549908)
			(end -0.849884 -1.549908)
			(stroke
				(width 0.1)
				(type default)
			)
			(layer "B.Fab")
		)
		(fp_line
			(start -0.849884 -1.549908)
			(end 0.849884 -1.549908)
			(stroke
				(width 0.1)
				(type default)
			)
			(layer "B.Fab")
		)
		(fp_poly
			(pts
				(xy 2.4384 -1.20396) (xy 2.4384 -0.69596) (xy 1.9304 -0.94996)
			)
			(stroke
				(width 0)
				(type default)
			)
			(fill yes)
			(layer "B.Fab")
		)
		(pad "1" smd rect
			(at 1.199896 -0.94996 90)
			(size 0.5588 0.8128)
			(layers "B.Cu" "B.Mask" "B.Paste")
			(net "Net_245")
		)
		(pad "2" smd rect
			(at 1.199896 0 90)
			(size 0.5588 0.8128)
			(layers "B.Cu" "B.Mask" "B.Paste")
			(net "DEBUG_PORT_PRSNT")
		)
		(pad "3" smd rect
			(at 1.199896 0.94996 90)
			(size 0.5588 0.8128)
			(layers "B.Cu" "B.Mask" "B.Paste")
			(net "GND")
		)
		(pad "4" smd rect
			(at -1.199896 0.94996 90)
			(size 0.5588 0.8128)
			(layers "B.Cu" "B.Mask" "B.Paste")
			(net "DEBUG_PORT_PRSNT_BUF_R_EN")
		)
		(pad "5" smd rect
			(at -1.199896 -0.94996 90)
			(size 0.5588 0.8128)
			(layers "B.Cu" "B.Mask" "B.Paste")
			(net "P3V3_AUX")
		)
	)
	(footprint ""
		(layer "B.Cu")
		(at 55.499 -34.671 90)
		(property "Reference" "R583"
			(at 0 0 90)
			(layer "B.SilkS")
			(hide yes)
			(effects
				(font
					(size 1.27 1.27)
				)
				(justify mirror)
			)
		)
		(property "Value" ""
			(at 0 0 90)
			(layer "B.Fab")
			(effects
				(font
					(size 1.27 1.27)
				)
				(justify mirror)
			)
		)
		(duplicate_pad_numbers_are_jumpers no)
		(fp_line
			(start 0.7874 -0.4064)
			(end -0.7874 -0.4064)
			(stroke
				(width 0.1524)
				(type default)
			)
			(layer "B.SilkS")
		)
		(fp_line
			(start -0.7874 -0.4064)
			(end -0.7874 0.4064)
			(stroke
				(width 0.1524)
				(type default)
			)
			(layer "B.SilkS")
		)
		(fp_line
			(start 0.7874 0.4064)
			(end 0.7874 -0.4064)
			(stroke
				(width 0.1524)
				(type default)
			)
			(layer "B.SilkS")
		)
		(fp_line
			(start -0.7874 0.4064)
			(end 0.7874 0.4064)
			(stroke
				(width 0.1524)
				(type default)
			)
			(layer "B.SilkS")
		)
		(fp_line
			(start 0.67945 -0.305054)
			(end 0.12065 -0.305054)
			(stroke
				(width 0.1)
				(type default)
			)
			(layer "B.Fab")
		)
		(fp_line
			(start 0.12065 -0.305054)
			(end 0.12065 -0.2794)
			(stroke
				(width 0.1)
				(type default)
			)
			(layer "B.Fab")
		)
		(fp_line
			(start -0.12065 -0.3048)
			(end -0.67945 -0.3048)
			(stroke
				(width 0.1)
				(type default)
			)
			(layer "B.Fab")
		)
		(fp_line
			(start -0.67945 -0.3048)
			(end -0.67945 0.3048)
			(stroke
				(width 0.1)
				(type default)
			)
			(layer "B.Fab")
		)
		(fp_line
			(start 0.12065 -0.2794)
			(end -0.12065 -0.2794)
			(stroke
				(width 0.1)
				(type default)
			)
			(layer "B.Fab")
		)
		(fp_line
			(start -0.12065 -0.2794)
			(end -0.12065 -0.3048)
			(stroke
				(width 0.1)
				(type default)
			)
			(layer "B.Fab")
		)
		(fp_line
			(start 0.12065 0.2794)
			(end 0.12065 0.3048)
			(stroke
				(width 0.1)
				(type default)
			)
			(layer "B.Fab")
		)
		(fp_line
			(start -0.120396 0.2794)
			(end 0.12065 0.2794)
			(stroke
				(width 0.1)
				(type default)
			)
			(layer "B.Fab")
		)
		(fp_line
			(start 0.67945 0.3048)
			(end 0.67945 -0.305054)
			(stroke
				(width 0.1)
				(type default)
			)
			(layer "B.Fab")
		)
		(fp_line
			(start 0.12065 0.3048)
			(end 0.67945 0.3048)
			(stroke
				(width 0.1)
				(type default)
			)
			(layer "B.Fab")
		)
		(fp_line
			(start -0.120396 0.3048)
			(end -0.120396 0.2794)
			(stroke
				(width 0.1)
				(type default)
			)
			(layer "B.Fab")
		)
		(fp_line
			(start -0.67945 0.3048)
			(end -0.120396 0.3048)
			(stroke
				(width 0.1)
				(type default)
			)
			(layer "B.Fab")
		)
		(pad "1" smd circle
			(at 0.40005 0 270)
			(size 0 0)
			(layers "B.Cu" "B.Mask" "B.Paste")
			(net "SMB_BMC_MM10_R_SCL")
		)
		(pad "2" smd circle
			(at -0.40005 0 270)
			(size 0 0)
			(layers "B.Cu" "B.Mask" "B.Paste")
			(net "SMB_BMC_MM10_SCL")
		)
	)
	(footprint ""
		(layer "B.Cu")
		(at 114.554 4.572 -90)
		(property "Reference" "X19"
			(at 2.07137 1.4605 0)
			(unlocked yes)
			(layer "B.SilkS")
			(effects
				(font
					(size 0.7874 0.5842)
					(thickness 0.1524)
				)
				(justify left mirror)
			)
		)
		(property "Value" ""
			(at 0 0 90)
			(layer "B.Fab")
			(effects
				(font
					(size 1.27 1.27)
				)
				(justify mirror)
			)
		)
		(property "Device Type" "TP_TDR_4P_FTS_TH-TP_TDR_4P_DIPA"
			(at -1.30175 1.27 180)
			(unlocked yes)
			(layer "B.Fab")
			(hide yes)
			(effects
				(font
					(size 0.635 0.4064)
					(thickness 0.1524)
				)
				(justify mirror)
			)
		)
		(property "User Part Number" "N_A"
			(at -1.30175 1.27 180)
			(unlocked yes)
			(layer "Cmts.User")
			(hide yes)
			(effects
				(font
					(size 0.635 0.4064)
					(thickness 0.1524)
				)
				(justify mirror)
			)
		)
		(duplicate_pad_numbers_are_jumpers no)
		(fp_line
			(start -2.54 3.81)
			(end -2.54 3.6703)
			(stroke
				(width 0.1524)
				(type default)
			)
			(layer "B.SilkS")
		)
		(fp_line
			(start 0 3.81)
			(end -2.54 3.81)
			(stroke
				(width 0.1524)
				(type default)
			)
			(layer "B.SilkS")
		)
		(fp_line
			(start 0 3.175)
			(end 0 3.81)
			(stroke
				(width 0.1524)
				(type default)
			)
			(layer "B.SilkS")
		)
		(fp_line
			(start -2.54 1.4097)
			(end -2.54 1.1303)
			(stroke
				(width 0.1524)
				(type default)
			)
			(layer "B.SilkS")
		)
		(fp_line
			(start 0 0.635)
			(end 0 1.905)
			(stroke
				(width 0.1524)
				(type default)
			)
			(layer "B.SilkS")
		)
		(fp_line
			(start -2.54 -1.1303)
			(end -2.54 -1.27)
			(stroke
				(width 0.1524)
				(type default)
			)
			(layer "B.SilkS")
		)
		(fp_line
			(start -2.54 -1.27)
			(end 0 -1.27)
			(stroke
				(width 0.1524)
				(type default)
			)
			(layer "B.SilkS")
		)
		(fp_line
			(start 0 -1.27)
			(end 0 -0.635)
			(stroke
				(width 0.1524)
				(type default)
			)
			(layer "B.SilkS")
		)
		(fp_poly
			(pts
				(xy 0.761746 0) (xy 2.285746 -0.762) (xy 2.285746 0.762)
			)
			(stroke
				(width 0)
				(type default)
			)
			(fill yes)
			(layer "B.SilkS")
		)
		(fp_line
			(start -2.54 3.81)
			(end -2.54 -1.27)
			(stroke
				(width 0.1)
				(type default)
			)
			(layer "B.Fab")
		)
		(fp_line
			(start 0 3.81)
			(end -2.54 3.81)
			(stroke
				(width 0.1)
				(type default)
			)
			(layer "B.Fab")
		)
		(fp_line
			(start -2.54 -1.27)
			(end 0 -1.27)
			(stroke
				(width 0.1)
				(type default)
			)
			(layer "B.Fab")
		)
		(fp_line
			(start 0 -1.27)
			(end 0 3.81)
			(stroke
				(width 0.1)
				(type default)
			)
			(layer "B.Fab")
		)
		(fp_poly
			(pts
				(xy 0.761746 0) (xy 2.285746 -0.762) (xy 2.285746 0.762)
			)
			(stroke
				(width 0)
				(type default)
			)
			(fill yes)
			(layer "B.Fab")
		)
		(pad "1" thru_hole circle
			(at 0 0 90)
			(size 1.0033 1.0033)
			(drill 0.249936)
			(layers "*.Cu" "*.Mask")
			(remove_unused_layers no)
			(net "TDR_DIFF_100_TOP_DN")
			(clearance 0.10795)
			(padstack
				(mode front_inner_back)
				(layer "Inner"
					(shape circle)
					(size 0.8001 0.8001)
					(clearance 0.1524)
				)
				(layer "B.Cu"
					(shape circle)
					(size 1.0033 1.0033)
					(thermal_gap 0.10795)
					(clearance 0.10795)
				)
			)
		)
		(pad "2" thru_hole circle
			(at -2.54 0 90)
			(size 1.9939 1.9939)
			(drill 0.249936)
			(layers "*.Cu" "*.Mask")
			(remove_unused_layers no)
			(net "GND_P1")
			(clearance 0.10795)
			(padstack
				(mode front_inner_back)
				(layer "Inner"
					(shape circle)
					(size 0.8001 0.8001)
					(clearance 0.1524)
				)
				(layer "B.Cu"
					(shape circle)
					(size 1.9939 1.9939)
					(thermal_gap 0.10795)
					(clearance 0.10795)
				)
			)
		)
		(pad "3" thru_hole circle
			(at -2.54 2.54 90)
			(size 1.9939 1.9939)
			(drill 0.249936)
			(layers "*.Cu" "*.Mask")
			(remove_unused_layers no)
			(net "GND_P1")
			(clearance 0.10795)
			(padstack
				(mode front_inner_back)
				(layer "Inner"
					(shape circle)
					(size 0.8001 0.8001)
					(clearance 0.1524)
				)
				(layer "B.Cu"
					(shape circle)
					(size 1.9939 1.9939)
					(thermal_gap 0.10795)
					(clearance 0.10795)
				)
			)
		)
		(pad "4" thru_hole circle
			(at 0 2.54 90)
			(size 1.0033 1.0033)
			(drill 0.249936)
			(layers "*.Cu" "*.Mask")
			(remove_unused_layers no)
			(net "TDR_DIFF_100_TOP_DP")
			(clearance 0.10795)
			(padstack
				(mode front_inner_back)
				(layer "Inner"
					(shape circle)
					(size 0.8001 0.8001)
					(clearance 0.1524)
				)
				(layer "B.Cu"
					(shape circle)
					(size 1.0033 1.0033)
					(thermal_gap 0.10795)
					(clearance 0.10795)
				)
			)
		)
	)
	(footprint ""
		(layer "B.Cu")
		(at 43.367452 -30.816804 -90)
		(property "Reference" "R247"
			(at 0 0 90)
			(layer "B.SilkS")
			(hide yes)
			(effects
				(font
					(size 1.27 1.27)
				)
				(justify mirror)
			)
		)
		(property "Value" ""
			(at 0 0 90)
			(layer "B.Fab")
			(effects
				(font
					(size 1.27 1.27)
				)
				(justify mirror)
			)
		)
		(duplicate_pad_numbers_are_jumpers no)
		(fp_line
			(start -0.7874 0.4064)
			(end 0.7874 0.4064)
			(stroke
				(width 0.1524)
				(type default)
			)
			(layer "B.SilkS")
		)
		(fp_line
			(start 0.7874 0.4064)
			(end 0.7874 -0.4064)
			(stroke
				(width 0.1524)
				(type default)
			)
			(layer "B.SilkS")
		)
		(fp_line
			(start -0.7874 -0.4064)
			(end -0.7874 0.4064)
			(stroke
				(width 0.1524)
				(type default)
			)
			(layer "B.SilkS")
		)
		(fp_line
			(start 0.7874 -0.4064)
			(end -0.7874 -0.4064)
			(stroke
				(width 0.1524)
				(type default)
			)
			(layer "B.SilkS")
		)
		(fp_line
			(start -0.67945 0.3048)
			(end -0.120396 0.3048)
			(stroke
				(width 0.1)
				(type default)
			)
			(layer "B.Fab")
		)
		(fp_line
			(start -0.120396 0.3048)
			(end -0.120396 0.2794)
			(stroke
				(width 0.1)
				(type default)
			)
			(layer "B.Fab")
		)
		(fp_line
			(start 0.12065 0.3048)
			(end 0.67945 0.3048)
			(stroke
				(width 0.1)
				(type default)
			)
			(layer "B.Fab")
		)
		(fp_line
			(start 0.67945 0.3048)
			(end 0.67945 -0.305054)
			(stroke
				(width 0.1)
				(type default)
			)
			(layer "B.Fab")
		)
		(fp_line
			(start -0.120396 0.2794)
			(end 0.12065 0.2794)
			(stroke
				(width 0.1)
				(type default)
			)
			(layer "B.Fab")
		)
		(fp_line
			(start 0.12065 0.2794)
			(end 0.12065 0.3048)
			(stroke
				(width 0.1)
				(type default)
			)
			(layer "B.Fab")
		)
		(fp_line
			(start -0.12065 -0.2794)
			(end -0.12065 -0.3048)
			(stroke
				(width 0.1)
				(type default)
			)
			(layer "B.Fab")
		)
		(fp_line
			(start 0.12065 -0.2794)
			(end -0.12065 -0.2794)
			(stroke
				(width 0.1)
				(type default)
			)
			(layer "B.Fab")
		)
		(fp_line
			(start -0.67945 -0.3048)
			(end -0.67945 0.3048)
			(stroke
				(width 0.1)
				(type default)
			)
			(layer "B.Fab")
		)
		(fp_line
			(start -0.12065 -0.3048)
			(end -0.67945 -0.3048)
			(stroke
				(width 0.1)
				(type default)
			)
			(layer "B.Fab")
		)
		(fp_line
			(start 0.12065 -0.305054)
			(end 0.12065 -0.2794)
			(stroke
				(width 0.1)
				(type default)
			)
			(layer "B.Fab")
		)
		(fp_line
			(start 0.67945 -0.305054)
			(end 0.12065 -0.305054)
			(stroke
				(width 0.1)
				(type default)
			)
			(layer "B.Fab")
		)
		(pad "1" smd circle
			(at 0.40005 0 90)
			(size 0 0)
			(layers "B.Cu" "B.Mask" "B.Paste")
			(net "P3V3_AUX")
		)
		(pad "2" smd circle
			(at -0.40005 0 90)
			(size 0 0)
			(layers "B.Cu" "B.Mask" "B.Paste")
			(net "SMB_BMC_MM2_SDA")
		)
	)
	(footprint ""
		(layer "B.Cu")
		(at 57.785 -24.13 -90)
		(property "Reference" "R219"
			(at 0 0 90)
			(layer "B.SilkS")
			(hide yes)
			(effects
				(font
					(size 1.27 1.27)
				)
				(justify mirror)
			)
		)
		(property "Value" ""
			(at 0 0 90)
			(layer "B.Fab")
			(effects
				(font
					(size 1.27 1.27)
				)
				(justify mirror)
			)
		)
		(duplicate_pad_numbers_are_jumpers no)
		(fp_line
			(start -0.7874 0.4064)
			(end 0.7874 0.4064)
			(stroke
				(width 0.1524)
				(type default)
			)
			(layer "B.SilkS")
		)
		(fp_line
			(start 0.7874 0.4064)
			(end 0.7874 -0.4064)
			(stroke
				(width 0.1524)
				(type default)
			)
			(layer "B.SilkS")
		)
		(fp_line
			(start -0.7874 -0.4064)
			(end -0.7874 0.4064)
			(stroke
				(width 0.1524)
				(type default)
			)
			(layer "B.SilkS")
		)
		(fp_line
			(start 0.7874 -0.4064)
			(end -0.7874 -0.4064)
			(stroke
				(width 0.1524)
				(type default)
			)
			(layer "B.SilkS")
		)
		(fp_line
			(start -0.67945 0.3048)
			(end -0.120396 0.3048)
			(stroke
				(width 0.1)
				(type default)
			)
			(layer "B.Fab")
		)
		(fp_line
			(start -0.120396 0.3048)
			(end -0.120396 0.2794)
			(stroke
				(width 0.1)
				(type default)
			)
			(layer "B.Fab")
		)
		(fp_line
			(start 0.12065 0.3048)
			(end 0.67945 0.3048)
			(stroke
				(width 0.1)
				(type default)
			)
			(layer "B.Fab")
		)
		(fp_line
			(start 0.67945 0.3048)
			(end 0.67945 -0.305054)
			(stroke
				(width 0.1)
				(type default)
			)
			(layer "B.Fab")
		)
		(fp_line
			(start -0.120396 0.2794)
			(end 0.12065 0.2794)
			(stroke
				(width 0.1)
				(type default)
			)
			(layer "B.Fab")
		)
		(fp_line
			(start 0.12065 0.2794)
			(end 0.12065 0.3048)
			(stroke
				(width 0.1)
				(type default)
			)
			(layer "B.Fab")
		)
		(fp_line
			(start -0.12065 -0.2794)
			(end -0.12065 -0.3048)
			(stroke
				(width 0.1)
				(type default)
			)
			(layer "B.Fab")
		)
		(fp_line
			(start 0.12065 -0.2794)
			(end -0.12065 -0.2794)
			(stroke
				(width 0.1)
				(type default)
			)
			(layer "B.Fab")
		)
		(fp_line
			(start -0.67945 -0.3048)
			(end -0.67945 0.3048)
			(stroke
				(width 0.1)
				(type default)
			)
			(layer "B.Fab")
		)
		(fp_line
			(start -0.12065 -0.3048)
			(end -0.67945 -0.3048)
			(stroke
				(width 0.1)
				(type default)
			)
			(layer "B.Fab")
		)
		(fp_line
			(start 0.12065 -0.305054)
			(end 0.12065 -0.2794)
			(stroke
				(width 0.1)
				(type default)
			)
			(layer "B.Fab")
		)
		(fp_line
			(start 0.67945 -0.305054)
			(end 0.12065 -0.305054)
			(stroke
				(width 0.1)
				(type default)
			)
			(layer "B.Fab")
		)
		(pad "1" smd circle
			(at 0.40005 0 90)
			(size 0 0)
			(layers "B.Cu" "B.Mask" "B.Paste")
			(net "DEBUG_PORT_UART_TX")
		)
		(pad "2" smd circle
			(at -0.40005 0 90)
			(size 0 0)
			(layers "B.Cu" "B.Mask" "B.Paste")
			(net "GND")
		)
	)
	(footprint ""
		(layer "B.Cu")
		(at 55.08117 -47.85741 -90)
		(property "Reference" "C116"
			(at 0 0 90)
			(layer "B.SilkS")
			(hide yes)
			(effects
				(font
					(size 1.27 1.27)
				)
				(justify mirror)
			)
		)
		(property "Value" ""
			(at 0 0 90)
			(layer "B.Fab")
			(effects
				(font
					(size 1.27 1.27)
				)
				(justify mirror)
			)
		)
		(duplicate_pad_numbers_are_jumpers no)
		(fp_line
			(start -0.7874 0.4064)
			(end 0.7874 0.4064)
			(stroke
				(width 0.1524)
				(type default)
			)
			(layer "B.SilkS")
		)
		(fp_line
			(start 0.7874 0.4064)
			(end 0.7874 -0.4064)
			(stroke
				(width 0.1524)
				(type default)
			)
			(layer "B.SilkS")
		)
		(fp_line
			(start -0.7874 -0.4064)
			(end -0.7874 0.4064)
			(stroke
				(width 0.1524)
				(type default)
			)
			(layer "B.SilkS")
		)
		(fp_line
			(start 0.7874 -0.4064)
			(end -0.7874 -0.4064)
			(stroke
				(width 0.1524)
				(type default)
			)
			(layer "B.SilkS")
		)
		(fp_line
			(start -0.67945 0.3048)
			(end -0.120396 0.3048)
			(stroke
				(width 0.1)
				(type default)
			)
			(layer "B.Fab")
		)
		(fp_line
			(start -0.120396 0.3048)
			(end -0.120396 0.2794)
			(stroke
				(width 0.1)
				(type default)
			)
			(layer "B.Fab")
		)
		(fp_line
			(start 0.12065 0.3048)
			(end 0.67945 0.3048)
			(stroke
				(width 0.1)
				(type default)
			)
			(layer "B.Fab")
		)
		(fp_line
			(start 0.67945 0.3048)
			(end 0.67945 -0.305054)
			(stroke
				(width 0.1)
				(type default)
			)
			(layer "B.Fab")
		)
		(fp_line
			(start -0.120396 0.2794)
			(end 0.12065 0.2794)
			(stroke
				(width 0.1)
				(type default)
			)
			(layer "B.Fab")
		)
		(fp_line
			(start 0.12065 0.2794)
			(end 0.12065 0.3048)
			(stroke
				(width 0.1)
				(type default)
			)
			(layer "B.Fab")
		)
		(fp_line
			(start -0.12065 -0.2794)
			(end -0.12065 -0.3048)
			(stroke
				(width 0.1)
				(type default)
			)
			(layer "B.Fab")
		)
		(fp_line
			(start 0.12065 -0.2794)
			(end -0.12065 -0.2794)
			(stroke
				(width 0.1)
				(type default)
			)
			(layer "B.Fab")
		)
		(fp_line
			(start -0.67945 -0.3048)
			(end -0.67945 0.3048)
			(stroke
				(width 0.1)
				(type default)
			)
			(layer "B.Fab")
		)
		(fp_line
			(start -0.12065 -0.3048)
			(end -0.67945 -0.3048)
			(stroke
				(width 0.1)
				(type default)
			)
			(layer "B.Fab")
		)
		(fp_line
			(start 0.12065 -0.305054)
			(end 0.12065 -0.2794)
			(stroke
				(width 0.1)
				(type default)
			)
			(layer "B.Fab")
		)
		(fp_line
			(start 0.67945 -0.305054)
			(end 0.12065 -0.305054)
			(stroke
				(width 0.1)
				(type default)
			)
			(layer "B.Fab")
		)
		(pad "1" smd circle
			(at 0.40005 0 90)
			(size 0 0)
			(layers "B.Cu" "B.Mask" "B.Paste")
			(net "P1V8_AUX")
		)
		(pad "2" smd circle
			(at -0.40005 0 90)
			(size 0 0)
			(layers "B.Cu" "B.Mask" "B.Paste")
			(net "GND")
		)
	)
	(footprint ""
		(layer "B.Cu")
		(at 63.61811 -62.014862 -90)
		(property "Reference" "R131"
			(at 0 0 90)
			(layer "B.SilkS")
			(hide yes)
			(effects
				(font
					(size 1.27 1.27)
				)
				(justify mirror)
			)
		)
		(property "Value" ""
			(at 0 0 90)
			(layer "B.Fab")
			(effects
				(font
					(size 1.27 1.27)
				)
				(justify mirror)
			)
		)
		(duplicate_pad_numbers_are_jumpers no)
		(fp_line
			(start -0.7874 0.4064)
			(end 0.7874 0.4064)
			(stroke
				(width 0.1524)
				(type default)
			)
			(layer "B.SilkS")
		)
		(fp_line
			(start 0.7874 0.4064)
			(end 0.7874 -0.4064)
			(stroke
				(width 0.1524)
				(type default)
			)
			(layer "B.SilkS")
		)
		(fp_line
			(start -0.7874 -0.4064)
			(end -0.7874 0.4064)
			(stroke
				(width 0.1524)
				(type default)
			)
			(layer "B.SilkS")
		)
		(fp_line
			(start 0.7874 -0.4064)
			(end -0.7874 -0.4064)
			(stroke
				(width 0.1524)
				(type default)
			)
			(layer "B.SilkS")
		)
		(fp_line
			(start -0.67945 0.3048)
			(end -0.120396 0.3048)
			(stroke
				(width 0.1)
				(type default)
			)
			(layer "B.Fab")
		)
		(fp_line
			(start -0.120396 0.3048)
			(end -0.120396 0.2794)
			(stroke
				(width 0.1)
				(type default)
			)
			(layer "B.Fab")
		)
		(fp_line
			(start 0.12065 0.3048)
			(end 0.67945 0.3048)
			(stroke
				(width 0.1)
				(type default)
			)
			(layer "B.Fab")
		)
		(fp_line
			(start 0.67945 0.3048)
			(end 0.67945 -0.305054)
			(stroke
				(width 0.1)
				(type default)
			)
			(layer "B.Fab")
		)
		(fp_line
			(start -0.120396 0.2794)
			(end 0.12065 0.2794)
			(stroke
				(width 0.1)
				(type default)
			)
			(layer "B.Fab")
		)
		(fp_line
			(start 0.12065 0.2794)
			(end 0.12065 0.3048)
			(stroke
				(width 0.1)
				(type default)
			)
			(layer "B.Fab")
		)
		(fp_line
			(start -0.12065 -0.2794)
			(end -0.12065 -0.3048)
			(stroke
				(width 0.1)
				(type default)
			)
			(layer "B.Fab")
		)
		(fp_line
			(start 0.12065 -0.2794)
			(end -0.12065 -0.2794)
			(stroke
				(width 0.1)
				(type default)
			)
			(layer "B.Fab")
		)
		(fp_line
			(start -0.67945 -0.3048)
			(end -0.67945 0.3048)
			(stroke
				(width 0.1)
				(type default)
			)
			(layer "B.Fab")
		)
		(fp_line
			(start -0.12065 -0.3048)
			(end -0.67945 -0.3048)
			(stroke
				(width 0.1)
				(type default)
			)
			(layer "B.Fab")
		)
		(fp_line
			(start 0.12065 -0.305054)
			(end 0.12065 -0.2794)
			(stroke
				(width 0.1)
				(type default)
			)
			(layer "B.Fab")
		)
		(fp_line
			(start 0.67945 -0.305054)
			(end 0.12065 -0.305054)
			(stroke
				(width 0.1)
				(type default)
			)
			(layer "B.Fab")
		)
		(pad "1" smd circle
			(at 0.40005 0 90)
			(size 0 0)
			(layers "B.Cu" "B.Mask" "B.Paste")
			(net "ESPI_LPC_D3_IO3")
		)
		(pad "2" smd circle
			(at -0.40005 0 90)
			(size 0 0)
			(layers "B.Cu" "B.Mask" "B.Paste")
			(net "ESPI_LPC_LAD3_IO3")
		)
	)
	(footprint ""
		(layer "B.Cu")
		(at 85.32241 -27.607768)
		(property "Reference" "R13"
			(at 0 0 0)
			(layer "B.SilkS")
			(hide yes)
			(effects
				(font
					(size 1.27 1.27)
				)
				(justify mirror)
			)
		)
		(property "Value" ""
			(at 0 0 0)
			(layer "B.Fab")
			(effects
				(font
					(size 1.27 1.27)
				)
				(justify mirror)
			)
		)
		(duplicate_pad_numbers_are_jumpers no)
		(fp_line
			(start -0.7874 -0.4064)
			(end -0.7874 0.4064)
			(stroke
				(width 0.1524)
				(type default)
			)
			(layer "B.SilkS")
		)
		(fp_line
			(start -0.7874 0.4064)
			(end 0.7874 0.4064)
			(stroke
				(width 0.1524)
				(type default)
			)
			(layer "B.SilkS")
		)
		(fp_line
			(start 0.7874 -0.4064)
			(end -0.7874 -0.4064)
			(stroke
				(width 0.1524)
				(type default)
			)
			(layer "B.SilkS")
		)
		(fp_line
			(start 0.7874 0.4064)
			(end 0.7874 -0.4064)
			(stroke
				(width 0.1524)
				(type default)
			)
			(layer "B.SilkS")
		)
		(fp_line
			(start -0.67945 -0.3048)
			(end -0.67945 0.3048)
			(stroke
				(width 0.1)
				(type default)
			)
			(layer "B.Fab")
		)
		(fp_line
			(start -0.67945 0.3048)
			(end -0.120396 0.3048)
			(stroke
				(width 0.1)
				(type default)
			)
			(layer "B.Fab")
		)
		(fp_line
			(start -0.12065 -0.3048)
			(end -0.67945 -0.3048)
			(stroke
				(width 0.1)
				(type default)
			)
			(layer "B.Fab")
		)
		(fp_line
			(start -0.12065 -0.2794)
			(end -0.12065 -0.3048)
			(stroke
				(width 0.1)
				(type default)
			)
			(layer "B.Fab")
		)
		(fp_line
			(start -0.120396 0.2794)
			(end 0.12065 0.2794)
			(stroke
				(width 0.1)
				(type default)
			)
			(layer "B.Fab")
		)
		(fp_line
			(start -0.120396 0.3048)
			(end -0.120396 0.2794)
			(stroke
				(width 0.1)
				(type default)
			)
			(layer "B.Fab")
		)
		(fp_line
			(start 0.12065 -0.305054)
			(end 0.12065 -0.2794)
			(stroke
				(width 0.1)
				(type default)
			)
			(layer "B.Fab")
		)
		(fp_line
			(start 0.12065 -0.2794)
			(end -0.12065 -0.2794)
			(stroke
				(width 0.1)
				(type default)
			)
			(layer "B.Fab")
		)
		(fp_line
			(start 0.12065 0.2794)
			(end 0.12065 0.3048)
			(stroke
				(width 0.1)
				(type default)
			)
			(layer "B.Fab")
		)
		(fp_line
			(start 0.12065 0.3048)
			(end 0.67945 0.3048)
			(stroke
				(width 0.1)
				(type default)
			)
			(layer "B.Fab")
		)
		(fp_line
			(start 0.67945 -0.305054)
			(end 0.12065 -0.305054)
			(stroke
				(width 0.1)
				(type default)
			)
			(layer "B.Fab")
		)
		(fp_line
			(start 0.67945 0.3048)
			(end 0.67945 -0.305054)
			(stroke
				(width 0.1)
				(type default)
			)
			(layer "B.Fab")
		)
		(pad "1" smd circle
			(at 0.40005 0 180)
			(size 0 0)
			(layers "B.Cu" "B.Mask" "B.Paste")
			(net "P3V3_AUX")
		)
		(pad "2" smd circle
			(at -0.40005 0 180)
			(size 0 0)
			(layers "B.Cu" "B.Mask" "B.Paste")
			(net "FRU_E1")
		)
	)
	(footprint ""
		(layer "B.Cu")
		(at 38.608 -64.5922 90)
		(property "Reference" "R644"
			(at 0 0 90)
			(layer "B.SilkS")
			(hide yes)
			(effects
				(font
					(size 1.27 1.27)
				)
				(justify mirror)
			)
		)
		(property "Value" ""
			(at 0 0 90)
			(layer "B.Fab")
			(effects
				(font
					(size 1.27 1.27)
				)
				(justify mirror)
			)
		)
		(duplicate_pad_numbers_are_jumpers no)
		(fp_line
			(start 0.7874 -0.4064)
			(end -0.7874 -0.4064)
			(stroke
				(width 0.1524)
				(type default)
			)
			(layer "B.SilkS")
		)
		(fp_line
			(start -0.7874 -0.4064)
			(end -0.7874 0.4064)
			(stroke
				(width 0.1524)
				(type default)
			)
			(layer "B.SilkS")
		)
		(fp_line
			(start 0.7874 0.4064)
			(end 0.7874 -0.4064)
			(stroke
				(width 0.1524)
				(type default)
			)
			(layer "B.SilkS")
		)
		(fp_line
			(start -0.7874 0.4064)
			(end 0.7874 0.4064)
			(stroke
				(width 0.1524)
				(type default)
			)
			(layer "B.SilkS")
		)
		(fp_line
			(start 0.67945 -0.305054)
			(end 0.12065 -0.305054)
			(stroke
				(width 0.1)
				(type default)
			)
			(layer "B.Fab")
		)
		(fp_line
			(start 0.12065 -0.305054)
			(end 0.12065 -0.2794)
			(stroke
				(width 0.1)
				(type default)
			)
			(layer "B.Fab")
		)
		(fp_line
			(start -0.12065 -0.3048)
			(end -0.67945 -0.3048)
			(stroke
				(width 0.1)
				(type default)
			)
			(layer "B.Fab")
		)
		(fp_line
			(start -0.67945 -0.3048)
			(end -0.67945 0.3048)
			(stroke
				(width 0.1)
				(type default)
			)
			(layer "B.Fab")
		)
		(fp_line
			(start 0.12065 -0.2794)
			(end -0.12065 -0.2794)
			(stroke
				(width 0.1)
				(type default)
			)
			(layer "B.Fab")
		)
		(fp_line
			(start -0.12065 -0.2794)
			(end -0.12065 -0.3048)
			(stroke
				(width 0.1)
				(type default)
			)
			(layer "B.Fab")
		)
		(fp_line
			(start 0.12065 0.2794)
			(end 0.12065 0.3048)
			(stroke
				(width 0.1)
				(type default)
			)
			(layer "B.Fab")
		)
		(fp_line
			(start -0.120396 0.2794)
			(end 0.12065 0.2794)
			(stroke
				(width 0.1)
				(type default)
			)
			(layer "B.Fab")
		)
		(fp_line
			(start 0.67945 0.3048)
			(end 0.67945 -0.305054)
			(stroke
				(width 0.1)
				(type default)
			)
			(layer "B.Fab")
		)
		(fp_line
			(start 0.12065 0.3048)
			(end 0.67945 0.3048)
			(stroke
				(width 0.1)
				(type default)
			)
			(layer "B.Fab")
		)
		(fp_line
			(start -0.120396 0.3048)
			(end -0.120396 0.2794)
			(stroke
				(width 0.1)
				(type default)
			)
			(layer "B.Fab")
		)
		(fp_line
			(start -0.67945 0.3048)
			(end -0.120396 0.3048)
			(stroke
				(width 0.1)
				(type default)
			)
			(layer "B.Fab")
		)
		(pad "1" smd circle
			(at 0.40005 0 270)
			(size 0 0)
			(layers "B.Cu" "B.Mask" "B.Paste")
			(net "FM_JTAG_BMC_MUX_SEL")
		)
		(pad "2" smd circle
			(at -0.40005 0 270)
			(size 0 0)
			(layers "B.Cu" "B.Mask" "B.Paste")
			(net "FM_JTAG_BMC_MUX_SEL_R1")
		)
	)
	(footprint ""
		(layer "B.Cu")
		(at 21.059394 -95.187008 90)
		(property "Reference" "C245"
			(at 0 0 90)
			(layer "B.SilkS")
			(hide yes)
			(effects
				(font
					(size 1.27 1.27)
				)
				(justify mirror)
			)
		)
		(property "Value" ""
			(at 0 0 90)
			(layer "B.Fab")
			(effects
				(font
					(size 1.27 1.27)
				)
				(justify mirror)
			)
		)
		(duplicate_pad_numbers_are_jumpers no)
		(fp_line
			(start 0.69215 -0.2921)
			(end -0.69215 -0.2921)
			(stroke
				(width 0.1524)
				(type default)
			)
			(layer "B.SilkS")
		)
		(fp_line
			(start -0.69215 -0.2921)
			(end -0.69215 0.2921)
			(stroke
				(width 0.1524)
				(type default)
			)
			(layer "B.SilkS")
		)
		(fp_line
			(start 0.69215 0.2921)
			(end 0.69215 -0.2921)
			(stroke
				(width 0.1524)
				(type default)
			)
			(layer "B.SilkS")
		)
		(fp_line
			(start -0.69215 0.2921)
			(end 0.69215 0.2921)
			(stroke
				(width 0.1524)
				(type default)
			)
			(layer "B.SilkS")
		)
		(fp_line
			(start 0.51435 -0.2794)
			(end -0.51435 -0.2794)
			(stroke
				(width 0.1)
				(type default)
			)
			(layer "B.Fab")
		)
		(fp_line
			(start -0.51435 -0.2794)
			(end -0.51435 0.2794)
			(stroke
				(width 0.1)
				(type default)
			)
			(layer "B.Fab")
		)
		(fp_line
			(start 0.51435 0.2794)
			(end 0.51435 -0.2794)
			(stroke
				(width 0.1)
				(type default)
			)
			(layer "B.Fab")
		)
		(fp_line
			(start -0.51435 0.2794)
			(end 0.51435 0.2794)
			(stroke
				(width 0.1)
				(type default)
			)
			(layer "B.Fab")
		)
		(pad "1" smd circle
			(at 0.40005 0 270)
			(size 0 0)
			(layers "B.Cu" "B.Mask" "B.Paste")
			(net "VCCIO2")
		)
		(pad "2" smd circle
			(at -0.40005 0 270)
			(size 0 0)
			(layers "B.Cu" "B.Mask" "B.Paste")
			(net "GND")
		)
		(zone
			(layer "B.Cu")
			(hatch none 0.5)
			(connect_pads
				(clearance 0)
			)
			(min_thickness 0.25)
			(keepout
				(tracks not_allowed)
				(vias allowed)
				(pads allowed)
				(copperpour not_allowed)
				(footprints allowed)
			)
			(placement
				(enabled no)
				(sheetname "")
			)
			(fill
				(thermal_gap 0.5)
				(thermal_bridge_width 0.5)
				(island_removal_mode 0)
			)
			(polygon
				(pts
					(xy 21.147024 -95.377508) (xy 21.20519 -95.286068) (xy 21.20519 -95.086678) (xy 21.147024 -94.996508)
					(xy 20.971764 -94.996508) (xy 20.913344 -95.086678) (xy 20.913344 -95.286068) (xy 20.97151 -95.377508)
				)
			)
		)
	)
	(footprint ""
		(layer "B.Cu")
		(at 74.8538 -33.4518 180)
		(property "Reference" "R674"
			(at 0 0 0)
			(layer "B.SilkS")
			(hide yes)
			(effects
				(font
					(size 1.27 1.27)
				)
				(justify mirror)
			)
		)
		(property "Value" ""
			(at 0 0 0)
			(layer "B.Fab")
			(effects
				(font
					(size 1.27 1.27)
				)
				(justify mirror)
			)
		)
		(duplicate_pad_numbers_are_jumpers no)
		(fp_line
			(start 0.7874 0.4064)
			(end 0.7874 -0.4064)
			(stroke
				(width 0.1524)
				(type default)
			)
			(layer "B.SilkS")
		)
		(fp_line
			(start 0.7874 -0.4064)
			(end -0.7874 -0.4064)
			(stroke
				(width 0.1524)
				(type default)
			)
			(layer "B.SilkS")
		)
		(fp_line
			(start -0.7874 0.4064)
			(end 0.7874 0.4064)
			(stroke
				(width 0.1524)
				(type default)
			)
			(layer "B.SilkS")
		)
		(fp_line
			(start -0.7874 -0.4064)
			(end -0.7874 0.4064)
			(stroke
				(width 0.1524)
				(type default)
			)
			(layer "B.SilkS")
		)
		(fp_line
			(start 0.67945 0.3048)
			(end 0.67945 -0.305054)
			(stroke
				(width 0.1)
				(type default)
			)
			(layer "B.Fab")
		)
		(fp_line
			(start 0.67945 -0.305054)
			(end 0.12065 -0.305054)
			(stroke
				(width 0.1)
				(type default)
			)
			(layer "B.Fab")
		)
		(fp_line
			(start 0.12065 0.3048)
			(end 0.67945 0.3048)
			(stroke
				(width 0.1)
				(type default)
			)
			(layer "B.Fab")
		)
		(fp_line
			(start 0.12065 0.2794)
			(end 0.12065 0.3048)
			(stroke
				(width 0.1)
				(type default)
			)
			(layer "B.Fab")
		)
		(fp_line
			(start 0.12065 -0.2794)
			(end -0.12065 -0.2794)
			(stroke
				(width 0.1)
				(type default)
			)
			(layer "B.Fab")
		)
		(fp_line
			(start 0.12065 -0.305054)
			(end 0.12065 -0.2794)
			(stroke
				(width 0.1)
				(type default)
			)
			(layer "B.Fab")
		)
		(fp_line
			(start -0.120396 0.3048)
			(end -0.120396 0.2794)
			(stroke
				(width 0.1)
				(type default)
			)
			(layer "B.Fab")
		)
		(fp_line
			(start -0.120396 0.2794)
			(end 0.12065 0.2794)
			(stroke
				(width 0.1)
				(type default)
			)
			(layer "B.Fab")
		)
		(fp_line
			(start -0.12065 -0.2794)
			(end -0.12065 -0.3048)
			(stroke
				(width 0.1)
				(type default)
			)
			(layer "B.Fab")
		)
		(fp_line
			(start -0.12065 -0.3048)
			(end -0.67945 -0.3048)
			(stroke
				(width 0.1)
				(type default)
			)
			(layer "B.Fab")
		)
		(fp_line
			(start -0.67945 0.3048)
			(end -0.120396 0.3048)
			(stroke
				(width 0.1)
				(type default)
			)
			(layer "B.Fab")
		)
		(fp_line
			(start -0.67945 -0.3048)
			(end -0.67945 0.3048)
			(stroke
				(width 0.1)
				(type default)
			)
			(layer "B.Fab")
		)
		(pad "1" smd circle
			(at 0.40005 0)
			(size 0 0)
			(layers "B.Cu" "B.Mask" "B.Paste")
			(net "LED_POSTCODE_6")
		)
		(pad "2" smd circle
			(at -0.40005 0)
			(size 0 0)
			(layers "B.Cu" "B.Mask" "B.Paste")
			(net "LED_POSTCODE_6_R1")
		)
	)
	(footprint ""
		(layer "B.Cu")
		(at 65.2018 -34.637726 90)
		(property "Reference" "R170"
			(at 0 0 90)
			(layer "B.SilkS")
			(hide yes)
			(effects
				(font
					(size 1.27 1.27)
				)
				(justify mirror)
			)
		)
		(property "Value" ""
			(at 0 0 90)
			(layer "B.Fab")
			(effects
				(font
					(size 1.27 1.27)
				)
				(justify mirror)
			)
		)
		(duplicate_pad_numbers_are_jumpers no)
		(fp_line
			(start 0.7874 -0.4064)
			(end -0.7874 -0.4064)
			(stroke
				(width 0.1524)
				(type default)
			)
			(layer "B.SilkS")
		)
		(fp_line
			(start -0.7874 -0.4064)
			(end -0.7874 0.4064)
			(stroke
				(width 0.1524)
				(type default)
			)
			(layer "B.SilkS")
		)
		(fp_line
			(start 0.7874 0.4064)
			(end 0.7874 -0.4064)
			(stroke
				(width 0.1524)
				(type default)
			)
			(layer "B.SilkS")
		)
		(fp_line
			(start -0.7874 0.4064)
			(end 0.7874 0.4064)
			(stroke
				(width 0.1524)
				(type default)
			)
			(layer "B.SilkS")
		)
		(fp_line
			(start 0.67945 -0.305054)
			(end 0.12065 -0.305054)
			(stroke
				(width 0.1)
				(type default)
			)
			(layer "B.Fab")
		)
		(fp_line
			(start 0.12065 -0.305054)
			(end 0.12065 -0.2794)
			(stroke
				(width 0.1)
				(type default)
			)
			(layer "B.Fab")
		)
		(fp_line
			(start -0.12065 -0.3048)
			(end -0.67945 -0.3048)
			(stroke
				(width 0.1)
				(type default)
			)
			(layer "B.Fab")
		)
		(fp_line
			(start -0.67945 -0.3048)
			(end -0.67945 0.3048)
			(stroke
				(width 0.1)
				(type default)
			)
			(layer "B.Fab")
		)
		(fp_line
			(start 0.12065 -0.2794)
			(end -0.12065 -0.2794)
			(stroke
				(width 0.1)
				(type default)
			)
			(layer "B.Fab")
		)
		(fp_line
			(start -0.12065 -0.2794)
			(end -0.12065 -0.3048)
			(stroke
				(width 0.1)
				(type default)
			)
			(layer "B.Fab")
		)
		(fp_line
			(start 0.12065 0.2794)
			(end 0.12065 0.3048)
			(stroke
				(width 0.1)
				(type default)
			)
			(layer "B.Fab")
		)
		(fp_line
			(start -0.120396 0.2794)
			(end 0.12065 0.2794)
			(stroke
				(width 0.1)
				(type default)
			)
			(layer "B.Fab")
		)
		(fp_line
			(start 0.67945 0.3048)
			(end 0.67945 -0.305054)
			(stroke
				(width 0.1)
				(type default)
			)
			(layer "B.Fab")
		)
		(fp_line
			(start 0.12065 0.3048)
			(end 0.67945 0.3048)
			(stroke
				(width 0.1)
				(type default)
			)
			(layer "B.Fab")
		)
		(fp_line
			(start -0.120396 0.3048)
			(end -0.120396 0.2794)
			(stroke
				(width 0.1)
				(type default)
			)
			(layer "B.Fab")
		)
		(fp_line
			(start -0.67945 0.3048)
			(end -0.120396 0.3048)
			(stroke
				(width 0.1)
				(type default)
			)
			(layer "B.Fab")
		)
		(pad "1" smd circle
			(at 0.40005 0 270)
			(size 0 0)
			(layers "B.Cu" "B.Mask" "B.Paste")
			(net "UART_BMC_5_TXD")
		)
		(pad "2" smd circle
			(at -0.40005 0 270)
			(size 0 0)
			(layers "B.Cu" "B.Mask" "B.Paste")
			(net "UART_BMC_5_TXD_R")
		)
	)
	(footprint ""
		(layer "B.Cu")
		(at 67.70878 -34.155126 -90)
		(property "Reference" "L4"
			(at 0 0 90)
			(layer "B.SilkS")
			(hide yes)
			(effects
				(font
					(size 1.27 1.27)
				)
				(justify mirror)
			)
		)
		(property "Value" ""
			(at 0 0 90)
			(layer "B.Fab")
			(effects
				(font
					(size 1.27 1.27)
				)
				(justify mirror)
			)
		)
		(duplicate_pad_numbers_are_jumpers no)
		(fp_line
			(start -1.27 0.5842)
			(end 1.27 0.5842)
			(stroke
				(width 0.1524)
				(type default)
			)
			(layer "B.SilkS")
		)
		(fp_line
			(start -1.27 0.5842)
			(end -1.27 -0.5842)
			(stroke
				(width 0.1524)
				(type default)
			)
			(layer "B.SilkS")
		)
		(fp_line
			(start -0.127 0.5842)
			(end -0.127 -0.5842)
			(stroke
				(width 0.1524)
				(type default)
			)
			(layer "B.SilkS")
		)
		(fp_line
			(start 0.127 0.5842)
			(end 0.127 -0.5842)
			(stroke
				(width 0.1524)
				(type default)
			)
			(layer "B.SilkS")
		)
		(fp_line
			(start 1.27 0.5842)
			(end 1.27 -0.5842)
			(stroke
				(width 0.1524)
				(type default)
			)
			(layer "B.SilkS")
		)
		(fp_line
			(start 1.27 -0.5588)
			(end 1.27 -0.5842)
			(stroke
				(width 0.1524)
				(type default)
			)
			(layer "B.SilkS")
		)
		(fp_line
			(start 1.27 -0.5842)
			(end -1.27 -0.5842)
			(stroke
				(width 0.1524)
				(type default)
			)
			(layer "B.SilkS")
		)
		(fp_line
			(start -0.9144 0.508)
			(end 0.9144 0.508)
			(stroke
				(width 0.1)
				(type default)
			)
			(layer "B.Fab")
		)
		(fp_line
			(start 0.9144 0.508)
			(end 0.9144 0.406654)
			(stroke
				(width 0.1)
				(type default)
			)
			(layer "B.Fab")
		)
		(fp_line
			(start 0.9144 0.406654)
			(end 1.194308 0.406654)
			(stroke
				(width 0.1)
				(type default)
			)
			(layer "B.Fab")
		)
		(fp_line
			(start 1.194308 0.406654)
			(end 1.194308 -0.406654)
			(stroke
				(width 0.1)
				(type default)
			)
			(layer "B.Fab")
		)
		(fp_line
			(start -1.1938 0.4064)
			(end -0.9144 0.4064)
			(stroke
				(width 0.1)
				(type default)
			)
			(layer "B.Fab")
		)
		(fp_line
			(start -0.9144 0.4064)
			(end -0.9144 0.508)
			(stroke
				(width 0.1)
				(type default)
			)
			(layer "B.Fab")
		)
		(fp_line
			(start -1.1938 -0.406654)
			(end -1.1938 0.4064)
			(stroke
				(width 0.1)
				(type default)
			)
			(layer "B.Fab")
		)
		(fp_line
			(start -0.9144 -0.406654)
			(end -1.1938 -0.406654)
			(stroke
				(width 0.1)
				(type default)
			)
			(layer "B.Fab")
		)
		(fp_line
			(start 0.9144 -0.406654)
			(end 0.9144 -0.508)
			(stroke
				(width 0.1)
				(type default)
			)
			(layer "B.Fab")
		)
		(fp_line
			(start 1.194308 -0.406654)
			(end 0.9144 -0.406654)
			(stroke
				(width 0.1)
				(type default)
			)
			(layer "B.Fab")
		)
		(fp_line
			(start -0.9144 -0.508)
			(end -0.9144 -0.406654)
			(stroke
				(width 0.1)
				(type default)
			)
			(layer "B.Fab")
		)
		(fp_line
			(start 0.9144 -0.508)
			(end -0.9144 -0.508)
			(stroke
				(width 0.1)
				(type default)
			)
			(layer "B.Fab")
		)
		(pad "1" smd rect
			(at 0.7366 0 180)
			(size 0.7112 0.8128)
			(layers "B.Cu" "B.Mask" "B.Paste")
			(net "P3V3_AUX")
		)
		(pad "2" smd rect
			(at -0.7366 0 180)
			(size 0.7112 0.8128)
			(layers "B.Cu" "B.Mask" "B.Paste")
			(net "P3V3_BMC_USB2AV33")
		)
	)
	(footprint ""
		(layer "B.Cu")
		(at 73.431908 -58.038492 -90)
		(property "Reference" "L15"
			(at 0 0 90)
			(layer "B.SilkS")
			(hide yes)
			(effects
				(font
					(size 1.27 1.27)
				)
				(justify mirror)
			)
		)
		(property "Value" ""
			(at 0 0 90)
			(layer "B.Fab")
			(effects
				(font
					(size 1.27 1.27)
				)
				(justify mirror)
			)
		)
		(duplicate_pad_numbers_are_jumpers no)
		(fp_line
			(start -1.27 0.5842)
			(end 1.27 0.5842)
			(stroke
				(width 0.1524)
				(type default)
			)
			(layer "B.SilkS")
		)
		(fp_line
			(start -1.27 0.5842)
			(end -1.27 -0.5842)
			(stroke
				(width 0.1524)
				(type default)
			)
			(layer "B.SilkS")
		)
		(fp_line
			(start -0.127 0.5842)
			(end -0.127 -0.5842)
			(stroke
				(width 0.1524)
				(type default)
			)
			(layer "B.SilkS")
		)
		(fp_line
			(start 0.127 0.5842)
			(end 0.127 -0.5842)
			(stroke
				(width 0.1524)
				(type default)
			)
			(layer "B.SilkS")
		)
		(fp_line
			(start 1.27 0.5842)
			(end 1.27 -0.5842)
			(stroke
				(width 0.1524)
				(type default)
			)
			(layer "B.SilkS")
		)
		(fp_line
			(start 1.27 -0.5588)
			(end 1.27 -0.5842)
			(stroke
				(width 0.1524)
				(type default)
			)
			(layer "B.SilkS")
		)
		(fp_line
			(start 1.27 -0.5842)
			(end -1.27 -0.5842)
			(stroke
				(width 0.1524)
				(type default)
			)
			(layer "B.SilkS")
		)
		(fp_line
			(start -0.9144 0.508)
			(end 0.9144 0.508)
			(stroke
				(width 0.1)
				(type default)
			)
			(layer "B.Fab")
		)
		(fp_line
			(start 0.9144 0.508)
			(end 0.9144 0.406654)
			(stroke
				(width 0.1)
				(type default)
			)
			(layer "B.Fab")
		)
		(fp_line
			(start 0.9144 0.406654)
			(end 1.194308 0.406654)
			(stroke
				(width 0.1)
				(type default)
			)
			(layer "B.Fab")
		)
		(fp_line
			(start 1.194308 0.406654)
			(end 1.194308 -0.406654)
			(stroke
				(width 0.1)
				(type default)
			)
			(layer "B.Fab")
		)
		(fp_line
			(start -1.1938 0.4064)
			(end -0.9144 0.4064)
			(stroke
				(width 0.1)
				(type default)
			)
			(layer "B.Fab")
		)
		(fp_line
			(start -0.9144 0.4064)
			(end -0.9144 0.508)
			(stroke
				(width 0.1)
				(type default)
			)
			(layer "B.Fab")
		)
		(fp_line
			(start -1.1938 -0.406654)
			(end -1.1938 0.4064)
			(stroke
				(width 0.1)
				(type default)
			)
			(layer "B.Fab")
		)
		(fp_line
			(start -0.9144 -0.406654)
			(end -1.1938 -0.406654)
			(stroke
				(width 0.1)
				(type default)
			)
			(layer "B.Fab")
		)
		(fp_line
			(start 0.9144 -0.406654)
			(end 0.9144 -0.508)
			(stroke
				(width 0.1)
				(type default)
			)
			(layer "B.Fab")
		)
		(fp_line
			(start 1.194308 -0.406654)
			(end 0.9144 -0.406654)
			(stroke
				(width 0.1)
				(type default)
			)
			(layer "B.Fab")
		)
		(fp_line
			(start -0.9144 -0.508)
			(end -0.9144 -0.406654)
			(stroke
				(width 0.1)
				(type default)
			)
			(layer "B.Fab")
		)
		(fp_line
			(start 0.9144 -0.508)
			(end -0.9144 -0.508)
			(stroke
				(width 0.1)
				(type default)
			)
			(layer "B.Fab")
		)
		(pad "1" smd rect
			(at 0.7366 0 180)
			(size 0.7112 0.8128)
			(layers "B.Cu" "B.Mask" "B.Paste")
			(net "P1V0_AUX")
		)
		(pad "2" smd rect
			(at -0.7366 0 180)
			(size 0.7112 0.8128)
			(layers "B.Cu" "B.Mask" "B.Paste")
			(net "P1V0_STBY_DP_VCC10A")
		)
	)
	(footprint ""
		(layer "B.Cu")
		(at 56.256174 -43.77436)
		(property "Reference" "C100"
			(at 0 0 0)
			(layer "B.SilkS")
			(hide yes)
			(effects
				(font
					(size 1.27 1.27)
				)
				(justify mirror)
			)
		)
		(property "Value" ""
			(at 0 0 0)
			(layer "B.Fab")
			(effects
				(font
					(size 1.27 1.27)
				)
				(justify mirror)
			)
		)
		(duplicate_pad_numbers_are_jumpers no)
		(fp_line
			(start -0.7874 -0.4064)
			(end -0.7874 0.4064)
			(stroke
				(width 0.1524)
				(type default)
			)
			(layer "B.SilkS")
		)
		(fp_line
			(start -0.7874 0.4064)
			(end 0.7874 0.4064)
			(stroke
				(width 0.1524)
				(type default)
			)
			(layer "B.SilkS")
		)
		(fp_line
			(start 0.7874 -0.4064)
			(end -0.7874 -0.4064)
			(stroke
				(width 0.1524)
				(type default)
			)
			(layer "B.SilkS")
		)
		(fp_line
			(start 0.7874 0.4064)
			(end 0.7874 -0.4064)
			(stroke
				(width 0.1524)
				(type default)
			)
			(layer "B.SilkS")
		)
		(fp_line
			(start -0.67945 -0.3048)
			(end -0.67945 0.3048)
			(stroke
				(width 0.1)
				(type default)
			)
			(layer "B.Fab")
		)
		(fp_line
			(start -0.67945 0.3048)
			(end -0.120396 0.3048)
			(stroke
				(width 0.1)
				(type default)
			)
			(layer "B.Fab")
		)
		(fp_line
			(start -0.12065 -0.3048)
			(end -0.67945 -0.3048)
			(stroke
				(width 0.1)
				(type default)
			)
			(layer "B.Fab")
		)
		(fp_line
			(start -0.12065 -0.2794)
			(end -0.12065 -0.3048)
			(stroke
				(width 0.1)
				(type default)
			)
			(layer "B.Fab")
		)
		(fp_line
			(start -0.120396 0.2794)
			(end 0.12065 0.2794)
			(stroke
				(width 0.1)
				(type default)
			)
			(layer "B.Fab")
		)
		(fp_line
			(start -0.120396 0.3048)
			(end -0.120396 0.2794)
			(stroke
				(width 0.1)
				(type default)
			)
			(layer "B.Fab")
		)
		(fp_line
			(start 0.12065 -0.305054)
			(end 0.12065 -0.2794)
			(stroke
				(width 0.1)
				(type default)
			)
			(layer "B.Fab")
		)
		(fp_line
			(start 0.12065 -0.2794)
			(end -0.12065 -0.2794)
			(stroke
				(width 0.1)
				(type default)
			)
			(layer "B.Fab")
		)
		(fp_line
			(start 0.12065 0.2794)
			(end 0.12065 0.3048)
			(stroke
				(width 0.1)
				(type default)
			)
			(layer "B.Fab")
		)
		(fp_line
			(start 0.12065 0.3048)
			(end 0.67945 0.3048)
			(stroke
				(width 0.1)
				(type default)
			)
			(layer "B.Fab")
		)
		(fp_line
			(start 0.67945 -0.305054)
			(end 0.12065 -0.305054)
			(stroke
				(width 0.1)
				(type default)
			)
			(layer "B.Fab")
		)
		(fp_line
			(start 0.67945 0.3048)
			(end 0.67945 -0.305054)
			(stroke
				(width 0.1)
				(type default)
			)
			(layer "B.Fab")
		)
		(pad "1" smd circle
			(at 0.40005 0 180)
			(size 0 0)
			(layers "B.Cu" "B.Mask" "B.Paste")
			(net "P1V8_AUX")
		)
		(pad "2" smd circle
			(at -0.40005 0 180)
			(size 0 0)
			(layers "B.Cu" "B.Mask" "B.Paste")
			(net "GND")
		)
	)
	(footprint ""
		(layer "B.Cu")
		(at 61.64326 -65.85585 -90)
		(property "Reference" "R469"
			(at 0 0 90)
			(layer "B.SilkS")
			(hide yes)
			(effects
				(font
					(size 1.27 1.27)
				)
				(justify mirror)
			)
		)
		(property "Value" ""
			(at 0 0 90)
			(layer "B.Fab")
			(effects
				(font
					(size 1.27 1.27)
				)
				(justify mirror)
			)
		)
		(duplicate_pad_numbers_are_jumpers no)
		(fp_line
			(start -0.7874 0.4064)
			(end 0.7874 0.4064)
			(stroke
				(width 0.1524)
				(type default)
			)
			(layer "B.SilkS")
		)
		(fp_line
			(start 0.7874 0.4064)
			(end 0.7874 -0.4064)
			(stroke
				(width 0.1524)
				(type default)
			)
			(layer "B.SilkS")
		)
		(fp_line
			(start -0.7874 -0.4064)
			(end -0.7874 0.4064)
			(stroke
				(width 0.1524)
				(type default)
			)
			(layer "B.SilkS")
		)
		(fp_line
			(start 0.7874 -0.4064)
			(end -0.7874 -0.4064)
			(stroke
				(width 0.1524)
				(type default)
			)
			(layer "B.SilkS")
		)
		(fp_line
			(start -0.67945 0.3048)
			(end -0.120396 0.3048)
			(stroke
				(width 0.1)
				(type default)
			)
			(layer "B.Fab")
		)
		(fp_line
			(start -0.120396 0.3048)
			(end -0.120396 0.2794)
			(stroke
				(width 0.1)
				(type default)
			)
			(layer "B.Fab")
		)
		(fp_line
			(start 0.12065 0.3048)
			(end 0.67945 0.3048)
			(stroke
				(width 0.1)
				(type default)
			)
			(layer "B.Fab")
		)
		(fp_line
			(start 0.67945 0.3048)
			(end 0.67945 -0.305054)
			(stroke
				(width 0.1)
				(type default)
			)
			(layer "B.Fab")
		)
		(fp_line
			(start -0.120396 0.2794)
			(end 0.12065 0.2794)
			(stroke
				(width 0.1)
				(type default)
			)
			(layer "B.Fab")
		)
		(fp_line
			(start 0.12065 0.2794)
			(end 0.12065 0.3048)
			(stroke
				(width 0.1)
				(type default)
			)
			(layer "B.Fab")
		)
		(fp_line
			(start -0.12065 -0.2794)
			(end -0.12065 -0.3048)
			(stroke
				(width 0.1)
				(type default)
			)
			(layer "B.Fab")
		)
		(fp_line
			(start 0.12065 -0.2794)
			(end -0.12065 -0.2794)
			(stroke
				(width 0.1)
				(type default)
			)
			(layer "B.Fab")
		)
		(fp_line
			(start -0.67945 -0.3048)
			(end -0.67945 0.3048)
			(stroke
				(width 0.1)
				(type default)
			)
			(layer "B.Fab")
		)
		(fp_line
			(start -0.12065 -0.3048)
			(end -0.67945 -0.3048)
			(stroke
				(width 0.1)
				(type default)
			)
			(layer "B.Fab")
		)
		(fp_line
			(start 0.12065 -0.305054)
			(end 0.12065 -0.2794)
			(stroke
				(width 0.1)
				(type default)
			)
			(layer "B.Fab")
		)
		(fp_line
			(start 0.67945 -0.305054)
			(end 0.12065 -0.305054)
			(stroke
				(width 0.1)
				(type default)
			)
			(layer "B.Fab")
		)
		(pad "1" smd circle
			(at 0.40005 0 90)
			(size 0 0)
			(layers "B.Cu" "B.Mask" "B.Paste")
			(net "SPI_BMC_TPM_MISO_R1")
		)
		(pad "2" smd circle
			(at -0.40005 0 90)
			(size 0 0)
			(layers "B.Cu" "B.Mask" "B.Paste")
			(net "SPI_BMC_TPM_MISO")
		)
	)
	(footprint ""
		(layer "B.Cu")
		(at 64.262 -18.669 90)
		(property "Reference" "R629"
			(at 0 0 90)
			(layer "B.SilkS")
			(hide yes)
			(effects
				(font
					(size 1.27 1.27)
				)
				(justify mirror)
			)
		)
		(property "Value" ""
			(at 0 0 90)
			(layer "B.Fab")
			(effects
				(font
					(size 1.27 1.27)
				)
				(justify mirror)
			)
		)
		(duplicate_pad_numbers_are_jumpers no)
		(fp_line
			(start 0.7874 -0.4064)
			(end -0.7874 -0.4064)
			(stroke
				(width 0.1524)
				(type default)
			)
			(layer "B.SilkS")
		)
		(fp_line
			(start -0.7874 -0.4064)
			(end -0.7874 0.4064)
			(stroke
				(width 0.1524)
				(type default)
			)
			(layer "B.SilkS")
		)
		(fp_line
			(start 0.7874 0.4064)
			(end 0.7874 -0.4064)
			(stroke
				(width 0.1524)
				(type default)
			)
			(layer "B.SilkS")
		)
		(fp_line
			(start -0.7874 0.4064)
			(end 0.7874 0.4064)
			(stroke
				(width 0.1524)
				(type default)
			)
			(layer "B.SilkS")
		)
		(fp_line
			(start 0.67945 -0.305054)
			(end 0.12065 -0.305054)
			(stroke
				(width 0.1)
				(type default)
			)
			(layer "B.Fab")
		)
		(fp_line
			(start 0.12065 -0.305054)
			(end 0.12065 -0.2794)
			(stroke
				(width 0.1)
				(type default)
			)
			(layer "B.Fab")
		)
		(fp_line
			(start -0.12065 -0.3048)
			(end -0.67945 -0.3048)
			(stroke
				(width 0.1)
				(type default)
			)
			(layer "B.Fab")
		)
		(fp_line
			(start -0.67945 -0.3048)
			(end -0.67945 0.3048)
			(stroke
				(width 0.1)
				(type default)
			)
			(layer "B.Fab")
		)
		(fp_line
			(start 0.12065 -0.2794)
			(end -0.12065 -0.2794)
			(stroke
				(width 0.1)
				(type default)
			)
			(layer "B.Fab")
		)
		(fp_line
			(start -0.12065 -0.2794)
			(end -0.12065 -0.3048)
			(stroke
				(width 0.1)
				(type default)
			)
			(layer "B.Fab")
		)
		(fp_line
			(start 0.12065 0.2794)
			(end 0.12065 0.3048)
			(stroke
				(width 0.1)
				(type default)
			)
			(layer "B.Fab")
		)
		(fp_line
			(start -0.120396 0.2794)
			(end 0.12065 0.2794)
			(stroke
				(width 0.1)
				(type default)
			)
			(layer "B.Fab")
		)
		(fp_line
			(start 0.67945 0.3048)
			(end 0.67945 -0.305054)
			(stroke
				(width 0.1)
				(type default)
			)
			(layer "B.Fab")
		)
		(fp_line
			(start 0.12065 0.3048)
			(end 0.67945 0.3048)
			(stroke
				(width 0.1)
				(type default)
			)
			(layer "B.Fab")
		)
		(fp_line
			(start -0.120396 0.3048)
			(end -0.120396 0.2794)
			(stroke
				(width 0.1)
				(type default)
			)
			(layer "B.Fab")
		)
		(fp_line
			(start -0.67945 0.3048)
			(end -0.120396 0.3048)
			(stroke
				(width 0.1)
				(type default)
			)
			(layer "B.Fab")
		)
		(pad "1" smd circle
			(at 0.40005 0 270)
			(size 0 0)
			(layers "B.Cu" "B.Mask" "B.Paste")
			(net "BMC_CPLD_GPIO_2")
		)
		(pad "2" smd circle
			(at -0.40005 0 270)
			(size 0 0)
			(layers "B.Cu" "B.Mask" "B.Paste")
			(net "FM_DBG_SW_N")
		)
	)
	(footprint ""
		(layer "B.Cu")
		(at 56.983376 -53.376322)
		(property "Reference" "C81"
			(at 0 0 0)
			(layer "B.SilkS")
			(hide yes)
			(effects
				(font
					(size 1.27 1.27)
				)
				(justify mirror)
			)
		)
		(property "Value" ""
			(at 0 0 0)
			(layer "B.Fab")
			(effects
				(font
					(size 1.27 1.27)
				)
				(justify mirror)
			)
		)
		(duplicate_pad_numbers_are_jumpers no)
		(fp_line
			(start -0.7874 -0.4064)
			(end -0.7874 0.4064)
			(stroke
				(width 0.1524)
				(type default)
			)
			(layer "B.SilkS")
		)
		(fp_line
			(start -0.7874 0.4064)
			(end 0.7874 0.4064)
			(stroke
				(width 0.1524)
				(type default)
			)
			(layer "B.SilkS")
		)
		(fp_line
			(start 0.7874 -0.4064)
			(end -0.7874 -0.4064)
			(stroke
				(width 0.1524)
				(type default)
			)
			(layer "B.SilkS")
		)
		(fp_line
			(start 0.7874 0.4064)
			(end 0.7874 -0.4064)
			(stroke
				(width 0.1524)
				(type default)
			)
			(layer "B.SilkS")
		)
		(fp_line
			(start -0.67945 -0.3048)
			(end -0.67945 0.3048)
			(stroke
				(width 0.1)
				(type default)
			)
			(layer "B.Fab")
		)
		(fp_line
			(start -0.67945 0.3048)
			(end -0.120396 0.3048)
			(stroke
				(width 0.1)
				(type default)
			)
			(layer "B.Fab")
		)
		(fp_line
			(start -0.12065 -0.3048)
			(end -0.67945 -0.3048)
			(stroke
				(width 0.1)
				(type default)
			)
			(layer "B.Fab")
		)
		(fp_line
			(start -0.12065 -0.2794)
			(end -0.12065 -0.3048)
			(stroke
				(width 0.1)
				(type default)
			)
			(layer "B.Fab")
		)
		(fp_line
			(start -0.120396 0.2794)
			(end 0.12065 0.2794)
			(stroke
				(width 0.1)
				(type default)
			)
			(layer "B.Fab")
		)
		(fp_line
			(start -0.120396 0.3048)
			(end -0.120396 0.2794)
			(stroke
				(width 0.1)
				(type default)
			)
			(layer "B.Fab")
		)
		(fp_line
			(start 0.12065 -0.305054)
			(end 0.12065 -0.2794)
			(stroke
				(width 0.1)
				(type default)
			)
			(layer "B.Fab")
		)
		(fp_line
			(start 0.12065 -0.2794)
			(end -0.12065 -0.2794)
			(stroke
				(width 0.1)
				(type default)
			)
			(layer "B.Fab")
		)
		(fp_line
			(start 0.12065 0.2794)
			(end 0.12065 0.3048)
			(stroke
				(width 0.1)
				(type default)
			)
			(layer "B.Fab")
		)
		(fp_line
			(start 0.12065 0.3048)
			(end 0.67945 0.3048)
			(stroke
				(width 0.1)
				(type default)
			)
			(layer "B.Fab")
		)
		(fp_line
			(start 0.67945 -0.305054)
			(end 0.12065 -0.305054)
			(stroke
				(width 0.1)
				(type default)
			)
			(layer "B.Fab")
		)
		(fp_line
			(start 0.67945 0.3048)
			(end 0.67945 -0.305054)
			(stroke
				(width 0.1)
				(type default)
			)
			(layer "B.Fab")
		)
		(pad "1" smd circle
			(at 0.40005 0 180)
			(size 0 0)
			(layers "B.Cu" "B.Mask" "B.Paste")
			(net "P1V8_STBY_RC_VCC18A")
		)
		(pad "2" smd circle
			(at -0.40005 0 180)
			(size 0 0)
			(layers "B.Cu" "B.Mask" "B.Paste")
			(net "GND")
		)
	)
	(footprint ""
		(layer "B.Cu")
		(at 21.971 -24.003 -90)
		(property "Reference" "PC270"
			(at 0 0 90)
			(layer "B.SilkS")
			(hide yes)
			(effects
				(font
					(size 1.27 1.27)
				)
				(justify mirror)
			)
		)
		(property "Value" ""
			(at 0 0 90)
			(layer "B.Fab")
			(effects
				(font
					(size 1.27 1.27)
				)
				(justify mirror)
			)
		)
		(duplicate_pad_numbers_are_jumpers no)
		(fp_line
			(start -1.651 0.8382)
			(end 1.651 0.8382)
			(stroke
				(width 0.1524)
				(type default)
			)
			(layer "B.SilkS")
		)
		(fp_line
			(start 0 0.8382)
			(end 0 -0.8382)
			(stroke
				(width 0.1524)
				(type default)
			)
			(layer "B.SilkS")
		)
		(fp_line
			(start 1.651 0.8382)
			(end 1.651 -0.8382)
			(stroke
				(width 0.1524)
				(type default)
			)
			(layer "B.SilkS")
		)
		(fp_line
			(start -1.651 -0.8382)
			(end -1.651 0.8382)
			(stroke
				(width 0.1524)
				(type default)
			)
			(layer "B.SilkS")
		)
		(fp_line
			(start 1.651 -0.8382)
			(end -1.651 -0.8382)
			(stroke
				(width 0.1524)
				(type default)
			)
			(layer "B.SilkS")
		)
		(fp_line
			(start -1.55956 0.7366)
			(end -1.55956 -0.7366)
			(stroke
				(width 0.1)
				(type default)
			)
			(layer "B.Fab")
		)
		(fp_line
			(start -1.524 0.7366)
			(end -1.55956 0.7366)
			(stroke
				(width 0.1)
				(type default)
			)
			(layer "B.Fab")
		)
		(fp_line
			(start 1.524 0.7366)
			(end -1.524 0.7366)
			(stroke
				(width 0.1)
				(type default)
			)
			(layer "B.Fab")
		)
		(fp_line
			(start 1.55956 0.7366)
			(end 1.524 0.7366)
			(stroke
				(width 0.1)
				(type default)
			)
			(layer "B.Fab")
		)
		(fp_line
			(start -1.55956 -0.7366)
			(end -1.524 -0.7366)
			(stroke
				(width 0.1)
				(type default)
			)
			(layer "B.Fab")
		)
		(fp_line
			(start -1.524 -0.7366)
			(end 1.524 -0.7366)
			(stroke
				(width 0.1)
				(type default)
			)
			(layer "B.Fab")
		)
		(fp_line
			(start 1.524 -0.7366)
			(end 1.55956 -0.7366)
			(stroke
				(width 0.1)
				(type default)
			)
			(layer "B.Fab")
		)
		(fp_line
			(start 1.55956 -0.7366)
			(end 1.55956 0.7366)
			(stroke
				(width 0.1)
				(type default)
			)
			(layer "B.Fab")
		)
		(pad "1" smd rect
			(at 0.94996 0 270)
			(size 1.1176 1.3716)
			(layers "B.Cu" "B.Mask" "B.Paste")
			(net "P1V0_AUX")
		)
		(pad "2" smd rect
			(at -0.94996 0 270)
			(size 1.1176 1.3716)
			(layers "B.Cu" "B.Mask" "B.Paste")
			(net "GND")
		)
	)
	(footprint ""
		(layer "B.Cu")
		(at 39.93007 -46.119542 180)
		(property "Reference" "R149"
			(at 0 0 0)
			(layer "B.SilkS")
			(hide yes)
			(effects
				(font
					(size 1.27 1.27)
				)
				(justify mirror)
			)
		)
		(property "Value" ""
			(at 0 0 0)
			(layer "B.Fab")
			(effects
				(font
					(size 1.27 1.27)
				)
				(justify mirror)
			)
		)
		(duplicate_pad_numbers_are_jumpers no)
		(fp_line
			(start 0.7874 0.4064)
			(end 0.7874 -0.4064)
			(stroke
				(width 0.1524)
				(type default)
			)
			(layer "B.SilkS")
		)
		(fp_line
			(start 0.7874 -0.4064)
			(end -0.7874 -0.4064)
			(stroke
				(width 0.1524)
				(type default)
			)
			(layer "B.SilkS")
		)
		(fp_line
			(start -0.7874 0.4064)
			(end 0.7874 0.4064)
			(stroke
				(width 0.1524)
				(type default)
			)
			(layer "B.SilkS")
		)
		(fp_line
			(start -0.7874 -0.4064)
			(end -0.7874 0.4064)
			(stroke
				(width 0.1524)
				(type default)
			)
			(layer "B.SilkS")
		)
		(fp_line
			(start 0.67945 0.3048)
			(end 0.67945 -0.305054)
			(stroke
				(width 0.1)
				(type default)
			)
			(layer "B.Fab")
		)
		(fp_line
			(start 0.67945 -0.305054)
			(end 0.12065 -0.305054)
			(stroke
				(width 0.1)
				(type default)
			)
			(layer "B.Fab")
		)
		(fp_line
			(start 0.12065 0.3048)
			(end 0.67945 0.3048)
			(stroke
				(width 0.1)
				(type default)
			)
			(layer "B.Fab")
		)
		(fp_line
			(start 0.12065 0.2794)
			(end 0.12065 0.3048)
			(stroke
				(width 0.1)
				(type default)
			)
			(layer "B.Fab")
		)
		(fp_line
			(start 0.12065 -0.2794)
			(end -0.12065 -0.2794)
			(stroke
				(width 0.1)
				(type default)
			)
			(layer "B.Fab")
		)
		(fp_line
			(start 0.12065 -0.305054)
			(end 0.12065 -0.2794)
			(stroke
				(width 0.1)
				(type default)
			)
			(layer "B.Fab")
		)
		(fp_line
			(start -0.120396 0.3048)
			(end -0.120396 0.2794)
			(stroke
				(width 0.1)
				(type default)
			)
			(layer "B.Fab")
		)
		(fp_line
			(start -0.120396 0.2794)
			(end 0.12065 0.2794)
			(stroke
				(width 0.1)
				(type default)
			)
			(layer "B.Fab")
		)
		(fp_line
			(start -0.12065 -0.2794)
			(end -0.12065 -0.3048)
			(stroke
				(width 0.1)
				(type default)
			)
			(layer "B.Fab")
		)
		(fp_line
			(start -0.12065 -0.3048)
			(end -0.67945 -0.3048)
			(stroke
				(width 0.1)
				(type default)
			)
			(layer "B.Fab")
		)
		(fp_line
			(start -0.67945 0.3048)
			(end -0.120396 0.3048)
			(stroke
				(width 0.1)
				(type default)
			)
			(layer "B.Fab")
		)
		(fp_line
			(start -0.67945 -0.3048)
			(end -0.67945 0.3048)
			(stroke
				(width 0.1)
				(type default)
			)
			(layer "B.Fab")
		)
		(pad "1" smd circle
			(at 0.40005 0)
			(size 0 0)
			(layers "B.Cu" "B.Mask" "B.Paste")
			(net "P3V3_AUX")
		)
		(pad "2" smd circle
			(at -0.40005 0)
			(size 0 0)
			(layers "B.Cu" "B.Mask" "B.Paste")
			(net "SMB_BMC_MM12_SDA")
		)
	)
	(footprint ""
		(layer "B.Cu")
		(at 53.68798 -30.86608 -90)
		(property "Reference" "R260"
			(at 0 0 90)
			(layer "B.SilkS")
			(hide yes)
			(effects
				(font
					(size 1.27 1.27)
				)
				(justify mirror)
			)
		)
		(property "Value" ""
			(at 0 0 90)
			(layer "B.Fab")
			(effects
				(font
					(size 1.27 1.27)
				)
				(justify mirror)
			)
		)
		(duplicate_pad_numbers_are_jumpers no)
		(fp_line
			(start -0.7874 0.4064)
			(end 0.7874 0.4064)
			(stroke
				(width 0.1524)
				(type default)
			)
			(layer "B.SilkS")
		)
		(fp_line
			(start 0.7874 0.4064)
			(end 0.7874 -0.4064)
			(stroke
				(width 0.1524)
				(type default)
			)
			(layer "B.SilkS")
		)
		(fp_line
			(start -0.7874 -0.4064)
			(end -0.7874 0.4064)
			(stroke
				(width 0.1524)
				(type default)
			)
			(layer "B.SilkS")
		)
		(fp_line
			(start 0.7874 -0.4064)
			(end -0.7874 -0.4064)
			(stroke
				(width 0.1524)
				(type default)
			)
			(layer "B.SilkS")
		)
		(fp_line
			(start -0.67945 0.3048)
			(end -0.120396 0.3048)
			(stroke
				(width 0.1)
				(type default)
			)
			(layer "B.Fab")
		)
		(fp_line
			(start -0.120396 0.3048)
			(end -0.120396 0.2794)
			(stroke
				(width 0.1)
				(type default)
			)
			(layer "B.Fab")
		)
		(fp_line
			(start 0.12065 0.3048)
			(end 0.67945 0.3048)
			(stroke
				(width 0.1)
				(type default)
			)
			(layer "B.Fab")
		)
		(fp_line
			(start 0.67945 0.3048)
			(end 0.67945 -0.305054)
			(stroke
				(width 0.1)
				(type default)
			)
			(layer "B.Fab")
		)
		(fp_line
			(start -0.120396 0.2794)
			(end 0.12065 0.2794)
			(stroke
				(width 0.1)
				(type default)
			)
			(layer "B.Fab")
		)
		(fp_line
			(start 0.12065 0.2794)
			(end 0.12065 0.3048)
			(stroke
				(width 0.1)
				(type default)
			)
			(layer "B.Fab")
		)
		(fp_line
			(start -0.12065 -0.2794)
			(end -0.12065 -0.3048)
			(stroke
				(width 0.1)
				(type default)
			)
			(layer "B.Fab")
		)
		(fp_line
			(start 0.12065 -0.2794)
			(end -0.12065 -0.2794)
			(stroke
				(width 0.1)
				(type default)
			)
			(layer "B.Fab")
		)
		(fp_line
			(start -0.67945 -0.3048)
			(end -0.67945 0.3048)
			(stroke
				(width 0.1)
				(type default)
			)
			(layer "B.Fab")
		)
		(fp_line
			(start -0.12065 -0.3048)
			(end -0.67945 -0.3048)
			(stroke
				(width 0.1)
				(type default)
			)
			(layer "B.Fab")
		)
		(fp_line
			(start 0.12065 -0.305054)
			(end 0.12065 -0.2794)
			(stroke
				(width 0.1)
				(type default)
			)
			(layer "B.Fab")
		)
		(fp_line
			(start 0.67945 -0.305054)
			(end 0.12065 -0.305054)
			(stroke
				(width 0.1)
				(type default)
			)
			(layer "B.Fab")
		)
		(pad "1" smd circle
			(at 0.40005 0 90)
			(size 0 0)
			(layers "B.Cu" "B.Mask" "B.Paste")
			(net "P3V3_AUX")
		)
		(pad "2" smd circle
			(at -0.40005 0 90)
			(size 0 0)
			(layers "B.Cu" "B.Mask" "B.Paste")
			(net "SMB_BMC_MM9_SCL")
		)
	)
	(footprint ""
		(layer "B.Cu")
		(at 78.723744 -35.540188 -90)
		(property "Reference" "R334"
			(at 0 0 90)
			(layer "B.SilkS")
			(hide yes)
			(effects
				(font
					(size 1.27 1.27)
				)
				(justify mirror)
			)
		)
		(property "Value" ""
			(at 0 0 90)
			(layer "B.Fab")
			(effects
				(font
					(size 1.27 1.27)
				)
				(justify mirror)
			)
		)
		(duplicate_pad_numbers_are_jumpers no)
		(fp_line
			(start -0.7874 0.4064)
			(end 0.7874 0.4064)
			(stroke
				(width 0.1524)
				(type default)
			)
			(layer "B.SilkS")
		)
		(fp_line
			(start 0.7874 0.4064)
			(end 0.7874 -0.4064)
			(stroke
				(width 0.1524)
				(type default)
			)
			(layer "B.SilkS")
		)
		(fp_line
			(start -0.7874 -0.4064)
			(end -0.7874 0.4064)
			(stroke
				(width 0.1524)
				(type default)
			)
			(layer "B.SilkS")
		)
		(fp_line
			(start 0.7874 -0.4064)
			(end -0.7874 -0.4064)
			(stroke
				(width 0.1524)
				(type default)
			)
			(layer "B.SilkS")
		)
		(fp_line
			(start -0.67945 0.3048)
			(end -0.120396 0.3048)
			(stroke
				(width 0.1)
				(type default)
			)
			(layer "B.Fab")
		)
		(fp_line
			(start -0.120396 0.3048)
			(end -0.120396 0.2794)
			(stroke
				(width 0.1)
				(type default)
			)
			(layer "B.Fab")
		)
		(fp_line
			(start 0.12065 0.3048)
			(end 0.67945 0.3048)
			(stroke
				(width 0.1)
				(type default)
			)
			(layer "B.Fab")
		)
		(fp_line
			(start 0.67945 0.3048)
			(end 0.67945 -0.305054)
			(stroke
				(width 0.1)
				(type default)
			)
			(layer "B.Fab")
		)
		(fp_line
			(start -0.120396 0.2794)
			(end 0.12065 0.2794)
			(stroke
				(width 0.1)
				(type default)
			)
			(layer "B.Fab")
		)
		(fp_line
			(start 0.12065 0.2794)
			(end 0.12065 0.3048)
			(stroke
				(width 0.1)
				(type default)
			)
			(layer "B.Fab")
		)
		(fp_line
			(start -0.12065 -0.2794)
			(end -0.12065 -0.3048)
			(stroke
				(width 0.1)
				(type default)
			)
			(layer "B.Fab")
		)
		(fp_line
			(start 0.12065 -0.2794)
			(end -0.12065 -0.2794)
			(stroke
				(width 0.1)
				(type default)
			)
			(layer "B.Fab")
		)
		(fp_line
			(start -0.67945 -0.3048)
			(end -0.67945 0.3048)
			(stroke
				(width 0.1)
				(type default)
			)
			(layer "B.Fab")
		)
		(fp_line
			(start -0.12065 -0.3048)
			(end -0.67945 -0.3048)
			(stroke
				(width 0.1)
				(type default)
			)
			(layer "B.Fab")
		)
		(fp_line
			(start 0.12065 -0.305054)
			(end 0.12065 -0.2794)
			(stroke
				(width 0.1)
				(type default)
			)
			(layer "B.Fab")
		)
		(fp_line
			(start 0.67945 -0.305054)
			(end 0.12065 -0.305054)
			(stroke
				(width 0.1)
				(type default)
			)
			(layer "B.Fab")
		)
		(pad "1" smd circle
			(at 0.40005 0 90)
			(size 0 0)
			(layers "B.Cu" "B.Mask" "B.Paste")
			(net "GND")
		)
		(pad "2" smd circle
			(at -0.40005 0 90)
			(size 0 0)
			(layers "B.Cu" "B.Mask" "B.Paste")
			(net "M_BMC_DDR4_MA<8>")
		)
	)
	(footprint ""
		(layer "B.Cu")
		(at 17.399 -17.907 -90)
		(property "Reference" "R416"
			(at 0 0 90)
			(layer "B.SilkS")
			(hide yes)
			(effects
				(font
					(size 1.27 1.27)
				)
				(justify mirror)
			)
		)
		(property "Value" ""
			(at 0 0 90)
			(layer "B.Fab")
			(effects
				(font
					(size 1.27 1.27)
				)
				(justify mirror)
			)
		)
		(duplicate_pad_numbers_are_jumpers no)
		(fp_line
			(start -0.7874 0.4064)
			(end 0.7874 0.4064)
			(stroke
				(width 0.1524)
				(type default)
			)
			(layer "B.SilkS")
		)
		(fp_line
			(start 0.7874 0.4064)
			(end 0.7874 -0.4064)
			(stroke
				(width 0.1524)
				(type default)
			)
			(layer "B.SilkS")
		)
		(fp_line
			(start -0.7874 -0.4064)
			(end -0.7874 0.4064)
			(stroke
				(width 0.1524)
				(type default)
			)
			(layer "B.SilkS")
		)
		(fp_line
			(start 0.7874 -0.4064)
			(end -0.7874 -0.4064)
			(stroke
				(width 0.1524)
				(type default)
			)
			(layer "B.SilkS")
		)
		(fp_line
			(start -0.67945 0.3048)
			(end -0.120396 0.3048)
			(stroke
				(width 0.1)
				(type default)
			)
			(layer "B.Fab")
		)
		(fp_line
			(start -0.120396 0.3048)
			(end -0.120396 0.2794)
			(stroke
				(width 0.1)
				(type default)
			)
			(layer "B.Fab")
		)
		(fp_line
			(start 0.12065 0.3048)
			(end 0.67945 0.3048)
			(stroke
				(width 0.1)
				(type default)
			)
			(layer "B.Fab")
		)
		(fp_line
			(start 0.67945 0.3048)
			(end 0.67945 -0.305054)
			(stroke
				(width 0.1)
				(type default)
			)
			(layer "B.Fab")
		)
		(fp_line
			(start -0.120396 0.2794)
			(end 0.12065 0.2794)
			(stroke
				(width 0.1)
				(type default)
			)
			(layer "B.Fab")
		)
		(fp_line
			(start 0.12065 0.2794)
			(end 0.12065 0.3048)
			(stroke
				(width 0.1)
				(type default)
			)
			(layer "B.Fab")
		)
		(fp_line
			(start -0.12065 -0.2794)
			(end -0.12065 -0.3048)
			(stroke
				(width 0.1)
				(type default)
			)
			(layer "B.Fab")
		)
		(fp_line
			(start 0.12065 -0.2794)
			(end -0.12065 -0.2794)
			(stroke
				(width 0.1)
				(type default)
			)
			(layer "B.Fab")
		)
		(fp_line
			(start -0.67945 -0.3048)
			(end -0.67945 0.3048)
			(stroke
				(width 0.1)
				(type default)
			)
			(layer "B.Fab")
		)
		(fp_line
			(start -0.12065 -0.3048)
			(end -0.67945 -0.3048)
			(stroke
				(width 0.1)
				(type default)
			)
			(layer "B.Fab")
		)
		(fp_line
			(start 0.12065 -0.305054)
			(end 0.12065 -0.2794)
			(stroke
				(width 0.1)
				(type default)
			)
			(layer "B.Fab")
		)
		(fp_line
			(start 0.67945 -0.305054)
			(end 0.12065 -0.305054)
			(stroke
				(width 0.1)
				(type default)
			)
			(layer "B.Fab")
		)
		(pad "1" smd circle
			(at 0.40005 0 90)
			(size 0 0)
			(layers "B.Cu" "B.Mask" "B.Paste")
			(net "P3V3_AUX")
		)
		(pad "2" smd circle
			(at -0.40005 0 90)
			(size 0 0)
			(layers "B.Cu" "B.Mask" "B.Paste")
			(net "TMC75_A0")
		)
	)
	(footprint ""
		(layer "B.Cu")
		(at 64.1604 -32.4612 90)
		(property "Reference" "R570"
			(at 0 0 90)
			(layer "B.SilkS")
			(hide yes)
			(effects
				(font
					(size 1.27 1.27)
				)
				(justify mirror)
			)
		)
		(property "Value" ""
			(at 0 0 90)
			(layer "B.Fab")
			(effects
				(font
					(size 1.27 1.27)
				)
				(justify mirror)
			)
		)
		(duplicate_pad_numbers_are_jumpers no)
		(fp_line
			(start 0.7874 -0.4064)
			(end -0.7874 -0.4064)
			(stroke
				(width 0.1524)
				(type default)
			)
			(layer "B.SilkS")
		)
		(fp_line
			(start -0.7874 -0.4064)
			(end -0.7874 0.4064)
			(stroke
				(width 0.1524)
				(type default)
			)
			(layer "B.SilkS")
		)
		(fp_line
			(start 0.7874 0.4064)
			(end 0.7874 -0.4064)
			(stroke
				(width 0.1524)
				(type default)
			)
			(layer "B.SilkS")
		)
		(fp_line
			(start -0.7874 0.4064)
			(end 0.7874 0.4064)
			(stroke
				(width 0.1524)
				(type default)
			)
			(layer "B.SilkS")
		)
		(fp_line
			(start 0.67945 -0.305054)
			(end 0.12065 -0.305054)
			(stroke
				(width 0.1)
				(type default)
			)
			(layer "B.Fab")
		)
		(fp_line
			(start 0.12065 -0.305054)
			(end 0.12065 -0.2794)
			(stroke
				(width 0.1)
				(type default)
			)
			(layer "B.Fab")
		)
		(fp_line
			(start -0.12065 -0.3048)
			(end -0.67945 -0.3048)
			(stroke
				(width 0.1)
				(type default)
			)
			(layer "B.Fab")
		)
		(fp_line
			(start -0.67945 -0.3048)
			(end -0.67945 0.3048)
			(stroke
				(width 0.1)
				(type default)
			)
			(layer "B.Fab")
		)
		(fp_line
			(start 0.12065 -0.2794)
			(end -0.12065 -0.2794)
			(stroke
				(width 0.1)
				(type default)
			)
			(layer "B.Fab")
		)
		(fp_line
			(start -0.12065 -0.2794)
			(end -0.12065 -0.3048)
			(stroke
				(width 0.1)
				(type default)
			)
			(layer "B.Fab")
		)
		(fp_line
			(start 0.12065 0.2794)
			(end 0.12065 0.3048)
			(stroke
				(width 0.1)
				(type default)
			)
			(layer "B.Fab")
		)
		(fp_line
			(start -0.120396 0.2794)
			(end 0.12065 0.2794)
			(stroke
				(width 0.1)
				(type default)
			)
			(layer "B.Fab")
		)
		(fp_line
			(start 0.67945 0.3048)
			(end 0.67945 -0.305054)
			(stroke
				(width 0.1)
				(type default)
			)
			(layer "B.Fab")
		)
		(fp_line
			(start 0.12065 0.3048)
			(end 0.67945 0.3048)
			(stroke
				(width 0.1)
				(type default)
			)
			(layer "B.Fab")
		)
		(fp_line
			(start -0.120396 0.3048)
			(end -0.120396 0.2794)
			(stroke
				(width 0.1)
				(type default)
			)
			(layer "B.Fab")
		)
		(fp_line
			(start -0.67945 0.3048)
			(end -0.120396 0.3048)
			(stroke
				(width 0.1)
				(type default)
			)
			(layer "B.Fab")
		)
		(pad "1" smd circle
			(at 0.40005 0 270)
			(size 0 0)
			(layers "B.Cu" "B.Mask" "B.Paste")
			(net "SMB_BMC_MM7_R_SDA")
		)
		(pad "2" smd circle
			(at -0.40005 0 270)
			(size 0 0)
			(layers "B.Cu" "B.Mask" "B.Paste")
			(net "SMB_BMC_MM7_SDA")
		)
	)
	(footprint ""
		(layer "B.Cu")
		(at 32.639 -106.553 -90)
		(property "Reference" "R243"
			(at 0 0 90)
			(layer "B.SilkS")
			(hide yes)
			(effects
				(font
					(size 1.27 1.27)
				)
				(justify mirror)
			)
		)
		(property "Value" ""
			(at 0 0 90)
			(layer "B.Fab")
			(effects
				(font
					(size 1.27 1.27)
				)
				(justify mirror)
			)
		)
		(duplicate_pad_numbers_are_jumpers no)
		(fp_line
			(start -0.7874 0.4064)
			(end 0.7874 0.4064)
			(stroke
				(width 0.1524)
				(type default)
			)
			(layer "B.SilkS")
		)
		(fp_line
			(start 0.7874 0.4064)
			(end 0.7874 -0.4064)
			(stroke
				(width 0.1524)
				(type default)
			)
			(layer "B.SilkS")
		)
		(fp_line
			(start -0.7874 -0.4064)
			(end -0.7874 0.4064)
			(stroke
				(width 0.1524)
				(type default)
			)
			(layer "B.SilkS")
		)
		(fp_line
			(start 0.7874 -0.4064)
			(end -0.7874 -0.4064)
			(stroke
				(width 0.1524)
				(type default)
			)
			(layer "B.SilkS")
		)
		(fp_line
			(start -0.67945 0.3048)
			(end -0.120396 0.3048)
			(stroke
				(width 0.1)
				(type default)
			)
			(layer "B.Fab")
		)
		(fp_line
			(start -0.120396 0.3048)
			(end -0.120396 0.2794)
			(stroke
				(width 0.1)
				(type default)
			)
			(layer "B.Fab")
		)
		(fp_line
			(start 0.12065 0.3048)
			(end 0.67945 0.3048)
			(stroke
				(width 0.1)
				(type default)
			)
			(layer "B.Fab")
		)
		(fp_line
			(start 0.67945 0.3048)
			(end 0.67945 -0.305054)
			(stroke
				(width 0.1)
				(type default)
			)
			(layer "B.Fab")
		)
		(fp_line
			(start -0.120396 0.2794)
			(end 0.12065 0.2794)
			(stroke
				(width 0.1)
				(type default)
			)
			(layer "B.Fab")
		)
		(fp_line
			(start 0.12065 0.2794)
			(end 0.12065 0.3048)
			(stroke
				(width 0.1)
				(type default)
			)
			(layer "B.Fab")
		)
		(fp_line
			(start -0.12065 -0.2794)
			(end -0.12065 -0.3048)
			(stroke
				(width 0.1)
				(type default)
			)
			(layer "B.Fab")
		)
		(fp_line
			(start 0.12065 -0.2794)
			(end -0.12065 -0.2794)
			(stroke
				(width 0.1)
				(type default)
			)
			(layer "B.Fab")
		)
		(fp_line
			(start -0.67945 -0.3048)
			(end -0.67945 0.3048)
			(stroke
				(width 0.1)
				(type default)
			)
			(layer "B.Fab")
		)
		(fp_line
			(start -0.12065 -0.3048)
			(end -0.67945 -0.3048)
			(stroke
				(width 0.1)
				(type default)
			)
			(layer "B.Fab")
		)
		(fp_line
			(start 0.12065 -0.305054)
			(end 0.12065 -0.2794)
			(stroke
				(width 0.1)
				(type default)
			)
			(layer "B.Fab")
		)
		(fp_line
			(start 0.67945 -0.305054)
			(end 0.12065 -0.305054)
			(stroke
				(width 0.1)
				(type default)
			)
			(layer "B.Fab")
		)
		(pad "1" smd circle
			(at 0.40005 0 90)
			(size 0 0)
			(layers "B.Cu" "B.Mask" "B.Paste")
			(net "PWRGD_PSU_AC_PWROK")
		)
		(pad "2" smd circle
			(at -0.40005 0 90)
			(size 0 0)
			(layers "B.Cu" "B.Mask" "B.Paste")
			(net "PWRGD_PSU_AC_PWROK_R")
		)
	)
	(footprint ""
		(layer "B.Cu")
		(at 17.907 -24.003 -90)
		(property "Reference" "PC268"
			(at 0 0 90)
			(layer "B.SilkS")
			(hide yes)
			(effects
				(font
					(size 1.27 1.27)
				)
				(justify mirror)
			)
		)
		(property "Value" ""
			(at 0 0 90)
			(layer "B.Fab")
			(effects
				(font
					(size 1.27 1.27)
				)
				(justify mirror)
			)
		)
		(duplicate_pad_numbers_are_jumpers no)
		(fp_line
			(start -1.651 0.8382)
			(end 1.651 0.8382)
			(stroke
				(width 0.1524)
				(type default)
			)
			(layer "B.SilkS")
		)
		(fp_line
			(start 0 0.8382)
			(end 0 -0.8382)
			(stroke
				(width 0.1524)
				(type default)
			)
			(layer "B.SilkS")
		)
		(fp_line
			(start 1.651 0.8382)
			(end 1.651 -0.8382)
			(stroke
				(width 0.1524)
				(type default)
			)
			(layer "B.SilkS")
		)
		(fp_line
			(start -1.651 -0.8382)
			(end -1.651 0.8382)
			(stroke
				(width 0.1524)
				(type default)
			)
			(layer "B.SilkS")
		)
		(fp_line
			(start 1.651 -0.8382)
			(end -1.651 -0.8382)
			(stroke
				(width 0.1524)
				(type default)
			)
			(layer "B.SilkS")
		)
		(fp_line
			(start -1.55956 0.7366)
			(end -1.55956 -0.7366)
			(stroke
				(width 0.1)
				(type default)
			)
			(layer "B.Fab")
		)
		(fp_line
			(start -1.524 0.7366)
			(end -1.55956 0.7366)
			(stroke
				(width 0.1)
				(type default)
			)
			(layer "B.Fab")
		)
		(fp_line
			(start 1.524 0.7366)
			(end -1.524 0.7366)
			(stroke
				(width 0.1)
				(type default)
			)
			(layer "B.Fab")
		)
		(fp_line
			(start 1.55956 0.7366)
			(end 1.524 0.7366)
			(stroke
				(width 0.1)
				(type default)
			)
			(layer "B.Fab")
		)
		(fp_line
			(start -1.55956 -0.7366)
			(end -1.524 -0.7366)
			(stroke
				(width 0.1)
				(type default)
			)
			(layer "B.Fab")
		)
		(fp_line
			(start -1.524 -0.7366)
			(end 1.524 -0.7366)
			(stroke
				(width 0.1)
				(type default)
			)
			(layer "B.Fab")
		)
		(fp_line
			(start 1.524 -0.7366)
			(end 1.55956 -0.7366)
			(stroke
				(width 0.1)
				(type default)
			)
			(layer "B.Fab")
		)
		(fp_line
			(start 1.55956 -0.7366)
			(end 1.55956 0.7366)
			(stroke
				(width 0.1)
				(type default)
			)
			(layer "B.Fab")
		)
		(pad "1" smd rect
			(at 0.94996 0 270)
			(size 1.1176 1.3716)
			(layers "B.Cu" "B.Mask" "B.Paste")
			(net "P1V0_AUX")
		)
		(pad "2" smd rect
			(at -0.94996 0 270)
			(size 1.1176 1.3716)
			(layers "B.Cu" "B.Mask" "B.Paste")
			(net "GND")
		)
	)
	(footprint ""
		(layer "B.Cu")
		(at 95.926656 53.375814 90)
		(property "Reference" "J11"
			(at -0.980186 -2.862326 270)
			(unlocked yes)
			(layer "B.SilkS")
			(effects
				(font
					(size 0.7874 0.5842)
					(thickness 0.1524)
				)
				(justify left mirror)
			)
		)
		(property "Value" ""
			(at 0 0 90)
			(layer "B.Fab")
			(effects
				(font
					(size 1.27 1.27)
				)
				(justify mirror)
			)
		)
		(duplicate_pad_numbers_are_jumpers no)
		(fp_line
			(start 1.2192 -2.1082)
			(end -1.2192 -2.1082)
			(stroke
				(width 0.1524)
				(type default)
			)
			(layer "B.SilkS")
		)
		(fp_line
			(start -1.2192 -2.1082)
			(end -1.2192 -0.801624)
			(stroke
				(width 0.1524)
				(type default)
			)
			(layer "B.SilkS")
		)
		(fp_line
			(start -1.2192 0.866394)
			(end -1.2192 2.1082)
			(stroke
				(width 0.1524)
				(type default)
			)
			(layer "B.SilkS")
		)
		(fp_line
			(start 1.2192 2.1082)
			(end 1.2192 -2.1082)
			(stroke
				(width 0.1524)
				(type default)
			)
			(layer "B.SilkS")
		)
		(fp_line
			(start -1.2192 2.1082)
			(end 1.2192 2.1082)
			(stroke
				(width 0.1524)
				(type default)
			)
			(layer "B.SilkS")
		)
		(pad "" np_thru_hole circle
			(at -3.4671 -1.27)
			(size 1.0414 1.0414)
			(drill 1.0414)
			(layers "*.Cu" "*.Mask")
			(clearance 0.381)
			(thermal_gap 0.381)
		)
		(pad "" np_thru_hole circle
			(at -3.4671 1.27)
			(size 1.0414 1.0414)
			(drill 1.0414)
			(layers "*.Cu" "*.Mask")
			(clearance 0.381)
			(thermal_gap 0.381)
		)
		(pad "" np_thru_hole circle
			(at 2.8829 -1.27)
			(size 1.0414 1.0414)
			(drill 1.0414)
			(layers "*.Cu" "*.Mask")
			(clearance 0.381)
			(thermal_gap 0.381)
		)
		(pad "" np_thru_hole circle
			(at 2.8829 1.27)
			(size 1.0414 1.0414)
			(drill 1.0414)
			(layers "*.Cu" "*.Mask")
			(clearance 0.381)
			(thermal_gap 0.381)
		)
		(pad "1" smd rect
			(at -0.8255 -0.249936)
			(size 0.3048 0.508)
			(layers "B.Cu" "B.Mask" "B.Paste")
			(net "85_5INCH_IN1_DN")
		)
		(pad "2" smd rect
			(at -0.8255 0.249936)
			(size 0.3048 0.508)
			(layers "B.Cu" "B.Mask" "B.Paste")
			(net "85_5INCH_IN1_DP")
		)
		(pad "3" smd circle
			(at 0 0 270)
			(size 0 0)
			(layers "B.Cu" "B.Mask" "B.Paste")
			(net "GND_P1")
		)
		(zone
			(layers "F.Cu" "B.Cu" "In1.Cu" "In2.Cu" "In3.Cu" "In4.Cu" "In5.Cu" "In6.Cu"
				"In7.Cu" "In8.Cu" "In9.Cu" "In10.Cu"
			)
			(hatch none 0.5)
			(connect_pads
				(clearance 0)
			)
			(min_thickness 0.25)
			(keepout
				(tracks not_allowed)
				(vias allowed)
				(pads allowed)
				(copperpour not_allowed)
				(footprints allowed)
			)
			(placement
				(enabled no)
				(sheetname "")
			)
			(fill
				(thermal_gap 0.5)
				(thermal_bridge_width 0.5)
				(island_removal_mode 0)
			)
			(polygon
				(pts
					(arc
						(start 95.583756 50.492914)
						(mid 93.729556 50.492914)
						(end 95.583756 50.492914)
					)
				)
			)
		)
		(zone
			(layers "F.Cu" "B.Cu" "In1.Cu" "In2.Cu" "In3.Cu" "In4.Cu" "In5.Cu" "In6.Cu"
				"In7.Cu" "In8.Cu" "In9.Cu" "In10.Cu"
			)
			(hatch none 0.5)
			(connect_pads
				(clearance 0)
			)
			(min_thickness 0.25)
			(keepout
				(tracks not_allowed)
				(vias allowed)
				(pads allowed)
				(copperpour not_allowed)
				(footprints allowed)
			)
			(placement
				(enabled no)
				(sheetname "")
			)
			(fill
				(thermal_gap 0.5)
				(thermal_bridge_width 0.5)
				(island_removal_mode 0)
			)
			(polygon
				(pts
					(arc
						(start 95.583756 56.842914)
						(mid 93.729556 56.842914)
						(end 95.583756 56.842914)
					)
				)
			)
		)
		(zone
			(layers "F.Cu" "B.Cu" "In1.Cu" "In2.Cu" "In3.Cu" "In4.Cu" "In5.Cu" "In6.Cu"
				"In7.Cu" "In8.Cu" "In9.Cu" "In10.Cu"
			)
			(hatch none 0.5)
			(connect_pads
				(clearance 0)
			)
			(min_thickness 0.25)
			(keepout
				(tracks not_allowed)
				(vias allowed)
				(pads allowed)
				(copperpour not_allowed)
				(footprints allowed)
			)
			(placement
				(enabled no)
				(sheetname "")
			)
			(fill
				(thermal_gap 0.5)
				(thermal_bridge_width 0.5)
				(island_removal_mode 0)
			)
			(polygon
				(pts
					(arc
						(start 98.123756 50.492914)
						(mid 96.269556 50.492914)
						(end 98.123756 50.492914)
					)
				)
			)
		)
		(zone
			(layers "F.Cu" "B.Cu" "In1.Cu" "In2.Cu" "In3.Cu" "In4.Cu" "In5.Cu" "In6.Cu"
				"In7.Cu" "In8.Cu" "In9.Cu" "In10.Cu"
			)
			(hatch none 0.5)
			(connect_pads
				(clearance 0)
			)
			(min_thickness 0.25)
			(keepout
				(tracks not_allowed)
				(vias allowed)
				(pads allowed)
				(copperpour not_allowed)
				(footprints allowed)
			)
			(placement
				(enabled no)
				(sheetname "")
			)
			(fill
				(thermal_gap 0.5)
				(thermal_bridge_width 0.5)
				(island_removal_mode 0)
			)
			(polygon
				(pts
					(arc
						(start 98.123756 56.842914)
						(mid 96.269556 56.842914)
						(end 98.123756 56.842914)
					)
				)
			)
		)
		(zone
			(layer "B.Cu")
			(hatch none 0.5)
			(connect_pads
				(clearance 0)
			)
			(min_thickness 0.25)
			(keepout
				(tracks not_allowed)
				(vias allowed)
				(pads allowed)
				(copperpour not_allowed)
				(footprints allowed)
			)
			(placement
				(enabled no)
				(sheetname "")
			)
			(fill
				(thermal_gap 0.5)
				(thermal_bridge_width 0.5)
				(island_removal_mode 0)
			)
			(polygon
				(pts
					(xy 95.378016 54.493414) (xy 95.47352 54.493414) (xy 95.47352 53.896514) (xy 95.87992 53.896514)
					(xy 95.87992 54.493414) (xy 95.973392 54.493414) (xy 95.973392 53.896514) (xy 96.379792 53.896514)
					(xy 96.379792 54.493414) (xy 96.475296 54.493414) (xy 96.475296 53.794914) (xy 95.378016 53.794914)
				)
			)
		)
	)
	(footprint ""
		(layer "B.Cu")
		(at 41.91 -43.053 180)
		(property "Reference" "R168"
			(at 0 0 0)
			(layer "B.SilkS")
			(hide yes)
			(effects
				(font
					(size 1.27 1.27)
				)
				(justify mirror)
			)
		)
		(property "Value" ""
			(at 0 0 0)
			(layer "B.Fab")
			(effects
				(font
					(size 1.27 1.27)
				)
				(justify mirror)
			)
		)
		(duplicate_pad_numbers_are_jumpers no)
		(fp_line
			(start 0.7874 0.4064)
			(end 0.7874 -0.4064)
			(stroke
				(width 0.1524)
				(type default)
			)
			(layer "B.SilkS")
		)
		(fp_line
			(start 0.7874 -0.4064)
			(end -0.7874 -0.4064)
			(stroke
				(width 0.1524)
				(type default)
			)
			(layer "B.SilkS")
		)
		(fp_line
			(start -0.7874 0.4064)
			(end 0.7874 0.4064)
			(stroke
				(width 0.1524)
				(type default)
			)
			(layer "B.SilkS")
		)
		(fp_line
			(start -0.7874 -0.4064)
			(end -0.7874 0.4064)
			(stroke
				(width 0.1524)
				(type default)
			)
			(layer "B.SilkS")
		)
		(fp_line
			(start 0.67945 0.3048)
			(end 0.67945 -0.305054)
			(stroke
				(width 0.1)
				(type default)
			)
			(layer "B.Fab")
		)
		(fp_line
			(start 0.67945 -0.305054)
			(end 0.12065 -0.305054)
			(stroke
				(width 0.1)
				(type default)
			)
			(layer "B.Fab")
		)
		(fp_line
			(start 0.12065 0.3048)
			(end 0.67945 0.3048)
			(stroke
				(width 0.1)
				(type default)
			)
			(layer "B.Fab")
		)
		(fp_line
			(start 0.12065 0.2794)
			(end 0.12065 0.3048)
			(stroke
				(width 0.1)
				(type default)
			)
			(layer "B.Fab")
		)
		(fp_line
			(start 0.12065 -0.2794)
			(end -0.12065 -0.2794)
			(stroke
				(width 0.1)
				(type default)
			)
			(layer "B.Fab")
		)
		(fp_line
			(start 0.12065 -0.305054)
			(end 0.12065 -0.2794)
			(stroke
				(width 0.1)
				(type default)
			)
			(layer "B.Fab")
		)
		(fp_line
			(start -0.120396 0.3048)
			(end -0.120396 0.2794)
			(stroke
				(width 0.1)
				(type default)
			)
			(layer "B.Fab")
		)
		(fp_line
			(start -0.120396 0.2794)
			(end 0.12065 0.2794)
			(stroke
				(width 0.1)
				(type default)
			)
			(layer "B.Fab")
		)
		(fp_line
			(start -0.12065 -0.2794)
			(end -0.12065 -0.3048)
			(stroke
				(width 0.1)
				(type default)
			)
			(layer "B.Fab")
		)
		(fp_line
			(start -0.12065 -0.3048)
			(end -0.67945 -0.3048)
			(stroke
				(width 0.1)
				(type default)
			)
			(layer "B.Fab")
		)
		(fp_line
			(start -0.67945 0.3048)
			(end -0.120396 0.3048)
			(stroke
				(width 0.1)
				(type default)
			)
			(layer "B.Fab")
		)
		(fp_line
			(start -0.67945 -0.3048)
			(end -0.67945 0.3048)
			(stroke
				(width 0.1)
				(type default)
			)
			(layer "B.Fab")
		)
		(pad "1" smd circle
			(at 0.40005 0)
			(size 0 0)
			(layers "B.Cu" "B.Mask" "B.Paste")
			(net "RST_PLTRST_N")
		)
		(pad "2" smd circle
			(at -0.40005 0)
			(size 0 0)
			(layers "B.Cu" "B.Mask" "B.Paste")
			(net "RST_PLTRST_R_N")
		)
	)
	(footprint ""
		(layer "B.Cu")
		(at 52.891182 -70.799706)
		(property "Reference" "C277"
			(at 0 0 0)
			(layer "B.SilkS")
			(hide yes)
			(effects
				(font
					(size 1.27 1.27)
				)
				(justify mirror)
			)
		)
		(property "Value" ""
			(at 0 0 0)
			(layer "B.Fab")
			(effects
				(font
					(size 1.27 1.27)
				)
				(justify mirror)
			)
		)
		(duplicate_pad_numbers_are_jumpers no)
		(fp_line
			(start -0.7874 -0.4064)
			(end -0.7874 0.4064)
			(stroke
				(width 0.1524)
				(type default)
			)
			(layer "B.SilkS")
		)
		(fp_line
			(start -0.7874 0.4064)
			(end 0.7874 0.4064)
			(stroke
				(width 0.1524)
				(type default)
			)
			(layer "B.SilkS")
		)
		(fp_line
			(start 0.7874 -0.4064)
			(end -0.7874 -0.4064)
			(stroke
				(width 0.1524)
				(type default)
			)
			(layer "B.SilkS")
		)
		(fp_line
			(start 0.7874 0.4064)
			(end 0.7874 -0.4064)
			(stroke
				(width 0.1524)
				(type default)
			)
			(layer "B.SilkS")
		)
		(fp_line
			(start -0.67945 -0.3048)
			(end -0.67945 0.3048)
			(stroke
				(width 0.1)
				(type default)
			)
			(layer "B.Fab")
		)
		(fp_line
			(start -0.67945 0.3048)
			(end -0.120396 0.3048)
			(stroke
				(width 0.1)
				(type default)
			)
			(layer "B.Fab")
		)
		(fp_line
			(start -0.12065 -0.3048)
			(end -0.67945 -0.3048)
			(stroke
				(width 0.1)
				(type default)
			)
			(layer "B.Fab")
		)
		(fp_line
			(start -0.12065 -0.2794)
			(end -0.12065 -0.3048)
			(stroke
				(width 0.1)
				(type default)
			)
			(layer "B.Fab")
		)
		(fp_line
			(start -0.120396 0.2794)
			(end 0.12065 0.2794)
			(stroke
				(width 0.1)
				(type default)
			)
			(layer "B.Fab")
		)
		(fp_line
			(start -0.120396 0.3048)
			(end -0.120396 0.2794)
			(stroke
				(width 0.1)
				(type default)
			)
			(layer "B.Fab")
		)
		(fp_line
			(start 0.12065 -0.305054)
			(end 0.12065 -0.2794)
			(stroke
				(width 0.1)
				(type default)
			)
			(layer "B.Fab")
		)
		(fp_line
			(start 0.12065 -0.2794)
			(end -0.12065 -0.2794)
			(stroke
				(width 0.1)
				(type default)
			)
			(layer "B.Fab")
		)
		(fp_line
			(start 0.12065 0.2794)
			(end 0.12065 0.3048)
			(stroke
				(width 0.1)
				(type default)
			)
			(layer "B.Fab")
		)
		(fp_line
			(start 0.12065 0.3048)
			(end 0.67945 0.3048)
			(stroke
				(width 0.1)
				(type default)
			)
			(layer "B.Fab")
		)
		(fp_line
			(start 0.67945 -0.305054)
			(end 0.12065 -0.305054)
			(stroke
				(width 0.1)
				(type default)
			)
			(layer "B.Fab")
		)
		(fp_line
			(start 0.67945 0.3048)
			(end 0.67945 -0.305054)
			(stroke
				(width 0.1)
				(type default)
			)
			(layer "B.Fab")
		)
		(pad "1" smd circle
			(at 0.40005 0 180)
			(size 0 0)
			(layers "B.Cu" "B.Mask" "B.Paste")
			(net "ADCVREFEXT1")
		)
		(pad "2" smd circle
			(at -0.40005 0 180)
			(size 0 0)
			(layers "B.Cu" "B.Mask" "B.Paste")
			(net "GND")
		)
	)
	(footprint ""
		(layer "B.Cu")
		(at 66.802 -13.462 180)
		(property "Reference" "R884"
			(at 0 0 0)
			(layer "B.SilkS")
			(hide yes)
			(effects
				(font
					(size 1.27 1.27)
				)
				(justify mirror)
			)
		)
		(property "Value" ""
			(at 0 0 0)
			(layer "B.Fab")
			(effects
				(font
					(size 1.27 1.27)
				)
				(justify mirror)
			)
		)
		(duplicate_pad_numbers_are_jumpers no)
		(fp_line
			(start 0.7874 0.4064)
			(end 0.7874 -0.4064)
			(stroke
				(width 0.1524)
				(type default)
			)
			(layer "B.SilkS")
		)
		(fp_line
			(start 0.7874 -0.4064)
			(end -0.7874 -0.4064)
			(stroke
				(width 0.1524)
				(type default)
			)
			(layer "B.SilkS")
		)
		(fp_line
			(start -0.7874 0.4064)
			(end 0.7874 0.4064)
			(stroke
				(width 0.1524)
				(type default)
			)
			(layer "B.SilkS")
		)
		(fp_line
			(start -0.7874 -0.4064)
			(end -0.7874 0.4064)
			(stroke
				(width 0.1524)
				(type default)
			)
			(layer "B.SilkS")
		)
		(fp_line
			(start 0.67945 0.3048)
			(end 0.67945 -0.305054)
			(stroke
				(width 0.1)
				(type default)
			)
			(layer "B.Fab")
		)
		(fp_line
			(start 0.67945 -0.305054)
			(end 0.12065 -0.305054)
			(stroke
				(width 0.1)
				(type default)
			)
			(layer "B.Fab")
		)
		(fp_line
			(start 0.12065 0.3048)
			(end 0.67945 0.3048)
			(stroke
				(width 0.1)
				(type default)
			)
			(layer "B.Fab")
		)
		(fp_line
			(start 0.12065 0.2794)
			(end 0.12065 0.3048)
			(stroke
				(width 0.1)
				(type default)
			)
			(layer "B.Fab")
		)
		(fp_line
			(start 0.12065 -0.2794)
			(end -0.12065 -0.2794)
			(stroke
				(width 0.1)
				(type default)
			)
			(layer "B.Fab")
		)
		(fp_line
			(start 0.12065 -0.305054)
			(end 0.12065 -0.2794)
			(stroke
				(width 0.1)
				(type default)
			)
			(layer "B.Fab")
		)
		(fp_line
			(start -0.120396 0.3048)
			(end -0.120396 0.2794)
			(stroke
				(width 0.1)
				(type default)
			)
			(layer "B.Fab")
		)
		(fp_line
			(start -0.120396 0.2794)
			(end 0.12065 0.2794)
			(stroke
				(width 0.1)
				(type default)
			)
			(layer "B.Fab")
		)
		(fp_line
			(start -0.12065 -0.2794)
			(end -0.12065 -0.3048)
			(stroke
				(width 0.1)
				(type default)
			)
			(layer "B.Fab")
		)
		(fp_line
			(start -0.12065 -0.3048)
			(end -0.67945 -0.3048)
			(stroke
				(width 0.1)
				(type default)
			)
			(layer "B.Fab")
		)
		(fp_line
			(start -0.67945 0.3048)
			(end -0.120396 0.3048)
			(stroke
				(width 0.1)
				(type default)
			)
			(layer "B.Fab")
		)
		(fp_line
			(start -0.67945 -0.3048)
			(end -0.67945 0.3048)
			(stroke
				(width 0.1)
				(type default)
			)
			(layer "B.Fab")
		)
		(pad "1" smd circle
			(at 0.40005 0)
			(size 0 0)
			(layers "B.Cu" "B.Mask" "B.Paste")
			(net "AC_PWR_BMC_BTN_R_N")
		)
		(pad "2" smd circle
			(at -0.40005 0)
			(size 0 0)
			(layers "B.Cu" "B.Mask" "B.Paste")
			(net "AC_PWR_BMC_BTN_N")
		)
	)
	(footprint ""
		(layer "B.Cu")
		(at 47.92726 -67.818 180)
		(property "Reference" "R842"
			(at 0 0 0)
			(layer "B.SilkS")
			(hide yes)
			(effects
				(font
					(size 1.27 1.27)
				)
				(justify mirror)
			)
		)
		(property "Value" ""
			(at 0 0 0)
			(layer "B.Fab")
			(effects
				(font
					(size 1.27 1.27)
				)
				(justify mirror)
			)
		)
		(duplicate_pad_numbers_are_jumpers no)
		(fp_line
			(start 0.7874 0.4064)
			(end 0.7874 -0.4064)
			(stroke
				(width 0.1524)
				(type default)
			)
			(layer "B.SilkS")
		)
		(fp_line
			(start 0.7874 -0.4064)
			(end -0.7874 -0.4064)
			(stroke
				(width 0.1524)
				(type default)
			)
			(layer "B.SilkS")
		)
		(fp_line
			(start -0.7874 0.4064)
			(end 0.7874 0.4064)
			(stroke
				(width 0.1524)
				(type default)
			)
			(layer "B.SilkS")
		)
		(fp_line
			(start -0.7874 -0.4064)
			(end -0.7874 0.4064)
			(stroke
				(width 0.1524)
				(type default)
			)
			(layer "B.SilkS")
		)
		(fp_line
			(start 0.67945 0.3048)
			(end 0.67945 -0.305054)
			(stroke
				(width 0.1)
				(type default)
			)
			(layer "B.Fab")
		)
		(fp_line
			(start 0.67945 -0.305054)
			(end 0.12065 -0.305054)
			(stroke
				(width 0.1)
				(type default)
			)
			(layer "B.Fab")
		)
		(fp_line
			(start 0.12065 0.3048)
			(end 0.67945 0.3048)
			(stroke
				(width 0.1)
				(type default)
			)
			(layer "B.Fab")
		)
		(fp_line
			(start 0.12065 0.2794)
			(end 0.12065 0.3048)
			(stroke
				(width 0.1)
				(type default)
			)
			(layer "B.Fab")
		)
		(fp_line
			(start 0.12065 -0.2794)
			(end -0.12065 -0.2794)
			(stroke
				(width 0.1)
				(type default)
			)
			(layer "B.Fab")
		)
		(fp_line
			(start 0.12065 -0.305054)
			(end 0.12065 -0.2794)
			(stroke
				(width 0.1)
				(type default)
			)
			(layer "B.Fab")
		)
		(fp_line
			(start -0.120396 0.3048)
			(end -0.120396 0.2794)
			(stroke
				(width 0.1)
				(type default)
			)
			(layer "B.Fab")
		)
		(fp_line
			(start -0.120396 0.2794)
			(end 0.12065 0.2794)
			(stroke
				(width 0.1)
				(type default)
			)
			(layer "B.Fab")
		)
		(fp_line
			(start -0.12065 -0.2794)
			(end -0.12065 -0.3048)
			(stroke
				(width 0.1)
				(type default)
			)
			(layer "B.Fab")
		)
		(fp_line
			(start -0.12065 -0.3048)
			(end -0.67945 -0.3048)
			(stroke
				(width 0.1)
				(type default)
			)
			(layer "B.Fab")
		)
		(fp_line
			(start -0.67945 0.3048)
			(end -0.120396 0.3048)
			(stroke
				(width 0.1)
				(type default)
			)
			(layer "B.Fab")
		)
		(fp_line
			(start -0.67945 -0.3048)
			(end -0.67945 0.3048)
			(stroke
				(width 0.1)
				(type default)
			)
			(layer "B.Fab")
		)
		(pad "1" smd circle
			(at 0.40005 0)
			(size 0 0)
			(layers "B.Cu" "B.Mask" "B.Paste")
			(net "P3V3_AUX")
		)
		(pad "2" smd circle
			(at -0.40005 0)
			(size 0 0)
			(layers "B.Cu" "B.Mask" "B.Paste")
			(net "SMB_BMC_ALERT9_N")
		)
	)
	(footprint ""
		(layer "B.Cu")
		(at 31.496 -70.358 180)
		(property "Reference" "C11"
			(at 0 0 0)
			(layer "B.SilkS")
			(hide yes)
			(effects
				(font
					(size 1.27 1.27)
				)
				(justify mirror)
			)
		)
		(property "Value" ""
			(at 0 0 0)
			(layer "B.Fab")
			(effects
				(font
					(size 1.27 1.27)
				)
				(justify mirror)
			)
		)
		(duplicate_pad_numbers_are_jumpers no)
		(fp_line
			(start 0.7874 0.4064)
			(end 0.7874 -0.4064)
			(stroke
				(width 0.1524)
				(type default)
			)
			(layer "B.SilkS")
		)
		(fp_line
			(start 0.7874 -0.4064)
			(end -0.7874 -0.4064)
			(stroke
				(width 0.1524)
				(type default)
			)
			(layer "B.SilkS")
		)
		(fp_line
			(start -0.7874 0.4064)
			(end 0.7874 0.4064)
			(stroke
				(width 0.1524)
				(type default)
			)
			(layer "B.SilkS")
		)
		(fp_line
			(start -0.7874 -0.4064)
			(end -0.7874 0.4064)
			(stroke
				(width 0.1524)
				(type default)
			)
			(layer "B.SilkS")
		)
		(fp_line
			(start 0.67945 0.3048)
			(end 0.67945 -0.305054)
			(stroke
				(width 0.1)
				(type default)
			)
			(layer "B.Fab")
		)
		(fp_line
			(start 0.67945 -0.305054)
			(end 0.12065 -0.305054)
			(stroke
				(width 0.1)
				(type default)
			)
			(layer "B.Fab")
		)
		(fp_line
			(start 0.12065 0.3048)
			(end 0.67945 0.3048)
			(stroke
				(width 0.1)
				(type default)
			)
			(layer "B.Fab")
		)
		(fp_line
			(start 0.12065 0.2794)
			(end 0.12065 0.3048)
			(stroke
				(width 0.1)
				(type default)
			)
			(layer "B.Fab")
		)
		(fp_line
			(start 0.12065 -0.2794)
			(end -0.12065 -0.2794)
			(stroke
				(width 0.1)
				(type default)
			)
			(layer "B.Fab")
		)
		(fp_line
			(start 0.12065 -0.305054)
			(end 0.12065 -0.2794)
			(stroke
				(width 0.1)
				(type default)
			)
			(layer "B.Fab")
		)
		(fp_line
			(start -0.120396 0.3048)
			(end -0.120396 0.2794)
			(stroke
				(width 0.1)
				(type default)
			)
			(layer "B.Fab")
		)
		(fp_line
			(start -0.120396 0.2794)
			(end 0.12065 0.2794)
			(stroke
				(width 0.1)
				(type default)
			)
			(layer "B.Fab")
		)
		(fp_line
			(start -0.12065 -0.2794)
			(end -0.12065 -0.3048)
			(stroke
				(width 0.1)
				(type default)
			)
			(layer "B.Fab")
		)
		(fp_line
			(start -0.12065 -0.3048)
			(end -0.67945 -0.3048)
			(stroke
				(width 0.1)
				(type default)
			)
			(layer "B.Fab")
		)
		(fp_line
			(start -0.67945 0.3048)
			(end -0.120396 0.3048)
			(stroke
				(width 0.1)
				(type default)
			)
			(layer "B.Fab")
		)
		(fp_line
			(start -0.67945 -0.3048)
			(end -0.67945 0.3048)
			(stroke
				(width 0.1)
				(type default)
			)
			(layer "B.Fab")
		)
		(pad "1" smd circle
			(at 0.40005 0)
			(size 0 0)
			(layers "B.Cu" "B.Mask" "B.Paste")
			(net "P3V3_AUX")
		)
		(pad "2" smd circle
			(at -0.40005 0)
			(size 0 0)
			(layers "B.Cu" "B.Mask" "B.Paste")
			(net "GND")
		)
	)
	(footprint ""
		(layer "B.Cu")
		(at 63.9572 -90.2208)
		(property "Reference" "R740"
			(at 0 0 0)
			(layer "B.SilkS")
			(hide yes)
			(effects
				(font
					(size 1.27 1.27)
				)
				(justify mirror)
			)
		)
		(property "Value" ""
			(at 0 0 0)
			(layer "B.Fab")
			(effects
				(font
					(size 1.27 1.27)
				)
				(justify mirror)
			)
		)
		(duplicate_pad_numbers_are_jumpers no)
		(fp_line
			(start -0.7874 -0.4064)
			(end -0.7874 0.4064)
			(stroke
				(width 0.1524)
				(type default)
			)
			(layer "B.SilkS")
		)
		(fp_line
			(start -0.7874 0.4064)
			(end 0.7874 0.4064)
			(stroke
				(width 0.1524)
				(type default)
			)
			(layer "B.SilkS")
		)
		(fp_line
			(start 0.7874 -0.4064)
			(end -0.7874 -0.4064)
			(stroke
				(width 0.1524)
				(type default)
			)
			(layer "B.SilkS")
		)
		(fp_line
			(start 0.7874 0.4064)
			(end 0.7874 -0.4064)
			(stroke
				(width 0.1524)
				(type default)
			)
			(layer "B.SilkS")
		)
		(fp_line
			(start -0.67945 -0.3048)
			(end -0.67945 0.3048)
			(stroke
				(width 0.1)
				(type default)
			)
			(layer "B.Fab")
		)
		(fp_line
			(start -0.67945 0.3048)
			(end -0.120396 0.3048)
			(stroke
				(width 0.1)
				(type default)
			)
			(layer "B.Fab")
		)
		(fp_line
			(start -0.12065 -0.3048)
			(end -0.67945 -0.3048)
			(stroke
				(width 0.1)
				(type default)
			)
			(layer "B.Fab")
		)
		(fp_line
			(start -0.12065 -0.2794)
			(end -0.12065 -0.3048)
			(stroke
				(width 0.1)
				(type default)
			)
			(layer "B.Fab")
		)
		(fp_line
			(start -0.120396 0.2794)
			(end 0.12065 0.2794)
			(stroke
				(width 0.1)
				(type default)
			)
			(layer "B.Fab")
		)
		(fp_line
			(start -0.120396 0.3048)
			(end -0.120396 0.2794)
			(stroke
				(width 0.1)
				(type default)
			)
			(layer "B.Fab")
		)
		(fp_line
			(start 0.12065 -0.305054)
			(end 0.12065 -0.2794)
			(stroke
				(width 0.1)
				(type default)
			)
			(layer "B.Fab")
		)
		(fp_line
			(start 0.12065 -0.2794)
			(end -0.12065 -0.2794)
			(stroke
				(width 0.1)
				(type default)
			)
			(layer "B.Fab")
		)
		(fp_line
			(start 0.12065 0.2794)
			(end 0.12065 0.3048)
			(stroke
				(width 0.1)
				(type default)
			)
			(layer "B.Fab")
		)
		(fp_line
			(start 0.12065 0.3048)
			(end 0.67945 0.3048)
			(stroke
				(width 0.1)
				(type default)
			)
			(layer "B.Fab")
		)
		(fp_line
			(start 0.67945 -0.305054)
			(end 0.12065 -0.305054)
			(stroke
				(width 0.1)
				(type default)
			)
			(layer "B.Fab")
		)
		(fp_line
			(start 0.67945 0.3048)
			(end 0.67945 -0.305054)
			(stroke
				(width 0.1)
				(type default)
			)
			(layer "B.Fab")
		)
		(pad "1" smd circle
			(at 0.40005 0 180)
			(size 0 0)
			(layers "B.Cu" "B.Mask" "B.Paste")
			(net "P3V3_AUX")
		)
		(pad "2" smd circle
			(at -0.40005 0 180)
			(size 0 0)
			(layers "B.Cu" "B.Mask" "B.Paste")
			(net "LED_POSTCODE_A2")
		)
	)
	(footprint ""
		(layer "B.Cu")
		(at 95.911416 112.766602 -90)
		(property "Reference" "J29"
			(at 6.105398 -1.470914 270)
			(unlocked yes)
			(layer "B.SilkS")
			(effects
				(font
					(size 0.7874 0.5842)
					(thickness 0.1524)
				)
				(justify left mirror)
			)
		)
		(property "Value" ""
			(at 0 0 90)
			(layer "B.Fab")
			(effects
				(font
					(size 1.27 1.27)
				)
				(justify mirror)
			)
		)
		(duplicate_pad_numbers_are_jumpers no)
		(fp_line
			(start -1.2192 2.1082)
			(end 1.2192 2.1082)
			(stroke
				(width 0.1524)
				(type default)
			)
			(layer "B.SilkS")
		)
		(fp_line
			(start 1.2192 2.1082)
			(end 1.2192 -2.1082)
			(stroke
				(width 0.1524)
				(type default)
			)
			(layer "B.SilkS")
		)
		(fp_line
			(start -1.2192 0.813562)
			(end -1.2192 2.1082)
			(stroke
				(width 0.1524)
				(type default)
			)
			(layer "B.SilkS")
		)
		(fp_line
			(start -1.2192 -2.1082)
			(end -1.2192 -0.82677)
			(stroke
				(width 0.1524)
				(type default)
			)
			(layer "B.SilkS")
		)
		(fp_line
			(start 1.2192 -2.1082)
			(end -1.2192 -2.1082)
			(stroke
				(width 0.1524)
				(type default)
			)
			(layer "B.SilkS")
		)
		(pad "" np_thru_hole circle
			(at -3.4671 -1.27 180)
			(size 1.0414 1.0414)
			(drill 1.0414)
			(layers "*.Cu" "*.Mask")
			(clearance 0.381)
			(thermal_gap 0.381)
		)
		(pad "" np_thru_hole circle
			(at -3.4671 1.27 180)
			(size 1.0414 1.0414)
			(drill 1.0414)
			(layers "*.Cu" "*.Mask")
			(clearance 0.381)
			(thermal_gap 0.381)
		)
		(pad "" np_thru_hole circle
			(at 2.8829 -1.27 180)
			(size 1.0414 1.0414)
			(drill 1.0414)
			(layers "*.Cu" "*.Mask")
			(clearance 0.381)
			(thermal_gap 0.381)
		)
		(pad "" np_thru_hole circle
			(at 2.8829 1.27 180)
			(size 1.0414 1.0414)
			(drill 1.0414)
			(layers "*.Cu" "*.Mask")
			(clearance 0.381)
			(thermal_gap 0.381)
		)
		(pad "1" smd rect
			(at -0.8255 -0.249936 180)
			(size 0.3048 0.508)
			(layers "B.Cu" "B.Mask" "B.Paste")
			(net "85_5INCH_IN1_DP")
		)
		(pad "2" smd rect
			(at -0.8255 0.249936 180)
			(size 0.3048 0.508)
			(layers "B.Cu" "B.Mask" "B.Paste")
			(net "85_5INCH_IN1_DN")
		)
		(pad "3" smd circle
			(at 0 0 90)
			(size 0 0)
			(layers "B.Cu" "B.Mask" "B.Paste")
			(net "GND_P1")
		)
		(zone
			(layers "F.Cu" "B.Cu" "In1.Cu" "In2.Cu" "In3.Cu" "In4.Cu" "In5.Cu" "In6.Cu"
				"In7.Cu" "In8.Cu" "In9.Cu" "In10.Cu"
			)
			(hatch none 0.5)
			(connect_pads
				(clearance 0)
			)
			(min_thickness 0.25)
			(keepout
				(tracks not_allowed)
				(vias allowed)
				(pads allowed)
				(copperpour not_allowed)
				(footprints allowed)
			)
			(placement
				(enabled no)
				(sheetname "")
			)
			(fill
				(thermal_gap 0.5)
				(thermal_bridge_width 0.5)
				(island_removal_mode 0)
			)
			(polygon
				(pts
					(arc
						(start 95.568516 109.299502)
						(mid 93.714316 109.299502)
						(end 95.568516 109.299502)
					)
				)
			)
		)
		(zone
			(layers "F.Cu" "B.Cu" "In1.Cu" "In2.Cu" "In3.Cu" "In4.Cu" "In5.Cu" "In6.Cu"
				"In7.Cu" "In8.Cu" "In9.Cu" "In10.Cu"
			)
			(hatch none 0.5)
			(connect_pads
				(clearance 0)
			)
			(min_thickness 0.25)
			(keepout
				(tracks not_allowed)
				(vias allowed)
				(pads allowed)
				(copperpour not_allowed)
				(footprints allowed)
			)
			(placement
				(enabled no)
				(sheetname "")
			)
			(fill
				(thermal_gap 0.5)
				(thermal_bridge_width 0.5)
				(island_removal_mode 0)
			)
			(polygon
				(pts
					(arc
						(start 95.568516 115.649502)
						(mid 93.714316 115.649502)
						(end 95.568516 115.649502)
					)
				)
			)
		)
		(zone
			(layers "F.Cu" "B.Cu" "In1.Cu" "In2.Cu" "In3.Cu" "In4.Cu" "In5.Cu" "In6.Cu"
				"In7.Cu" "In8.Cu" "In9.Cu" "In10.Cu"
			)
			(hatch none 0.5)
			(connect_pads
				(clearance 0)
			)
			(min_thickness 0.25)
			(keepout
				(tracks not_allowed)
				(vias allowed)
				(pads allowed)
				(copperpour not_allowed)
				(footprints allowed)
			)
			(placement
				(enabled no)
				(sheetname "")
			)
			(fill
				(thermal_gap 0.5)
				(thermal_bridge_width 0.5)
				(island_removal_mode 0)
			)
			(polygon
				(pts
					(arc
						(start 98.108516 109.299502)
						(mid 96.254316 109.299502)
						(end 98.108516 109.299502)
					)
				)
			)
		)
		(zone
			(layers "F.Cu" "B.Cu" "In1.Cu" "In2.Cu" "In3.Cu" "In4.Cu" "In5.Cu" "In6.Cu"
				"In7.Cu" "In8.Cu" "In9.Cu" "In10.Cu"
			)
			(hatch none 0.5)
			(connect_pads
				(clearance 0)
			)
			(min_thickness 0.25)
			(keepout
				(tracks not_allowed)
				(vias allowed)
				(pads allowed)
				(copperpour not_allowed)
				(footprints allowed)
			)
			(placement
				(enabled no)
				(sheetname "")
			)
			(fill
				(thermal_gap 0.5)
				(thermal_bridge_width 0.5)
				(island_removal_mode 0)
			)
			(polygon
				(pts
					(arc
						(start 98.108516 115.649502)
						(mid 96.254316 115.649502)
						(end 98.108516 115.649502)
					)
				)
			)
		)
		(zone
			(layer "B.Cu")
			(hatch none 0.5)
			(connect_pads
				(clearance 0)
			)
			(min_thickness 0.25)
			(keepout
				(tracks not_allowed)
				(vias allowed)
				(pads allowed)
				(copperpour not_allowed)
				(footprints allowed)
			)
			(placement
				(enabled no)
				(sheetname "")
			)
			(fill
				(thermal_gap 0.5)
				(thermal_bridge_width 0.5)
				(island_removal_mode 0)
			)
			(polygon
				(pts
					(xy 96.460056 111.649002) (xy 96.364552 111.649002) (xy 96.364552 112.245902) (xy 95.958152 112.245902)
					(xy 95.958152 111.649002) (xy 95.86468 111.649002) (xy 95.86468 112.245902) (xy 95.45828 112.245902)
					(xy 95.45828 111.649002) (xy 95.362776 111.649002) (xy 95.362776 112.347502) (xy 96.460056 112.347502)
				)
			)
		)
	)
	(footprint ""
		(layer "B.Cu")
		(at 78.867 -29.718 -90)
		(property "Reference" "R698"
			(at 0 0 90)
			(layer "B.SilkS")
			(hide yes)
			(effects
				(font
					(size 1.27 1.27)
				)
				(justify mirror)
			)
		)
		(property "Value" ""
			(at 0 0 90)
			(layer "B.Fab")
			(effects
				(font
					(size 1.27 1.27)
				)
				(justify mirror)
			)
		)
		(duplicate_pad_numbers_are_jumpers no)
		(fp_line
			(start -0.7874 0.4064)
			(end 0.7874 0.4064)
			(stroke
				(width 0.1524)
				(type default)
			)
			(layer "B.SilkS")
		)
		(fp_line
			(start 0.7874 0.4064)
			(end 0.7874 -0.4064)
			(stroke
				(width 0.1524)
				(type default)
			)
			(layer "B.SilkS")
		)
		(fp_line
			(start -0.7874 -0.4064)
			(end -0.7874 0.4064)
			(stroke
				(width 0.1524)
				(type default)
			)
			(layer "B.SilkS")
		)
		(fp_line
			(start 0.7874 -0.4064)
			(end -0.7874 -0.4064)
			(stroke
				(width 0.1524)
				(type default)
			)
			(layer "B.SilkS")
		)
		(fp_line
			(start -0.67945 0.3048)
			(end -0.120396 0.3048)
			(stroke
				(width 0.1)
				(type default)
			)
			(layer "B.Fab")
		)
		(fp_line
			(start -0.120396 0.3048)
			(end -0.120396 0.2794)
			(stroke
				(width 0.1)
				(type default)
			)
			(layer "B.Fab")
		)
		(fp_line
			(start 0.12065 0.3048)
			(end 0.67945 0.3048)
			(stroke
				(width 0.1)
				(type default)
			)
			(layer "B.Fab")
		)
		(fp_line
			(start 0.67945 0.3048)
			(end 0.67945 -0.305054)
			(stroke
				(width 0.1)
				(type default)
			)
			(layer "B.Fab")
		)
		(fp_line
			(start -0.120396 0.2794)
			(end 0.12065 0.2794)
			(stroke
				(width 0.1)
				(type default)
			)
			(layer "B.Fab")
		)
		(fp_line
			(start 0.12065 0.2794)
			(end 0.12065 0.3048)
			(stroke
				(width 0.1)
				(type default)
			)
			(layer "B.Fab")
		)
		(fp_line
			(start -0.12065 -0.2794)
			(end -0.12065 -0.3048)
			(stroke
				(width 0.1)
				(type default)
			)
			(layer "B.Fab")
		)
		(fp_line
			(start 0.12065 -0.2794)
			(end -0.12065 -0.2794)
			(stroke
				(width 0.1)
				(type default)
			)
			(layer "B.Fab")
		)
		(fp_line
			(start -0.67945 -0.3048)
			(end -0.67945 0.3048)
			(stroke
				(width 0.1)
				(type default)
			)
			(layer "B.Fab")
		)
		(fp_line
			(start -0.12065 -0.3048)
			(end -0.67945 -0.3048)
			(stroke
				(width 0.1)
				(type default)
			)
			(layer "B.Fab")
		)
		(fp_line
			(start 0.12065 -0.305054)
			(end 0.12065 -0.2794)
			(stroke
				(width 0.1)
				(type default)
			)
			(layer "B.Fab")
		)
		(fp_line
			(start 0.67945 -0.305054)
			(end 0.12065 -0.305054)
			(stroke
				(width 0.1)
				(type default)
			)
			(layer "B.Fab")
		)
		(pad "1" smd circle
			(at 0.40005 0 90)
			(size 0 0)
			(layers "B.Cu" "B.Mask" "B.Paste")
			(net "LED_POSTCODE_1")
		)
		(pad "2" smd circle
			(at -0.40005 0 90)
			(size 0 0)
			(layers "B.Cu" "B.Mask" "B.Paste")
			(net "LED_POSTCODE_1_R1")
		)
	)
	(footprint ""
		(layer "B.Cu")
		(at 16.383 -17.907 -90)
		(property "Reference" "R409"
			(at 0 0 90)
			(layer "B.SilkS")
			(hide yes)
			(effects
				(font
					(size 1.27 1.27)
				)
				(justify mirror)
			)
		)
		(property "Value" ""
			(at 0 0 90)
			(layer "B.Fab")
			(effects
				(font
					(size 1.27 1.27)
				)
				(justify mirror)
			)
		)
		(duplicate_pad_numbers_are_jumpers no)
		(fp_line
			(start -0.7874 0.4064)
			(end 0.7874 0.4064)
			(stroke
				(width 0.1524)
				(type default)
			)
			(layer "B.SilkS")
		)
		(fp_line
			(start 0.7874 0.4064)
			(end 0.7874 -0.4064)
			(stroke
				(width 0.1524)
				(type default)
			)
			(layer "B.SilkS")
		)
		(fp_line
			(start -0.7874 -0.4064)
			(end -0.7874 0.4064)
			(stroke
				(width 0.1524)
				(type default)
			)
			(layer "B.SilkS")
		)
		(fp_line
			(start 0.7874 -0.4064)
			(end -0.7874 -0.4064)
			(stroke
				(width 0.1524)
				(type default)
			)
			(layer "B.SilkS")
		)
		(fp_line
			(start -0.67945 0.3048)
			(end -0.120396 0.3048)
			(stroke
				(width 0.1)
				(type default)
			)
			(layer "B.Fab")
		)
		(fp_line
			(start -0.120396 0.3048)
			(end -0.120396 0.2794)
			(stroke
				(width 0.1)
				(type default)
			)
			(layer "B.Fab")
		)
		(fp_line
			(start 0.12065 0.3048)
			(end 0.67945 0.3048)
			(stroke
				(width 0.1)
				(type default)
			)
			(layer "B.Fab")
		)
		(fp_line
			(start 0.67945 0.3048)
			(end 0.67945 -0.305054)
			(stroke
				(width 0.1)
				(type default)
			)
			(layer "B.Fab")
		)
		(fp_line
			(start -0.120396 0.2794)
			(end 0.12065 0.2794)
			(stroke
				(width 0.1)
				(type default)
			)
			(layer "B.Fab")
		)
		(fp_line
			(start 0.12065 0.2794)
			(end 0.12065 0.3048)
			(stroke
				(width 0.1)
				(type default)
			)
			(layer "B.Fab")
		)
		(fp_line
			(start -0.12065 -0.2794)
			(end -0.12065 -0.3048)
			(stroke
				(width 0.1)
				(type default)
			)
			(layer "B.Fab")
		)
		(fp_line
			(start 0.12065 -0.2794)
			(end -0.12065 -0.2794)
			(stroke
				(width 0.1)
				(type default)
			)
			(layer "B.Fab")
		)
		(fp_line
			(start -0.67945 -0.3048)
			(end -0.67945 0.3048)
			(stroke
				(width 0.1)
				(type default)
			)
			(layer "B.Fab")
		)
		(fp_line
			(start -0.12065 -0.3048)
			(end -0.67945 -0.3048)
			(stroke
				(width 0.1)
				(type default)
			)
			(layer "B.Fab")
		)
		(fp_line
			(start 0.12065 -0.305054)
			(end 0.12065 -0.2794)
			(stroke
				(width 0.1)
				(type default)
			)
			(layer "B.Fab")
		)
		(fp_line
			(start 0.67945 -0.305054)
			(end 0.12065 -0.305054)
			(stroke
				(width 0.1)
				(type default)
			)
			(layer "B.Fab")
		)
		(pad "1" smd circle
			(at 0.40005 0 90)
			(size 0 0)
			(layers "B.Cu" "B.Mask" "B.Paste")
			(net "SMB_TMP421_BMC_MM2_SDA")
		)
		(pad "2" smd circle
			(at -0.40005 0 90)
			(size 0 0)
			(layers "B.Cu" "B.Mask" "B.Paste")
			(net "SMB_BMC_MM2_SDA")
		)
	)
	(footprint ""
		(layer "B.Cu")
		(at 49.53 -34.671 -90)
		(property "Reference" "R153"
			(at 0 0 90)
			(layer "B.SilkS")
			(hide yes)
			(effects
				(font
					(size 1.27 1.27)
				)
				(justify mirror)
			)
		)
		(property "Value" ""
			(at 0 0 90)
			(layer "B.Fab")
			(effects
				(font
					(size 1.27 1.27)
				)
				(justify mirror)
			)
		)
		(duplicate_pad_numbers_are_jumpers no)
		(fp_line
			(start -0.7874 0.4064)
			(end 0.7874 0.4064)
			(stroke
				(width 0.1524)
				(type default)
			)
			(layer "B.SilkS")
		)
		(fp_line
			(start 0.7874 0.4064)
			(end 0.7874 -0.4064)
			(stroke
				(width 0.1524)
				(type default)
			)
			(layer "B.SilkS")
		)
		(fp_line
			(start -0.7874 -0.4064)
			(end -0.7874 0.4064)
			(stroke
				(width 0.1524)
				(type default)
			)
			(layer "B.SilkS")
		)
		(fp_line
			(start 0.7874 -0.4064)
			(end -0.7874 -0.4064)
			(stroke
				(width 0.1524)
				(type default)
			)
			(layer "B.SilkS")
		)
		(fp_line
			(start -0.67945 0.3048)
			(end -0.120396 0.3048)
			(stroke
				(width 0.1)
				(type default)
			)
			(layer "B.Fab")
		)
		(fp_line
			(start -0.120396 0.3048)
			(end -0.120396 0.2794)
			(stroke
				(width 0.1)
				(type default)
			)
			(layer "B.Fab")
		)
		(fp_line
			(start 0.12065 0.3048)
			(end 0.67945 0.3048)
			(stroke
				(width 0.1)
				(type default)
			)
			(layer "B.Fab")
		)
		(fp_line
			(start 0.67945 0.3048)
			(end 0.67945 -0.305054)
			(stroke
				(width 0.1)
				(type default)
			)
			(layer "B.Fab")
		)
		(fp_line
			(start -0.120396 0.2794)
			(end 0.12065 0.2794)
			(stroke
				(width 0.1)
				(type default)
			)
			(layer "B.Fab")
		)
		(fp_line
			(start 0.12065 0.2794)
			(end 0.12065 0.3048)
			(stroke
				(width 0.1)
				(type default)
			)
			(layer "B.Fab")
		)
		(fp_line
			(start -0.12065 -0.2794)
			(end -0.12065 -0.3048)
			(stroke
				(width 0.1)
				(type default)
			)
			(layer "B.Fab")
		)
		(fp_line
			(start 0.12065 -0.2794)
			(end -0.12065 -0.2794)
			(stroke
				(width 0.1)
				(type default)
			)
			(layer "B.Fab")
		)
		(fp_line
			(start -0.67945 -0.3048)
			(end -0.67945 0.3048)
			(stroke
				(width 0.1)
				(type default)
			)
			(layer "B.Fab")
		)
		(fp_line
			(start -0.12065 -0.3048)
			(end -0.67945 -0.3048)
			(stroke
				(width 0.1)
				(type default)
			)
			(layer "B.Fab")
		)
		(fp_line
			(start 0.12065 -0.305054)
			(end 0.12065 -0.2794)
			(stroke
				(width 0.1)
				(type default)
			)
			(layer "B.Fab")
		)
		(fp_line
			(start 0.67945 -0.305054)
			(end 0.12065 -0.305054)
			(stroke
				(width 0.1)
				(type default)
			)
			(layer "B.Fab")
		)
		(pad "1" smd circle
			(at 0.40005 0 90)
			(size 0 0)
			(layers "B.Cu" "B.Mask" "B.Paste")
			(net "SMB_BMC_MM16_SDA")
		)
		(pad "2" smd circle
			(at -0.40005 0 90)
			(size 0 0)
			(layers "B.Cu" "B.Mask" "B.Paste")
			(net "SMB_BMC_MM16_R_SDA")
		)
	)
	(footprint ""
		(layer "B.Cu")
		(at 67.529964 -37.0205 -90)
		(property "Reference" "C46"
			(at 0 0 90)
			(layer "B.SilkS")
			(hide yes)
			(effects
				(font
					(size 1.27 1.27)
				)
				(justify mirror)
			)
		)
		(property "Value" ""
			(at 0 0 90)
			(layer "B.Fab")
			(effects
				(font
					(size 1.27 1.27)
				)
				(justify mirror)
			)
		)
		(duplicate_pad_numbers_are_jumpers no)
		(fp_line
			(start -0.7874 0.4064)
			(end 0.7874 0.4064)
			(stroke
				(width 0.1524)
				(type default)
			)
			(layer "B.SilkS")
		)
		(fp_line
			(start 0.7874 0.4064)
			(end 0.7874 -0.4064)
			(stroke
				(width 0.1524)
				(type default)
			)
			(layer "B.SilkS")
		)
		(fp_line
			(start -0.7874 -0.4064)
			(end -0.7874 0.4064)
			(stroke
				(width 0.1524)
				(type default)
			)
			(layer "B.SilkS")
		)
		(fp_line
			(start 0.7874 -0.4064)
			(end -0.7874 -0.4064)
			(stroke
				(width 0.1524)
				(type default)
			)
			(layer "B.SilkS")
		)
		(fp_line
			(start -0.67945 0.3048)
			(end -0.120396 0.3048)
			(stroke
				(width 0.1)
				(type default)
			)
			(layer "B.Fab")
		)
		(fp_line
			(start -0.120396 0.3048)
			(end -0.120396 0.2794)
			(stroke
				(width 0.1)
				(type default)
			)
			(layer "B.Fab")
		)
		(fp_line
			(start 0.12065 0.3048)
			(end 0.67945 0.3048)
			(stroke
				(width 0.1)
				(type default)
			)
			(layer "B.Fab")
		)
		(fp_line
			(start 0.67945 0.3048)
			(end 0.67945 -0.305054)
			(stroke
				(width 0.1)
				(type default)
			)
			(layer "B.Fab")
		)
		(fp_line
			(start -0.120396 0.2794)
			(end 0.12065 0.2794)
			(stroke
				(width 0.1)
				(type default)
			)
			(layer "B.Fab")
		)
		(fp_line
			(start 0.12065 0.2794)
			(end 0.12065 0.3048)
			(stroke
				(width 0.1)
				(type default)
			)
			(layer "B.Fab")
		)
		(fp_line
			(start -0.12065 -0.2794)
			(end -0.12065 -0.3048)
			(stroke
				(width 0.1)
				(type default)
			)
			(layer "B.Fab")
		)
		(fp_line
			(start 0.12065 -0.2794)
			(end -0.12065 -0.2794)
			(stroke
				(width 0.1)
				(type default)
			)
			(layer "B.Fab")
		)
		(fp_line
			(start -0.67945 -0.3048)
			(end -0.67945 0.3048)
			(stroke
				(width 0.1)
				(type default)
			)
			(layer "B.Fab")
		)
		(fp_line
			(start -0.12065 -0.3048)
			(end -0.67945 -0.3048)
			(stroke
				(width 0.1)
				(type default)
			)
			(layer "B.Fab")
		)
		(fp_line
			(start 0.12065 -0.305054)
			(end 0.12065 -0.2794)
			(stroke
				(width 0.1)
				(type default)
			)
			(layer "B.Fab")
		)
		(fp_line
			(start 0.67945 -0.305054)
			(end 0.12065 -0.305054)
			(stroke
				(width 0.1)
				(type default)
			)
			(layer "B.Fab")
		)
		(pad "1" smd circle
			(at 0.40005 0 90)
			(size 0 0)
			(layers "B.Cu" "B.Mask" "B.Paste")
			(net "P1V8_STBY_AVDDPLL")
		)
		(pad "2" smd circle
			(at -0.40005 0 90)
			(size 0 0)
			(layers "B.Cu" "B.Mask" "B.Paste")
			(net "GND")
		)
	)
	(footprint ""
		(layer "B.Cu")
		(at 28.9306 -63.4746 180)
		(property "Reference" "R544"
			(at 0 0 0)
			(layer "B.SilkS")
			(hide yes)
			(effects
				(font
					(size 1.27 1.27)
				)
				(justify mirror)
			)
		)
		(property "Value" ""
			(at 0 0 0)
			(layer "B.Fab")
			(effects
				(font
					(size 1.27 1.27)
				)
				(justify mirror)
			)
		)
		(duplicate_pad_numbers_are_jumpers no)
		(fp_line
			(start 0.7874 0.4064)
			(end 0.7874 -0.4064)
			(stroke
				(width 0.1524)
				(type default)
			)
			(layer "B.SilkS")
		)
		(fp_line
			(start 0.7874 -0.4064)
			(end -0.7874 -0.4064)
			(stroke
				(width 0.1524)
				(type default)
			)
			(layer "B.SilkS")
		)
		(fp_line
			(start -0.7874 0.4064)
			(end 0.7874 0.4064)
			(stroke
				(width 0.1524)
				(type default)
			)
			(layer "B.SilkS")
		)
		(fp_line
			(start -0.7874 -0.4064)
			(end -0.7874 0.4064)
			(stroke
				(width 0.1524)
				(type default)
			)
			(layer "B.SilkS")
		)
		(fp_line
			(start 0.67945 0.3048)
			(end 0.67945 -0.305054)
			(stroke
				(width 0.1)
				(type default)
			)
			(layer "B.Fab")
		)
		(fp_line
			(start 0.67945 -0.305054)
			(end 0.12065 -0.305054)
			(stroke
				(width 0.1)
				(type default)
			)
			(layer "B.Fab")
		)
		(fp_line
			(start 0.12065 0.3048)
			(end 0.67945 0.3048)
			(stroke
				(width 0.1)
				(type default)
			)
			(layer "B.Fab")
		)
		(fp_line
			(start 0.12065 0.2794)
			(end 0.12065 0.3048)
			(stroke
				(width 0.1)
				(type default)
			)
			(layer "B.Fab")
		)
		(fp_line
			(start 0.12065 -0.2794)
			(end -0.12065 -0.2794)
			(stroke
				(width 0.1)
				(type default)
			)
			(layer "B.Fab")
		)
		(fp_line
			(start 0.12065 -0.305054)
			(end 0.12065 -0.2794)
			(stroke
				(width 0.1)
				(type default)
			)
			(layer "B.Fab")
		)
		(fp_line
			(start -0.120396 0.3048)
			(end -0.120396 0.2794)
			(stroke
				(width 0.1)
				(type default)
			)
			(layer "B.Fab")
		)
		(fp_line
			(start -0.120396 0.2794)
			(end 0.12065 0.2794)
			(stroke
				(width 0.1)
				(type default)
			)
			(layer "B.Fab")
		)
		(fp_line
			(start -0.12065 -0.2794)
			(end -0.12065 -0.3048)
			(stroke
				(width 0.1)
				(type default)
			)
			(layer "B.Fab")
		)
		(fp_line
			(start -0.12065 -0.3048)
			(end -0.67945 -0.3048)
			(stroke
				(width 0.1)
				(type default)
			)
			(layer "B.Fab")
		)
		(fp_line
			(start -0.67945 0.3048)
			(end -0.120396 0.3048)
			(stroke
				(width 0.1)
				(type default)
			)
			(layer "B.Fab")
		)
		(fp_line
			(start -0.67945 -0.3048)
			(end -0.67945 0.3048)
			(stroke
				(width 0.1)
				(type default)
			)
			(layer "B.Fab")
		)
		(pad "1" smd circle
			(at 0.40005 0)
			(size 0 0)
			(layers "B.Cu" "B.Mask" "B.Paste")
			(net "UART_SYS_DBG_TX")
		)
		(pad "2" smd circle
			(at -0.40005 0)
			(size 0 0)
			(layers "B.Cu" "B.Mask" "B.Paste")
			(net "UART_SYS_DBG_TX_R")
		)
	)
	(footprint ""
		(layer "B.Cu")
		(at 57.884822 -72.621648)
		(property "Reference" "R788"
			(at 0 0 0)
			(layer "B.SilkS")
			(hide yes)
			(effects
				(font
					(size 1.27 1.27)
				)
				(justify mirror)
			)
		)
		(property "Value" ""
			(at 0 0 0)
			(layer "B.Fab")
			(effects
				(font
					(size 1.27 1.27)
				)
				(justify mirror)
			)
		)
		(duplicate_pad_numbers_are_jumpers no)
		(fp_line
			(start -0.7874 -0.4064)
			(end -0.7874 0.4064)
			(stroke
				(width 0.1524)
				(type default)
			)
			(layer "B.SilkS")
		)
		(fp_line
			(start -0.7874 0.4064)
			(end 0.7874 0.4064)
			(stroke
				(width 0.1524)
				(type default)
			)
			(layer "B.SilkS")
		)
		(fp_line
			(start 0.7874 -0.4064)
			(end -0.7874 -0.4064)
			(stroke
				(width 0.1524)
				(type default)
			)
			(layer "B.SilkS")
		)
		(fp_line
			(start 0.7874 0.4064)
			(end 0.7874 -0.4064)
			(stroke
				(width 0.1524)
				(type default)
			)
			(layer "B.SilkS")
		)
		(fp_line
			(start -0.67945 -0.3048)
			(end -0.67945 0.3048)
			(stroke
				(width 0.1)
				(type default)
			)
			(layer "B.Fab")
		)
		(fp_line
			(start -0.67945 0.3048)
			(end -0.120396 0.3048)
			(stroke
				(width 0.1)
				(type default)
			)
			(layer "B.Fab")
		)
		(fp_line
			(start -0.12065 -0.3048)
			(end -0.67945 -0.3048)
			(stroke
				(width 0.1)
				(type default)
			)
			(layer "B.Fab")
		)
		(fp_line
			(start -0.12065 -0.2794)
			(end -0.12065 -0.3048)
			(stroke
				(width 0.1)
				(type default)
			)
			(layer "B.Fab")
		)
		(fp_line
			(start -0.120396 0.2794)
			(end 0.12065 0.2794)
			(stroke
				(width 0.1)
				(type default)
			)
			(layer "B.Fab")
		)
		(fp_line
			(start -0.120396 0.3048)
			(end -0.120396 0.2794)
			(stroke
				(width 0.1)
				(type default)
			)
			(layer "B.Fab")
		)
		(fp_line
			(start 0.12065 -0.305054)
			(end 0.12065 -0.2794)
			(stroke
				(width 0.1)
				(type default)
			)
			(layer "B.Fab")
		)
		(fp_line
			(start 0.12065 -0.2794)
			(end -0.12065 -0.2794)
			(stroke
				(width 0.1)
				(type default)
			)
			(layer "B.Fab")
		)
		(fp_line
			(start 0.12065 0.2794)
			(end 0.12065 0.3048)
			(stroke
				(width 0.1)
				(type default)
			)
			(layer "B.Fab")
		)
		(fp_line
			(start 0.12065 0.3048)
			(end 0.67945 0.3048)
			(stroke
				(width 0.1)
				(type default)
			)
			(layer "B.Fab")
		)
		(fp_line
			(start 0.67945 -0.305054)
			(end 0.12065 -0.305054)
			(stroke
				(width 0.1)
				(type default)
			)
			(layer "B.Fab")
		)
		(fp_line
			(start 0.67945 0.3048)
			(end 0.67945 -0.305054)
			(stroke
				(width 0.1)
				(type default)
			)
			(layer "B.Fab")
		)
		(pad "1" smd circle
			(at 0.40005 0 180)
			(size 0 0)
			(layers "B.Cu" "B.Mask" "B.Paste")
			(net "P5V_SENSOR")
		)
		(pad "2" smd circle
			(at -0.40005 0 180)
			(size 0 0)
			(layers "B.Cu" "B.Mask" "B.Paste")
			(net "GND")
		)
	)
	(footprint ""
		(layer "B.Cu")
		(at 51.55946 -61.852048 90)
		(property "Reference" "C135"
			(at 0 0 90)
			(layer "B.SilkS")
			(hide yes)
			(effects
				(font
					(size 1.27 1.27)
				)
				(justify mirror)
			)
		)
		(property "Value" ""
			(at 0 0 90)
			(layer "B.Fab")
			(effects
				(font
					(size 1.27 1.27)
				)
				(justify mirror)
			)
		)
		(duplicate_pad_numbers_are_jumpers no)
		(fp_line
			(start 0.7874 -0.4064)
			(end -0.7874 -0.4064)
			(stroke
				(width 0.1524)
				(type default)
			)
			(layer "B.SilkS")
		)
		(fp_line
			(start -0.7874 -0.4064)
			(end -0.7874 0.4064)
			(stroke
				(width 0.1524)
				(type default)
			)
			(layer "B.SilkS")
		)
		(fp_line
			(start 0.7874 0.4064)
			(end 0.7874 -0.4064)
			(stroke
				(width 0.1524)
				(type default)
			)
			(layer "B.SilkS")
		)
		(fp_line
			(start -0.7874 0.4064)
			(end 0.7874 0.4064)
			(stroke
				(width 0.1524)
				(type default)
			)
			(layer "B.SilkS")
		)
		(fp_line
			(start 0.67945 -0.305054)
			(end 0.12065 -0.305054)
			(stroke
				(width 0.1)
				(type default)
			)
			(layer "B.Fab")
		)
		(fp_line
			(start 0.12065 -0.305054)
			(end 0.12065 -0.2794)
			(stroke
				(width 0.1)
				(type default)
			)
			(layer "B.Fab")
		)
		(fp_line
			(start -0.12065 -0.3048)
			(end -0.67945 -0.3048)
			(stroke
				(width 0.1)
				(type default)
			)
			(layer "B.Fab")
		)
		(fp_line
			(start -0.67945 -0.3048)
			(end -0.67945 0.3048)
			(stroke
				(width 0.1)
				(type default)
			)
			(layer "B.Fab")
		)
		(fp_line
			(start 0.12065 -0.2794)
			(end -0.12065 -0.2794)
			(stroke
				(width 0.1)
				(type default)
			)
			(layer "B.Fab")
		)
		(fp_line
			(start -0.12065 -0.2794)
			(end -0.12065 -0.3048)
			(stroke
				(width 0.1)
				(type default)
			)
			(layer "B.Fab")
		)
		(fp_line
			(start 0.12065 0.2794)
			(end 0.12065 0.3048)
			(stroke
				(width 0.1)
				(type default)
			)
			(layer "B.Fab")
		)
		(fp_line
			(start -0.120396 0.2794)
			(end 0.12065 0.2794)
			(stroke
				(width 0.1)
				(type default)
			)
			(layer "B.Fab")
		)
		(fp_line
			(start 0.67945 0.3048)
			(end 0.67945 -0.305054)
			(stroke
				(width 0.1)
				(type default)
			)
			(layer "B.Fab")
		)
		(fp_line
			(start 0.12065 0.3048)
			(end 0.67945 0.3048)
			(stroke
				(width 0.1)
				(type default)
			)
			(layer "B.Fab")
		)
		(fp_line
			(start -0.120396 0.3048)
			(end -0.120396 0.2794)
			(stroke
				(width 0.1)
				(type default)
			)
			(layer "B.Fab")
		)
		(fp_line
			(start -0.67945 0.3048)
			(end -0.120396 0.3048)
			(stroke
				(width 0.1)
				(type default)
			)
			(layer "B.Fab")
		)
		(pad "1" smd circle
			(at 0.40005 0 270)
			(size 0 0)
			(layers "B.Cu" "B.Mask" "B.Paste")
			(net "GND")
		)
		(pad "2" smd circle
			(at -0.40005 0 270)
			(size 0 0)
			(layers "B.Cu" "B.Mask" "B.Paste")
			(net "A_BMC_ADCVREFP1")
		)
	)
	(footprint ""
		(layer "B.Cu")
		(at 62.103 -54.61 -90)
		(property "Reference" "C87"
			(at 0 0 90)
			(layer "B.SilkS")
			(hide yes)
			(effects
				(font
					(size 1.27 1.27)
				)
				(justify mirror)
			)
		)
		(property "Value" ""
			(at 0 0 90)
			(layer "B.Fab")
			(effects
				(font
					(size 1.27 1.27)
				)
				(justify mirror)
			)
		)
		(duplicate_pad_numbers_are_jumpers no)
		(fp_line
			(start -0.7874 0.4064)
			(end 0.7874 0.4064)
			(stroke
				(width 0.1524)
				(type default)
			)
			(layer "B.SilkS")
		)
		(fp_line
			(start 0.7874 0.4064)
			(end 0.7874 -0.4064)
			(stroke
				(width 0.1524)
				(type default)
			)
			(layer "B.SilkS")
		)
		(fp_line
			(start -0.7874 -0.4064)
			(end -0.7874 0.4064)
			(stroke
				(width 0.1524)
				(type default)
			)
			(layer "B.SilkS")
		)
		(fp_line
			(start 0.7874 -0.4064)
			(end -0.7874 -0.4064)
			(stroke
				(width 0.1524)
				(type default)
			)
			(layer "B.SilkS")
		)
		(fp_line
			(start -0.67945 0.3048)
			(end -0.120396 0.3048)
			(stroke
				(width 0.1)
				(type default)
			)
			(layer "B.Fab")
		)
		(fp_line
			(start -0.120396 0.3048)
			(end -0.120396 0.2794)
			(stroke
				(width 0.1)
				(type default)
			)
			(layer "B.Fab")
		)
		(fp_line
			(start 0.12065 0.3048)
			(end 0.67945 0.3048)
			(stroke
				(width 0.1)
				(type default)
			)
			(layer "B.Fab")
		)
		(fp_line
			(start 0.67945 0.3048)
			(end 0.67945 -0.305054)
			(stroke
				(width 0.1)
				(type default)
			)
			(layer "B.Fab")
		)
		(fp_line
			(start -0.120396 0.2794)
			(end 0.12065 0.2794)
			(stroke
				(width 0.1)
				(type default)
			)
			(layer "B.Fab")
		)
		(fp_line
			(start 0.12065 0.2794)
			(end 0.12065 0.3048)
			(stroke
				(width 0.1)
				(type default)
			)
			(layer "B.Fab")
		)
		(fp_line
			(start -0.12065 -0.2794)
			(end -0.12065 -0.3048)
			(stroke
				(width 0.1)
				(type default)
			)
			(layer "B.Fab")
		)
		(fp_line
			(start 0.12065 -0.2794)
			(end -0.12065 -0.2794)
			(stroke
				(width 0.1)
				(type default)
			)
			(layer "B.Fab")
		)
		(fp_line
			(start -0.67945 -0.3048)
			(end -0.67945 0.3048)
			(stroke
				(width 0.1)
				(type default)
			)
			(layer "B.Fab")
		)
		(fp_line
			(start -0.12065 -0.3048)
			(end -0.67945 -0.3048)
			(stroke
				(width 0.1)
				(type default)
			)
			(layer "B.Fab")
		)
		(fp_line
			(start 0.12065 -0.305054)
			(end 0.12065 -0.2794)
			(stroke
				(width 0.1)
				(type default)
			)
			(layer "B.Fab")
		)
		(fp_line
			(start 0.67945 -0.305054)
			(end 0.12065 -0.305054)
			(stroke
				(width 0.1)
				(type default)
			)
			(layer "B.Fab")
		)
		(pad "1" smd circle
			(at 0.40005 0 90)
			(size 0 0)
			(layers "B.Cu" "B.Mask" "B.Paste")
			(net "P1V8_AUX")
		)
		(pad "2" smd circle
			(at -0.40005 0 90)
			(size 0 0)
			(layers "B.Cu" "B.Mask" "B.Paste")
			(net "GND")
		)
	)
	(footprint ""
		(layer "B.Cu")
		(at 56.710326 -60.8076 90)
		(property "Reference" "R801"
			(at 0 0 90)
			(layer "B.SilkS")
			(hide yes)
			(effects
				(font
					(size 1.27 1.27)
				)
				(justify mirror)
			)
		)
		(property "Value" ""
			(at 0 0 90)
			(layer "B.Fab")
			(effects
				(font
					(size 1.27 1.27)
				)
				(justify mirror)
			)
		)
		(duplicate_pad_numbers_are_jumpers no)
		(fp_line
			(start 0.7874 -0.4064)
			(end -0.7874 -0.4064)
			(stroke
				(width 0.1524)
				(type default)
			)
			(layer "B.SilkS")
		)
		(fp_line
			(start -0.7874 -0.4064)
			(end -0.7874 0.4064)
			(stroke
				(width 0.1524)
				(type default)
			)
			(layer "B.SilkS")
		)
		(fp_line
			(start 0.7874 0.4064)
			(end 0.7874 -0.4064)
			(stroke
				(width 0.1524)
				(type default)
			)
			(layer "B.SilkS")
		)
		(fp_line
			(start -0.7874 0.4064)
			(end 0.7874 0.4064)
			(stroke
				(width 0.1524)
				(type default)
			)
			(layer "B.SilkS")
		)
		(fp_line
			(start 0.67945 -0.305054)
			(end 0.12065 -0.305054)
			(stroke
				(width 0.1)
				(type default)
			)
			(layer "B.Fab")
		)
		(fp_line
			(start 0.12065 -0.305054)
			(end 0.12065 -0.2794)
			(stroke
				(width 0.1)
				(type default)
			)
			(layer "B.Fab")
		)
		(fp_line
			(start -0.12065 -0.3048)
			(end -0.67945 -0.3048)
			(stroke
				(width 0.1)
				(type default)
			)
			(layer "B.Fab")
		)
		(fp_line
			(start -0.67945 -0.3048)
			(end -0.67945 0.3048)
			(stroke
				(width 0.1)
				(type default)
			)
			(layer "B.Fab")
		)
		(fp_line
			(start 0.12065 -0.2794)
			(end -0.12065 -0.2794)
			(stroke
				(width 0.1)
				(type default)
			)
			(layer "B.Fab")
		)
		(fp_line
			(start -0.12065 -0.2794)
			(end -0.12065 -0.3048)
			(stroke
				(width 0.1)
				(type default)
			)
			(layer "B.Fab")
		)
		(fp_line
			(start 0.12065 0.2794)
			(end 0.12065 0.3048)
			(stroke
				(width 0.1)
				(type default)
			)
			(layer "B.Fab")
		)
		(fp_line
			(start -0.120396 0.2794)
			(end 0.12065 0.2794)
			(stroke
				(width 0.1)
				(type default)
			)
			(layer "B.Fab")
		)
		(fp_line
			(start 0.67945 0.3048)
			(end 0.67945 -0.305054)
			(stroke
				(width 0.1)
				(type default)
			)
			(layer "B.Fab")
		)
		(fp_line
			(start 0.12065 0.3048)
			(end 0.67945 0.3048)
			(stroke
				(width 0.1)
				(type default)
			)
			(layer "B.Fab")
		)
		(fp_line
			(start -0.120396 0.3048)
			(end -0.120396 0.2794)
			(stroke
				(width 0.1)
				(type default)
			)
			(layer "B.Fab")
		)
		(fp_line
			(start -0.67945 0.3048)
			(end -0.120396 0.3048)
			(stroke
				(width 0.1)
				(type default)
			)
			(layer "B.Fab")
		)
		(pad "1" smd circle
			(at 0.40005 0 270)
			(size 0 0)
			(layers "B.Cu" "B.Mask" "B.Paste")
			(net "SPI_BMC_BOOT_CS0_R_N")
		)
		(pad "2" smd circle
			(at -0.40005 0 270)
			(size 0 0)
			(layers "B.Cu" "B.Mask" "B.Paste")
			(net "SPI_BMC_BOOT_CS0_R1_N")
		)
	)
	(footprint ""
		(layer "B.Cu")
		(at 65.0494 -28.3464 90)
		(property "Reference" "R204"
			(at 0 0 90)
			(layer "B.SilkS")
			(hide yes)
			(effects
				(font
					(size 1.27 1.27)
				)
				(justify mirror)
			)
		)
		(property "Value" ""
			(at 0 0 90)
			(layer "B.Fab")
			(effects
				(font
					(size 1.27 1.27)
				)
				(justify mirror)
			)
		)
		(duplicate_pad_numbers_are_jumpers no)
		(fp_line
			(start 0.7874 -0.4064)
			(end -0.7874 -0.4064)
			(stroke
				(width 0.1524)
				(type default)
			)
			(layer "B.SilkS")
		)
		(fp_line
			(start -0.7874 -0.4064)
			(end -0.7874 0.4064)
			(stroke
				(width 0.1524)
				(type default)
			)
			(layer "B.SilkS")
		)
		(fp_line
			(start 0.7874 0.4064)
			(end 0.7874 -0.4064)
			(stroke
				(width 0.1524)
				(type default)
			)
			(layer "B.SilkS")
		)
		(fp_line
			(start -0.7874 0.4064)
			(end 0.7874 0.4064)
			(stroke
				(width 0.1524)
				(type default)
			)
			(layer "B.SilkS")
		)
		(fp_line
			(start 0.67945 -0.305054)
			(end 0.12065 -0.305054)
			(stroke
				(width 0.1)
				(type default)
			)
			(layer "B.Fab")
		)
		(fp_line
			(start 0.12065 -0.305054)
			(end 0.12065 -0.2794)
			(stroke
				(width 0.1)
				(type default)
			)
			(layer "B.Fab")
		)
		(fp_line
			(start -0.12065 -0.3048)
			(end -0.67945 -0.3048)
			(stroke
				(width 0.1)
				(type default)
			)
			(layer "B.Fab")
		)
		(fp_line
			(start -0.67945 -0.3048)
			(end -0.67945 0.3048)
			(stroke
				(width 0.1)
				(type default)
			)
			(layer "B.Fab")
		)
		(fp_line
			(start 0.12065 -0.2794)
			(end -0.12065 -0.2794)
			(stroke
				(width 0.1)
				(type default)
			)
			(layer "B.Fab")
		)
		(fp_line
			(start -0.12065 -0.2794)
			(end -0.12065 -0.3048)
			(stroke
				(width 0.1)
				(type default)
			)
			(layer "B.Fab")
		)
		(fp_line
			(start 0.12065 0.2794)
			(end 0.12065 0.3048)
			(stroke
				(width 0.1)
				(type default)
			)
			(layer "B.Fab")
		)
		(fp_line
			(start -0.120396 0.2794)
			(end 0.12065 0.2794)
			(stroke
				(width 0.1)
				(type default)
			)
			(layer "B.Fab")
		)
		(fp_line
			(start 0.67945 0.3048)
			(end 0.67945 -0.305054)
			(stroke
				(width 0.1)
				(type default)
			)
			(layer "B.Fab")
		)
		(fp_line
			(start 0.12065 0.3048)
			(end 0.67945 0.3048)
			(stroke
				(width 0.1)
				(type default)
			)
			(layer "B.Fab")
		)
		(fp_line
			(start -0.120396 0.3048)
			(end -0.120396 0.2794)
			(stroke
				(width 0.1)
				(type default)
			)
			(layer "B.Fab")
		)
		(fp_line
			(start -0.67945 0.3048)
			(end -0.120396 0.3048)
			(stroke
				(width 0.1)
				(type default)
			)
			(layer "B.Fab")
		)
		(pad "1" smd circle
			(at 0.40005 0 270)
			(size 0 0)
			(layers "B.Cu" "B.Mask" "B.Paste")
			(net "P3V3_RGM")
		)
		(pad "2" smd circle
			(at -0.40005 0 270)
			(size 0 0)
			(layers "B.Cu" "B.Mask" "B.Paste")
			(net "JTAG_SCM_TDI")
		)
	)
	(footprint ""
		(layer "B.Cu")
		(at 53.8734 -63.1952 -90)
		(property "Reference" "R722"
			(at 0 0 90)
			(layer "B.SilkS")
			(hide yes)
			(effects
				(font
					(size 1.27 1.27)
				)
				(justify mirror)
			)
		)
		(property "Value" ""
			(at 0 0 90)
			(layer "B.Fab")
			(effects
				(font
					(size 1.27 1.27)
				)
				(justify mirror)
			)
		)
		(duplicate_pad_numbers_are_jumpers no)
		(fp_line
			(start -0.7874 0.4064)
			(end 0.7874 0.4064)
			(stroke
				(width 0.1524)
				(type default)
			)
			(layer "B.SilkS")
		)
		(fp_line
			(start 0.7874 0.4064)
			(end 0.7874 -0.4064)
			(stroke
				(width 0.1524)
				(type default)
			)
			(layer "B.SilkS")
		)
		(fp_line
			(start -0.7874 -0.4064)
			(end -0.7874 0.4064)
			(stroke
				(width 0.1524)
				(type default)
			)
			(layer "B.SilkS")
		)
		(fp_line
			(start 0.7874 -0.4064)
			(end -0.7874 -0.4064)
			(stroke
				(width 0.1524)
				(type default)
			)
			(layer "B.SilkS")
		)
		(fp_line
			(start -0.67945 0.3048)
			(end -0.120396 0.3048)
			(stroke
				(width 0.1)
				(type default)
			)
			(layer "B.Fab")
		)
		(fp_line
			(start -0.120396 0.3048)
			(end -0.120396 0.2794)
			(stroke
				(width 0.1)
				(type default)
			)
			(layer "B.Fab")
		)
		(fp_line
			(start 0.12065 0.3048)
			(end 0.67945 0.3048)
			(stroke
				(width 0.1)
				(type default)
			)
			(layer "B.Fab")
		)
		(fp_line
			(start 0.67945 0.3048)
			(end 0.67945 -0.305054)
			(stroke
				(width 0.1)
				(type default)
			)
			(layer "B.Fab")
		)
		(fp_line
			(start -0.120396 0.2794)
			(end 0.12065 0.2794)
			(stroke
				(width 0.1)
				(type default)
			)
			(layer "B.Fab")
		)
		(fp_line
			(start 0.12065 0.2794)
			(end 0.12065 0.3048)
			(stroke
				(width 0.1)
				(type default)
			)
			(layer "B.Fab")
		)
		(fp_line
			(start -0.12065 -0.2794)
			(end -0.12065 -0.3048)
			(stroke
				(width 0.1)
				(type default)
			)
			(layer "B.Fab")
		)
		(fp_line
			(start 0.12065 -0.2794)
			(end -0.12065 -0.2794)
			(stroke
				(width 0.1)
				(type default)
			)
			(layer "B.Fab")
		)
		(fp_line
			(start -0.67945 -0.3048)
			(end -0.67945 0.3048)
			(stroke
				(width 0.1)
				(type default)
			)
			(layer "B.Fab")
		)
		(fp_line
			(start -0.12065 -0.3048)
			(end -0.67945 -0.3048)
			(stroke
				(width 0.1)
				(type default)
			)
			(layer "B.Fab")
		)
		(fp_line
			(start 0.12065 -0.305054)
			(end 0.12065 -0.2794)
			(stroke
				(width 0.1)
				(type default)
			)
			(layer "B.Fab")
		)
		(fp_line
			(start 0.67945 -0.305054)
			(end 0.12065 -0.305054)
			(stroke
				(width 0.1)
				(type default)
			)
			(layer "B.Fab")
		)
		(pad "1" smd circle
			(at 0.40005 0 90)
			(size 0 0)
			(layers "B.Cu" "B.Mask" "B.Paste")
			(net "FM_SLPS3_GF_R1_N")
		)
		(pad "2" smd circle
			(at -0.40005 0 90)
			(size 0 0)
			(layers "B.Cu" "B.Mask" "B.Paste")
			(net "FM_SLPS3_GF_N")
		)
	)
	(footprint ""
		(layer "B.Cu")
		(at 46.3804 -105.7783 90)
		(property "Reference" "C196"
			(at 0 0 90)
			(layer "B.SilkS")
			(hide yes)
			(effects
				(font
					(size 1.27 1.27)
				)
				(justify mirror)
			)
		)
		(property "Value" ""
			(at 0 0 90)
			(layer "B.Fab")
			(effects
				(font
					(size 1.27 1.27)
				)
				(justify mirror)
			)
		)
		(duplicate_pad_numbers_are_jumpers no)
		(fp_line
			(start 0.7874 -0.4064)
			(end -0.7874 -0.4064)
			(stroke
				(width 0.1524)
				(type default)
			)
			(layer "B.SilkS")
		)
		(fp_line
			(start -0.7874 -0.4064)
			(end -0.7874 0.4064)
			(stroke
				(width 0.1524)
				(type default)
			)
			(layer "B.SilkS")
		)
		(fp_line
			(start 0.7874 0.4064)
			(end 0.7874 -0.4064)
			(stroke
				(width 0.1524)
				(type default)
			)
			(layer "B.SilkS")
		)
		(fp_line
			(start -0.7874 0.4064)
			(end 0.7874 0.4064)
			(stroke
				(width 0.1524)
				(type default)
			)
			(layer "B.SilkS")
		)
		(fp_line
			(start 0.67945 -0.305054)
			(end 0.12065 -0.305054)
			(stroke
				(width 0.1)
				(type default)
			)
			(layer "B.Fab")
		)
		(fp_line
			(start 0.12065 -0.305054)
			(end 0.12065 -0.2794)
			(stroke
				(width 0.1)
				(type default)
			)
			(layer "B.Fab")
		)
		(fp_line
			(start -0.12065 -0.3048)
			(end -0.67945 -0.3048)
			(stroke
				(width 0.1)
				(type default)
			)
			(layer "B.Fab")
		)
		(fp_line
			(start -0.67945 -0.3048)
			(end -0.67945 0.3048)
			(stroke
				(width 0.1)
				(type default)
			)
			(layer "B.Fab")
		)
		(fp_line
			(start 0.12065 -0.2794)
			(end -0.12065 -0.2794)
			(stroke
				(width 0.1)
				(type default)
			)
			(layer "B.Fab")
		)
		(fp_line
			(start -0.12065 -0.2794)
			(end -0.12065 -0.3048)
			(stroke
				(width 0.1)
				(type default)
			)
			(layer "B.Fab")
		)
		(fp_line
			(start 0.12065 0.2794)
			(end 0.12065 0.3048)
			(stroke
				(width 0.1)
				(type default)
			)
			(layer "B.Fab")
		)
		(fp_line
			(start -0.120396 0.2794)
			(end 0.12065 0.2794)
			(stroke
				(width 0.1)
				(type default)
			)
			(layer "B.Fab")
		)
		(fp_line
			(start 0.67945 0.3048)
			(end 0.67945 -0.305054)
			(stroke
				(width 0.1)
				(type default)
			)
			(layer "B.Fab")
		)
		(fp_line
			(start 0.12065 0.3048)
			(end 0.67945 0.3048)
			(stroke
				(width 0.1)
				(type default)
			)
			(layer "B.Fab")
		)
		(fp_line
			(start -0.120396 0.3048)
			(end -0.120396 0.2794)
			(stroke
				(width 0.1)
				(type default)
			)
			(layer "B.Fab")
		)
		(fp_line
			(start -0.67945 0.3048)
			(end -0.120396 0.3048)
			(stroke
				(width 0.1)
				(type default)
			)
			(layer "B.Fab")
		)
		(pad "1" smd circle
			(at 0.40005 0 270)
			(size 0 0)
			(layers "B.Cu" "B.Mask" "B.Paste")
			(net "P3V3_RTC_AUX")
		)
		(pad "2" smd circle
			(at -0.40005 0 270)
			(size 0 0)
			(layers "B.Cu" "B.Mask" "B.Paste")
			(net "GND")
		)
	)
	(footprint ""
		(layer "B.Cu")
		(at 72.13346 -65.40627 90)
		(property "Reference" "L16"
			(at 0 0 90)
			(layer "B.SilkS")
			(hide yes)
			(effects
				(font
					(size 1.27 1.27)
				)
				(justify mirror)
			)
		)
		(property "Value" ""
			(at 0 0 90)
			(layer "B.Fab")
			(effects
				(font
					(size 1.27 1.27)
				)
				(justify mirror)
			)
		)
		(duplicate_pad_numbers_are_jumpers no)
		(fp_line
			(start 1.27 -0.5842)
			(end -1.27 -0.5842)
			(stroke
				(width 0.1524)
				(type default)
			)
			(layer "B.SilkS")
		)
		(fp_line
			(start 1.27 -0.5588)
			(end 1.27 -0.5842)
			(stroke
				(width 0.1524)
				(type default)
			)
			(layer "B.SilkS")
		)
		(fp_line
			(start 1.27 0.5842)
			(end 1.27 -0.5842)
			(stroke
				(width 0.1524)
				(type default)
			)
			(layer "B.SilkS")
		)
		(fp_line
			(start 0.127 0.5842)
			(end 0.127 -0.5842)
			(stroke
				(width 0.1524)
				(type default)
			)
			(layer "B.SilkS")
		)
		(fp_line
			(start -0.127 0.5842)
			(end -0.127 -0.5842)
			(stroke
				(width 0.1524)
				(type default)
			)
			(layer "B.SilkS")
		)
		(fp_line
			(start -1.27 0.5842)
			(end -1.27 -0.5842)
			(stroke
				(width 0.1524)
				(type default)
			)
			(layer "B.SilkS")
		)
		(fp_line
			(start -1.27 0.5842)
			(end 1.27 0.5842)
			(stroke
				(width 0.1524)
				(type default)
			)
			(layer "B.SilkS")
		)
		(fp_line
			(start 0.9144 -0.508)
			(end -0.9144 -0.508)
			(stroke
				(width 0.1)
				(type default)
			)
			(layer "B.Fab")
		)
		(fp_line
			(start -0.9144 -0.508)
			(end -0.9144 -0.406654)
			(stroke
				(width 0.1)
				(type default)
			)
			(layer "B.Fab")
		)
		(fp_line
			(start 1.194308 -0.406654)
			(end 0.9144 -0.406654)
			(stroke
				(width 0.1)
				(type default)
			)
			(layer "B.Fab")
		)
		(fp_line
			(start 0.9144 -0.406654)
			(end 0.9144 -0.508)
			(stroke
				(width 0.1)
				(type default)
			)
			(layer "B.Fab")
		)
		(fp_line
			(start -0.9144 -0.406654)
			(end -1.1938 -0.406654)
			(stroke
				(width 0.1)
				(type default)
			)
			(layer "B.Fab")
		)
		(fp_line
			(start -1.1938 -0.406654)
			(end -1.1938 0.4064)
			(stroke
				(width 0.1)
				(type default)
			)
			(layer "B.Fab")
		)
		(fp_line
			(start -0.9144 0.4064)
			(end -0.9144 0.508)
			(stroke
				(width 0.1)
				(type default)
			)
			(layer "B.Fab")
		)
		(fp_line
			(start -1.1938 0.4064)
			(end -0.9144 0.4064)
			(stroke
				(width 0.1)
				(type default)
			)
			(layer "B.Fab")
		)
		(fp_line
			(start 1.194308 0.406654)
			(end 1.194308 -0.406654)
			(stroke
				(width 0.1)
				(type default)
			)
			(layer "B.Fab")
		)
		(fp_line
			(start 0.9144 0.406654)
			(end 1.194308 0.406654)
			(stroke
				(width 0.1)
				(type default)
			)
			(layer "B.Fab")
		)
		(fp_line
			(start 0.9144 0.508)
			(end 0.9144 0.406654)
			(stroke
				(width 0.1)
				(type default)
			)
			(layer "B.Fab")
		)
		(fp_line
			(start -0.9144 0.508)
			(end 0.9144 0.508)
			(stroke
				(width 0.1)
				(type default)
			)
			(layer "B.Fab")
		)
		(pad "1" smd rect
			(at 0.7366 0)
			(size 0.7112 0.8128)
			(layers "B.Cu" "B.Mask" "B.Paste")
			(net "P1V8_AUX")
		)
		(pad "2" smd rect
			(at -0.7366 0)
			(size 0.7112 0.8128)
			(layers "B.Cu" "B.Mask" "B.Paste")
			(net "P1V8_STBY_DP_VCC18A")
		)
	)
	(footprint ""
		(layer "B.Cu")
		(at 58.7375 -63.2333 -90)
		(property "Reference" "R458"
			(at 0 0 90)
			(layer "B.SilkS")
			(hide yes)
			(effects
				(font
					(size 1.27 1.27)
				)
				(justify mirror)
			)
		)
		(property "Value" ""
			(at 0 0 90)
			(layer "B.Fab")
			(effects
				(font
					(size 1.27 1.27)
				)
				(justify mirror)
			)
		)
		(duplicate_pad_numbers_are_jumpers no)
		(fp_line
			(start -0.7874 0.4064)
			(end 0.7874 0.4064)
			(stroke
				(width 0.1524)
				(type default)
			)
			(layer "B.SilkS")
		)
		(fp_line
			(start 0.7874 0.4064)
			(end 0.7874 -0.4064)
			(stroke
				(width 0.1524)
				(type default)
			)
			(layer "B.SilkS")
		)
		(fp_line
			(start -0.7874 -0.4064)
			(end -0.7874 0.4064)
			(stroke
				(width 0.1524)
				(type default)
			)
			(layer "B.SilkS")
		)
		(fp_line
			(start 0.7874 -0.4064)
			(end -0.7874 -0.4064)
			(stroke
				(width 0.1524)
				(type default)
			)
			(layer "B.SilkS")
		)
		(fp_line
			(start -0.67945 0.3048)
			(end -0.120396 0.3048)
			(stroke
				(width 0.1)
				(type default)
			)
			(layer "B.Fab")
		)
		(fp_line
			(start -0.120396 0.3048)
			(end -0.120396 0.2794)
			(stroke
				(width 0.1)
				(type default)
			)
			(layer "B.Fab")
		)
		(fp_line
			(start 0.12065 0.3048)
			(end 0.67945 0.3048)
			(stroke
				(width 0.1)
				(type default)
			)
			(layer "B.Fab")
		)
		(fp_line
			(start 0.67945 0.3048)
			(end 0.67945 -0.305054)
			(stroke
				(width 0.1)
				(type default)
			)
			(layer "B.Fab")
		)
		(fp_line
			(start -0.120396 0.2794)
			(end 0.12065 0.2794)
			(stroke
				(width 0.1)
				(type default)
			)
			(layer "B.Fab")
		)
		(fp_line
			(start 0.12065 0.2794)
			(end 0.12065 0.3048)
			(stroke
				(width 0.1)
				(type default)
			)
			(layer "B.Fab")
		)
		(fp_line
			(start -0.12065 -0.2794)
			(end -0.12065 -0.3048)
			(stroke
				(width 0.1)
				(type default)
			)
			(layer "B.Fab")
		)
		(fp_line
			(start 0.12065 -0.2794)
			(end -0.12065 -0.2794)
			(stroke
				(width 0.1)
				(type default)
			)
			(layer "B.Fab")
		)
		(fp_line
			(start -0.67945 -0.3048)
			(end -0.67945 0.3048)
			(stroke
				(width 0.1)
				(type default)
			)
			(layer "B.Fab")
		)
		(fp_line
			(start -0.12065 -0.3048)
			(end -0.67945 -0.3048)
			(stroke
				(width 0.1)
				(type default)
			)
			(layer "B.Fab")
		)
		(fp_line
			(start 0.12065 -0.305054)
			(end 0.12065 -0.2794)
			(stroke
				(width 0.1)
				(type default)
			)
			(layer "B.Fab")
		)
		(fp_line
			(start 0.67945 -0.305054)
			(end 0.12065 -0.305054)
			(stroke
				(width 0.1)
				(type default)
			)
			(layer "B.Fab")
		)
		(pad "1" smd circle
			(at 0.40005 0 90)
			(size 0 0)
			(layers "B.Cu" "B.Mask" "B.Paste")
			(net "FM_DEBUG_PORT_PRSNT_R1_N")
		)
		(pad "2" smd circle
			(at -0.40005 0 90)
			(size 0 0)
			(layers "B.Cu" "B.Mask" "B.Paste")
			(net "FM_DEBUG_PORT_PRSNT_N")
		)
	)
	(footprint ""
		(layer "B.Cu")
		(at 46.21784 -24.1173 90)
		(property "Reference" "R295"
			(at 0 0 90)
			(layer "B.SilkS")
			(hide yes)
			(effects
				(font
					(size 1.27 1.27)
				)
				(justify mirror)
			)
		)
		(property "Value" ""
			(at 0 0 90)
			(layer "B.Fab")
			(effects
				(font
					(size 1.27 1.27)
				)
				(justify mirror)
			)
		)
		(duplicate_pad_numbers_are_jumpers no)
		(fp_line
			(start 0.7874 -0.4064)
			(end -0.7874 -0.4064)
			(stroke
				(width 0.1524)
				(type default)
			)
			(layer "B.SilkS")
		)
		(fp_line
			(start -0.7874 -0.4064)
			(end -0.7874 0.4064)
			(stroke
				(width 0.1524)
				(type default)
			)
			(layer "B.SilkS")
		)
		(fp_line
			(start 0.7874 0.4064)
			(end 0.7874 -0.4064)
			(stroke
				(width 0.1524)
				(type default)
			)
			(layer "B.SilkS")
		)
		(fp_line
			(start -0.7874 0.4064)
			(end 0.7874 0.4064)
			(stroke
				(width 0.1524)
				(type default)
			)
			(layer "B.SilkS")
		)
		(fp_line
			(start 0.67945 -0.305054)
			(end 0.12065 -0.305054)
			(stroke
				(width 0.1)
				(type default)
			)
			(layer "B.Fab")
		)
		(fp_line
			(start 0.12065 -0.305054)
			(end 0.12065 -0.2794)
			(stroke
				(width 0.1)
				(type default)
			)
			(layer "B.Fab")
		)
		(fp_line
			(start -0.12065 -0.3048)
			(end -0.67945 -0.3048)
			(stroke
				(width 0.1)
				(type default)
			)
			(layer "B.Fab")
		)
		(fp_line
			(start -0.67945 -0.3048)
			(end -0.67945 0.3048)
			(stroke
				(width 0.1)
				(type default)
			)
			(layer "B.Fab")
		)
		(fp_line
			(start 0.12065 -0.2794)
			(end -0.12065 -0.2794)
			(stroke
				(width 0.1)
				(type default)
			)
			(layer "B.Fab")
		)
		(fp_line
			(start -0.12065 -0.2794)
			(end -0.12065 -0.3048)
			(stroke
				(width 0.1)
				(type default)
			)
			(layer "B.Fab")
		)
		(fp_line
			(start 0.12065 0.2794)
			(end 0.12065 0.3048)
			(stroke
				(width 0.1)
				(type default)
			)
			(layer "B.Fab")
		)
		(fp_line
			(start -0.120396 0.2794)
			(end 0.12065 0.2794)
			(stroke
				(width 0.1)
				(type default)
			)
			(layer "B.Fab")
		)
		(fp_line
			(start 0.67945 0.3048)
			(end 0.67945 -0.305054)
			(stroke
				(width 0.1)
				(type default)
			)
			(layer "B.Fab")
		)
		(fp_line
			(start 0.12065 0.3048)
			(end 0.67945 0.3048)
			(stroke
				(width 0.1)
				(type default)
			)
			(layer "B.Fab")
		)
		(fp_line
			(start -0.120396 0.3048)
			(end -0.120396 0.2794)
			(stroke
				(width 0.1)
				(type default)
			)
			(layer "B.Fab")
		)
		(fp_line
			(start -0.67945 0.3048)
			(end -0.120396 0.3048)
			(stroke
				(width 0.1)
				(type default)
			)
			(layer "B.Fab")
		)
		(pad "1" smd circle
			(at 0.40005 0 270)
			(size 0 0)
			(layers "B.Cu" "B.Mask" "B.Paste")
			(net "P3V3_AUX")
		)
		(pad "2" smd circle
			(at -0.40005 0 270)
			(size 0 0)
			(layers "B.Cu" "B.Mask" "B.Paste")
			(net "DEBUG_PORT_PRSNT_BUF_R_EN")
		)
	)
	(footprint ""
		(layer "B.Cu")
		(at 16.764 -70.104 90)
		(property "Reference" "R299"
			(at 0 0 90)
			(layer "B.SilkS")
			(hide yes)
			(effects
				(font
					(size 1.27 1.27)
				)
				(justify mirror)
			)
		)
		(property "Value" ""
			(at 0 0 90)
			(layer "B.Fab")
			(effects
				(font
					(size 1.27 1.27)
				)
				(justify mirror)
			)
		)
		(duplicate_pad_numbers_are_jumpers no)
		(fp_line
			(start 0.7874 -0.4064)
			(end -0.7874 -0.4064)
			(stroke
				(width 0.1524)
				(type default)
			)
			(layer "B.SilkS")
		)
		(fp_line
			(start -0.7874 -0.4064)
			(end -0.7874 0.4064)
			(stroke
				(width 0.1524)
				(type default)
			)
			(layer "B.SilkS")
		)
		(fp_line
			(start 0.7874 0.4064)
			(end 0.7874 -0.4064)
			(stroke
				(width 0.1524)
				(type default)
			)
			(layer "B.SilkS")
		)
		(fp_line
			(start -0.7874 0.4064)
			(end 0.7874 0.4064)
			(stroke
				(width 0.1524)
				(type default)
			)
			(layer "B.SilkS")
		)
		(fp_line
			(start 0.67945 -0.305054)
			(end 0.12065 -0.305054)
			(stroke
				(width 0.1)
				(type default)
			)
			(layer "B.Fab")
		)
		(fp_line
			(start 0.12065 -0.305054)
			(end 0.12065 -0.2794)
			(stroke
				(width 0.1)
				(type default)
			)
			(layer "B.Fab")
		)
		(fp_line
			(start -0.12065 -0.3048)
			(end -0.67945 -0.3048)
			(stroke
				(width 0.1)
				(type default)
			)
			(layer "B.Fab")
		)
		(fp_line
			(start -0.67945 -0.3048)
			(end -0.67945 0.3048)
			(stroke
				(width 0.1)
				(type default)
			)
			(layer "B.Fab")
		)
		(fp_line
			(start 0.12065 -0.2794)
			(end -0.12065 -0.2794)
			(stroke
				(width 0.1)
				(type default)
			)
			(layer "B.Fab")
		)
		(fp_line
			(start -0.12065 -0.2794)
			(end -0.12065 -0.3048)
			(stroke
				(width 0.1)
				(type default)
			)
			(layer "B.Fab")
		)
		(fp_line
			(start 0.12065 0.2794)
			(end 0.12065 0.3048)
			(stroke
				(width 0.1)
				(type default)
			)
			(layer "B.Fab")
		)
		(fp_line
			(start -0.120396 0.2794)
			(end 0.12065 0.2794)
			(stroke
				(width 0.1)
				(type default)
			)
			(layer "B.Fab")
		)
		(fp_line
			(start 0.67945 0.3048)
			(end 0.67945 -0.305054)
			(stroke
				(width 0.1)
				(type default)
			)
			(layer "B.Fab")
		)
		(fp_line
			(start 0.12065 0.3048)
			(end 0.67945 0.3048)
			(stroke
				(width 0.1)
				(type default)
			)
			(layer "B.Fab")
		)
		(fp_line
			(start -0.120396 0.3048)
			(end -0.120396 0.2794)
			(stroke
				(width 0.1)
				(type default)
			)
			(layer "B.Fab")
		)
		(fp_line
			(start -0.67945 0.3048)
			(end -0.120396 0.3048)
			(stroke
				(width 0.1)
				(type default)
			)
			(layer "B.Fab")
		)
		(pad "1" smd circle
			(at 0.40005 0 270)
			(size 0 0)
			(layers "B.Cu" "B.Mask" "B.Paste")
			(net "P3V3_AUX")
		)
		(pad "2" smd circle
			(at -0.40005 0 270)
			(size 0 0)
			(layers "B.Cu" "B.Mask" "B.Paste")
			(net "SMB_DEBUG_AUX_LVC3_USB_R1_SDA")
		)
	)
	(footprint ""
		(layer "B.Cu")
		(at 71.599806 -69.576188 -90)
		(property "Reference" "R687"
			(at 0 0 90)
			(layer "B.SilkS")
			(hide yes)
			(effects
				(font
					(size 1.27 1.27)
				)
				(justify mirror)
			)
		)
		(property "Value" ""
			(at 0 0 90)
			(layer "B.Fab")
			(effects
				(font
					(size 1.27 1.27)
				)
				(justify mirror)
			)
		)
		(duplicate_pad_numbers_are_jumpers no)
		(fp_line
			(start -0.7874 0.4064)
			(end 0.7874 0.4064)
			(stroke
				(width 0.1524)
				(type default)
			)
			(layer "B.SilkS")
		)
		(fp_line
			(start 0.7874 0.4064)
			(end 0.7874 -0.4064)
			(stroke
				(width 0.1524)
				(type default)
			)
			(layer "B.SilkS")
		)
		(fp_line
			(start -0.7874 -0.4064)
			(end -0.7874 0.4064)
			(stroke
				(width 0.1524)
				(type default)
			)
			(layer "B.SilkS")
		)
		(fp_line
			(start 0.7874 -0.4064)
			(end -0.7874 -0.4064)
			(stroke
				(width 0.1524)
				(type default)
			)
			(layer "B.SilkS")
		)
		(fp_line
			(start -0.67945 0.3048)
			(end -0.120396 0.3048)
			(stroke
				(width 0.1)
				(type default)
			)
			(layer "B.Fab")
		)
		(fp_line
			(start -0.120396 0.3048)
			(end -0.120396 0.2794)
			(stroke
				(width 0.1)
				(type default)
			)
			(layer "B.Fab")
		)
		(fp_line
			(start 0.12065 0.3048)
			(end 0.67945 0.3048)
			(stroke
				(width 0.1)
				(type default)
			)
			(layer "B.Fab")
		)
		(fp_line
			(start 0.67945 0.3048)
			(end 0.67945 -0.305054)
			(stroke
				(width 0.1)
				(type default)
			)
			(layer "B.Fab")
		)
		(fp_line
			(start -0.120396 0.2794)
			(end 0.12065 0.2794)
			(stroke
				(width 0.1)
				(type default)
			)
			(layer "B.Fab")
		)
		(fp_line
			(start 0.12065 0.2794)
			(end 0.12065 0.3048)
			(stroke
				(width 0.1)
				(type default)
			)
			(layer "B.Fab")
		)
		(fp_line
			(start -0.12065 -0.2794)
			(end -0.12065 -0.3048)
			(stroke
				(width 0.1)
				(type default)
			)
			(layer "B.Fab")
		)
		(fp_line
			(start 0.12065 -0.2794)
			(end -0.12065 -0.2794)
			(stroke
				(width 0.1)
				(type default)
			)
			(layer "B.Fab")
		)
		(fp_line
			(start -0.67945 -0.3048)
			(end -0.67945 0.3048)
			(stroke
				(width 0.1)
				(type default)
			)
			(layer "B.Fab")
		)
		(fp_line
			(start -0.12065 -0.3048)
			(end -0.67945 -0.3048)
			(stroke
				(width 0.1)
				(type default)
			)
			(layer "B.Fab")
		)
		(fp_line
			(start 0.12065 -0.305054)
			(end 0.12065 -0.2794)
			(stroke
				(width 0.1)
				(type default)
			)
			(layer "B.Fab")
		)
		(fp_line
			(start 0.67945 -0.305054)
			(end 0.12065 -0.305054)
			(stroke
				(width 0.1)
				(type default)
			)
			(layer "B.Fab")
		)
		(pad "1" smd circle
			(at 0.40005 0 90)
			(size 0 0)
			(layers "B.Cu" "B.Mask" "B.Paste")
			(net "P3V3_AUX")
		)
		(pad "2" smd circle
			(at -0.40005 0 90)
			(size 0 0)
			(layers "B.Cu" "B.Mask" "B.Paste")
			(net "BMC_EMMC_CD_N")
		)
	)
	(footprint ""
		(layer "B.Cu")
		(at 38.518592 -56.120538)
		(property "Reference" "C42"
			(at 0 0 0)
			(layer "B.SilkS")
			(hide yes)
			(effects
				(font
					(size 1.27 1.27)
				)
				(justify mirror)
			)
		)
		(property "Value" ""
			(at 0 0 0)
			(layer "B.Fab")
			(effects
				(font
					(size 1.27 1.27)
				)
				(justify mirror)
			)
		)
		(duplicate_pad_numbers_are_jumpers no)
		(fp_line
			(start -1.2954 -0.5842)
			(end -1.2954 0.5842)
			(stroke
				(width 0.1524)
				(type default)
			)
			(layer "B.SilkS")
		)
		(fp_line
			(start -1.2954 0.5842)
			(end 1.2954 0.5842)
			(stroke
				(width 0.1524)
				(type default)
			)
			(layer "B.SilkS")
		)
		(fp_line
			(start 0 -0.5842)
			(end 0 0.5842)
			(stroke
				(width 0.1524)
				(type default)
			)
			(layer "B.SilkS")
		)
		(fp_line
			(start 1.2954 -0.5842)
			(end -1.2954 -0.5842)
			(stroke
				(width 0.1524)
				(type default)
			)
			(layer "B.SilkS")
		)
		(fp_line
			(start 1.2954 0.5842)
			(end 1.2954 -0.5842)
			(stroke
				(width 0.1524)
				(type default)
			)
			(layer "B.SilkS")
		)
		(fp_line
			(start -1.1938 -0.4064)
			(end -1.1938 0.4064)
			(stroke
				(width 0.1)
				(type default)
			)
			(layer "B.Fab")
		)
		(fp_line
			(start -1.1938 0.4064)
			(end -0.8636 0.4064)
			(stroke
				(width 0.1)
				(type default)
			)
			(layer "B.Fab")
		)
		(fp_line
			(start -0.8636 -0.4572)
			(end -0.8636 -0.4064)
			(stroke
				(width 0.1)
				(type default)
			)
			(layer "B.Fab")
		)
		(fp_line
			(start -0.8636 -0.4064)
			(end -1.1938 -0.4064)
			(stroke
				(width 0.1)
				(type default)
			)
			(layer "B.Fab")
		)
		(fp_line
			(start -0.8636 0.4064)
			(end -0.8636 0.4572)
			(stroke
				(width 0.1)
				(type default)
			)
			(layer "B.Fab")
		)
		(fp_line
			(start -0.8636 0.4572)
			(end 0.8636 0.4572)
			(stroke
				(width 0.1)
				(type default)
			)
			(layer "B.Fab")
		)
		(fp_line
			(start 0.8636 -0.4572)
			(end -0.8636 -0.4572)
			(stroke
				(width 0.1)
				(type default)
			)
			(layer "B.Fab")
		)
		(fp_line
			(start 0.8636 -0.4064)
			(end 0.8636 -0.4572)
			(stroke
				(width 0.1)
				(type default)
			)
			(layer "B.Fab")
		)
		(fp_line
			(start 0.8636 0.4064)
			(end 1.1938 0.4064)
			(stroke
				(width 0.1)
				(type default)
			)
			(layer "B.Fab")
		)
		(fp_line
			(start 0.8636 0.4572)
			(end 0.8636 0.4064)
			(stroke
				(width 0.1)
				(type default)
			)
			(layer "B.Fab")
		)
		(fp_line
			(start 1.1938 -0.4064)
			(end 0.8636 -0.4064)
			(stroke
				(width 0.1)
				(type default)
			)
			(layer "B.Fab")
		)
		(fp_line
			(start 1.1938 0.4064)
			(end 1.1938 -0.4064)
			(stroke
				(width 0.1)
				(type default)
			)
			(layer "B.Fab")
		)
		(pad "1" smd rect
			(at 0.7366 0 270)
			(size 0.7112 0.8128)
			(layers "B.Cu" "B.Mask" "B.Paste")
			(net "PVCCIO_PECI_BMC")
		)
		(pad "2" smd rect
			(at -0.7366 0 270)
			(size 0.7112 0.8128)
			(layers "B.Cu" "B.Mask" "B.Paste")
			(net "GND")
		)
	)
	(footprint ""
		(layer "B.Cu")
		(at 76.162154 -52.286916 180)
		(property "Reference" "C4"
			(at 0 0 0)
			(layer "B.SilkS")
			(hide yes)
			(effects
				(font
					(size 1.27 1.27)
				)
				(justify mirror)
			)
		)
		(property "Value" ""
			(at 0 0 0)
			(layer "B.Fab")
			(effects
				(font
					(size 1.27 1.27)
				)
				(justify mirror)
			)
		)
		(duplicate_pad_numbers_are_jumpers no)
		(fp_line
			(start 0.7874 0.4064)
			(end 0.7874 -0.4064)
			(stroke
				(width 0.1524)
				(type default)
			)
			(layer "B.SilkS")
		)
		(fp_line
			(start 0.7874 -0.4064)
			(end -0.7874 -0.4064)
			(stroke
				(width 0.1524)
				(type default)
			)
			(layer "B.SilkS")
		)
		(fp_line
			(start -0.7874 0.4064)
			(end 0.7874 0.4064)
			(stroke
				(width 0.1524)
				(type default)
			)
			(layer "B.SilkS")
		)
		(fp_line
			(start -0.7874 -0.4064)
			(end -0.7874 0.4064)
			(stroke
				(width 0.1524)
				(type default)
			)
			(layer "B.SilkS")
		)
		(fp_line
			(start 0.67945 0.3048)
			(end 0.67945 -0.305054)
			(stroke
				(width 0.1)
				(type default)
			)
			(layer "B.Fab")
		)
		(fp_line
			(start 0.67945 -0.305054)
			(end 0.12065 -0.305054)
			(stroke
				(width 0.1)
				(type default)
			)
			(layer "B.Fab")
		)
		(fp_line
			(start 0.12065 0.3048)
			(end 0.67945 0.3048)
			(stroke
				(width 0.1)
				(type default)
			)
			(layer "B.Fab")
		)
		(fp_line
			(start 0.12065 0.2794)
			(end 0.12065 0.3048)
			(stroke
				(width 0.1)
				(type default)
			)
			(layer "B.Fab")
		)
		(fp_line
			(start 0.12065 -0.2794)
			(end -0.12065 -0.2794)
			(stroke
				(width 0.1)
				(type default)
			)
			(layer "B.Fab")
		)
		(fp_line
			(start 0.12065 -0.305054)
			(end 0.12065 -0.2794)
			(stroke
				(width 0.1)
				(type default)
			)
			(layer "B.Fab")
		)
		(fp_line
			(start -0.120396 0.3048)
			(end -0.120396 0.2794)
			(stroke
				(width 0.1)
				(type default)
			)
			(layer "B.Fab")
		)
		(fp_line
			(start -0.120396 0.2794)
			(end 0.12065 0.2794)
			(stroke
				(width 0.1)
				(type default)
			)
			(layer "B.Fab")
		)
		(fp_line
			(start -0.12065 -0.2794)
			(end -0.12065 -0.3048)
			(stroke
				(width 0.1)
				(type default)
			)
			(layer "B.Fab")
		)
		(fp_line
			(start -0.12065 -0.3048)
			(end -0.67945 -0.3048)
			(stroke
				(width 0.1)
				(type default)
			)
			(layer "B.Fab")
		)
		(fp_line
			(start -0.67945 0.3048)
			(end -0.120396 0.3048)
			(stroke
				(width 0.1)
				(type default)
			)
			(layer "B.Fab")
		)
		(fp_line
			(start -0.67945 -0.3048)
			(end -0.67945 0.3048)
			(stroke
				(width 0.1)
				(type default)
			)
			(layer "B.Fab")
		)
		(pad "1" smd circle
			(at 0.40005 0)
			(size 0 0)
			(layers "B.Cu" "B.Mask" "B.Paste")
			(net "P1V2_AUX")
		)
		(pad "2" smd circle
			(at -0.40005 0)
			(size 0 0)
			(layers "B.Cu" "B.Mask" "B.Paste")
			(net "GND")
		)
	)
	(footprint ""
		(layer "B.Cu")
		(at 71.66102 -44.61129)
		(property "Reference" "C10"
			(at 0 0 0)
			(layer "B.SilkS")
			(hide yes)
			(effects
				(font
					(size 1.27 1.27)
				)
				(justify mirror)
			)
		)
		(property "Value" ""
			(at 0 0 0)
			(layer "B.Fab")
			(effects
				(font
					(size 1.27 1.27)
				)
				(justify mirror)
			)
		)
		(duplicate_pad_numbers_are_jumpers no)
		(fp_line
			(start -0.7874 -0.4064)
			(end -0.7874 0.4064)
			(stroke
				(width 0.1524)
				(type default)
			)
			(layer "B.SilkS")
		)
		(fp_line
			(start -0.7874 0.4064)
			(end 0.7874 0.4064)
			(stroke
				(width 0.1524)
				(type default)
			)
			(layer "B.SilkS")
		)
		(fp_line
			(start 0.7874 -0.4064)
			(end -0.7874 -0.4064)
			(stroke
				(width 0.1524)
				(type default)
			)
			(layer "B.SilkS")
		)
		(fp_line
			(start 0.7874 0.4064)
			(end 0.7874 -0.4064)
			(stroke
				(width 0.1524)
				(type default)
			)
			(layer "B.SilkS")
		)
		(fp_line
			(start -0.67945 -0.3048)
			(end -0.67945 0.3048)
			(stroke
				(width 0.1)
				(type default)
			)
			(layer "B.Fab")
		)
		(fp_line
			(start -0.67945 0.3048)
			(end -0.120396 0.3048)
			(stroke
				(width 0.1)
				(type default)
			)
			(layer "B.Fab")
		)
		(fp_line
			(start -0.12065 -0.3048)
			(end -0.67945 -0.3048)
			(stroke
				(width 0.1)
				(type default)
			)
			(layer "B.Fab")
		)
		(fp_line
			(start -0.12065 -0.2794)
			(end -0.12065 -0.3048)
			(stroke
				(width 0.1)
				(type default)
			)
			(layer "B.Fab")
		)
		(fp_line
			(start -0.120396 0.2794)
			(end 0.12065 0.2794)
			(stroke
				(width 0.1)
				(type default)
			)
			(layer "B.Fab")
		)
		(fp_line
			(start -0.120396 0.3048)
			(end -0.120396 0.2794)
			(stroke
				(width 0.1)
				(type default)
			)
			(layer "B.Fab")
		)
		(fp_line
			(start 0.12065 -0.305054)
			(end 0.12065 -0.2794)
			(stroke
				(width 0.1)
				(type default)
			)
			(layer "B.Fab")
		)
		(fp_line
			(start 0.12065 -0.2794)
			(end -0.12065 -0.2794)
			(stroke
				(width 0.1)
				(type default)
			)
			(layer "B.Fab")
		)
		(fp_line
			(start 0.12065 0.2794)
			(end 0.12065 0.3048)
			(stroke
				(width 0.1)
				(type default)
			)
			(layer "B.Fab")
		)
		(fp_line
			(start 0.12065 0.3048)
			(end 0.67945 0.3048)
			(stroke
				(width 0.1)
				(type default)
			)
			(layer "B.Fab")
		)
		(fp_line
			(start 0.67945 -0.305054)
			(end 0.12065 -0.305054)
			(stroke
				(width 0.1)
				(type default)
			)
			(layer "B.Fab")
		)
		(fp_line
			(start 0.67945 0.3048)
			(end 0.67945 -0.305054)
			(stroke
				(width 0.1)
				(type default)
			)
			(layer "B.Fab")
		)
		(pad "1" smd circle
			(at 0.40005 0 180)
			(size 0 0)
			(layers "B.Cu" "B.Mask" "B.Paste")
			(net "P0V6_DDR_VREF_AUX")
		)
		(pad "2" smd circle
			(at -0.40005 0 180)
			(size 0 0)
			(layers "B.Cu" "B.Mask" "B.Paste")
			(net "GND")
		)
	)
	(footprint ""
		(layer "B.Cu")
		(at 50.91684 -63.94704 90)
		(property "Reference" "R844"
			(at 0 0 90)
			(layer "B.SilkS")
			(hide yes)
			(effects
				(font
					(size 1.27 1.27)
				)
				(justify mirror)
			)
		)
		(property "Value" ""
			(at 0 0 90)
			(layer "B.Fab")
			(effects
				(font
					(size 1.27 1.27)
				)
				(justify mirror)
			)
		)
		(duplicate_pad_numbers_are_jumpers no)
		(fp_line
			(start 0.7874 -0.4064)
			(end -0.7874 -0.4064)
			(stroke
				(width 0.1524)
				(type default)
			)
			(layer "B.SilkS")
		)
		(fp_line
			(start -0.7874 -0.4064)
			(end -0.7874 0.4064)
			(stroke
				(width 0.1524)
				(type default)
			)
			(layer "B.SilkS")
		)
		(fp_line
			(start 0.7874 0.4064)
			(end 0.7874 -0.4064)
			(stroke
				(width 0.1524)
				(type default)
			)
			(layer "B.SilkS")
		)
		(fp_line
			(start -0.7874 0.4064)
			(end 0.7874 0.4064)
			(stroke
				(width 0.1524)
				(type default)
			)
			(layer "B.SilkS")
		)
		(fp_line
			(start 0.67945 -0.305054)
			(end 0.12065 -0.305054)
			(stroke
				(width 0.1)
				(type default)
			)
			(layer "B.Fab")
		)
		(fp_line
			(start 0.12065 -0.305054)
			(end 0.12065 -0.2794)
			(stroke
				(width 0.1)
				(type default)
			)
			(layer "B.Fab")
		)
		(fp_line
			(start -0.12065 -0.3048)
			(end -0.67945 -0.3048)
			(stroke
				(width 0.1)
				(type default)
			)
			(layer "B.Fab")
		)
		(fp_line
			(start -0.67945 -0.3048)
			(end -0.67945 0.3048)
			(stroke
				(width 0.1)
				(type default)
			)
			(layer "B.Fab")
		)
		(fp_line
			(start 0.12065 -0.2794)
			(end -0.12065 -0.2794)
			(stroke
				(width 0.1)
				(type default)
			)
			(layer "B.Fab")
		)
		(fp_line
			(start -0.12065 -0.2794)
			(end -0.12065 -0.3048)
			(stroke
				(width 0.1)
				(type default)
			)
			(layer "B.Fab")
		)
		(fp_line
			(start 0.12065 0.2794)
			(end 0.12065 0.3048)
			(stroke
				(width 0.1)
				(type default)
			)
			(layer "B.Fab")
		)
		(fp_line
			(start -0.120396 0.2794)
			(end 0.12065 0.2794)
			(stroke
				(width 0.1)
				(type default)
			)
			(layer "B.Fab")
		)
		(fp_line
			(start 0.67945 0.3048)
			(end 0.67945 -0.305054)
			(stroke
				(width 0.1)
				(type default)
			)
			(layer "B.Fab")
		)
		(fp_line
			(start 0.12065 0.3048)
			(end 0.67945 0.3048)
			(stroke
				(width 0.1)
				(type default)
			)
			(layer "B.Fab")
		)
		(fp_line
			(start -0.120396 0.3048)
			(end -0.120396 0.2794)
			(stroke
				(width 0.1)
				(type default)
			)
			(layer "B.Fab")
		)
		(fp_line
			(start -0.67945 0.3048)
			(end -0.120396 0.3048)
			(stroke
				(width 0.1)
				(type default)
			)
			(layer "B.Fab")
		)
		(pad "1" smd circle
			(at 0.40005 0 270)
			(size 0 0)
			(layers "B.Cu" "B.Mask" "B.Paste")
			(net "P3V3_AUX")
		)
		(pad "2" smd circle
			(at -0.40005 0 270)
			(size 0 0)
			(layers "B.Cu" "B.Mask" "B.Paste")
			(net "SMB_BMC_ALERT12_N")
		)
	)
	(footprint ""
		(layer "B.Cu")
		(at 57.906666 -73.645014)
		(property "Reference" "C295"
			(at 0 0 0)
			(layer "B.SilkS")
			(hide yes)
			(effects
				(font
					(size 1.27 1.27)
				)
				(justify mirror)
			)
		)
		(property "Value" ""
			(at 0 0 0)
			(layer "B.Fab")
			(effects
				(font
					(size 1.27 1.27)
				)
				(justify mirror)
			)
		)
		(duplicate_pad_numbers_are_jumpers no)
		(fp_line
			(start -0.7874 -0.4064)
			(end -0.7874 0.4064)
			(stroke
				(width 0.1524)
				(type default)
			)
			(layer "B.SilkS")
		)
		(fp_line
			(start -0.7874 0.4064)
			(end 0.7874 0.4064)
			(stroke
				(width 0.1524)
				(type default)
			)
			(layer "B.SilkS")
		)
		(fp_line
			(start 0.7874 -0.4064)
			(end -0.7874 -0.4064)
			(stroke
				(width 0.1524)
				(type default)
			)
			(layer "B.SilkS")
		)
		(fp_line
			(start 0.7874 0.4064)
			(end 0.7874 -0.4064)
			(stroke
				(width 0.1524)
				(type default)
			)
			(layer "B.SilkS")
		)
		(fp_line
			(start -0.67945 -0.3048)
			(end -0.67945 0.3048)
			(stroke
				(width 0.1)
				(type default)
			)
			(layer "B.Fab")
		)
		(fp_line
			(start -0.67945 0.3048)
			(end -0.120396 0.3048)
			(stroke
				(width 0.1)
				(type default)
			)
			(layer "B.Fab")
		)
		(fp_line
			(start -0.12065 -0.3048)
			(end -0.67945 -0.3048)
			(stroke
				(width 0.1)
				(type default)
			)
			(layer "B.Fab")
		)
		(fp_line
			(start -0.12065 -0.2794)
			(end -0.12065 -0.3048)
			(stroke
				(width 0.1)
				(type default)
			)
			(layer "B.Fab")
		)
		(fp_line
			(start -0.120396 0.2794)
			(end 0.12065 0.2794)
			(stroke
				(width 0.1)
				(type default)
			)
			(layer "B.Fab")
		)
		(fp_line
			(start -0.120396 0.3048)
			(end -0.120396 0.2794)
			(stroke
				(width 0.1)
				(type default)
			)
			(layer "B.Fab")
		)
		(fp_line
			(start 0.12065 -0.305054)
			(end 0.12065 -0.2794)
			(stroke
				(width 0.1)
				(type default)
			)
			(layer "B.Fab")
		)
		(fp_line
			(start 0.12065 -0.2794)
			(end -0.12065 -0.2794)
			(stroke
				(width 0.1)
				(type default)
			)
			(layer "B.Fab")
		)
		(fp_line
			(start 0.12065 0.2794)
			(end 0.12065 0.3048)
			(stroke
				(width 0.1)
				(type default)
			)
			(layer "B.Fab")
		)
		(fp_line
			(start 0.12065 0.3048)
			(end 0.67945 0.3048)
			(stroke
				(width 0.1)
				(type default)
			)
			(layer "B.Fab")
		)
		(fp_line
			(start 0.67945 -0.305054)
			(end 0.12065 -0.305054)
			(stroke
				(width 0.1)
				(type default)
			)
			(layer "B.Fab")
		)
		(fp_line
			(start 0.67945 0.3048)
			(end 0.67945 -0.305054)
			(stroke
				(width 0.1)
				(type default)
			)
			(layer "B.Fab")
		)
		(pad "1" smd circle
			(at 0.40005 0 180)
			(size 0 0)
			(layers "B.Cu" "B.Mask" "B.Paste")
			(net "P5V_SENSOR")
		)
		(pad "2" smd circle
			(at -0.40005 0 180)
			(size 0 0)
			(layers "B.Cu" "B.Mask" "B.Paste")
			(net "GND")
		)
	)
	(footprint ""
		(layer "B.Cu")
		(at 67.029838 -40.87622 90)
		(property "Reference" "C67"
			(at 0 0 90)
			(layer "B.SilkS")
			(hide yes)
			(effects
				(font
					(size 1.27 1.27)
				)
				(justify mirror)
			)
		)
		(property "Value" ""
			(at 0 0 90)
			(layer "B.Fab")
			(effects
				(font
					(size 1.27 1.27)
				)
				(justify mirror)
			)
		)
		(duplicate_pad_numbers_are_jumpers no)
		(fp_line
			(start 0.7874 -0.4064)
			(end -0.7874 -0.4064)
			(stroke
				(width 0.1524)
				(type default)
			)
			(layer "B.SilkS")
		)
		(fp_line
			(start -0.7874 -0.4064)
			(end -0.7874 0.4064)
			(stroke
				(width 0.1524)
				(type default)
			)
			(layer "B.SilkS")
		)
		(fp_line
			(start 0.7874 0.4064)
			(end 0.7874 -0.4064)
			(stroke
				(width 0.1524)
				(type default)
			)
			(layer "B.SilkS")
		)
		(fp_line
			(start -0.7874 0.4064)
			(end 0.7874 0.4064)
			(stroke
				(width 0.1524)
				(type default)
			)
			(layer "B.SilkS")
		)
		(fp_line
			(start 0.67945 -0.305054)
			(end 0.12065 -0.305054)
			(stroke
				(width 0.1)
				(type default)
			)
			(layer "B.Fab")
		)
		(fp_line
			(start 0.12065 -0.305054)
			(end 0.12065 -0.2794)
			(stroke
				(width 0.1)
				(type default)
			)
			(layer "B.Fab")
		)
		(fp_line
			(start -0.12065 -0.3048)
			(end -0.67945 -0.3048)
			(stroke
				(width 0.1)
				(type default)
			)
			(layer "B.Fab")
		)
		(fp_line
			(start -0.67945 -0.3048)
			(end -0.67945 0.3048)
			(stroke
				(width 0.1)
				(type default)
			)
			(layer "B.Fab")
		)
		(fp_line
			(start 0.12065 -0.2794)
			(end -0.12065 -0.2794)
			(stroke
				(width 0.1)
				(type default)
			)
			(layer "B.Fab")
		)
		(fp_line
			(start -0.12065 -0.2794)
			(end -0.12065 -0.3048)
			(stroke
				(width 0.1)
				(type default)
			)
			(layer "B.Fab")
		)
		(fp_line
			(start 0.12065 0.2794)
			(end 0.12065 0.3048)
			(stroke
				(width 0.1)
				(type default)
			)
			(layer "B.Fab")
		)
		(fp_line
			(start -0.120396 0.2794)
			(end 0.12065 0.2794)
			(stroke
				(width 0.1)
				(type default)
			)
			(layer "B.Fab")
		)
		(fp_line
			(start 0.67945 0.3048)
			(end 0.67945 -0.305054)
			(stroke
				(width 0.1)
				(type default)
			)
			(layer "B.Fab")
		)
		(fp_line
			(start 0.12065 0.3048)
			(end 0.67945 0.3048)
			(stroke
				(width 0.1)
				(type default)
			)
			(layer "B.Fab")
		)
		(fp_line
			(start -0.120396 0.3048)
			(end -0.120396 0.2794)
			(stroke
				(width 0.1)
				(type default)
			)
			(layer "B.Fab")
		)
		(fp_line
			(start -0.67945 0.3048)
			(end -0.120396 0.3048)
			(stroke
				(width 0.1)
				(type default)
			)
			(layer "B.Fab")
		)
		(pad "1" smd circle
			(at 0.40005 0 270)
			(size 0 0)
			(layers "B.Cu" "B.Mask" "B.Paste")
			(net "P1V2_STBY_MVDD_CK")
		)
		(pad "2" smd circle
			(at -0.40005 0 270)
			(size 0 0)
			(layers "B.Cu" "B.Mask" "B.Paste")
			(net "GND")
		)
	)
	(footprint ""
		(layer "B.Cu")
		(at 83.16722 -41.506394 180)
		(property "Reference" "R369"
			(at 0 0 0)
			(layer "B.SilkS")
			(hide yes)
			(effects
				(font
					(size 1.27 1.27)
				)
				(justify mirror)
			)
		)
		(property "Value" ""
			(at 0 0 0)
			(layer "B.Fab")
			(effects
				(font
					(size 1.27 1.27)
				)
				(justify mirror)
			)
		)
		(duplicate_pad_numbers_are_jumpers no)
		(fp_line
			(start 0.7874 0.4064)
			(end 0.7874 -0.4064)
			(stroke
				(width 0.1524)
				(type default)
			)
			(layer "B.SilkS")
		)
		(fp_line
			(start 0.7874 -0.4064)
			(end -0.7874 -0.4064)
			(stroke
				(width 0.1524)
				(type default)
			)
			(layer "B.SilkS")
		)
		(fp_line
			(start -0.7874 0.4064)
			(end 0.7874 0.4064)
			(stroke
				(width 0.1524)
				(type default)
			)
			(layer "B.SilkS")
		)
		(fp_line
			(start -0.7874 -0.4064)
			(end -0.7874 0.4064)
			(stroke
				(width 0.1524)
				(type default)
			)
			(layer "B.SilkS")
		)
		(fp_line
			(start 0.67945 0.3048)
			(end 0.67945 -0.305054)
			(stroke
				(width 0.1)
				(type default)
			)
			(layer "B.Fab")
		)
		(fp_line
			(start 0.67945 -0.305054)
			(end 0.12065 -0.305054)
			(stroke
				(width 0.1)
				(type default)
			)
			(layer "B.Fab")
		)
		(fp_line
			(start 0.12065 0.3048)
			(end 0.67945 0.3048)
			(stroke
				(width 0.1)
				(type default)
			)
			(layer "B.Fab")
		)
		(fp_line
			(start 0.12065 0.2794)
			(end 0.12065 0.3048)
			(stroke
				(width 0.1)
				(type default)
			)
			(layer "B.Fab")
		)
		(fp_line
			(start 0.12065 -0.2794)
			(end -0.12065 -0.2794)
			(stroke
				(width 0.1)
				(type default)
			)
			(layer "B.Fab")
		)
		(fp_line
			(start 0.12065 -0.305054)
			(end 0.12065 -0.2794)
			(stroke
				(width 0.1)
				(type default)
			)
			(layer "B.Fab")
		)
		(fp_line
			(start -0.120396 0.3048)
			(end -0.120396 0.2794)
			(stroke
				(width 0.1)
				(type default)
			)
			(layer "B.Fab")
		)
		(fp_line
			(start -0.120396 0.2794)
			(end 0.12065 0.2794)
			(stroke
				(width 0.1)
				(type default)
			)
			(layer "B.Fab")
		)
		(fp_line
			(start -0.12065 -0.2794)
			(end -0.12065 -0.3048)
			(stroke
				(width 0.1)
				(type default)
			)
			(layer "B.Fab")
		)
		(fp_line
			(start -0.12065 -0.3048)
			(end -0.67945 -0.3048)
			(stroke
				(width 0.1)
				(type default)
			)
			(layer "B.Fab")
		)
		(fp_line
			(start -0.67945 0.3048)
			(end -0.120396 0.3048)
			(stroke
				(width 0.1)
				(type default)
			)
			(layer "B.Fab")
		)
		(fp_line
			(start -0.67945 -0.3048)
			(end -0.67945 0.3048)
			(stroke
				(width 0.1)
				(type default)
			)
			(layer "B.Fab")
		)
		(pad "1" smd circle
			(at 0.40005 0)
			(size 0 0)
			(layers "B.Cu" "B.Mask" "B.Paste")
			(net "M_BMC_DDR4_MACT_N")
		)
		(pad "2" smd circle
			(at -0.40005 0)
			(size 0 0)
			(layers "B.Cu" "B.Mask" "B.Paste")
			(net "P1V2_AUX")
		)
	)
	(footprint ""
		(layer "B.Cu")
		(at 43.053 -6.604 -90)
		(property "Reference" "R84"
			(at 0 0 90)
			(layer "B.SilkS")
			(hide yes)
			(effects
				(font
					(size 1.27 1.27)
				)
				(justify mirror)
			)
		)
		(property "Value" ""
			(at 0 0 90)
			(layer "B.Fab")
			(effects
				(font
					(size 1.27 1.27)
				)
				(justify mirror)
			)
		)
		(duplicate_pad_numbers_are_jumpers no)
		(fp_line
			(start -0.7874 0.4064)
			(end 0.7874 0.4064)
			(stroke
				(width 0.1524)
				(type default)
			)
			(layer "B.SilkS")
		)
		(fp_line
			(start 0.7874 0.4064)
			(end 0.7874 -0.4064)
			(stroke
				(width 0.1524)
				(type default)
			)
			(layer "B.SilkS")
		)
		(fp_line
			(start -0.7874 -0.4064)
			(end -0.7874 0.4064)
			(stroke
				(width 0.1524)
				(type default)
			)
			(layer "B.SilkS")
		)
		(fp_line
			(start 0.7874 -0.4064)
			(end -0.7874 -0.4064)
			(stroke
				(width 0.1524)
				(type default)
			)
			(layer "B.SilkS")
		)
		(fp_line
			(start -0.67945 0.3048)
			(end -0.120396 0.3048)
			(stroke
				(width 0.1)
				(type default)
			)
			(layer "B.Fab")
		)
		(fp_line
			(start -0.120396 0.3048)
			(end -0.120396 0.2794)
			(stroke
				(width 0.1)
				(type default)
			)
			(layer "B.Fab")
		)
		(fp_line
			(start 0.12065 0.3048)
			(end 0.67945 0.3048)
			(stroke
				(width 0.1)
				(type default)
			)
			(layer "B.Fab")
		)
		(fp_line
			(start 0.67945 0.3048)
			(end 0.67945 -0.305054)
			(stroke
				(width 0.1)
				(type default)
			)
			(layer "B.Fab")
		)
		(fp_line
			(start -0.120396 0.2794)
			(end 0.12065 0.2794)
			(stroke
				(width 0.1)
				(type default)
			)
			(layer "B.Fab")
		)
		(fp_line
			(start 0.12065 0.2794)
			(end 0.12065 0.3048)
			(stroke
				(width 0.1)
				(type default)
			)
			(layer "B.Fab")
		)
		(fp_line
			(start -0.12065 -0.2794)
			(end -0.12065 -0.3048)
			(stroke
				(width 0.1)
				(type default)
			)
			(layer "B.Fab")
		)
		(fp_line
			(start 0.12065 -0.2794)
			(end -0.12065 -0.2794)
			(stroke
				(width 0.1)
				(type default)
			)
			(layer "B.Fab")
		)
		(fp_line
			(start -0.67945 -0.3048)
			(end -0.67945 0.3048)
			(stroke
				(width 0.1)
				(type default)
			)
			(layer "B.Fab")
		)
		(fp_line
			(start -0.12065 -0.3048)
			(end -0.67945 -0.3048)
			(stroke
				(width 0.1)
				(type default)
			)
			(layer "B.Fab")
		)
		(fp_line
			(start 0.12065 -0.305054)
			(end 0.12065 -0.2794)
			(stroke
				(width 0.1)
				(type default)
			)
			(layer "B.Fab")
		)
		(fp_line
			(start 0.67945 -0.305054)
			(end 0.12065 -0.305054)
			(stroke
				(width 0.1)
				(type default)
			)
			(layer "B.Fab")
		)
		(pad "1" smd circle
			(at 0.40005 0 90)
			(size 0 0)
			(layers "B.Cu" "B.Mask" "B.Paste")
			(net "V_VGAVS_BUF_R")
		)
		(pad "2" smd circle
			(at -0.40005 0 90)
			(size 0 0)
			(layers "B.Cu" "B.Mask" "B.Paste")
			(net "V_VGAVS_BUF")
		)
	)
	(footprint ""
		(layer "B.Cu")
		(at 76.982828 -46.19879)
		(property "Reference" "R7"
			(at 0 0 0)
			(layer "B.SilkS")
			(hide yes)
			(effects
				(font
					(size 1.27 1.27)
				)
				(justify mirror)
			)
		)
		(property "Value" ""
			(at 0 0 0)
			(layer "B.Fab")
			(effects
				(font
					(size 1.27 1.27)
				)
				(justify mirror)
			)
		)
		(duplicate_pad_numbers_are_jumpers no)
		(fp_line
			(start -0.7874 -0.4064)
			(end -0.7874 0.4064)
			(stroke
				(width 0.1524)
				(type default)
			)
			(layer "B.SilkS")
		)
		(fp_line
			(start -0.7874 0.4064)
			(end 0.7874 0.4064)
			(stroke
				(width 0.1524)
				(type default)
			)
			(layer "B.SilkS")
		)
		(fp_line
			(start 0.487172 -0.4064)
			(end -0.7874 -0.4064)
			(stroke
				(width 0.1524)
				(type default)
			)
			(layer "B.SilkS")
		)
		(fp_line
			(start 0.7874 0.4064)
			(end 0.7874 -0.02921)
			(stroke
				(width 0.1524)
				(type default)
			)
			(layer "B.SilkS")
		)
		(fp_line
			(start -0.67945 -0.3048)
			(end -0.67945 0.3048)
			(stroke
				(width 0.1)
				(type default)
			)
			(layer "B.Fab")
		)
		(fp_line
			(start -0.67945 0.3048)
			(end -0.120396 0.3048)
			(stroke
				(width 0.1)
				(type default)
			)
			(layer "B.Fab")
		)
		(fp_line
			(start -0.12065 -0.3048)
			(end -0.67945 -0.3048)
			(stroke
				(width 0.1)
				(type default)
			)
			(layer "B.Fab")
		)
		(fp_line
			(start -0.12065 -0.2794)
			(end -0.12065 -0.3048)
			(stroke
				(width 0.1)
				(type default)
			)
			(layer "B.Fab")
		)
		(fp_line
			(start -0.120396 0.2794)
			(end 0.12065 0.2794)
			(stroke
				(width 0.1)
				(type default)
			)
			(layer "B.Fab")
		)
		(fp_line
			(start -0.120396 0.3048)
			(end -0.120396 0.2794)
			(stroke
				(width 0.1)
				(type default)
			)
			(layer "B.Fab")
		)
		(fp_line
			(start 0.12065 -0.305054)
			(end 0.12065 -0.2794)
			(stroke
				(width 0.1)
				(type default)
			)
			(layer "B.Fab")
		)
		(fp_line
			(start 0.12065 -0.2794)
			(end -0.12065 -0.2794)
			(stroke
				(width 0.1)
				(type default)
			)
			(layer "B.Fab")
		)
		(fp_line
			(start 0.12065 0.2794)
			(end 0.12065 0.3048)
			(stroke
				(width 0.1)
				(type default)
			)
			(layer "B.Fab")
		)
		(fp_line
			(start 0.12065 0.3048)
			(end 0.67945 0.3048)
			(stroke
				(width 0.1)
				(type default)
			)
			(layer "B.Fab")
		)
		(fp_line
			(start 0.67945 -0.305054)
			(end 0.12065 -0.305054)
			(stroke
				(width 0.1)
				(type default)
			)
			(layer "B.Fab")
		)
		(fp_line
			(start 0.67945 0.3048)
			(end 0.67945 -0.305054)
			(stroke
				(width 0.1)
				(type default)
			)
			(layer "B.Fab")
		)
		(pad "1" smd circle
			(at 0.40005 0 180)
			(size 0 0)
			(layers "B.Cu" "B.Mask" "B.Paste")
			(net "M_BMC_DDR4_MCLK_DN")
		)
		(pad "2" smd circle
			(at -0.40005 0 180)
			(size 0 0)
			(layers "B.Cu" "B.Mask" "B.Paste")
			(net "M_BMC_DDR4_MCLK_C")
		)
	)
	(footprint ""
		(layer "B.Cu")
		(at 21.971 -101.981 90)
		(property "Reference" "R750"
			(at 0 0 90)
			(layer "B.SilkS")
			(hide yes)
			(effects
				(font
					(size 1.27 1.27)
				)
				(justify mirror)
			)
		)
		(property "Value" ""
			(at 0 0 90)
			(layer "B.Fab")
			(effects
				(font
					(size 1.27 1.27)
				)
				(justify mirror)
			)
		)
		(duplicate_pad_numbers_are_jumpers no)
		(fp_line
			(start 0.7874 -0.4064)
			(end -0.7874 -0.4064)
			(stroke
				(width 0.1524)
				(type default)
			)
			(layer "B.SilkS")
		)
		(fp_line
			(start -0.7874 -0.4064)
			(end -0.7874 0.4064)
			(stroke
				(width 0.1524)
				(type default)
			)
			(layer "B.SilkS")
		)
		(fp_line
			(start 0.7874 0.4064)
			(end 0.7874 -0.4064)
			(stroke
				(width 0.1524)
				(type default)
			)
			(layer "B.SilkS")
		)
		(fp_line
			(start -0.7874 0.4064)
			(end 0.7874 0.4064)
			(stroke
				(width 0.1524)
				(type default)
			)
			(layer "B.SilkS")
		)
		(fp_line
			(start 0.67945 -0.305054)
			(end 0.12065 -0.305054)
			(stroke
				(width 0.1)
				(type default)
			)
			(layer "B.Fab")
		)
		(fp_line
			(start 0.12065 -0.305054)
			(end 0.12065 -0.2794)
			(stroke
				(width 0.1)
				(type default)
			)
			(layer "B.Fab")
		)
		(fp_line
			(start -0.12065 -0.3048)
			(end -0.67945 -0.3048)
			(stroke
				(width 0.1)
				(type default)
			)
			(layer "B.Fab")
		)
		(fp_line
			(start -0.67945 -0.3048)
			(end -0.67945 0.3048)
			(stroke
				(width 0.1)
				(type default)
			)
			(layer "B.Fab")
		)
		(fp_line
			(start 0.12065 -0.2794)
			(end -0.12065 -0.2794)
			(stroke
				(width 0.1)
				(type default)
			)
			(layer "B.Fab")
		)
		(fp_line
			(start -0.12065 -0.2794)
			(end -0.12065 -0.3048)
			(stroke
				(width 0.1)
				(type default)
			)
			(layer "B.Fab")
		)
		(fp_line
			(start 0.12065 0.2794)
			(end 0.12065 0.3048)
			(stroke
				(width 0.1)
				(type default)
			)
			(layer "B.Fab")
		)
		(fp_line
			(start -0.120396 0.2794)
			(end 0.12065 0.2794)
			(stroke
				(width 0.1)
				(type default)
			)
			(layer "B.Fab")
		)
		(fp_line
			(start 0.67945 0.3048)
			(end 0.67945 -0.305054)
			(stroke
				(width 0.1)
				(type default)
			)
			(layer "B.Fab")
		)
		(fp_line
			(start 0.12065 0.3048)
			(end 0.67945 0.3048)
			(stroke
				(width 0.1)
				(type default)
			)
			(layer "B.Fab")
		)
		(fp_line
			(start -0.120396 0.3048)
			(end -0.120396 0.2794)
			(stroke
				(width 0.1)
				(type default)
			)
			(layer "B.Fab")
		)
		(fp_line
			(start -0.67945 0.3048)
			(end -0.120396 0.3048)
			(stroke
				(width 0.1)
				(type default)
			)
			(layer "B.Fab")
		)
		(pad "1" smd circle
			(at 0.40005 0 270)
			(size 0 0)
			(layers "B.Cu" "B.Mask" "B.Paste")
			(net "FM_BMC_DEBUG_SW_N")
		)
		(pad "2" smd circle
			(at -0.40005 0 270)
			(size 0 0)
			(layers "B.Cu" "B.Mask" "B.Paste")
			(net "FM_BMC_DEBUG_SW_R2_N")
		)
	)
	(footprint ""
		(layer "B.Cu")
		(at 49.109122 -45.716444 90)
		(property "Reference" "C33"
			(at 0 0 90)
			(layer "B.SilkS")
			(hide yes)
			(effects
				(font
					(size 1.27 1.27)
				)
				(justify mirror)
			)
		)
		(property "Value" ""
			(at 0 0 90)
			(layer "B.Fab")
			(effects
				(font
					(size 1.27 1.27)
				)
				(justify mirror)
			)
		)
		(duplicate_pad_numbers_are_jumpers no)
		(fp_line
			(start 0.7874 -0.4064)
			(end -0.7874 -0.4064)
			(stroke
				(width 0.1524)
				(type default)
			)
			(layer "B.SilkS")
		)
		(fp_line
			(start -0.7874 -0.4064)
			(end -0.7874 0.4064)
			(stroke
				(width 0.1524)
				(type default)
			)
			(layer "B.SilkS")
		)
		(fp_line
			(start 0.7874 0.4064)
			(end 0.7874 -0.4064)
			(stroke
				(width 0.1524)
				(type default)
			)
			(layer "B.SilkS")
		)
		(fp_line
			(start -0.7874 0.4064)
			(end 0.7874 0.4064)
			(stroke
				(width 0.1524)
				(type default)
			)
			(layer "B.SilkS")
		)
		(fp_line
			(start 0.67945 -0.305054)
			(end 0.12065 -0.305054)
			(stroke
				(width 0.1)
				(type default)
			)
			(layer "B.Fab")
		)
		(fp_line
			(start 0.12065 -0.305054)
			(end 0.12065 -0.2794)
			(stroke
				(width 0.1)
				(type default)
			)
			(layer "B.Fab")
		)
		(fp_line
			(start -0.12065 -0.3048)
			(end -0.67945 -0.3048)
			(stroke
				(width 0.1)
				(type default)
			)
			(layer "B.Fab")
		)
		(fp_line
			(start -0.67945 -0.3048)
			(end -0.67945 0.3048)
			(stroke
				(width 0.1)
				(type default)
			)
			(layer "B.Fab")
		)
		(fp_line
			(start 0.12065 -0.2794)
			(end -0.12065 -0.2794)
			(stroke
				(width 0.1)
				(type default)
			)
			(layer "B.Fab")
		)
		(fp_line
			(start -0.12065 -0.2794)
			(end -0.12065 -0.3048)
			(stroke
				(width 0.1)
				(type default)
			)
			(layer "B.Fab")
		)
		(fp_line
			(start 0.12065 0.2794)
			(end 0.12065 0.3048)
			(stroke
				(width 0.1)
				(type default)
			)
			(layer "B.Fab")
		)
		(fp_line
			(start -0.120396 0.2794)
			(end 0.12065 0.2794)
			(stroke
				(width 0.1)
				(type default)
			)
			(layer "B.Fab")
		)
		(fp_line
			(start 0.67945 0.3048)
			(end 0.67945 -0.305054)
			(stroke
				(width 0.1)
				(type default)
			)
			(layer "B.Fab")
		)
		(fp_line
			(start 0.12065 0.3048)
			(end 0.67945 0.3048)
			(stroke
				(width 0.1)
				(type default)
			)
			(layer "B.Fab")
		)
		(fp_line
			(start -0.120396 0.3048)
			(end -0.120396 0.2794)
			(stroke
				(width 0.1)
				(type default)
			)
			(layer "B.Fab")
		)
		(fp_line
			(start -0.67945 0.3048)
			(end -0.120396 0.3048)
			(stroke
				(width 0.1)
				(type default)
			)
			(layer "B.Fab")
		)
		(pad "1" smd circle
			(at 0.40005 0 270)
			(size 0 0)
			(layers "B.Cu" "B.Mask" "B.Paste")
			(net "P3V3_P2V5_P1V8_RVDD")
		)
		(pad "2" smd circle
			(at -0.40005 0 270)
			(size 0 0)
			(layers "B.Cu" "B.Mask" "B.Paste")
			(net "GND")
		)
	)
	(footprint ""
		(layer "B.Cu")
		(at 60.45835 -47.844964 90)
		(property "Reference" "C71"
			(at 0 0 90)
			(layer "B.SilkS")
			(hide yes)
			(effects
				(font
					(size 1.27 1.27)
				)
				(justify mirror)
			)
		)
		(property "Value" ""
			(at 0 0 90)
			(layer "B.Fab")
			(effects
				(font
					(size 1.27 1.27)
				)
				(justify mirror)
			)
		)
		(duplicate_pad_numbers_are_jumpers no)
		(fp_line
			(start 0.7874 -0.4064)
			(end -0.7874 -0.4064)
			(stroke
				(width 0.1524)
				(type default)
			)
			(layer "B.SilkS")
		)
		(fp_line
			(start -0.7874 -0.4064)
			(end -0.7874 0.4064)
			(stroke
				(width 0.1524)
				(type default)
			)
			(layer "B.SilkS")
		)
		(fp_line
			(start 0.7874 0.4064)
			(end 0.7874 -0.4064)
			(stroke
				(width 0.1524)
				(type default)
			)
			(layer "B.SilkS")
		)
		(fp_line
			(start -0.7874 0.4064)
			(end 0.7874 0.4064)
			(stroke
				(width 0.1524)
				(type default)
			)
			(layer "B.SilkS")
		)
		(fp_line
			(start 0.67945 -0.305054)
			(end 0.12065 -0.305054)
			(stroke
				(width 0.1)
				(type default)
			)
			(layer "B.Fab")
		)
		(fp_line
			(start 0.12065 -0.305054)
			(end 0.12065 -0.2794)
			(stroke
				(width 0.1)
				(type default)
			)
			(layer "B.Fab")
		)
		(fp_line
			(start -0.12065 -0.3048)
			(end -0.67945 -0.3048)
			(stroke
				(width 0.1)
				(type default)
			)
			(layer "B.Fab")
		)
		(fp_line
			(start -0.67945 -0.3048)
			(end -0.67945 0.3048)
			(stroke
				(width 0.1)
				(type default)
			)
			(layer "B.Fab")
		)
		(fp_line
			(start 0.12065 -0.2794)
			(end -0.12065 -0.2794)
			(stroke
				(width 0.1)
				(type default)
			)
			(layer "B.Fab")
		)
		(fp_line
			(start -0.12065 -0.2794)
			(end -0.12065 -0.3048)
			(stroke
				(width 0.1)
				(type default)
			)
			(layer "B.Fab")
		)
		(fp_line
			(start 0.12065 0.2794)
			(end 0.12065 0.3048)
			(stroke
				(width 0.1)
				(type default)
			)
			(layer "B.Fab")
		)
		(fp_line
			(start -0.120396 0.2794)
			(end 0.12065 0.2794)
			(stroke
				(width 0.1)
				(type default)
			)
			(layer "B.Fab")
		)
		(fp_line
			(start 0.67945 0.3048)
			(end 0.67945 -0.305054)
			(stroke
				(width 0.1)
				(type default)
			)
			(layer "B.Fab")
		)
		(fp_line
			(start 0.12065 0.3048)
			(end 0.67945 0.3048)
			(stroke
				(width 0.1)
				(type default)
			)
			(layer "B.Fab")
		)
		(fp_line
			(start -0.120396 0.3048)
			(end -0.120396 0.2794)
			(stroke
				(width 0.1)
				(type default)
			)
			(layer "B.Fab")
		)
		(fp_line
			(start -0.67945 0.3048)
			(end -0.120396 0.3048)
			(stroke
				(width 0.1)
				(type default)
			)
			(layer "B.Fab")
		)
		(pad "1" smd circle
			(at 0.40005 0 270)
			(size 0 0)
			(layers "B.Cu" "B.Mask" "B.Paste")
			(net "P1V2_STBY_MVDD_CK")
		)
		(pad "2" smd circle
			(at -0.40005 0 270)
			(size 0 0)
			(layers "B.Cu" "B.Mask" "B.Paste")
			(net "GND")
		)
	)
	(footprint ""
		(layer "B.Cu")
		(at 24.384 -94.234 180)
		(property "Reference" "C195"
			(at 0 0 0)
			(layer "B.SilkS")
			(hide yes)
			(effects
				(font
					(size 1.27 1.27)
				)
				(justify mirror)
			)
		)
		(property "Value" ""
			(at 0 0 0)
			(layer "B.Fab")
			(effects
				(font
					(size 1.27 1.27)
				)
				(justify mirror)
			)
		)
		(duplicate_pad_numbers_are_jumpers no)
		(fp_line
			(start 0.69215 0.2921)
			(end 0.69215 -0.2921)
			(stroke
				(width 0.1524)
				(type default)
			)
			(layer "B.SilkS")
		)
		(fp_line
			(start 0.69215 -0.2921)
			(end -0.69215 -0.2921)
			(stroke
				(width 0.1524)
				(type default)
			)
			(layer "B.SilkS")
		)
		(fp_line
			(start -0.69215 0.2921)
			(end 0.69215 0.2921)
			(stroke
				(width 0.1524)
				(type default)
			)
			(layer "B.SilkS")
		)
		(fp_line
			(start -0.69215 -0.2921)
			(end -0.69215 0.2921)
			(stroke
				(width 0.1524)
				(type default)
			)
			(layer "B.SilkS")
		)
		(fp_line
			(start 0.51435 0.2794)
			(end 0.51435 -0.2794)
			(stroke
				(width 0.1)
				(type default)
			)
			(layer "B.Fab")
		)
		(fp_line
			(start 0.51435 -0.2794)
			(end -0.51435 -0.2794)
			(stroke
				(width 0.1)
				(type default)
			)
			(layer "B.Fab")
		)
		(fp_line
			(start -0.51435 0.2794)
			(end 0.51435 0.2794)
			(stroke
				(width 0.1)
				(type default)
			)
			(layer "B.Fab")
		)
		(fp_line
			(start -0.51435 -0.2794)
			(end -0.51435 0.2794)
			(stroke
				(width 0.1)
				(type default)
			)
			(layer "B.Fab")
		)
		(pad "1" smd circle
			(at 0.40005 0)
			(size 0 0)
			(layers "B.Cu" "B.Mask" "B.Paste")
			(net "VCCIO4")
		)
		(pad "2" smd circle
			(at -0.40005 0)
			(size 0 0)
			(layers "B.Cu" "B.Mask" "B.Paste")
			(net "GND")
		)
		(zone
			(layer "B.Cu")
			(hatch none 0.5)
			(connect_pads
				(clearance 0)
			)
			(min_thickness 0.25)
			(keepout
				(tracks not_allowed)
				(vias allowed)
				(pads allowed)
				(copperpour not_allowed)
				(footprints allowed)
			)
			(placement
				(enabled no)
				(sheetname "")
			)
			(fill
				(thermal_gap 0.5)
				(thermal_bridge_width 0.5)
				(island_removal_mode 0)
			)
			(polygon
				(pts
					(xy 24.1935 -94.32163) (xy 24.28494 -94.379796) (xy 24.48433 -94.379796) (xy 24.5745 -94.32163)
					(xy 24.5745 -94.14637) (xy 24.48433 -94.08795) (xy 24.28494 -94.08795) (xy 24.1935 -94.146116)
				)
			)
		)
	)
	(footprint ""
		(layer "B.Cu")
		(at 63.964058 -71.317612)
		(property "Reference" "R120"
			(at 0 0 0)
			(layer "B.SilkS")
			(hide yes)
			(effects
				(font
					(size 1.27 1.27)
				)
				(justify mirror)
			)
		)
		(property "Value" ""
			(at 0 0 0)
			(layer "B.Fab")
			(effects
				(font
					(size 1.27 1.27)
				)
				(justify mirror)
			)
		)
		(duplicate_pad_numbers_are_jumpers no)
		(fp_line
			(start -0.7874 -0.4064)
			(end -0.7874 0.4064)
			(stroke
				(width 0.1524)
				(type default)
			)
			(layer "B.SilkS")
		)
		(fp_line
			(start -0.7874 0.4064)
			(end 0.7874 0.4064)
			(stroke
				(width 0.1524)
				(type default)
			)
			(layer "B.SilkS")
		)
		(fp_line
			(start 0.7874 -0.4064)
			(end -0.7874 -0.4064)
			(stroke
				(width 0.1524)
				(type default)
			)
			(layer "B.SilkS")
		)
		(fp_line
			(start 0.7874 0.4064)
			(end 0.7874 -0.4064)
			(stroke
				(width 0.1524)
				(type default)
			)
			(layer "B.SilkS")
		)
		(fp_line
			(start -0.67945 -0.3048)
			(end -0.67945 0.3048)
			(stroke
				(width 0.1)
				(type default)
			)
			(layer "B.Fab")
		)
		(fp_line
			(start -0.67945 0.3048)
			(end -0.120396 0.3048)
			(stroke
				(width 0.1)
				(type default)
			)
			(layer "B.Fab")
		)
		(fp_line
			(start -0.12065 -0.3048)
			(end -0.67945 -0.3048)
			(stroke
				(width 0.1)
				(type default)
			)
			(layer "B.Fab")
		)
		(fp_line
			(start -0.12065 -0.2794)
			(end -0.12065 -0.3048)
			(stroke
				(width 0.1)
				(type default)
			)
			(layer "B.Fab")
		)
		(fp_line
			(start -0.120396 0.2794)
			(end 0.12065 0.2794)
			(stroke
				(width 0.1)
				(type default)
			)
			(layer "B.Fab")
		)
		(fp_line
			(start -0.120396 0.3048)
			(end -0.120396 0.2794)
			(stroke
				(width 0.1)
				(type default)
			)
			(layer "B.Fab")
		)
		(fp_line
			(start 0.12065 -0.305054)
			(end 0.12065 -0.2794)
			(stroke
				(width 0.1)
				(type default)
			)
			(layer "B.Fab")
		)
		(fp_line
			(start 0.12065 -0.2794)
			(end -0.12065 -0.2794)
			(stroke
				(width 0.1)
				(type default)
			)
			(layer "B.Fab")
		)
		(fp_line
			(start 0.12065 0.2794)
			(end 0.12065 0.3048)
			(stroke
				(width 0.1)
				(type default)
			)
			(layer "B.Fab")
		)
		(fp_line
			(start 0.12065 0.3048)
			(end 0.67945 0.3048)
			(stroke
				(width 0.1)
				(type default)
			)
			(layer "B.Fab")
		)
		(fp_line
			(start 0.67945 -0.305054)
			(end 0.12065 -0.305054)
			(stroke
				(width 0.1)
				(type default)
			)
			(layer "B.Fab")
		)
		(fp_line
			(start 0.67945 0.3048)
			(end 0.67945 -0.305054)
			(stroke
				(width 0.1)
				(type default)
			)
			(layer "B.Fab")
		)
		(pad "1" smd circle
			(at 0.40005 0 180)
			(size 0 0)
			(layers "B.Cu" "B.Mask" "B.Paste")
			(net "RST_BMC_LPC_ESPI_N")
		)
		(pad "2" smd circle
			(at -0.40005 0 180)
			(size 0 0)
			(layers "B.Cu" "B.Mask" "B.Paste")
			(net "RST_ESPI_LPC_BMC_N")
		)
	)
	(footprint ""
		(layer "B.Cu")
		(at 52.024534 -54.93258 180)
		(property "Reference" "C94"
			(at 0 0 0)
			(layer "B.SilkS")
			(hide yes)
			(effects
				(font
					(size 1.27 1.27)
				)
				(justify mirror)
			)
		)
		(property "Value" ""
			(at 0 0 0)
			(layer "B.Fab")
			(effects
				(font
					(size 1.27 1.27)
				)
				(justify mirror)
			)
		)
		(duplicate_pad_numbers_are_jumpers no)
		(fp_line
			(start 0.7874 0.4064)
			(end 0.7874 -0.4064)
			(stroke
				(width 0.1524)
				(type default)
			)
			(layer "B.SilkS")
		)
		(fp_line
			(start 0.7874 -0.4064)
			(end -0.7874 -0.4064)
			(stroke
				(width 0.1524)
				(type default)
			)
			(layer "B.SilkS")
		)
		(fp_line
			(start -0.7874 0.4064)
			(end 0.7874 0.4064)
			(stroke
				(width 0.1524)
				(type default)
			)
			(layer "B.SilkS")
		)
		(fp_line
			(start -0.7874 -0.4064)
			(end -0.7874 0.4064)
			(stroke
				(width 0.1524)
				(type default)
			)
			(layer "B.SilkS")
		)
		(fp_line
			(start 0.67945 0.3048)
			(end 0.67945 -0.305054)
			(stroke
				(width 0.1)
				(type default)
			)
			(layer "B.Fab")
		)
		(fp_line
			(start 0.67945 -0.305054)
			(end 0.12065 -0.305054)
			(stroke
				(width 0.1)
				(type default)
			)
			(layer "B.Fab")
		)
		(fp_line
			(start 0.12065 0.3048)
			(end 0.67945 0.3048)
			(stroke
				(width 0.1)
				(type default)
			)
			(layer "B.Fab")
		)
		(fp_line
			(start 0.12065 0.2794)
			(end 0.12065 0.3048)
			(stroke
				(width 0.1)
				(type default)
			)
			(layer "B.Fab")
		)
		(fp_line
			(start 0.12065 -0.2794)
			(end -0.12065 -0.2794)
			(stroke
				(width 0.1)
				(type default)
			)
			(layer "B.Fab")
		)
		(fp_line
			(start 0.12065 -0.305054)
			(end 0.12065 -0.2794)
			(stroke
				(width 0.1)
				(type default)
			)
			(layer "B.Fab")
		)
		(fp_line
			(start -0.120396 0.3048)
			(end -0.120396 0.2794)
			(stroke
				(width 0.1)
				(type default)
			)
			(layer "B.Fab")
		)
		(fp_line
			(start -0.120396 0.2794)
			(end 0.12065 0.2794)
			(stroke
				(width 0.1)
				(type default)
			)
			(layer "B.Fab")
		)
		(fp_line
			(start -0.12065 -0.2794)
			(end -0.12065 -0.3048)
			(stroke
				(width 0.1)
				(type default)
			)
			(layer "B.Fab")
		)
		(fp_line
			(start -0.12065 -0.3048)
			(end -0.67945 -0.3048)
			(stroke
				(width 0.1)
				(type default)
			)
			(layer "B.Fab")
		)
		(fp_line
			(start -0.67945 0.3048)
			(end -0.120396 0.3048)
			(stroke
				(width 0.1)
				(type default)
			)
			(layer "B.Fab")
		)
		(fp_line
			(start -0.67945 -0.3048)
			(end -0.67945 0.3048)
			(stroke
				(width 0.1)
				(type default)
			)
			(layer "B.Fab")
		)
		(pad "1" smd circle
			(at 0.40005 0)
			(size 0 0)
			(layers "B.Cu" "B.Mask" "B.Paste")
			(net "P3V3_AUX")
		)
		(pad "2" smd circle
			(at -0.40005 0)
			(size 0 0)
			(layers "B.Cu" "B.Mask" "B.Paste")
			(net "GND")
		)
	)
	(footprint ""
		(layer "B.Cu")
		(at 17.653 -60.325 90)
		(property "Reference" "C158"
			(at 0 0 90)
			(layer "B.SilkS")
			(hide yes)
			(effects
				(font
					(size 1.27 1.27)
				)
				(justify mirror)
			)
		)
		(property "Value" ""
			(at 0 0 90)
			(layer "B.Fab")
			(effects
				(font
					(size 1.27 1.27)
				)
				(justify mirror)
			)
		)
		(duplicate_pad_numbers_are_jumpers no)
		(fp_line
			(start 0.7874 -0.4064)
			(end -0.7874 -0.4064)
			(stroke
				(width 0.1524)
				(type default)
			)
			(layer "B.SilkS")
		)
		(fp_line
			(start -0.7874 -0.4064)
			(end -0.7874 0.4064)
			(stroke
				(width 0.1524)
				(type default)
			)
			(layer "B.SilkS")
		)
		(fp_line
			(start 0.7874 0.4064)
			(end 0.7874 -0.4064)
			(stroke
				(width 0.1524)
				(type default)
			)
			(layer "B.SilkS")
		)
		(fp_line
			(start -0.7874 0.4064)
			(end 0.7874 0.4064)
			(stroke
				(width 0.1524)
				(type default)
			)
			(layer "B.SilkS")
		)
		(fp_line
			(start 0.67945 -0.305054)
			(end 0.12065 -0.305054)
			(stroke
				(width 0.1)
				(type default)
			)
			(layer "B.Fab")
		)
		(fp_line
			(start 0.12065 -0.305054)
			(end 0.12065 -0.2794)
			(stroke
				(width 0.1)
				(type default)
			)
			(layer "B.Fab")
		)
		(fp_line
			(start -0.12065 -0.3048)
			(end -0.67945 -0.3048)
			(stroke
				(width 0.1)
				(type default)
			)
			(layer "B.Fab")
		)
		(fp_line
			(start -0.67945 -0.3048)
			(end -0.67945 0.3048)
			(stroke
				(width 0.1)
				(type default)
			)
			(layer "B.Fab")
		)
		(fp_line
			(start 0.12065 -0.2794)
			(end -0.12065 -0.2794)
			(stroke
				(width 0.1)
				(type default)
			)
			(layer "B.Fab")
		)
		(fp_line
			(start -0.12065 -0.2794)
			(end -0.12065 -0.3048)
			(stroke
				(width 0.1)
				(type default)
			)
			(layer "B.Fab")
		)
		(fp_line
			(start 0.12065 0.2794)
			(end 0.12065 0.3048)
			(stroke
				(width 0.1)
				(type default)
			)
			(layer "B.Fab")
		)
		(fp_line
			(start -0.120396 0.2794)
			(end 0.12065 0.2794)
			(stroke
				(width 0.1)
				(type default)
			)
			(layer "B.Fab")
		)
		(fp_line
			(start 0.67945 0.3048)
			(end 0.67945 -0.305054)
			(stroke
				(width 0.1)
				(type default)
			)
			(layer "B.Fab")
		)
		(fp_line
			(start 0.12065 0.3048)
			(end 0.67945 0.3048)
			(stroke
				(width 0.1)
				(type default)
			)
			(layer "B.Fab")
		)
		(fp_line
			(start -0.120396 0.3048)
			(end -0.120396 0.2794)
			(stroke
				(width 0.1)
				(type default)
			)
			(layer "B.Fab")
		)
		(fp_line
			(start -0.67945 0.3048)
			(end -0.120396 0.3048)
			(stroke
				(width 0.1)
				(type default)
			)
			(layer "B.Fab")
		)
		(pad "1" smd circle
			(at 0.40005 0 270)
			(size 0 0)
			(layers "B.Cu" "B.Mask" "B.Paste")
			(net "P3V3_AUX")
		)
		(pad "2" smd circle
			(at -0.40005 0 270)
			(size 0 0)
			(layers "B.Cu" "B.Mask" "B.Paste")
			(net "GND")
		)
	)
	(footprint ""
		(layer "B.Cu")
		(at 49.461166 -62.116462 90)
		(property "Reference" "R846"
			(at 0 0 90)
			(layer "B.SilkS")
			(hide yes)
			(effects
				(font
					(size 1.27 1.27)
				)
				(justify mirror)
			)
		)
		(property "Value" ""
			(at 0 0 90)
			(layer "B.Fab")
			(effects
				(font
					(size 1.27 1.27)
				)
				(justify mirror)
			)
		)
		(duplicate_pad_numbers_are_jumpers no)
		(fp_line
			(start 0.7874 -0.4064)
			(end -0.7874 -0.4064)
			(stroke
				(width 0.1524)
				(type default)
			)
			(layer "B.SilkS")
		)
		(fp_line
			(start -0.7874 -0.4064)
			(end -0.7874 0.4064)
			(stroke
				(width 0.1524)
				(type default)
			)
			(layer "B.SilkS")
		)
		(fp_line
			(start 0.7874 0.4064)
			(end 0.7874 -0.4064)
			(stroke
				(width 0.1524)
				(type default)
			)
			(layer "B.SilkS")
		)
		(fp_line
			(start -0.7874 0.4064)
			(end 0.7874 0.4064)
			(stroke
				(width 0.1524)
				(type default)
			)
			(layer "B.SilkS")
		)
		(fp_line
			(start 0.67945 -0.305054)
			(end 0.12065 -0.305054)
			(stroke
				(width 0.1)
				(type default)
			)
			(layer "B.Fab")
		)
		(fp_line
			(start 0.12065 -0.305054)
			(end 0.12065 -0.2794)
			(stroke
				(width 0.1)
				(type default)
			)
			(layer "B.Fab")
		)
		(fp_line
			(start -0.12065 -0.3048)
			(end -0.67945 -0.3048)
			(stroke
				(width 0.1)
				(type default)
			)
			(layer "B.Fab")
		)
		(fp_line
			(start -0.67945 -0.3048)
			(end -0.67945 0.3048)
			(stroke
				(width 0.1)
				(type default)
			)
			(layer "B.Fab")
		)
		(fp_line
			(start 0.12065 -0.2794)
			(end -0.12065 -0.2794)
			(stroke
				(width 0.1)
				(type default)
			)
			(layer "B.Fab")
		)
		(fp_line
			(start -0.12065 -0.2794)
			(end -0.12065 -0.3048)
			(stroke
				(width 0.1)
				(type default)
			)
			(layer "B.Fab")
		)
		(fp_line
			(start 0.12065 0.2794)
			(end 0.12065 0.3048)
			(stroke
				(width 0.1)
				(type default)
			)
			(layer "B.Fab")
		)
		(fp_line
			(start -0.120396 0.2794)
			(end 0.12065 0.2794)
			(stroke
				(width 0.1)
				(type default)
			)
			(layer "B.Fab")
		)
		(fp_line
			(start 0.67945 0.3048)
			(end 0.67945 -0.305054)
			(stroke
				(width 0.1)
				(type default)
			)
			(layer "B.Fab")
		)
		(fp_line
			(start 0.12065 0.3048)
			(end 0.67945 0.3048)
			(stroke
				(width 0.1)
				(type default)
			)
			(layer "B.Fab")
		)
		(fp_line
			(start -0.120396 0.3048)
			(end -0.120396 0.2794)
			(stroke
				(width 0.1)
				(type default)
			)
			(layer "B.Fab")
		)
		(fp_line
			(start -0.67945 0.3048)
			(end -0.120396 0.3048)
			(stroke
				(width 0.1)
				(type default)
			)
			(layer "B.Fab")
		)
		(pad "1" smd circle
			(at 0.40005 0 270)
			(size 0 0)
			(layers "B.Cu" "B.Mask" "B.Paste")
			(net "P3V3_AUX")
		)
		(pad "2" smd circle
			(at -0.40005 0 270)
			(size 0 0)
			(layers "B.Cu" "B.Mask" "B.Paste")
			(net "FM_BMC_EN_DET_R")
		)
	)
	(footprint ""
		(layer "B.Cu")
		(at 71.034656 -54.23662)
		(property "Reference" "C3"
			(at 0 0 0)
			(layer "B.SilkS")
			(hide yes)
			(effects
				(font
					(size 1.27 1.27)
				)
				(justify mirror)
			)
		)
		(property "Value" ""
			(at 0 0 0)
			(layer "B.Fab")
			(effects
				(font
					(size 1.27 1.27)
				)
				(justify mirror)
			)
		)
		(duplicate_pad_numbers_are_jumpers no)
		(fp_line
			(start -0.7874 -0.4064)
			(end -0.7874 0.4064)
			(stroke
				(width 0.1524)
				(type default)
			)
			(layer "B.SilkS")
		)
		(fp_line
			(start -0.7874 0.4064)
			(end 0.7874 0.4064)
			(stroke
				(width 0.1524)
				(type default)
			)
			(layer "B.SilkS")
		)
		(fp_line
			(start 0.7874 -0.4064)
			(end -0.7874 -0.4064)
			(stroke
				(width 0.1524)
				(type default)
			)
			(layer "B.SilkS")
		)
		(fp_line
			(start 0.7874 0.4064)
			(end 0.7874 -0.4064)
			(stroke
				(width 0.1524)
				(type default)
			)
			(layer "B.SilkS")
		)
		(fp_line
			(start -0.67945 -0.3048)
			(end -0.67945 0.3048)
			(stroke
				(width 0.1)
				(type default)
			)
			(layer "B.Fab")
		)
		(fp_line
			(start -0.67945 0.3048)
			(end -0.120396 0.3048)
			(stroke
				(width 0.1)
				(type default)
			)
			(layer "B.Fab")
		)
		(fp_line
			(start -0.12065 -0.3048)
			(end -0.67945 -0.3048)
			(stroke
				(width 0.1)
				(type default)
			)
			(layer "B.Fab")
		)
		(fp_line
			(start -0.12065 -0.2794)
			(end -0.12065 -0.3048)
			(stroke
				(width 0.1)
				(type default)
			)
			(layer "B.Fab")
		)
		(fp_line
			(start -0.120396 0.2794)
			(end 0.12065 0.2794)
			(stroke
				(width 0.1)
				(type default)
			)
			(layer "B.Fab")
		)
		(fp_line
			(start -0.120396 0.3048)
			(end -0.120396 0.2794)
			(stroke
				(width 0.1)
				(type default)
			)
			(layer "B.Fab")
		)
		(fp_line
			(start 0.12065 -0.305054)
			(end 0.12065 -0.2794)
			(stroke
				(width 0.1)
				(type default)
			)
			(layer "B.Fab")
		)
		(fp_line
			(start 0.12065 -0.2794)
			(end -0.12065 -0.2794)
			(stroke
				(width 0.1)
				(type default)
			)
			(layer "B.Fab")
		)
		(fp_line
			(start 0.12065 0.2794)
			(end 0.12065 0.3048)
			(stroke
				(width 0.1)
				(type default)
			)
			(layer "B.Fab")
		)
		(fp_line
			(start 0.12065 0.3048)
			(end 0.67945 0.3048)
			(stroke
				(width 0.1)
				(type default)
			)
			(layer "B.Fab")
		)
		(fp_line
			(start 0.67945 -0.305054)
			(end 0.12065 -0.305054)
			(stroke
				(width 0.1)
				(type default)
			)
			(layer "B.Fab")
		)
		(fp_line
			(start 0.67945 0.3048)
			(end 0.67945 -0.305054)
			(stroke
				(width 0.1)
				(type default)
			)
			(layer "B.Fab")
		)
		(pad "1" smd circle
			(at 0.40005 0 180)
			(size 0 0)
			(layers "B.Cu" "B.Mask" "B.Paste")
			(net "P1V2_AUX")
		)
		(pad "2" smd circle
			(at -0.40005 0 180)
			(size 0 0)
			(layers "B.Cu" "B.Mask" "B.Paste")
			(net "GND")
		)
	)
	(footprint ""
		(layer "B.Cu")
		(at 39.930832 -48.915828)
		(property "Reference" "R425"
			(at 0 0 0)
			(layer "B.SilkS")
			(hide yes)
			(effects
				(font
					(size 1.27 1.27)
				)
				(justify mirror)
			)
		)
		(property "Value" ""
			(at 0 0 0)
			(layer "B.Fab")
			(effects
				(font
					(size 1.27 1.27)
				)
				(justify mirror)
			)
		)
		(duplicate_pad_numbers_are_jumpers no)
		(fp_line
			(start -0.7874 -0.4064)
			(end -0.7874 0.4064)
			(stroke
				(width 0.1524)
				(type default)
			)
			(layer "B.SilkS")
		)
		(fp_line
			(start -0.7874 0.4064)
			(end 0.7874 0.4064)
			(stroke
				(width 0.1524)
				(type default)
			)
			(layer "B.SilkS")
		)
		(fp_line
			(start 0.7874 -0.4064)
			(end -0.7874 -0.4064)
			(stroke
				(width 0.1524)
				(type default)
			)
			(layer "B.SilkS")
		)
		(fp_line
			(start 0.7874 0.4064)
			(end 0.7874 -0.4064)
			(stroke
				(width 0.1524)
				(type default)
			)
			(layer "B.SilkS")
		)
		(fp_line
			(start -0.67945 -0.3048)
			(end -0.67945 0.3048)
			(stroke
				(width 0.1)
				(type default)
			)
			(layer "B.Fab")
		)
		(fp_line
			(start -0.67945 0.3048)
			(end -0.120396 0.3048)
			(stroke
				(width 0.1)
				(type default)
			)
			(layer "B.Fab")
		)
		(fp_line
			(start -0.12065 -0.3048)
			(end -0.67945 -0.3048)
			(stroke
				(width 0.1)
				(type default)
			)
			(layer "B.Fab")
		)
		(fp_line
			(start -0.12065 -0.2794)
			(end -0.12065 -0.3048)
			(stroke
				(width 0.1)
				(type default)
			)
			(layer "B.Fab")
		)
		(fp_line
			(start -0.120396 0.2794)
			(end 0.12065 0.2794)
			(stroke
				(width 0.1)
				(type default)
			)
			(layer "B.Fab")
		)
		(fp_line
			(start -0.120396 0.3048)
			(end -0.120396 0.2794)
			(stroke
				(width 0.1)
				(type default)
			)
			(layer "B.Fab")
		)
		(fp_line
			(start 0.12065 -0.305054)
			(end 0.12065 -0.2794)
			(stroke
				(width 0.1)
				(type default)
			)
			(layer "B.Fab")
		)
		(fp_line
			(start 0.12065 -0.2794)
			(end -0.12065 -0.2794)
			(stroke
				(width 0.1)
				(type default)
			)
			(layer "B.Fab")
		)
		(fp_line
			(start 0.12065 0.2794)
			(end 0.12065 0.3048)
			(stroke
				(width 0.1)
				(type default)
			)
			(layer "B.Fab")
		)
		(fp_line
			(start 0.12065 0.3048)
			(end 0.67945 0.3048)
			(stroke
				(width 0.1)
				(type default)
			)
			(layer "B.Fab")
		)
		(fp_line
			(start 0.67945 -0.305054)
			(end 0.12065 -0.305054)
			(stroke
				(width 0.1)
				(type default)
			)
			(layer "B.Fab")
		)
		(fp_line
			(start 0.67945 0.3048)
			(end 0.67945 -0.305054)
			(stroke
				(width 0.1)
				(type default)
			)
			(layer "B.Fab")
		)
		(pad "1" smd circle
			(at 0.40005 0 180)
			(size 0 0)
			(layers "B.Cu" "B.Mask" "B.Paste")
			(net "SMB_BMC_MM14_R_SCL")
		)
		(pad "2" smd circle
			(at -0.40005 0 180)
			(size 0 0)
			(layers "B.Cu" "B.Mask" "B.Paste")
			(net "SMB_BMC_MM14_SCL")
		)
	)
	(footprint ""
		(layer "B.Cu")
		(at 49.39919 -60.207652 -90)
		(property "Reference" "C284"
			(at 0 0 90)
			(layer "B.SilkS")
			(hide yes)
			(effects
				(font
					(size 1.27 1.27)
				)
				(justify mirror)
			)
		)
		(property "Value" ""
			(at 0 0 90)
			(layer "B.Fab")
			(effects
				(font
					(size 1.27 1.27)
				)
				(justify mirror)
			)
		)
		(duplicate_pad_numbers_are_jumpers no)
		(fp_line
			(start -0.7874 0.4064)
			(end 0.7874 0.4064)
			(stroke
				(width 0.1524)
				(type default)
			)
			(layer "B.SilkS")
		)
		(fp_line
			(start 0.7874 0.4064)
			(end 0.7874 -0.4064)
			(stroke
				(width 0.1524)
				(type default)
			)
			(layer "B.SilkS")
		)
		(fp_line
			(start -0.7874 -0.4064)
			(end -0.7874 0.4064)
			(stroke
				(width 0.1524)
				(type default)
			)
			(layer "B.SilkS")
		)
		(fp_line
			(start 0.7874 -0.4064)
			(end -0.7874 -0.4064)
			(stroke
				(width 0.1524)
				(type default)
			)
			(layer "B.SilkS")
		)
		(fp_line
			(start -0.67945 0.3048)
			(end -0.120396 0.3048)
			(stroke
				(width 0.1)
				(type default)
			)
			(layer "B.Fab")
		)
		(fp_line
			(start -0.120396 0.3048)
			(end -0.120396 0.2794)
			(stroke
				(width 0.1)
				(type default)
			)
			(layer "B.Fab")
		)
		(fp_line
			(start 0.12065 0.3048)
			(end 0.67945 0.3048)
			(stroke
				(width 0.1)
				(type default)
			)
			(layer "B.Fab")
		)
		(fp_line
			(start 0.67945 0.3048)
			(end 0.67945 -0.305054)
			(stroke
				(width 0.1)
				(type default)
			)
			(layer "B.Fab")
		)
		(fp_line
			(start -0.120396 0.2794)
			(end 0.12065 0.2794)
			(stroke
				(width 0.1)
				(type default)
			)
			(layer "B.Fab")
		)
		(fp_line
			(start 0.12065 0.2794)
			(end 0.12065 0.3048)
			(stroke
				(width 0.1)
				(type default)
			)
			(layer "B.Fab")
		)
		(fp_line
			(start -0.12065 -0.2794)
			(end -0.12065 -0.3048)
			(stroke
				(width 0.1)
				(type default)
			)
			(layer "B.Fab")
		)
		(fp_line
			(start 0.12065 -0.2794)
			(end -0.12065 -0.2794)
			(stroke
				(width 0.1)
				(type default)
			)
			(layer "B.Fab")
		)
		(fp_line
			(start -0.67945 -0.3048)
			(end -0.67945 0.3048)
			(stroke
				(width 0.1)
				(type default)
			)
			(layer "B.Fab")
		)
		(fp_line
			(start -0.12065 -0.3048)
			(end -0.67945 -0.3048)
			(stroke
				(width 0.1)
				(type default)
			)
			(layer "B.Fab")
		)
		(fp_line
			(start 0.12065 -0.305054)
			(end 0.12065 -0.2794)
			(stroke
				(width 0.1)
				(type default)
			)
			(layer "B.Fab")
		)
		(fp_line
			(start 0.67945 -0.305054)
			(end 0.12065 -0.305054)
			(stroke
				(width 0.1)
				(type default)
			)
			(layer "B.Fab")
		)
		(pad "1" smd circle
			(at 0.40005 0 90)
			(size 0 0)
			(layers "B.Cu" "B.Mask" "B.Paste")
			(net "ADCVREFEXT0")
		)
		(pad "2" smd circle
			(at -0.40005 0 90)
			(size 0 0)
			(layers "B.Cu" "B.Mask" "B.Paste")
			(net "GND")
		)
	)
	(footprint ""
		(layer "B.Cu")
		(at 71.374 -41.402 -90)
		(property "Reference" "C40"
			(at 0 0 90)
			(layer "B.SilkS")
			(hide yes)
			(effects
				(font
					(size 1.27 1.27)
				)
				(justify mirror)
			)
		)
		(property "Value" ""
			(at 0 0 90)
			(layer "B.Fab")
			(effects
				(font
					(size 1.27 1.27)
				)
				(justify mirror)
			)
		)
		(duplicate_pad_numbers_are_jumpers no)
		(fp_line
			(start -1.2954 0.5842)
			(end 1.2954 0.5842)
			(stroke
				(width 0.1524)
				(type default)
			)
			(layer "B.SilkS")
		)
		(fp_line
			(start 1.2954 0.5842)
			(end 1.2954 -0.5842)
			(stroke
				(width 0.1524)
				(type default)
			)
			(layer "B.SilkS")
		)
		(fp_line
			(start -1.2954 -0.5842)
			(end -1.2954 0.5842)
			(stroke
				(width 0.1524)
				(type default)
			)
			(layer "B.SilkS")
		)
		(fp_line
			(start 0 -0.5842)
			(end 0 0.5842)
			(stroke
				(width 0.1524)
				(type default)
			)
			(layer "B.SilkS")
		)
		(fp_line
			(start 1.2954 -0.5842)
			(end -1.2954 -0.5842)
			(stroke
				(width 0.1524)
				(type default)
			)
			(layer "B.SilkS")
		)
		(fp_line
			(start -0.8636 0.4572)
			(end 0.8636 0.4572)
			(stroke
				(width 0.1)
				(type default)
			)
			(layer "B.Fab")
		)
		(fp_line
			(start 0.8636 0.4572)
			(end 0.8636 0.4064)
			(stroke
				(width 0.1)
				(type default)
			)
			(layer "B.Fab")
		)
		(fp_line
			(start -1.1938 0.4064)
			(end -0.8636 0.4064)
			(stroke
				(width 0.1)
				(type default)
			)
			(layer "B.Fab")
		)
		(fp_line
			(start -0.8636 0.4064)
			(end -0.8636 0.4572)
			(stroke
				(width 0.1)
				(type default)
			)
			(layer "B.Fab")
		)
		(fp_line
			(start 0.8636 0.4064)
			(end 1.1938 0.4064)
			(stroke
				(width 0.1)
				(type default)
			)
			(layer "B.Fab")
		)
		(fp_line
			(start 1.1938 0.4064)
			(end 1.1938 -0.4064)
			(stroke
				(width 0.1)
				(type default)
			)
			(layer "B.Fab")
		)
		(fp_line
			(start -1.1938 -0.4064)
			(end -1.1938 0.4064)
			(stroke
				(width 0.1)
				(type default)
			)
			(layer "B.Fab")
		)
		(fp_line
			(start -0.8636 -0.4064)
			(end -1.1938 -0.4064)
			(stroke
				(width 0.1)
				(type default)
			)
			(layer "B.Fab")
		)
		(fp_line
			(start 0.8636 -0.4064)
			(end 0.8636 -0.4572)
			(stroke
				(width 0.1)
				(type default)
			)
			(layer "B.Fab")
		)
		(fp_line
			(start 1.1938 -0.4064)
			(end 0.8636 -0.4064)
			(stroke
				(width 0.1)
				(type default)
			)
			(layer "B.Fab")
		)
		(fp_line
			(start -0.8636 -0.4572)
			(end -0.8636 -0.4064)
			(stroke
				(width 0.1)
				(type default)
			)
			(layer "B.Fab")
		)
		(fp_line
			(start 0.8636 -0.4572)
			(end -0.8636 -0.4572)
			(stroke
				(width 0.1)
				(type default)
			)
			(layer "B.Fab")
		)
		(pad "1" smd rect
			(at 0.7366 0 180)
			(size 0.7112 0.8128)
			(layers "B.Cu" "B.Mask" "B.Paste")
			(net "P1V8_BMC_USB2AV18")
		)
		(pad "2" smd rect
			(at -0.7366 0 180)
			(size 0.7112 0.8128)
			(layers "B.Cu" "B.Mask" "B.Paste")
			(net "GND")
		)
	)
	(footprint ""
		(layer "B.Cu")
		(at 22.987 -18.669 -90)
		(property "Reference" "C197"
			(at 0 0 90)
			(layer "B.SilkS")
			(hide yes)
			(effects
				(font
					(size 1.27 1.27)
				)
				(justify mirror)
			)
		)
		(property "Value" ""
			(at 0 0 90)
			(layer "B.Fab")
			(effects
				(font
					(size 1.27 1.27)
				)
				(justify mirror)
			)
		)
		(duplicate_pad_numbers_are_jumpers no)
		(fp_line
			(start -0.7874 0.4064)
			(end 0.7874 0.4064)
			(stroke
				(width 0.1524)
				(type default)
			)
			(layer "B.SilkS")
		)
		(fp_line
			(start 0.7874 0.4064)
			(end 0.7874 -0.4064)
			(stroke
				(width 0.1524)
				(type default)
			)
			(layer "B.SilkS")
		)
		(fp_line
			(start -0.7874 -0.4064)
			(end -0.7874 0.4064)
			(stroke
				(width 0.1524)
				(type default)
			)
			(layer "B.SilkS")
		)
		(fp_line
			(start 0.7874 -0.4064)
			(end -0.7874 -0.4064)
			(stroke
				(width 0.1524)
				(type default)
			)
			(layer "B.SilkS")
		)
		(fp_line
			(start -0.67945 0.3048)
			(end -0.120396 0.3048)
			(stroke
				(width 0.1)
				(type default)
			)
			(layer "B.Fab")
		)
		(fp_line
			(start -0.120396 0.3048)
			(end -0.120396 0.2794)
			(stroke
				(width 0.1)
				(type default)
			)
			(layer "B.Fab")
		)
		(fp_line
			(start 0.12065 0.3048)
			(end 0.67945 0.3048)
			(stroke
				(width 0.1)
				(type default)
			)
			(layer "B.Fab")
		)
		(fp_line
			(start 0.67945 0.3048)
			(end 0.67945 -0.305054)
			(stroke
				(width 0.1)
				(type default)
			)
			(layer "B.Fab")
		)
		(fp_line
			(start -0.120396 0.2794)
			(end 0.12065 0.2794)
			(stroke
				(width 0.1)
				(type default)
			)
			(layer "B.Fab")
		)
		(fp_line
			(start 0.12065 0.2794)
			(end 0.12065 0.3048)
			(stroke
				(width 0.1)
				(type default)
			)
			(layer "B.Fab")
		)
		(fp_line
			(start -0.12065 -0.2794)
			(end -0.12065 -0.3048)
			(stroke
				(width 0.1)
				(type default)
			)
			(layer "B.Fab")
		)
		(fp_line
			(start 0.12065 -0.2794)
			(end -0.12065 -0.2794)
			(stroke
				(width 0.1)
				(type default)
			)
			(layer "B.Fab")
		)
		(fp_line
			(start -0.67945 -0.3048)
			(end -0.67945 0.3048)
			(stroke
				(width 0.1)
				(type default)
			)
			(layer "B.Fab")
		)
		(fp_line
			(start -0.12065 -0.3048)
			(end -0.67945 -0.3048)
			(stroke
				(width 0.1)
				(type default)
			)
			(layer "B.Fab")
		)
		(fp_line
			(start 0.12065 -0.305054)
			(end 0.12065 -0.2794)
			(stroke
				(width 0.1)
				(type default)
			)
			(layer "B.Fab")
		)
		(fp_line
			(start 0.67945 -0.305054)
			(end 0.12065 -0.305054)
			(stroke
				(width 0.1)
				(type default)
			)
			(layer "B.Fab")
		)
		(pad "1" smd circle
			(at 0.40005 0 90)
			(size 0 0)
			(layers "B.Cu" "B.Mask" "B.Paste")
			(net "HDD_LED_P5V_AUX")
		)
		(pad "2" smd circle
			(at -0.40005 0 90)
			(size 0 0)
			(layers "B.Cu" "B.Mask" "B.Paste")
			(net "GND")
		)
	)
	(footprint ""
		(layer "B.Cu")
		(at 50.8 -28.829 -90)
		(property "Reference" "R879"
			(at 0 0 90)
			(layer "B.SilkS")
			(hide yes)
			(effects
				(font
					(size 1.27 1.27)
				)
				(justify mirror)
			)
		)
		(property "Value" ""
			(at 0 0 90)
			(layer "B.Fab")
			(effects
				(font
					(size 1.27 1.27)
				)
				(justify mirror)
			)
		)
		(duplicate_pad_numbers_are_jumpers no)
		(fp_line
			(start -0.7874 0.4064)
			(end 0.7874 0.4064)
			(stroke
				(width 0.1524)
				(type default)
			)
			(layer "B.SilkS")
		)
		(fp_line
			(start 0.7874 0.4064)
			(end 0.7874 -0.4064)
			(stroke
				(width 0.1524)
				(type default)
			)
			(layer "B.SilkS")
		)
		(fp_line
			(start -0.7874 -0.4064)
			(end -0.7874 0.4064)
			(stroke
				(width 0.1524)
				(type default)
			)
			(layer "B.SilkS")
		)
		(fp_line
			(start 0.7874 -0.4064)
			(end -0.7874 -0.4064)
			(stroke
				(width 0.1524)
				(type default)
			)
			(layer "B.SilkS")
		)
		(fp_line
			(start -0.67945 0.3048)
			(end -0.120396 0.3048)
			(stroke
				(width 0.1)
				(type default)
			)
			(layer "B.Fab")
		)
		(fp_line
			(start -0.120396 0.3048)
			(end -0.120396 0.2794)
			(stroke
				(width 0.1)
				(type default)
			)
			(layer "B.Fab")
		)
		(fp_line
			(start 0.12065 0.3048)
			(end 0.67945 0.3048)
			(stroke
				(width 0.1)
				(type default)
			)
			(layer "B.Fab")
		)
		(fp_line
			(start 0.67945 0.3048)
			(end 0.67945 -0.305054)
			(stroke
				(width 0.1)
				(type default)
			)
			(layer "B.Fab")
		)
		(fp_line
			(start -0.120396 0.2794)
			(end 0.12065 0.2794)
			(stroke
				(width 0.1)
				(type default)
			)
			(layer "B.Fab")
		)
		(fp_line
			(start 0.12065 0.2794)
			(end 0.12065 0.3048)
			(stroke
				(width 0.1)
				(type default)
			)
			(layer "B.Fab")
		)
		(fp_line
			(start -0.12065 -0.2794)
			(end -0.12065 -0.3048)
			(stroke
				(width 0.1)
				(type default)
			)
			(layer "B.Fab")
		)
		(fp_line
			(start 0.12065 -0.2794)
			(end -0.12065 -0.2794)
			(stroke
				(width 0.1)
				(type default)
			)
			(layer "B.Fab")
		)
		(fp_line
			(start -0.67945 -0.3048)
			(end -0.67945 0.3048)
			(stroke
				(width 0.1)
				(type default)
			)
			(layer "B.Fab")
		)
		(fp_line
			(start -0.12065 -0.3048)
			(end -0.67945 -0.3048)
			(stroke
				(width 0.1)
				(type default)
			)
			(layer "B.Fab")
		)
		(fp_line
			(start 0.12065 -0.305054)
			(end 0.12065 -0.2794)
			(stroke
				(width 0.1)
				(type default)
			)
			(layer "B.Fab")
		)
		(fp_line
			(start 0.67945 -0.305054)
			(end 0.12065 -0.305054)
			(stroke
				(width 0.1)
				(type default)
			)
			(layer "B.Fab")
		)
		(pad "1" smd circle
			(at 0.40005 0 90)
			(size 0 0)
			(layers "B.Cu" "B.Mask" "B.Paste")
			(net "SMB_BMC_MM16_R5_SCL")
		)
		(pad "2" smd circle
			(at -0.40005 0 90)
			(size 0 0)
			(layers "B.Cu" "B.Mask" "B.Paste")
			(net "SMB_BMC_MM16_SCL")
		)
	)
	(footprint ""
		(layer "B.Cu")
		(at 47.55388 -88.265 90)
		(property "Reference" "R770"
			(at 0 0 90)
			(layer "B.SilkS")
			(hide yes)
			(effects
				(font
					(size 1.27 1.27)
				)
				(justify mirror)
			)
		)
		(property "Value" ""
			(at 0 0 90)
			(layer "B.Fab")
			(effects
				(font
					(size 1.27 1.27)
				)
				(justify mirror)
			)
		)
		(duplicate_pad_numbers_are_jumpers no)
		(fp_line
			(start 0.7874 -0.4064)
			(end -0.7874 -0.4064)
			(stroke
				(width 0.1524)
				(type default)
			)
			(layer "B.SilkS")
		)
		(fp_line
			(start -0.7874 -0.4064)
			(end -0.7874 0.4064)
			(stroke
				(width 0.1524)
				(type default)
			)
			(layer "B.SilkS")
		)
		(fp_line
			(start 0.7874 0.4064)
			(end 0.7874 -0.4064)
			(stroke
				(width 0.1524)
				(type default)
			)
			(layer "B.SilkS")
		)
		(fp_line
			(start -0.7874 0.4064)
			(end 0.7874 0.4064)
			(stroke
				(width 0.1524)
				(type default)
			)
			(layer "B.SilkS")
		)
		(fp_line
			(start 0.67945 -0.305054)
			(end 0.12065 -0.305054)
			(stroke
				(width 0.1)
				(type default)
			)
			(layer "B.Fab")
		)
		(fp_line
			(start 0.12065 -0.305054)
			(end 0.12065 -0.2794)
			(stroke
				(width 0.1)
				(type default)
			)
			(layer "B.Fab")
		)
		(fp_line
			(start -0.12065 -0.3048)
			(end -0.67945 -0.3048)
			(stroke
				(width 0.1)
				(type default)
			)
			(layer "B.Fab")
		)
		(fp_line
			(start -0.67945 -0.3048)
			(end -0.67945 0.3048)
			(stroke
				(width 0.1)
				(type default)
			)
			(layer "B.Fab")
		)
		(fp_line
			(start 0.12065 -0.2794)
			(end -0.12065 -0.2794)
			(stroke
				(width 0.1)
				(type default)
			)
			(layer "B.Fab")
		)
		(fp_line
			(start -0.12065 -0.2794)
			(end -0.12065 -0.3048)
			(stroke
				(width 0.1)
				(type default)
			)
			(layer "B.Fab")
		)
		(fp_line
			(start 0.12065 0.2794)
			(end 0.12065 0.3048)
			(stroke
				(width 0.1)
				(type default)
			)
			(layer "B.Fab")
		)
		(fp_line
			(start -0.120396 0.2794)
			(end 0.12065 0.2794)
			(stroke
				(width 0.1)
				(type default)
			)
			(layer "B.Fab")
		)
		(fp_line
			(start 0.67945 0.3048)
			(end 0.67945 -0.305054)
			(stroke
				(width 0.1)
				(type default)
			)
			(layer "B.Fab")
		)
		(fp_line
			(start 0.12065 0.3048)
			(end 0.67945 0.3048)
			(stroke
				(width 0.1)
				(type default)
			)
			(layer "B.Fab")
		)
		(fp_line
			(start -0.120396 0.3048)
			(end -0.120396 0.2794)
			(stroke
				(width 0.1)
				(type default)
			)
			(layer "B.Fab")
		)
		(fp_line
			(start -0.67945 0.3048)
			(end -0.120396 0.3048)
			(stroke
				(width 0.1)
				(type default)
			)
			(layer "B.Fab")
		)
		(pad "1" smd circle
			(at 0.40005 0 270)
			(size 0 0)
			(layers "B.Cu" "B.Mask" "B.Paste")
			(net "GND")
		)
		(pad "2" smd circle
			(at -0.40005 0 270)
			(size 0 0)
			(layers "B.Cu" "B.Mask" "B.Paste")
			(net "UART_BMC_5_TXD_R")
		)
	)
	(footprint ""
		(layer "B.Cu")
		(at 24.590756 -106.50982 -90)
		(property "Reference" "R44"
			(at 0 0 90)
			(layer "B.SilkS")
			(hide yes)
			(effects
				(font
					(size 1.27 1.27)
				)
				(justify mirror)
			)
		)
		(property "Value" ""
			(at 0 0 90)
			(layer "B.Fab")
			(effects
				(font
					(size 1.27 1.27)
				)
				(justify mirror)
			)
		)
		(duplicate_pad_numbers_are_jumpers no)
		(fp_line
			(start -0.7874 0.4064)
			(end 0.7874 0.4064)
			(stroke
				(width 0.1524)
				(type default)
			)
			(layer "B.SilkS")
		)
		(fp_line
			(start 0.7874 0.4064)
			(end 0.7874 -0.4064)
			(stroke
				(width 0.1524)
				(type default)
			)
			(layer "B.SilkS")
		)
		(fp_line
			(start -0.7874 -0.4064)
			(end -0.7874 0.4064)
			(stroke
				(width 0.1524)
				(type default)
			)
			(layer "B.SilkS")
		)
		(fp_line
			(start 0.7874 -0.4064)
			(end -0.7874 -0.4064)
			(stroke
				(width 0.1524)
				(type default)
			)
			(layer "B.SilkS")
		)
		(fp_line
			(start -0.67945 0.3048)
			(end -0.120396 0.3048)
			(stroke
				(width 0.1)
				(type default)
			)
			(layer "B.Fab")
		)
		(fp_line
			(start -0.120396 0.3048)
			(end -0.120396 0.2794)
			(stroke
				(width 0.1)
				(type default)
			)
			(layer "B.Fab")
		)
		(fp_line
			(start 0.12065 0.3048)
			(end 0.67945 0.3048)
			(stroke
				(width 0.1)
				(type default)
			)
			(layer "B.Fab")
		)
		(fp_line
			(start 0.67945 0.3048)
			(end 0.67945 -0.305054)
			(stroke
				(width 0.1)
				(type default)
			)
			(layer "B.Fab")
		)
		(fp_line
			(start -0.120396 0.2794)
			(end 0.12065 0.2794)
			(stroke
				(width 0.1)
				(type default)
			)
			(layer "B.Fab")
		)
		(fp_line
			(start 0.12065 0.2794)
			(end 0.12065 0.3048)
			(stroke
				(width 0.1)
				(type default)
			)
			(layer "B.Fab")
		)
		(fp_line
			(start -0.12065 -0.2794)
			(end -0.12065 -0.3048)
			(stroke
				(width 0.1)
				(type default)
			)
			(layer "B.Fab")
		)
		(fp_line
			(start 0.12065 -0.2794)
			(end -0.12065 -0.2794)
			(stroke
				(width 0.1)
				(type default)
			)
			(layer "B.Fab")
		)
		(fp_line
			(start -0.67945 -0.3048)
			(end -0.67945 0.3048)
			(stroke
				(width 0.1)
				(type default)
			)
			(layer "B.Fab")
		)
		(fp_line
			(start -0.12065 -0.3048)
			(end -0.67945 -0.3048)
			(stroke
				(width 0.1)
				(type default)
			)
			(layer "B.Fab")
		)
		(fp_line
			(start 0.12065 -0.305054)
			(end 0.12065 -0.2794)
			(stroke
				(width 0.1)
				(type default)
			)
			(layer "B.Fab")
		)
		(fp_line
			(start 0.67945 -0.305054)
			(end 0.12065 -0.305054)
			(stroke
				(width 0.1)
				(type default)
			)
			(layer "B.Fab")
		)
		(pad "1" smd circle
			(at 0.40005 0 90)
			(size 0 0)
			(layers "B.Cu" "B.Mask" "B.Paste")
			(net "P3V3_AUX")
		)
		(pad "2" smd circle
			(at -0.40005 0 90)
			(size 0 0)
			(layers "B.Cu" "B.Mask" "B.Paste")
			(net "SYS_PWRBTN_N")
		)
	)
	(footprint ""
		(layer "B.Cu")
		(at 52.578 -34.6456 -90)
		(property "Reference" "R158"
			(at 0 0 90)
			(layer "B.SilkS")
			(hide yes)
			(effects
				(font
					(size 1.27 1.27)
				)
				(justify mirror)
			)
		)
		(property "Value" ""
			(at 0 0 90)
			(layer "B.Fab")
			(effects
				(font
					(size 1.27 1.27)
				)
				(justify mirror)
			)
		)
		(duplicate_pad_numbers_are_jumpers no)
		(fp_line
			(start -0.7874 0.4064)
			(end 0.7874 0.4064)
			(stroke
				(width 0.1524)
				(type default)
			)
			(layer "B.SilkS")
		)
		(fp_line
			(start 0.7874 0.4064)
			(end 0.7874 -0.4064)
			(stroke
				(width 0.1524)
				(type default)
			)
			(layer "B.SilkS")
		)
		(fp_line
			(start -0.7874 -0.4064)
			(end -0.7874 0.4064)
			(stroke
				(width 0.1524)
				(type default)
			)
			(layer "B.SilkS")
		)
		(fp_line
			(start 0.7874 -0.4064)
			(end -0.7874 -0.4064)
			(stroke
				(width 0.1524)
				(type default)
			)
			(layer "B.SilkS")
		)
		(fp_line
			(start -0.67945 0.3048)
			(end -0.120396 0.3048)
			(stroke
				(width 0.1)
				(type default)
			)
			(layer "B.Fab")
		)
		(fp_line
			(start -0.120396 0.3048)
			(end -0.120396 0.2794)
			(stroke
				(width 0.1)
				(type default)
			)
			(layer "B.Fab")
		)
		(fp_line
			(start 0.12065 0.3048)
			(end 0.67945 0.3048)
			(stroke
				(width 0.1)
				(type default)
			)
			(layer "B.Fab")
		)
		(fp_line
			(start 0.67945 0.3048)
			(end 0.67945 -0.305054)
			(stroke
				(width 0.1)
				(type default)
			)
			(layer "B.Fab")
		)
		(fp_line
			(start -0.120396 0.2794)
			(end 0.12065 0.2794)
			(stroke
				(width 0.1)
				(type default)
			)
			(layer "B.Fab")
		)
		(fp_line
			(start 0.12065 0.2794)
			(end 0.12065 0.3048)
			(stroke
				(width 0.1)
				(type default)
			)
			(layer "B.Fab")
		)
		(fp_line
			(start -0.12065 -0.2794)
			(end -0.12065 -0.3048)
			(stroke
				(width 0.1)
				(type default)
			)
			(layer "B.Fab")
		)
		(fp_line
			(start 0.12065 -0.2794)
			(end -0.12065 -0.2794)
			(stroke
				(width 0.1)
				(type default)
			)
			(layer "B.Fab")
		)
		(fp_line
			(start -0.67945 -0.3048)
			(end -0.67945 0.3048)
			(stroke
				(width 0.1)
				(type default)
			)
			(layer "B.Fab")
		)
		(fp_line
			(start -0.12065 -0.3048)
			(end -0.67945 -0.3048)
			(stroke
				(width 0.1)
				(type default)
			)
			(layer "B.Fab")
		)
		(fp_line
			(start 0.12065 -0.305054)
			(end 0.12065 -0.2794)
			(stroke
				(width 0.1)
				(type default)
			)
			(layer "B.Fab")
		)
		(fp_line
			(start 0.67945 -0.305054)
			(end 0.12065 -0.305054)
			(stroke
				(width 0.1)
				(type default)
			)
			(layer "B.Fab")
		)
		(pad "1" smd circle
			(at 0.40005 0 90)
			(size 0 0)
			(layers "B.Cu" "B.Mask" "B.Paste")
			(net "FM_DBP_CPU_PREQ_GF_R_N")
		)
		(pad "2" smd circle
			(at -0.40005 0 90)
			(size 0 0)
			(layers "B.Cu" "B.Mask" "B.Paste")
			(net "FM_DBP_CPU_PREQ_GF_N")
		)
	)
	(footprint ""
		(layer "B.Cu")
		(at 17.18056 -85.14588)
		(property "Reference" "R270"
			(at 0 0 0)
			(layer "B.SilkS")
			(hide yes)
			(effects
				(font
					(size 1.27 1.27)
				)
				(justify mirror)
			)
		)
		(property "Value" ""
			(at 0 0 0)
			(layer "B.Fab")
			(effects
				(font
					(size 1.27 1.27)
				)
				(justify mirror)
			)
		)
		(duplicate_pad_numbers_are_jumpers no)
		(fp_line
			(start -0.7874 -0.4064)
			(end -0.7874 0.4064)
			(stroke
				(width 0.1524)
				(type default)
			)
			(layer "B.SilkS")
		)
		(fp_line
			(start -0.7874 0.4064)
			(end 0.7874 0.4064)
			(stroke
				(width 0.1524)
				(type default)
			)
			(layer "B.SilkS")
		)
		(fp_line
			(start 0.7874 -0.4064)
			(end -0.7874 -0.4064)
			(stroke
				(width 0.1524)
				(type default)
			)
			(layer "B.SilkS")
		)
		(fp_line
			(start 0.7874 0.4064)
			(end 0.7874 -0.4064)
			(stroke
				(width 0.1524)
				(type default)
			)
			(layer "B.SilkS")
		)
		(fp_line
			(start -0.67945 -0.3048)
			(end -0.67945 0.3048)
			(stroke
				(width 0.1)
				(type default)
			)
			(layer "B.Fab")
		)
		(fp_line
			(start -0.67945 0.3048)
			(end -0.120396 0.3048)
			(stroke
				(width 0.1)
				(type default)
			)
			(layer "B.Fab")
		)
		(fp_line
			(start -0.12065 -0.3048)
			(end -0.67945 -0.3048)
			(stroke
				(width 0.1)
				(type default)
			)
			(layer "B.Fab")
		)
		(fp_line
			(start -0.12065 -0.2794)
			(end -0.12065 -0.3048)
			(stroke
				(width 0.1)
				(type default)
			)
			(layer "B.Fab")
		)
		(fp_line
			(start -0.120396 0.2794)
			(end 0.12065 0.2794)
			(stroke
				(width 0.1)
				(type default)
			)
			(layer "B.Fab")
		)
		(fp_line
			(start -0.120396 0.3048)
			(end -0.120396 0.2794)
			(stroke
				(width 0.1)
				(type default)
			)
			(layer "B.Fab")
		)
		(fp_line
			(start 0.12065 -0.305054)
			(end 0.12065 -0.2794)
			(stroke
				(width 0.1)
				(type default)
			)
			(layer "B.Fab")
		)
		(fp_line
			(start 0.12065 -0.2794)
			(end -0.12065 -0.2794)
			(stroke
				(width 0.1)
				(type default)
			)
			(layer "B.Fab")
		)
		(fp_line
			(start 0.12065 0.2794)
			(end 0.12065 0.3048)
			(stroke
				(width 0.1)
				(type default)
			)
			(layer "B.Fab")
		)
		(fp_line
			(start 0.12065 0.3048)
			(end 0.67945 0.3048)
			(stroke
				(width 0.1)
				(type default)
			)
			(layer "B.Fab")
		)
		(fp_line
			(start 0.67945 -0.305054)
			(end 0.12065 -0.305054)
			(stroke
				(width 0.1)
				(type default)
			)
			(layer "B.Fab")
		)
		(fp_line
			(start 0.67945 0.3048)
			(end 0.67945 -0.305054)
			(stroke
				(width 0.1)
				(type default)
			)
			(layer "B.Fab")
		)
		(pad "1" smd circle
			(at 0.40005 0 180)
			(size 0 0)
			(layers "B.Cu" "B.Mask" "B.Paste")
			(net "FM_CPU_MSMI_CATERR_LVT3_PLD_N")
		)
		(pad "2" smd circle
			(at -0.40005 0 180)
			(size 0 0)
			(layers "B.Cu" "B.Mask" "B.Paste")
			(net "FM_CPU_MSMI_CATERR_LVT3_N")
		)
	)
	(footprint ""
		(layer "B.Cu")
		(at 42.855896 -55.297324 180)
		(property "Reference" "L7"
			(at 0 0 0)
			(layer "B.SilkS")
			(hide yes)
			(effects
				(font
					(size 1.27 1.27)
				)
				(justify mirror)
			)
		)
		(property "Value" ""
			(at 0 0 0)
			(layer "B.Fab")
			(effects
				(font
					(size 1.27 1.27)
				)
				(justify mirror)
			)
		)
		(duplicate_pad_numbers_are_jumpers no)
		(fp_line
			(start 1.27 0.5842)
			(end 1.27 -0.5842)
			(stroke
				(width 0.1524)
				(type default)
			)
			(layer "B.SilkS")
		)
		(fp_line
			(start 1.27 -0.5588)
			(end 1.27 -0.5842)
			(stroke
				(width 0.1524)
				(type default)
			)
			(layer "B.SilkS")
		)
		(fp_line
			(start 1.27 -0.5842)
			(end -1.27 -0.5842)
			(stroke
				(width 0.1524)
				(type default)
			)
			(layer "B.SilkS")
		)
		(fp_line
			(start 0.127 0.5842)
			(end 0.127 -0.5842)
			(stroke
				(width 0.1524)
				(type default)
			)
			(layer "B.SilkS")
		)
		(fp_line
			(start -0.127 0.5842)
			(end -0.127 -0.5842)
			(stroke
				(width 0.1524)
				(type default)
			)
			(layer "B.SilkS")
		)
		(fp_line
			(start -1.27 0.5842)
			(end 1.27 0.5842)
			(stroke
				(width 0.1524)
				(type default)
			)
			(layer "B.SilkS")
		)
		(fp_line
			(start -1.27 0.5842)
			(end -1.27 -0.5842)
			(stroke
				(width 0.1524)
				(type default)
			)
			(layer "B.SilkS")
		)
		(fp_line
			(start 1.194308 0.406654)
			(end 1.194308 -0.406654)
			(stroke
				(width 0.1)
				(type default)
			)
			(layer "B.Fab")
		)
		(fp_line
			(start 1.194308 -0.406654)
			(end 0.9144 -0.406654)
			(stroke
				(width 0.1)
				(type default)
			)
			(layer "B.Fab")
		)
		(fp_line
			(start 0.9144 0.508)
			(end 0.9144 0.406654)
			(stroke
				(width 0.1)
				(type default)
			)
			(layer "B.Fab")
		)
		(fp_line
			(start 0.9144 0.406654)
			(end 1.194308 0.406654)
			(stroke
				(width 0.1)
				(type default)
			)
			(layer "B.Fab")
		)
		(fp_line
			(start 0.9144 -0.406654)
			(end 0.9144 -0.508)
			(stroke
				(width 0.1)
				(type default)
			)
			(layer "B.Fab")
		)
		(fp_line
			(start 0.9144 -0.508)
			(end -0.9144 -0.508)
			(stroke
				(width 0.1)
				(type default)
			)
			(layer "B.Fab")
		)
		(fp_line
			(start -0.9144 0.508)
			(end 0.9144 0.508)
			(stroke
				(width 0.1)
				(type default)
			)
			(layer "B.Fab")
		)
		(fp_line
			(start -0.9144 0.4064)
			(end -0.9144 0.508)
			(stroke
				(width 0.1)
				(type default)
			)
			(layer "B.Fab")
		)
		(fp_line
			(start -0.9144 -0.406654)
			(end -1.1938 -0.406654)
			(stroke
				(width 0.1)
				(type default)
			)
			(layer "B.Fab")
		)
		(fp_line
			(start -0.9144 -0.508)
			(end -0.9144 -0.406654)
			(stroke
				(width 0.1)
				(type default)
			)
			(layer "B.Fab")
		)
		(fp_line
			(start -1.1938 0.4064)
			(end -0.9144 0.4064)
			(stroke
				(width 0.1)
				(type default)
			)
			(layer "B.Fab")
		)
		(fp_line
			(start -1.1938 -0.406654)
			(end -1.1938 0.4064)
			(stroke
				(width 0.1)
				(type default)
			)
			(layer "B.Fab")
		)
		(pad "1" smd rect
			(at 0.7366 0 90)
			(size 0.7112 0.8128)
			(layers "B.Cu" "B.Mask" "B.Paste")
			(net "P3V3_AUX")
		)
		(pad "2" smd rect
			(at -0.7366 0 90)
			(size 0.7112 0.8128)
			(layers "B.Cu" "B.Mask" "B.Paste")
			(net "P3V3_STBY_DACAV33")
		)
	)
	(footprint ""
		(layer "B.Cu")
		(at 19.853656 -93.98 180)
		(property "Reference" "C243"
			(at 0 0 0)
			(layer "B.SilkS")
			(hide yes)
			(effects
				(font
					(size 1.27 1.27)
				)
				(justify mirror)
			)
		)
		(property "Value" ""
			(at 0 0 0)
			(layer "B.Fab")
			(effects
				(font
					(size 1.27 1.27)
				)
				(justify mirror)
			)
		)
		(duplicate_pad_numbers_are_jumpers no)
		(fp_line
			(start 0.69215 0.2921)
			(end 0.69215 -0.2921)
			(stroke
				(width 0.1524)
				(type default)
			)
			(layer "B.SilkS")
		)
		(fp_line
			(start 0.69215 -0.2921)
			(end -0.69215 -0.2921)
			(stroke
				(width 0.1524)
				(type default)
			)
			(layer "B.SilkS")
		)
		(fp_line
			(start -0.69215 0.2921)
			(end 0.69215 0.2921)
			(stroke
				(width 0.1524)
				(type default)
			)
			(layer "B.SilkS")
		)
		(fp_line
			(start -0.69215 -0.2921)
			(end -0.69215 0.2921)
			(stroke
				(width 0.1524)
				(type default)
			)
			(layer "B.SilkS")
		)
		(fp_line
			(start 0.51435 0.2794)
			(end 0.51435 -0.2794)
			(stroke
				(width 0.1)
				(type default)
			)
			(layer "B.Fab")
		)
		(fp_line
			(start 0.51435 -0.2794)
			(end -0.51435 -0.2794)
			(stroke
				(width 0.1)
				(type default)
			)
			(layer "B.Fab")
		)
		(fp_line
			(start -0.51435 0.2794)
			(end 0.51435 0.2794)
			(stroke
				(width 0.1)
				(type default)
			)
			(layer "B.Fab")
		)
		(fp_line
			(start -0.51435 -0.2794)
			(end -0.51435 0.2794)
			(stroke
				(width 0.1)
				(type default)
			)
			(layer "B.Fab")
		)
		(pad "1" smd circle
			(at 0.40005 0)
			(size 0 0)
			(layers "B.Cu" "B.Mask" "B.Paste")
			(net "VCCIO1")
		)
		(pad "2" smd circle
			(at -0.40005 0)
			(size 0 0)
			(layers "B.Cu" "B.Mask" "B.Paste")
			(net "GND")
		)
		(zone
			(layer "B.Cu")
			(hatch none 0.5)
			(connect_pads
				(clearance 0)
			)
			(min_thickness 0.25)
			(keepout
				(tracks not_allowed)
				(vias allowed)
				(pads allowed)
				(copperpour not_allowed)
				(footprints allowed)
			)
			(placement
				(enabled no)
				(sheetname "")
			)
			(fill
				(thermal_gap 0.5)
				(thermal_bridge_width 0.5)
				(island_removal_mode 0)
			)
			(polygon
				(pts
					(xy 19.663156 -94.06763) (xy 19.754596 -94.125796) (xy 19.953986 -94.125796) (xy 20.044156 -94.06763)
					(xy 20.044156 -93.89237) (xy 19.953986 -93.83395) (xy 19.754596 -93.83395) (xy 19.663156 -93.892116)
				)
			)
		)
	)
	(footprint ""
		(layer "B.Cu")
		(at 50.974244 -49.38141 180)
		(property "Reference" "C103"
			(at 0 0 0)
			(layer "B.SilkS")
			(hide yes)
			(effects
				(font
					(size 1.27 1.27)
				)
				(justify mirror)
			)
		)
		(property "Value" ""
			(at 0 0 0)
			(layer "B.Fab")
			(effects
				(font
					(size 1.27 1.27)
				)
				(justify mirror)
			)
		)
		(duplicate_pad_numbers_are_jumpers no)
		(fp_line
			(start 0.7874 0.4064)
			(end 0.7874 -0.4064)
			(stroke
				(width 0.1524)
				(type default)
			)
			(layer "B.SilkS")
		)
		(fp_line
			(start 0.7874 -0.4064)
			(end -0.7874 -0.4064)
			(stroke
				(width 0.1524)
				(type default)
			)
			(layer "B.SilkS")
		)
		(fp_line
			(start -0.7874 0.4064)
			(end 0.7874 0.4064)
			(stroke
				(width 0.1524)
				(type default)
			)
			(layer "B.SilkS")
		)
		(fp_line
			(start -0.7874 -0.4064)
			(end -0.7874 0.4064)
			(stroke
				(width 0.1524)
				(type default)
			)
			(layer "B.SilkS")
		)
		(fp_line
			(start 0.67945 0.3048)
			(end 0.67945 -0.305054)
			(stroke
				(width 0.1)
				(type default)
			)
			(layer "B.Fab")
		)
		(fp_line
			(start 0.67945 -0.305054)
			(end 0.12065 -0.305054)
			(stroke
				(width 0.1)
				(type default)
			)
			(layer "B.Fab")
		)
		(fp_line
			(start 0.12065 0.3048)
			(end 0.67945 0.3048)
			(stroke
				(width 0.1)
				(type default)
			)
			(layer "B.Fab")
		)
		(fp_line
			(start 0.12065 0.2794)
			(end 0.12065 0.3048)
			(stroke
				(width 0.1)
				(type default)
			)
			(layer "B.Fab")
		)
		(fp_line
			(start 0.12065 -0.2794)
			(end -0.12065 -0.2794)
			(stroke
				(width 0.1)
				(type default)
			)
			(layer "B.Fab")
		)
		(fp_line
			(start 0.12065 -0.305054)
			(end 0.12065 -0.2794)
			(stroke
				(width 0.1)
				(type default)
			)
			(layer "B.Fab")
		)
		(fp_line
			(start -0.120396 0.3048)
			(end -0.120396 0.2794)
			(stroke
				(width 0.1)
				(type default)
			)
			(layer "B.Fab")
		)
		(fp_line
			(start -0.120396 0.2794)
			(end 0.12065 0.2794)
			(stroke
				(width 0.1)
				(type default)
			)
			(layer "B.Fab")
		)
		(fp_line
			(start -0.12065 -0.2794)
			(end -0.12065 -0.3048)
			(stroke
				(width 0.1)
				(type default)
			)
			(layer "B.Fab")
		)
		(fp_line
			(start -0.12065 -0.3048)
			(end -0.67945 -0.3048)
			(stroke
				(width 0.1)
				(type default)
			)
			(layer "B.Fab")
		)
		(fp_line
			(start -0.67945 0.3048)
			(end -0.120396 0.3048)
			(stroke
				(width 0.1)
				(type default)
			)
			(layer "B.Fab")
		)
		(fp_line
			(start -0.67945 -0.3048)
			(end -0.67945 0.3048)
			(stroke
				(width 0.1)
				(type default)
			)
			(layer "B.Fab")
		)
		(pad "1" smd circle
			(at 0.40005 0)
			(size 0 0)
			(layers "B.Cu" "B.Mask" "B.Paste")
			(net "P1V2_AUX")
		)
		(pad "2" smd circle
			(at -0.40005 0)
			(size 0 0)
			(layers "B.Cu" "B.Mask" "B.Paste")
			(net "GND")
		)
	)
	(footprint ""
		(layer "B.Cu")
		(at 48.940466 -79.960216 180)
		(property "Reference" "U30"
			(at -3.447034 3.439414 0)
			(unlocked yes)
			(layer "B.SilkS")
			(effects
				(font
					(size 0.7874 0.5842)
					(thickness 0.1524)
				)
				(justify left mirror)
			)
		)
		(property "Value" ""
			(at 0 0 0)
			(layer "B.Fab")
			(effects
				(font
					(size 1.27 1.27)
				)
				(justify mirror)
			)
		)
		(duplicate_pad_numbers_are_jumpers no)
		(fp_line
			(start 2.0066 2.5654)
			(end 2.0066 -2.5654)
			(stroke
				(width 0.1524)
				(type default)
			)
			(layer "B.SilkS")
		)
		(fp_line
			(start 2.0066 -2.5654)
			(end 0.5842 -2.5654)
			(stroke
				(width 0.1524)
				(type default)
			)
			(layer "B.SilkS")
		)
		(fp_line
			(start 0.5842 -2.5654)
			(end 0 -1.9812)
			(stroke
				(width 0.1524)
				(type default)
			)
			(layer "B.SilkS")
		)
		(fp_line
			(start 0 -1.9812)
			(end -0.5842 -2.5654)
			(stroke
				(width 0.1524)
				(type default)
			)
			(layer "B.SilkS")
		)
		(fp_line
			(start -0.5842 -2.5654)
			(end -2.0066 -2.5654)
			(stroke
				(width 0.1524)
				(type default)
			)
			(layer "B.SilkS")
		)
		(fp_line
			(start -2.0066 2.5654)
			(end 2.0066 2.5654)
			(stroke
				(width 0.1524)
				(type default)
			)
			(layer "B.SilkS")
		)
		(fp_line
			(start -2.0066 -2.5654)
			(end -2.0066 2.5654)
			(stroke
				(width 0.1524)
				(type default)
			)
			(layer "B.SilkS")
		)
		(fp_poly
			(pts
				(xy 3.955288 -2.275078) (xy 4.971288 -2.783078) (xy 4.971288 -1.767078)
			)
			(stroke
				(width 0)
				(type default)
			)
			(fill yes)
			(layer "B.SilkS")
		)
		(fp_line
			(start 3.7338 2.5654)
			(end 3.6703 2.5654)
			(stroke
				(width 0.1)
				(type default)
			)
			(layer "B.Fab")
		)
		(fp_line
			(start 3.7338 -2.5654)
			(end 3.7338 2.5654)
			(stroke
				(width 0.1)
				(type default)
			)
			(layer "B.Fab")
		)
		(fp_line
			(start 3.6703 2.5654)
			(end -3.6703 2.5654)
			(stroke
				(width 0.1)
				(type default)
			)
			(layer "B.Fab")
		)
		(fp_line
			(start 3.6703 -2.5654)
			(end 3.7338 -2.5654)
			(stroke
				(width 0.1)
				(type default)
			)
			(layer "B.Fab")
		)
		(fp_line
			(start -3.6703 2.5654)
			(end -3.7338 2.5654)
			(stroke
				(width 0.1)
				(type default)
			)
			(layer "B.Fab")
		)
		(fp_line
			(start -3.6703 -2.5654)
			(end 3.6703 -2.5654)
			(stroke
				(width 0.1)
				(type default)
			)
			(layer "B.Fab")
		)
		(fp_line
			(start -3.7338 2.5654)
			(end -3.7338 -2.5654)
			(stroke
				(width 0.1)
				(type default)
			)
			(layer "B.Fab")
		)
		(fp_line
			(start -3.7338 -2.5654)
			(end -3.6703 -2.5654)
			(stroke
				(width 0.1)
				(type default)
			)
			(layer "B.Fab")
		)
		(fp_poly
			(pts
				(xy 3.955288 -2.275078) (xy 4.971288 -2.783078) (xy 4.971288 -1.767078)
			)
			(stroke
				(width 0)
				(type default)
			)
			(fill yes)
			(layer "B.Fab")
		)
		(pad "1" smd rect
			(at 2.921 -2.275078 90)
			(size 0.3556 1.4986)
			(layers "B.Cu" "B.Mask" "B.Paste")
			(net "FM_BMC_BIOS_MUX_CS_SPI_R_SEL_0")
		)
		(pad "2" smd rect
			(at 2.921 -1.625092 90)
			(size 0.3556 1.4986)
			(layers "B.Cu" "B.Mask" "B.Paste")
			(net "SPI_SYS_MUX_MOSI")
		)
		(pad "3" smd rect
			(at 2.921 -0.975106 90)
			(size 0.3556 1.4986)
			(layers "B.Cu" "B.Mask" "B.Paste")
			(net "SPI_BMC_BIOS_ROM_R_MOSI")
		)
		(pad "4" smd rect
			(at 2.921 -0.32512 90)
			(size 0.3556 1.4986)
			(layers "B.Cu" "B.Mask" "B.Paste")
			(net "SPI_PCH_MUXED_IO0")
		)
		(pad "5" smd rect
			(at 2.921 0.32512 90)
			(size 0.3556 1.4986)
			(layers "B.Cu" "B.Mask" "B.Paste")
			(net "SPI_SYS_MUX_HOLD_IO3")
		)
		(pad "6" smd rect
			(at 2.921 0.975106 90)
			(size 0.3556 1.4986)
			(layers "B.Cu" "B.Mask" "B.Paste")
			(net "SPI_BMC_BIOS_ROM_R_IO3")
		)
		(pad "7" smd rect
			(at 2.921 1.625092 90)
			(size 0.3556 1.4986)
			(layers "B.Cu" "B.Mask" "B.Paste")
			(net "SPI_PCH_MUXED_IO3")
		)
		(pad "8" smd rect
			(at 2.921 2.275078 90)
			(size 0.3556 1.4986)
			(layers "B.Cu" "B.Mask" "B.Paste")
			(net "GND")
		)
		(pad "9" smd rect
			(at -2.921 2.275078 90)
			(size 0.3556 1.4986)
			(layers "B.Cu" "B.Mask" "B.Paste")
			(net "SPI_PCH_MUXED_CLK")
		)
		(pad "10" smd rect
			(at -2.921 1.625092 90)
			(size 0.3556 1.4986)
			(layers "B.Cu" "B.Mask" "B.Paste")
			(net "SPI_BMC_BIOS_ROM_R_CLK")
		)
		(pad "11" smd rect
			(at -2.921 0.975106 90)
			(size 0.3556 1.4986)
			(layers "B.Cu" "B.Mask" "B.Paste")
			(net "SPI_SYS_MUX_CLK")
		)
		(pad "12" smd rect
			(at -2.921 0.32512 90)
			(size 0.3556 1.4986)
			(layers "B.Cu" "B.Mask" "B.Paste")
			(net "TP_BIOS_MUX0_PIN12")
		)
		(pad "13" smd rect
			(at -2.921 -0.32512 90)
			(size 0.3556 1.4986)
			(layers "B.Cu" "B.Mask" "B.Paste")
			(net "TP_BIOS_MUX0_PIN13")
		)
		(pad "14" smd rect
			(at -2.921 -0.975106 90)
			(size 0.3556 1.4986)
			(layers "B.Cu" "B.Mask" "B.Paste")
			(net "TP_BIOS_MUX0_PIN14")
		)
		(pad "15" smd rect
			(at -2.921 -1.625092 90)
			(size 0.3556 1.4986)
			(layers "B.Cu" "B.Mask" "B.Paste")
			(net "PD_BIOS_MUX_EN_N")
		)
		(pad "16" smd rect
			(at -2.921 -2.275078 90)
			(size 0.3556 1.4986)
			(layers "B.Cu" "B.Mask" "B.Paste")
			(net "P3V3_AUX")
		)
	)
	(footprint ""
		(layer "B.Cu")
		(at 62.103 -52.832 -90)
		(property "Reference" "C22"
			(at 0 0 90)
			(layer "B.SilkS")
			(hide yes)
			(effects
				(font
					(size 1.27 1.27)
				)
				(justify mirror)
			)
		)
		(property "Value" ""
			(at 0 0 90)
			(layer "B.Fab")
			(effects
				(font
					(size 1.27 1.27)
				)
				(justify mirror)
			)
		)
		(duplicate_pad_numbers_are_jumpers no)
		(fp_line
			(start -0.7874 0.4064)
			(end 0.7874 0.4064)
			(stroke
				(width 0.1524)
				(type default)
			)
			(layer "B.SilkS")
		)
		(fp_line
			(start 0.7874 0.4064)
			(end 0.7874 -0.4064)
			(stroke
				(width 0.1524)
				(type default)
			)
			(layer "B.SilkS")
		)
		(fp_line
			(start -0.7874 -0.4064)
			(end -0.7874 0.4064)
			(stroke
				(width 0.1524)
				(type default)
			)
			(layer "B.SilkS")
		)
		(fp_line
			(start 0.7874 -0.4064)
			(end -0.7874 -0.4064)
			(stroke
				(width 0.1524)
				(type default)
			)
			(layer "B.SilkS")
		)
		(fp_line
			(start -0.67945 0.3048)
			(end -0.120396 0.3048)
			(stroke
				(width 0.1)
				(type default)
			)
			(layer "B.Fab")
		)
		(fp_line
			(start -0.120396 0.3048)
			(end -0.120396 0.2794)
			(stroke
				(width 0.1)
				(type default)
			)
			(layer "B.Fab")
		)
		(fp_line
			(start 0.12065 0.3048)
			(end 0.67945 0.3048)
			(stroke
				(width 0.1)
				(type default)
			)
			(layer "B.Fab")
		)
		(fp_line
			(start 0.67945 0.3048)
			(end 0.67945 -0.305054)
			(stroke
				(width 0.1)
				(type default)
			)
			(layer "B.Fab")
		)
		(fp_line
			(start -0.120396 0.2794)
			(end 0.12065 0.2794)
			(stroke
				(width 0.1)
				(type default)
			)
			(layer "B.Fab")
		)
		(fp_line
			(start 0.12065 0.2794)
			(end 0.12065 0.3048)
			(stroke
				(width 0.1)
				(type default)
			)
			(layer "B.Fab")
		)
		(fp_line
			(start -0.12065 -0.2794)
			(end -0.12065 -0.3048)
			(stroke
				(width 0.1)
				(type default)
			)
			(layer "B.Fab")
		)
		(fp_line
			(start 0.12065 -0.2794)
			(end -0.12065 -0.2794)
			(stroke
				(width 0.1)
				(type default)
			)
			(layer "B.Fab")
		)
		(fp_line
			(start -0.67945 -0.3048)
			(end -0.67945 0.3048)
			(stroke
				(width 0.1)
				(type default)
			)
			(layer "B.Fab")
		)
		(fp_line
			(start -0.12065 -0.3048)
			(end -0.67945 -0.3048)
			(stroke
				(width 0.1)
				(type default)
			)
			(layer "B.Fab")
		)
		(fp_line
			(start 0.12065 -0.305054)
			(end 0.12065 -0.2794)
			(stroke
				(width 0.1)
				(type default)
			)
			(layer "B.Fab")
		)
		(fp_line
			(start 0.67945 -0.305054)
			(end 0.12065 -0.305054)
			(stroke
				(width 0.1)
				(type default)
			)
			(layer "B.Fab")
		)
		(pad "1" smd circle
			(at 0.40005 0 90)
			(size 0 0)
			(layers "B.Cu" "B.Mask" "B.Paste")
			(net "P0V6_DDR_VREF_AUX")
		)
		(pad "2" smd circle
			(at -0.40005 0 90)
			(size 0 0)
			(layers "B.Cu" "B.Mask" "B.Paste")
			(net "GND")
		)
	)
	(footprint ""
		(layer "B.Cu")
		(at 25.019 -92.456)
		(property "Reference" "R307"
			(at 0 0 0)
			(layer "B.SilkS")
			(hide yes)
			(effects
				(font
					(size 1.27 1.27)
				)
				(justify mirror)
			)
		)
		(property "Value" ""
			(at 0 0 0)
			(layer "B.Fab")
			(effects
				(font
					(size 1.27 1.27)
				)
				(justify mirror)
			)
		)
		(duplicate_pad_numbers_are_jumpers no)
		(fp_line
			(start -0.7874 -0.4064)
			(end -0.7874 0.4064)
			(stroke
				(width 0.1524)
				(type default)
			)
			(layer "B.SilkS")
		)
		(fp_line
			(start -0.7874 0.4064)
			(end 0.7874 0.4064)
			(stroke
				(width 0.1524)
				(type default)
			)
			(layer "B.SilkS")
		)
		(fp_line
			(start 0.7874 -0.4064)
			(end -0.7874 -0.4064)
			(stroke
				(width 0.1524)
				(type default)
			)
			(layer "B.SilkS")
		)
		(fp_line
			(start 0.7874 0.4064)
			(end 0.7874 -0.4064)
			(stroke
				(width 0.1524)
				(type default)
			)
			(layer "B.SilkS")
		)
		(fp_line
			(start -0.67945 -0.3048)
			(end -0.67945 0.3048)
			(stroke
				(width 0.1)
				(type default)
			)
			(layer "B.Fab")
		)
		(fp_line
			(start -0.67945 0.3048)
			(end -0.120396 0.3048)
			(stroke
				(width 0.1)
				(type default)
			)
			(layer "B.Fab")
		)
		(fp_line
			(start -0.12065 -0.3048)
			(end -0.67945 -0.3048)
			(stroke
				(width 0.1)
				(type default)
			)
			(layer "B.Fab")
		)
		(fp_line
			(start -0.12065 -0.2794)
			(end -0.12065 -0.3048)
			(stroke
				(width 0.1)
				(type default)
			)
			(layer "B.Fab")
		)
		(fp_line
			(start -0.120396 0.2794)
			(end 0.12065 0.2794)
			(stroke
				(width 0.1)
				(type default)
			)
			(layer "B.Fab")
		)
		(fp_line
			(start -0.120396 0.3048)
			(end -0.120396 0.2794)
			(stroke
				(width 0.1)
				(type default)
			)
			(layer "B.Fab")
		)
		(fp_line
			(start 0.12065 -0.305054)
			(end 0.12065 -0.2794)
			(stroke
				(width 0.1)
				(type default)
			)
			(layer "B.Fab")
		)
		(fp_line
			(start 0.12065 -0.2794)
			(end -0.12065 -0.2794)
			(stroke
				(width 0.1)
				(type default)
			)
			(layer "B.Fab")
		)
		(fp_line
			(start 0.12065 0.2794)
			(end 0.12065 0.3048)
			(stroke
				(width 0.1)
				(type default)
			)
			(layer "B.Fab")
		)
		(fp_line
			(start 0.12065 0.3048)
			(end 0.67945 0.3048)
			(stroke
				(width 0.1)
				(type default)
			)
			(layer "B.Fab")
		)
		(fp_line
			(start 0.67945 -0.305054)
			(end 0.12065 -0.305054)
			(stroke
				(width 0.1)
				(type default)
			)
			(layer "B.Fab")
		)
		(fp_line
			(start 0.67945 0.3048)
			(end 0.67945 -0.305054)
			(stroke
				(width 0.1)
				(type default)
			)
			(layer "B.Fab")
		)
		(pad "1" smd circle
			(at 0.40005 0 180)
			(size 0 0)
			(layers "B.Cu" "B.Mask" "B.Paste")
			(net "P3V3_AUX")
		)
		(pad "2" smd circle
			(at -0.40005 0 180)
			(size 0 0)
			(layers "B.Cu" "B.Mask" "B.Paste")
			(net "VCCIO4")
		)
	)
	(footprint ""
		(layer "B.Cu")
		(at 14.351 -106.426 90)
		(property "Reference" "R220"
			(at 0 0 90)
			(layer "B.SilkS")
			(hide yes)
			(effects
				(font
					(size 1.27 1.27)
				)
				(justify mirror)
			)
		)
		(property "Value" ""
			(at 0 0 90)
			(layer "B.Fab")
			(effects
				(font
					(size 1.27 1.27)
				)
				(justify mirror)
			)
		)
		(duplicate_pad_numbers_are_jumpers no)
		(fp_line
			(start 0.7874 -0.4064)
			(end -0.7874 -0.4064)
			(stroke
				(width 0.1524)
				(type default)
			)
			(layer "B.SilkS")
		)
		(fp_line
			(start -0.7874 -0.4064)
			(end -0.7874 0.4064)
			(stroke
				(width 0.1524)
				(type default)
			)
			(layer "B.SilkS")
		)
		(fp_line
			(start 0.7874 0.4064)
			(end 0.7874 -0.4064)
			(stroke
				(width 0.1524)
				(type default)
			)
			(layer "B.SilkS")
		)
		(fp_line
			(start -0.7874 0.4064)
			(end 0.7874 0.4064)
			(stroke
				(width 0.1524)
				(type default)
			)
			(layer "B.SilkS")
		)
		(fp_line
			(start 0.67945 -0.305054)
			(end 0.12065 -0.305054)
			(stroke
				(width 0.1)
				(type default)
			)
			(layer "B.Fab")
		)
		(fp_line
			(start 0.12065 -0.305054)
			(end 0.12065 -0.2794)
			(stroke
				(width 0.1)
				(type default)
			)
			(layer "B.Fab")
		)
		(fp_line
			(start -0.12065 -0.3048)
			(end -0.67945 -0.3048)
			(stroke
				(width 0.1)
				(type default)
			)
			(layer "B.Fab")
		)
		(fp_line
			(start -0.67945 -0.3048)
			(end -0.67945 0.3048)
			(stroke
				(width 0.1)
				(type default)
			)
			(layer "B.Fab")
		)
		(fp_line
			(start 0.12065 -0.2794)
			(end -0.12065 -0.2794)
			(stroke
				(width 0.1)
				(type default)
			)
			(layer "B.Fab")
		)
		(fp_line
			(start -0.12065 -0.2794)
			(end -0.12065 -0.3048)
			(stroke
				(width 0.1)
				(type default)
			)
			(layer "B.Fab")
		)
		(fp_line
			(start 0.12065 0.2794)
			(end 0.12065 0.3048)
			(stroke
				(width 0.1)
				(type default)
			)
			(layer "B.Fab")
		)
		(fp_line
			(start -0.120396 0.2794)
			(end 0.12065 0.2794)
			(stroke
				(width 0.1)
				(type default)
			)
			(layer "B.Fab")
		)
		(fp_line
			(start 0.67945 0.3048)
			(end 0.67945 -0.305054)
			(stroke
				(width 0.1)
				(type default)
			)
			(layer "B.Fab")
		)
		(fp_line
			(start 0.12065 0.3048)
			(end 0.67945 0.3048)
			(stroke
				(width 0.1)
				(type default)
			)
			(layer "B.Fab")
		)
		(fp_line
			(start -0.120396 0.3048)
			(end -0.120396 0.2794)
			(stroke
				(width 0.1)
				(type default)
			)
			(layer "B.Fab")
		)
		(fp_line
			(start -0.67945 0.3048)
			(end -0.120396 0.3048)
			(stroke
				(width 0.1)
				(type default)
			)
			(layer "B.Fab")
		)
		(pad "1" smd circle
			(at 0.40005 0 270)
			(size 0 0)
			(layers "B.Cu" "B.Mask" "B.Paste")
			(net "FM_BMC_UARTSW_MSB_N")
		)
		(pad "2" smd circle
			(at -0.40005 0 270)
			(size 0 0)
			(layers "B.Cu" "B.Mask" "B.Paste")
			(net "FM_UARTSW_MSB_N")
		)
	)
	(footprint ""
		(layer "B.Cu")
		(at 73.783698 -37.271706 -90)
		(property "Reference" "C58"
			(at 0 0 90)
			(layer "B.SilkS")
			(hide yes)
			(effects
				(font
					(size 1.27 1.27)
				)
				(justify mirror)
			)
		)
		(property "Value" ""
			(at 0 0 90)
			(layer "B.Fab")
			(effects
				(font
					(size 1.27 1.27)
				)
				(justify mirror)
			)
		)
		(duplicate_pad_numbers_are_jumpers no)
		(fp_line
			(start -0.7874 0.4064)
			(end 0.7874 0.4064)
			(stroke
				(width 0.1524)
				(type default)
			)
			(layer "B.SilkS")
		)
		(fp_line
			(start 0.7874 0.4064)
			(end 0.7874 -0.4064)
			(stroke
				(width 0.1524)
				(type default)
			)
			(layer "B.SilkS")
		)
		(fp_line
			(start -0.7874 -0.4064)
			(end -0.7874 0.4064)
			(stroke
				(width 0.1524)
				(type default)
			)
			(layer "B.SilkS")
		)
		(fp_line
			(start 0.7874 -0.4064)
			(end -0.7874 -0.4064)
			(stroke
				(width 0.1524)
				(type default)
			)
			(layer "B.SilkS")
		)
		(fp_line
			(start -0.67945 0.3048)
			(end -0.120396 0.3048)
			(stroke
				(width 0.1)
				(type default)
			)
			(layer "B.Fab")
		)
		(fp_line
			(start -0.120396 0.3048)
			(end -0.120396 0.2794)
			(stroke
				(width 0.1)
				(type default)
			)
			(layer "B.Fab")
		)
		(fp_line
			(start 0.12065 0.3048)
			(end 0.67945 0.3048)
			(stroke
				(width 0.1)
				(type default)
			)
			(layer "B.Fab")
		)
		(fp_line
			(start 0.67945 0.3048)
			(end 0.67945 -0.305054)
			(stroke
				(width 0.1)
				(type default)
			)
			(layer "B.Fab")
		)
		(fp_line
			(start -0.120396 0.2794)
			(end 0.12065 0.2794)
			(stroke
				(width 0.1)
				(type default)
			)
			(layer "B.Fab")
		)
		(fp_line
			(start 0.12065 0.2794)
			(end 0.12065 0.3048)
			(stroke
				(width 0.1)
				(type default)
			)
			(layer "B.Fab")
		)
		(fp_line
			(start -0.12065 -0.2794)
			(end -0.12065 -0.3048)
			(stroke
				(width 0.1)
				(type default)
			)
			(layer "B.Fab")
		)
		(fp_line
			(start 0.12065 -0.2794)
			(end -0.12065 -0.2794)
			(stroke
				(width 0.1)
				(type default)
			)
			(layer "B.Fab")
		)
		(fp_line
			(start -0.67945 -0.3048)
			(end -0.67945 0.3048)
			(stroke
				(width 0.1)
				(type default)
			)
			(layer "B.Fab")
		)
		(fp_line
			(start -0.12065 -0.3048)
			(end -0.67945 -0.3048)
			(stroke
				(width 0.1)
				(type default)
			)
			(layer "B.Fab")
		)
		(fp_line
			(start 0.12065 -0.305054)
			(end 0.12065 -0.2794)
			(stroke
				(width 0.1)
				(type default)
			)
			(layer "B.Fab")
		)
		(fp_line
			(start 0.67945 -0.305054)
			(end 0.12065 -0.305054)
			(stroke
				(width 0.1)
				(type default)
			)
			(layer "B.Fab")
		)
		(pad "1" smd circle
			(at 0.40005 0 90)
			(size 0 0)
			(layers "B.Cu" "B.Mask" "B.Paste")
			(net "P1V2_AUX")
		)
		(pad "2" smd circle
			(at -0.40005 0 90)
			(size 0 0)
			(layers "B.Cu" "B.Mask" "B.Paste")
			(net "GND")
		)
	)
	(footprint ""
		(layer "B.Cu")
		(at 66.4972 -72.4662 -90)
		(property "Reference" "R309"
			(at 0 0 90)
			(layer "B.SilkS")
			(hide yes)
			(effects
				(font
					(size 1.27 1.27)
				)
				(justify mirror)
			)
		)
		(property "Value" ""
			(at 0 0 90)
			(layer "B.Fab")
			(effects
				(font
					(size 1.27 1.27)
				)
				(justify mirror)
			)
		)
		(duplicate_pad_numbers_are_jumpers no)
		(fp_line
			(start -0.7874 0.4064)
			(end 0.7874 0.4064)
			(stroke
				(width 0.1524)
				(type default)
			)
			(layer "B.SilkS")
		)
		(fp_line
			(start 0.7874 0.4064)
			(end 0.7874 -0.4064)
			(stroke
				(width 0.1524)
				(type default)
			)
			(layer "B.SilkS")
		)
		(fp_line
			(start -0.7874 -0.4064)
			(end -0.7874 0.4064)
			(stroke
				(width 0.1524)
				(type default)
			)
			(layer "B.SilkS")
		)
		(fp_line
			(start 0.7874 -0.4064)
			(end -0.7874 -0.4064)
			(stroke
				(width 0.1524)
				(type default)
			)
			(layer "B.SilkS")
		)
		(fp_line
			(start -0.67945 0.3048)
			(end -0.120396 0.3048)
			(stroke
				(width 0.1)
				(type default)
			)
			(layer "B.Fab")
		)
		(fp_line
			(start -0.120396 0.3048)
			(end -0.120396 0.2794)
			(stroke
				(width 0.1)
				(type default)
			)
			(layer "B.Fab")
		)
		(fp_line
			(start 0.12065 0.3048)
			(end 0.67945 0.3048)
			(stroke
				(width 0.1)
				(type default)
			)
			(layer "B.Fab")
		)
		(fp_line
			(start 0.67945 0.3048)
			(end 0.67945 -0.305054)
			(stroke
				(width 0.1)
				(type default)
			)
			(layer "B.Fab")
		)
		(fp_line
			(start -0.120396 0.2794)
			(end 0.12065 0.2794)
			(stroke
				(width 0.1)
				(type default)
			)
			(layer "B.Fab")
		)
		(fp_line
			(start 0.12065 0.2794)
			(end 0.12065 0.3048)
			(stroke
				(width 0.1)
				(type default)
			)
			(layer "B.Fab")
		)
		(fp_line
			(start -0.12065 -0.2794)
			(end -0.12065 -0.3048)
			(stroke
				(width 0.1)
				(type default)
			)
			(layer "B.Fab")
		)
		(fp_line
			(start 0.12065 -0.2794)
			(end -0.12065 -0.2794)
			(stroke
				(width 0.1)
				(type default)
			)
			(layer "B.Fab")
		)
		(fp_line
			(start -0.67945 -0.3048)
			(end -0.67945 0.3048)
			(stroke
				(width 0.1)
				(type default)
			)
			(layer "B.Fab")
		)
		(fp_line
			(start -0.12065 -0.3048)
			(end -0.67945 -0.3048)
			(stroke
				(width 0.1)
				(type default)
			)
			(layer "B.Fab")
		)
		(fp_line
			(start 0.12065 -0.305054)
			(end 0.12065 -0.2794)
			(stroke
				(width 0.1)
				(type default)
			)
			(layer "B.Fab")
		)
		(fp_line
			(start 0.67945 -0.305054)
			(end 0.12065 -0.305054)
			(stroke
				(width 0.1)
				(type default)
			)
			(layer "B.Fab")
		)
		(pad "1" smd circle
			(at 0.40005 0 90)
			(size 0 0)
			(layers "B.Cu" "B.Mask" "B.Paste")
			(net "SPI_BMC_TPM_MOSI_R1")
		)
		(pad "2" smd circle
			(at -0.40005 0 90)
			(size 0 0)
			(layers "B.Cu" "B.Mask" "B.Paste")
			(net "SPI_BMC_TPM_MOSI")
		)
	)
	(footprint ""
		(layer "B.Cu")
		(at 51.2445 -93.2815 180)
		(property "Reference" "R632"
			(at 0 0 0)
			(layer "B.SilkS")
			(hide yes)
			(effects
				(font
					(size 1.27 1.27)
				)
				(justify mirror)
			)
		)
		(property "Value" ""
			(at 0 0 0)
			(layer "B.Fab")
			(effects
				(font
					(size 1.27 1.27)
				)
				(justify mirror)
			)
		)
		(duplicate_pad_numbers_are_jumpers no)
		(fp_line
			(start 0.7874 0.4064)
			(end 0.7874 -0.4064)
			(stroke
				(width 0.1524)
				(type default)
			)
			(layer "B.SilkS")
		)
		(fp_line
			(start 0.7874 -0.4064)
			(end -0.7874 -0.4064)
			(stroke
				(width 0.1524)
				(type default)
			)
			(layer "B.SilkS")
		)
		(fp_line
			(start -0.7874 0.4064)
			(end 0.7874 0.4064)
			(stroke
				(width 0.1524)
				(type default)
			)
			(layer "B.SilkS")
		)
		(fp_line
			(start -0.7874 -0.4064)
			(end -0.7874 0.4064)
			(stroke
				(width 0.1524)
				(type default)
			)
			(layer "B.SilkS")
		)
		(fp_line
			(start 0.67945 0.3048)
			(end 0.67945 -0.305054)
			(stroke
				(width 0.1)
				(type default)
			)
			(layer "B.Fab")
		)
		(fp_line
			(start 0.67945 -0.305054)
			(end 0.12065 -0.305054)
			(stroke
				(width 0.1)
				(type default)
			)
			(layer "B.Fab")
		)
		(fp_line
			(start 0.12065 0.3048)
			(end 0.67945 0.3048)
			(stroke
				(width 0.1)
				(type default)
			)
			(layer "B.Fab")
		)
		(fp_line
			(start 0.12065 0.2794)
			(end 0.12065 0.3048)
			(stroke
				(width 0.1)
				(type default)
			)
			(layer "B.Fab")
		)
		(fp_line
			(start 0.12065 -0.2794)
			(end -0.12065 -0.2794)
			(stroke
				(width 0.1)
				(type default)
			)
			(layer "B.Fab")
		)
		(fp_line
			(start 0.12065 -0.305054)
			(end 0.12065 -0.2794)
			(stroke
				(width 0.1)
				(type default)
			)
			(layer "B.Fab")
		)
		(fp_line
			(start -0.120396 0.3048)
			(end -0.120396 0.2794)
			(stroke
				(width 0.1)
				(type default)
			)
			(layer "B.Fab")
		)
		(fp_line
			(start -0.120396 0.2794)
			(end 0.12065 0.2794)
			(stroke
				(width 0.1)
				(type default)
			)
			(layer "B.Fab")
		)
		(fp_line
			(start -0.12065 -0.2794)
			(end -0.12065 -0.3048)
			(stroke
				(width 0.1)
				(type default)
			)
			(layer "B.Fab")
		)
		(fp_line
			(start -0.12065 -0.3048)
			(end -0.67945 -0.3048)
			(stroke
				(width 0.1)
				(type default)
			)
			(layer "B.Fab")
		)
		(fp_line
			(start -0.67945 0.3048)
			(end -0.120396 0.3048)
			(stroke
				(width 0.1)
				(type default)
			)
			(layer "B.Fab")
		)
		(fp_line
			(start -0.67945 -0.3048)
			(end -0.67945 0.3048)
			(stroke
				(width 0.1)
				(type default)
			)
			(layer "B.Fab")
		)
		(pad "1" smd circle
			(at 0.40005 0)
			(size 0 0)
			(layers "B.Cu" "B.Mask" "B.Paste")
			(net "SMB_DEBUG_AUX_LVC3_USB_SCL")
		)
		(pad "2" smd circle
			(at -0.40005 0)
			(size 0 0)
			(layers "B.Cu" "B.Mask" "B.Paste")
			(net "SMB_DEBUG_AUX_LVC3_USB_R3_SCL")
		)
	)
	(footprint ""
		(layer "B.Cu")
		(at 59.563 -34.7218 90)
		(property "Reference" "R142"
			(at 0 0 90)
			(layer "B.SilkS")
			(hide yes)
			(effects
				(font
					(size 1.27 1.27)
				)
				(justify mirror)
			)
		)
		(property "Value" ""
			(at 0 0 90)
			(layer "B.Fab")
			(effects
				(font
					(size 1.27 1.27)
				)
				(justify mirror)
			)
		)
		(duplicate_pad_numbers_are_jumpers no)
		(fp_line
			(start 0.7874 -0.4064)
			(end -0.7874 -0.4064)
			(stroke
				(width 0.1524)
				(type default)
			)
			(layer "B.SilkS")
		)
		(fp_line
			(start -0.7874 -0.4064)
			(end -0.7874 0.4064)
			(stroke
				(width 0.1524)
				(type default)
			)
			(layer "B.SilkS")
		)
		(fp_line
			(start 0.7874 0.4064)
			(end 0.7874 -0.4064)
			(stroke
				(width 0.1524)
				(type default)
			)
			(layer "B.SilkS")
		)
		(fp_line
			(start -0.7874 0.4064)
			(end 0.7874 0.4064)
			(stroke
				(width 0.1524)
				(type default)
			)
			(layer "B.SilkS")
		)
		(fp_line
			(start 0.67945 -0.305054)
			(end 0.12065 -0.305054)
			(stroke
				(width 0.1)
				(type default)
			)
			(layer "B.Fab")
		)
		(fp_line
			(start 0.12065 -0.305054)
			(end 0.12065 -0.2794)
			(stroke
				(width 0.1)
				(type default)
			)
			(layer "B.Fab")
		)
		(fp_line
			(start -0.12065 -0.3048)
			(end -0.67945 -0.3048)
			(stroke
				(width 0.1)
				(type default)
			)
			(layer "B.Fab")
		)
		(fp_line
			(start -0.67945 -0.3048)
			(end -0.67945 0.3048)
			(stroke
				(width 0.1)
				(type default)
			)
			(layer "B.Fab")
		)
		(fp_line
			(start 0.12065 -0.2794)
			(end -0.12065 -0.2794)
			(stroke
				(width 0.1)
				(type default)
			)
			(layer "B.Fab")
		)
		(fp_line
			(start -0.12065 -0.2794)
			(end -0.12065 -0.3048)
			(stroke
				(width 0.1)
				(type default)
			)
			(layer "B.Fab")
		)
		(fp_line
			(start 0.12065 0.2794)
			(end 0.12065 0.3048)
			(stroke
				(width 0.1)
				(type default)
			)
			(layer "B.Fab")
		)
		(fp_line
			(start -0.120396 0.2794)
			(end 0.12065 0.2794)
			(stroke
				(width 0.1)
				(type default)
			)
			(layer "B.Fab")
		)
		(fp_line
			(start 0.67945 0.3048)
			(end 0.67945 -0.305054)
			(stroke
				(width 0.1)
				(type default)
			)
			(layer "B.Fab")
		)
		(fp_line
			(start 0.12065 0.3048)
			(end 0.67945 0.3048)
			(stroke
				(width 0.1)
				(type default)
			)
			(layer "B.Fab")
		)
		(fp_line
			(start -0.120396 0.3048)
			(end -0.120396 0.2794)
			(stroke
				(width 0.1)
				(type default)
			)
			(layer "B.Fab")
		)
		(fp_line
			(start -0.67945 0.3048)
			(end -0.120396 0.3048)
			(stroke
				(width 0.1)
				(type default)
			)
			(layer "B.Fab")
		)
		(pad "1" smd circle
			(at 0.40005 0 270)
			(size 0 0)
			(layers "B.Cu" "B.Mask" "B.Paste")
			(net "SMB_BMC_MM6_R_SCL")
		)
		(pad "2" smd circle
			(at -0.40005 0 270)
			(size 0 0)
			(layers "B.Cu" "B.Mask" "B.Paste")
			(net "SMB_BMC_MM6_SCL")
		)
	)
	(footprint ""
		(layer "B.Cu")
		(at 71.68896 -49.849786 -90)
		(property "Reference" "C7"
			(at 0 0 90)
			(layer "B.SilkS")
			(hide yes)
			(effects
				(font
					(size 1.27 1.27)
				)
				(justify mirror)
			)
		)
		(property "Value" ""
			(at 0 0 90)
			(layer "B.Fab")
			(effects
				(font
					(size 1.27 1.27)
				)
				(justify mirror)
			)
		)
		(duplicate_pad_numbers_are_jumpers no)
		(fp_line
			(start -0.7874 0.4064)
			(end 0.7874 0.4064)
			(stroke
				(width 0.1524)
				(type default)
			)
			(layer "B.SilkS")
		)
		(fp_line
			(start 0.7874 0.4064)
			(end 0.7874 -0.4064)
			(stroke
				(width 0.1524)
				(type default)
			)
			(layer "B.SilkS")
		)
		(fp_line
			(start -0.7874 -0.4064)
			(end -0.7874 0.4064)
			(stroke
				(width 0.1524)
				(type default)
			)
			(layer "B.SilkS")
		)
		(fp_line
			(start 0.7874 -0.4064)
			(end -0.7874 -0.4064)
			(stroke
				(width 0.1524)
				(type default)
			)
			(layer "B.SilkS")
		)
		(fp_line
			(start -0.67945 0.3048)
			(end -0.120396 0.3048)
			(stroke
				(width 0.1)
				(type default)
			)
			(layer "B.Fab")
		)
		(fp_line
			(start -0.120396 0.3048)
			(end -0.120396 0.2794)
			(stroke
				(width 0.1)
				(type default)
			)
			(layer "B.Fab")
		)
		(fp_line
			(start 0.12065 0.3048)
			(end 0.67945 0.3048)
			(stroke
				(width 0.1)
				(type default)
			)
			(layer "B.Fab")
		)
		(fp_line
			(start 0.67945 0.3048)
			(end 0.67945 -0.305054)
			(stroke
				(width 0.1)
				(type default)
			)
			(layer "B.Fab")
		)
		(fp_line
			(start -0.120396 0.2794)
			(end 0.12065 0.2794)
			(stroke
				(width 0.1)
				(type default)
			)
			(layer "B.Fab")
		)
		(fp_line
			(start 0.12065 0.2794)
			(end 0.12065 0.3048)
			(stroke
				(width 0.1)
				(type default)
			)
			(layer "B.Fab")
		)
		(fp_line
			(start -0.12065 -0.2794)
			(end -0.12065 -0.3048)
			(stroke
				(width 0.1)
				(type default)
			)
			(layer "B.Fab")
		)
		(fp_line
			(start 0.12065 -0.2794)
			(end -0.12065 -0.2794)
			(stroke
				(width 0.1)
				(type default)
			)
			(layer "B.Fab")
		)
		(fp_line
			(start -0.67945 -0.3048)
			(end -0.67945 0.3048)
			(stroke
				(width 0.1)
				(type default)
			)
			(layer "B.Fab")
		)
		(fp_line
			(start -0.12065 -0.3048)
			(end -0.67945 -0.3048)
			(stroke
				(width 0.1)
				(type default)
			)
			(layer "B.Fab")
		)
		(fp_line
			(start 0.12065 -0.305054)
			(end 0.12065 -0.2794)
			(stroke
				(width 0.1)
				(type default)
			)
			(layer "B.Fab")
		)
		(fp_line
			(start 0.67945 -0.305054)
			(end 0.12065 -0.305054)
			(stroke
				(width 0.1)
				(type default)
			)
			(layer "B.Fab")
		)
		(pad "1" smd circle
			(at 0.40005 0 90)
			(size 0 0)
			(layers "B.Cu" "B.Mask" "B.Paste")
			(net "P1V2_AUX")
		)
		(pad "2" smd circle
			(at -0.40005 0 90)
			(size 0 0)
			(layers "B.Cu" "B.Mask" "B.Paste")
			(net "GND")
		)
	)
	(footprint ""
		(layer "B.Cu")
		(at 42.22115 -38.9636 180)
		(property "Reference" "R242"
			(at 0 0 0)
			(layer "B.SilkS")
			(hide yes)
			(effects
				(font
					(size 1.27 1.27)
				)
				(justify mirror)
			)
		)
		(property "Value" ""
			(at 0 0 0)
			(layer "B.Fab")
			(effects
				(font
					(size 1.27 1.27)
				)
				(justify mirror)
			)
		)
		(duplicate_pad_numbers_are_jumpers no)
		(fp_line
			(start 0.7874 0.4064)
			(end 0.7874 -0.4064)
			(stroke
				(width 0.1524)
				(type default)
			)
			(layer "B.SilkS")
		)
		(fp_line
			(start 0.7874 -0.4064)
			(end -0.7874 -0.4064)
			(stroke
				(width 0.1524)
				(type default)
			)
			(layer "B.SilkS")
		)
		(fp_line
			(start -0.7874 0.4064)
			(end 0.7874 0.4064)
			(stroke
				(width 0.1524)
				(type default)
			)
			(layer "B.SilkS")
		)
		(fp_line
			(start -0.7874 -0.4064)
			(end -0.7874 0.4064)
			(stroke
				(width 0.1524)
				(type default)
			)
			(layer "B.SilkS")
		)
		(fp_line
			(start 0.67945 0.3048)
			(end 0.67945 -0.305054)
			(stroke
				(width 0.1)
				(type default)
			)
			(layer "B.Fab")
		)
		(fp_line
			(start 0.67945 -0.305054)
			(end 0.12065 -0.305054)
			(stroke
				(width 0.1)
				(type default)
			)
			(layer "B.Fab")
		)
		(fp_line
			(start 0.12065 0.3048)
			(end 0.67945 0.3048)
			(stroke
				(width 0.1)
				(type default)
			)
			(layer "B.Fab")
		)
		(fp_line
			(start 0.12065 0.2794)
			(end 0.12065 0.3048)
			(stroke
				(width 0.1)
				(type default)
			)
			(layer "B.Fab")
		)
		(fp_line
			(start 0.12065 -0.2794)
			(end -0.12065 -0.2794)
			(stroke
				(width 0.1)
				(type default)
			)
			(layer "B.Fab")
		)
		(fp_line
			(start 0.12065 -0.305054)
			(end 0.12065 -0.2794)
			(stroke
				(width 0.1)
				(type default)
			)
			(layer "B.Fab")
		)
		(fp_line
			(start -0.120396 0.3048)
			(end -0.120396 0.2794)
			(stroke
				(width 0.1)
				(type default)
			)
			(layer "B.Fab")
		)
		(fp_line
			(start -0.120396 0.2794)
			(end 0.12065 0.2794)
			(stroke
				(width 0.1)
				(type default)
			)
			(layer "B.Fab")
		)
		(fp_line
			(start -0.12065 -0.2794)
			(end -0.12065 -0.3048)
			(stroke
				(width 0.1)
				(type default)
			)
			(layer "B.Fab")
		)
		(fp_line
			(start -0.12065 -0.3048)
			(end -0.67945 -0.3048)
			(stroke
				(width 0.1)
				(type default)
			)
			(layer "B.Fab")
		)
		(fp_line
			(start -0.67945 0.3048)
			(end -0.120396 0.3048)
			(stroke
				(width 0.1)
				(type default)
			)
			(layer "B.Fab")
		)
		(fp_line
			(start -0.67945 -0.3048)
			(end -0.67945 0.3048)
			(stroke
				(width 0.1)
				(type default)
			)
			(layer "B.Fab")
		)
		(pad "1" smd circle
			(at 0.40005 0)
			(size 0 0)
			(layers "B.Cu" "B.Mask" "B.Paste")
			(net "FM_BMC_CPU_FBRK_OUT_N")
		)
		(pad "2" smd circle
			(at -0.40005 0)
			(size 0 0)
			(layers "B.Cu" "B.Mask" "B.Paste")
			(net "FM_BMC_CPU_FBRK_OUT_R_N")
		)
	)
	(footprint ""
		(layer "B.Cu")
		(at 52.2986 -25.273)
		(property "Reference" ""
			(at 0 0 0)
			(layer "B.SilkS")
			(hide yes)
			(effects
				(font
					(size 1.27 1.27)
				)
				(justify mirror)
			)
		)
		(property "Value" ""
			(at 0 0 0)
			(layer "B.Fab")
			(effects
				(font
					(size 1.27 1.27)
				)
				(justify mirror)
			)
		)
		(duplicate_pad_numbers_are_jumpers no)
		(pad "1" smd circle
			(at 0 0 180)
			(size 0.9906 0.9906)
			(layers "B.Cu" "B.Mask" "B.Paste")
			(net "Net_159")
		)
		(zone
			(layer "B.Cu")
			(hatch none 0.5)
			(connect_pads
				(clearance 0)
			)
			(min_thickness 0.25)
			(keepout
				(tracks not_allowed)
				(vias allowed)
				(pads allowed)
				(copperpour not_allowed)
				(footprints allowed)
			)
			(placement
				(enabled no)
				(sheetname "")
			)
			(fill
				(thermal_gap 0.5)
				(thermal_bridge_width 0.5)
				(island_removal_mode 0)
			)
			(polygon
				(pts
					(arc
						(start 53.9242 -25.273)
						(mid 50.673 -25.273)
						(end 53.9242 -25.273)
					)
				)
			)
		)
	)
	(footprint ""
		(layer "B.Cu")
		(at 61.7855 -100.1395 90)
		(property "Reference" "R736"
			(at 0 0 90)
			(layer "B.SilkS")
			(hide yes)
			(effects
				(font
					(size 1.27 1.27)
				)
				(justify mirror)
			)
		)
		(property "Value" ""
			(at 0 0 90)
			(layer "B.Fab")
			(effects
				(font
					(size 1.27 1.27)
				)
				(justify mirror)
			)
		)
		(duplicate_pad_numbers_are_jumpers no)
		(fp_line
			(start 0.7874 -0.4064)
			(end -0.7874 -0.4064)
			(stroke
				(width 0.1524)
				(type default)
			)
			(layer "B.SilkS")
		)
		(fp_line
			(start -0.7874 -0.4064)
			(end -0.7874 0.4064)
			(stroke
				(width 0.1524)
				(type default)
			)
			(layer "B.SilkS")
		)
		(fp_line
			(start 0.7874 0.4064)
			(end 0.7874 -0.4064)
			(stroke
				(width 0.1524)
				(type default)
			)
			(layer "B.SilkS")
		)
		(fp_line
			(start -0.7874 0.4064)
			(end 0.7874 0.4064)
			(stroke
				(width 0.1524)
				(type default)
			)
			(layer "B.SilkS")
		)
		(fp_line
			(start 0.67945 -0.305054)
			(end 0.12065 -0.305054)
			(stroke
				(width 0.1)
				(type default)
			)
			(layer "B.Fab")
		)
		(fp_line
			(start 0.12065 -0.305054)
			(end 0.12065 -0.2794)
			(stroke
				(width 0.1)
				(type default)
			)
			(layer "B.Fab")
		)
		(fp_line
			(start -0.12065 -0.3048)
			(end -0.67945 -0.3048)
			(stroke
				(width 0.1)
				(type default)
			)
			(layer "B.Fab")
		)
		(fp_line
			(start -0.67945 -0.3048)
			(end -0.67945 0.3048)
			(stroke
				(width 0.1)
				(type default)
			)
			(layer "B.Fab")
		)
		(fp_line
			(start 0.12065 -0.2794)
			(end -0.12065 -0.2794)
			(stroke
				(width 0.1)
				(type default)
			)
			(layer "B.Fab")
		)
		(fp_line
			(start -0.12065 -0.2794)
			(end -0.12065 -0.3048)
			(stroke
				(width 0.1)
				(type default)
			)
			(layer "B.Fab")
		)
		(fp_line
			(start 0.12065 0.2794)
			(end 0.12065 0.3048)
			(stroke
				(width 0.1)
				(type default)
			)
			(layer "B.Fab")
		)
		(fp_line
			(start -0.120396 0.2794)
			(end 0.12065 0.2794)
			(stroke
				(width 0.1)
				(type default)
			)
			(layer "B.Fab")
		)
		(fp_line
			(start 0.67945 0.3048)
			(end 0.67945 -0.305054)
			(stroke
				(width 0.1)
				(type default)
			)
			(layer "B.Fab")
		)
		(fp_line
			(start 0.12065 0.3048)
			(end 0.67945 0.3048)
			(stroke
				(width 0.1)
				(type default)
			)
			(layer "B.Fab")
		)
		(fp_line
			(start -0.120396 0.3048)
			(end -0.120396 0.2794)
			(stroke
				(width 0.1)
				(type default)
			)
			(layer "B.Fab")
		)
		(fp_line
			(start -0.67945 0.3048)
			(end -0.120396 0.3048)
			(stroke
				(width 0.1)
				(type default)
			)
			(layer "B.Fab")
		)
		(pad "1" smd circle
			(at 0.40005 0 270)
			(size 0 0)
			(layers "B.Cu" "B.Mask" "B.Paste")
			(net "P3V3_AUX")
		)
		(pad "2" smd circle
			(at -0.40005 0 270)
			(size 0 0)
			(layers "B.Cu" "B.Mask" "B.Paste")
			(net "FM_SOL_UART_CH_SEL_R3")
		)
	)
	(footprint ""
		(layer "B.Cu")
		(at 39.868602 -63.756794 -90)
		(property "Reference" "R196"
			(at 0 0 90)
			(layer "B.SilkS")
			(hide yes)
			(effects
				(font
					(size 1.27 1.27)
				)
				(justify mirror)
			)
		)
		(property "Value" ""
			(at 0 0 90)
			(layer "B.Fab")
			(effects
				(font
					(size 1.27 1.27)
				)
				(justify mirror)
			)
		)
		(duplicate_pad_numbers_are_jumpers no)
		(fp_line
			(start -0.7874 0.4064)
			(end 0.7874 0.4064)
			(stroke
				(width 0.1524)
				(type default)
			)
			(layer "B.SilkS")
		)
		(fp_line
			(start 0.7874 0.4064)
			(end 0.7874 -0.4064)
			(stroke
				(width 0.1524)
				(type default)
			)
			(layer "B.SilkS")
		)
		(fp_line
			(start -0.7874 -0.4064)
			(end -0.7874 0.4064)
			(stroke
				(width 0.1524)
				(type default)
			)
			(layer "B.SilkS")
		)
		(fp_line
			(start 0.7874 -0.4064)
			(end -0.7874 -0.4064)
			(stroke
				(width 0.1524)
				(type default)
			)
			(layer "B.SilkS")
		)
		(fp_line
			(start -0.67945 0.3048)
			(end -0.120396 0.3048)
			(stroke
				(width 0.1)
				(type default)
			)
			(layer "B.Fab")
		)
		(fp_line
			(start -0.120396 0.3048)
			(end -0.120396 0.2794)
			(stroke
				(width 0.1)
				(type default)
			)
			(layer "B.Fab")
		)
		(fp_line
			(start 0.12065 0.3048)
			(end 0.67945 0.3048)
			(stroke
				(width 0.1)
				(type default)
			)
			(layer "B.Fab")
		)
		(fp_line
			(start 0.67945 0.3048)
			(end 0.67945 -0.305054)
			(stroke
				(width 0.1)
				(type default)
			)
			(layer "B.Fab")
		)
		(fp_line
			(start -0.120396 0.2794)
			(end 0.12065 0.2794)
			(stroke
				(width 0.1)
				(type default)
			)
			(layer "B.Fab")
		)
		(fp_line
			(start 0.12065 0.2794)
			(end 0.12065 0.3048)
			(stroke
				(width 0.1)
				(type default)
			)
			(layer "B.Fab")
		)
		(fp_line
			(start -0.12065 -0.2794)
			(end -0.12065 -0.3048)
			(stroke
				(width 0.1)
				(type default)
			)
			(layer "B.Fab")
		)
		(fp_line
			(start 0.12065 -0.2794)
			(end -0.12065 -0.2794)
			(stroke
				(width 0.1)
				(type default)
			)
			(layer "B.Fab")
		)
		(fp_line
			(start -0.67945 -0.3048)
			(end -0.67945 0.3048)
			(stroke
				(width 0.1)
				(type default)
			)
			(layer "B.Fab")
		)
		(fp_line
			(start -0.12065 -0.3048)
			(end -0.67945 -0.3048)
			(stroke
				(width 0.1)
				(type default)
			)
			(layer "B.Fab")
		)
		(fp_line
			(start 0.12065 -0.305054)
			(end 0.12065 -0.2794)
			(stroke
				(width 0.1)
				(type default)
			)
			(layer "B.Fab")
		)
		(fp_line
			(start 0.67945 -0.305054)
			(end 0.12065 -0.305054)
			(stroke
				(width 0.1)
				(type default)
			)
			(layer "B.Fab")
		)
		(pad "1" smd circle
			(at 0.40005 0 90)
			(size 0 0)
			(layers "B.Cu" "B.Mask" "B.Paste")
			(net "P1V2_P1V0_I3C_VDDL1")
		)
		(pad "2" smd circle
			(at -0.40005 0 90)
			(size 0 0)
			(layers "B.Cu" "B.Mask" "B.Paste")
			(net "I3C4_SPD_SCL")
		)
	)
	(footprint ""
		(layer "B.Cu")
		(at 74.095356 -100.93071 180)
		(property "Reference" "C267"
			(at 0 0 0)
			(layer "B.SilkS")
			(hide yes)
			(effects
				(font
					(size 1.27 1.27)
				)
				(justify mirror)
			)
		)
		(property "Value" ""
			(at 0 0 0)
			(layer "B.Fab")
			(effects
				(font
					(size 1.27 1.27)
				)
				(justify mirror)
			)
		)
		(duplicate_pad_numbers_are_jumpers no)
		(fp_line
			(start 0.7874 0.4064)
			(end 0.7874 -0.4064)
			(stroke
				(width 0.1524)
				(type default)
			)
			(layer "B.SilkS")
		)
		(fp_line
			(start 0.7874 -0.4064)
			(end -0.7874 -0.4064)
			(stroke
				(width 0.1524)
				(type default)
			)
			(layer "B.SilkS")
		)
		(fp_line
			(start -0.7874 0.4064)
			(end 0.7874 0.4064)
			(stroke
				(width 0.1524)
				(type default)
			)
			(layer "B.SilkS")
		)
		(fp_line
			(start -0.7874 -0.4064)
			(end -0.7874 0.4064)
			(stroke
				(width 0.1524)
				(type default)
			)
			(layer "B.SilkS")
		)
		(fp_line
			(start 0.67945 0.3048)
			(end 0.67945 -0.305054)
			(stroke
				(width 0.1)
				(type default)
			)
			(layer "B.Fab")
		)
		(fp_line
			(start 0.67945 -0.305054)
			(end 0.12065 -0.305054)
			(stroke
				(width 0.1)
				(type default)
			)
			(layer "B.Fab")
		)
		(fp_line
			(start 0.12065 0.3048)
			(end 0.67945 0.3048)
			(stroke
				(width 0.1)
				(type default)
			)
			(layer "B.Fab")
		)
		(fp_line
			(start 0.12065 0.2794)
			(end 0.12065 0.3048)
			(stroke
				(width 0.1)
				(type default)
			)
			(layer "B.Fab")
		)
		(fp_line
			(start 0.12065 -0.2794)
			(end -0.12065 -0.2794)
			(stroke
				(width 0.1)
				(type default)
			)
			(layer "B.Fab")
		)
		(fp_line
			(start 0.12065 -0.305054)
			(end 0.12065 -0.2794)
			(stroke
				(width 0.1)
				(type default)
			)
			(layer "B.Fab")
		)
		(fp_line
			(start -0.120396 0.3048)
			(end -0.120396 0.2794)
			(stroke
				(width 0.1)
				(type default)
			)
			(layer "B.Fab")
		)
		(fp_line
			(start -0.120396 0.2794)
			(end 0.12065 0.2794)
			(stroke
				(width 0.1)
				(type default)
			)
			(layer "B.Fab")
		)
		(fp_line
			(start -0.12065 -0.2794)
			(end -0.12065 -0.3048)
			(stroke
				(width 0.1)
				(type default)
			)
			(layer "B.Fab")
		)
		(fp_line
			(start -0.12065 -0.3048)
			(end -0.67945 -0.3048)
			(stroke
				(width 0.1)
				(type default)
			)
			(layer "B.Fab")
		)
		(fp_line
			(start -0.67945 0.3048)
			(end -0.120396 0.3048)
			(stroke
				(width 0.1)
				(type default)
			)
			(layer "B.Fab")
		)
		(fp_line
			(start -0.67945 -0.3048)
			(end -0.67945 0.3048)
			(stroke
				(width 0.1)
				(type default)
			)
			(layer "B.Fab")
		)
		(pad "1" smd circle
			(at 0.40005 0)
			(size 0 0)
			(layers "B.Cu" "B.Mask" "B.Paste")
			(net "LPC_ESPI_SEL_R1")
		)
		(pad "2" smd circle
			(at -0.40005 0)
			(size 0 0)
			(layers "B.Cu" "B.Mask" "B.Paste")
			(net "GND")
		)
	)
	(footprint ""
		(layer "B.Cu")
		(at 75.753468 -27.159966)
		(property "Reference" "U19"
			(at 3.304032 2.307336 0)
			(unlocked yes)
			(layer "B.SilkS")
			(effects
				(font
					(size 0.7874 0.5842)
					(thickness 0.1524)
				)
				(justify left mirror)
			)
		)
		(property "Value" ""
			(at 0 0 0)
			(layer "B.Fab")
			(effects
				(font
					(size 1.27 1.27)
				)
				(justify mirror)
			)
		)
		(duplicate_pad_numbers_are_jumpers no)
		(fp_line
			(start -1.954022 -1.549908)
			(end -1.954022 1.549908)
			(stroke
				(width 0.1524)
				(type default)
			)
			(layer "B.SilkS")
		)
		(fp_line
			(start -1.954022 1.549908)
			(end 1.954022 1.549908)
			(stroke
				(width 0.1524)
				(type default)
			)
			(layer "B.SilkS")
		)
		(fp_line
			(start -0.651256 -1.549908)
			(end -1.954022 -1.549908)
			(stroke
				(width 0.1524)
				(type default)
			)
			(layer "B.SilkS")
		)
		(fp_line
			(start 0 -0.898652)
			(end -0.651256 -1.549908)
			(stroke
				(width 0.1524)
				(type default)
			)
			(layer "B.SilkS")
		)
		(fp_line
			(start 0.651256 -1.549908)
			(end 0 -0.898652)
			(stroke
				(width 0.1524)
				(type default)
			)
			(layer "B.SilkS")
		)
		(fp_line
			(start 1.954022 -1.549908)
			(end 0.651256 -1.549908)
			(stroke
				(width 0.1524)
				(type default)
			)
			(layer "B.SilkS")
		)
		(fp_line
			(start 1.954022 1.549908)
			(end 1.954022 -1.549908)
			(stroke
				(width 0.1524)
				(type default)
			)
			(layer "B.SilkS")
		)
		(fp_poly
			(pts
				(xy 5.246624 -0.403352) (xy 4.528312 0.31496) (xy 4.168902 -0.762508)
			)
			(stroke
				(width 0)
				(type default)
			)
			(fill yes)
			(layer "B.SilkS")
		)
		(fp_line
			(start -2.249932 -1.549908)
			(end 2.249932 -1.549908)
			(stroke
				(width 0.1)
				(type default)
			)
			(layer "B.Fab")
		)
		(fp_line
			(start -2.249932 1.549908)
			(end -2.249932 -1.549908)
			(stroke
				(width 0.1)
				(type default)
			)
			(layer "B.Fab")
		)
		(fp_line
			(start 2.249932 -1.549908)
			(end 2.249932 1.549908)
			(stroke
				(width 0.1)
				(type default)
			)
			(layer "B.Fab")
		)
		(fp_line
			(start 2.249932 1.549908)
			(end -2.249932 1.549908)
			(stroke
				(width 0.1)
				(type default)
			)
			(layer "B.Fab")
		)
		(fp_poly
			(pts
				(xy 5.256022 -1.483106) (xy 5.256022 -0.467106) (xy 4.240022 -0.975106)
			)
			(stroke
				(width 0)
				(type default)
			)
			(fill yes)
			(layer "B.Fab")
		)
		(pad "1" smd rect
			(at 2.970022 -0.975106 270)
			(size 0.4318 1.778)
			(layers "B.Cu" "B.Mask" "B.Paste")
			(net "FRU_E0")
		)
		(pad "2" smd rect
			(at 2.970022 -0.32512 270)
			(size 0.4318 1.778)
			(layers "B.Cu" "B.Mask" "B.Paste")
			(net "FRU_E1")
		)
		(pad "3" smd rect
			(at 2.970022 0.32512 270)
			(size 0.4318 1.778)
			(layers "B.Cu" "B.Mask" "B.Paste")
			(net "FRU_E2")
		)
		(pad "4" smd rect
			(at 2.970022 0.975106 270)
			(size 0.4318 1.778)
			(layers "B.Cu" "B.Mask" "B.Paste")
			(net "GND")
		)
		(pad "5" smd rect
			(at -2.970022 0.975106 270)
			(size 0.4318 1.778)
			(layers "B.Cu" "B.Mask" "B.Paste")
			(net "SMB_BMC_MM16_R2_SDA")
		)
		(pad "6" smd rect
			(at -2.970022 0.32512 270)
			(size 0.4318 1.778)
			(layers "B.Cu" "B.Mask" "B.Paste")
			(net "SMB_BMC_MM16_R2_SCL")
		)
		(pad "7" smd rect
			(at -2.970022 -0.32512 270)
			(size 0.4318 1.778)
			(layers "B.Cu" "B.Mask" "B.Paste")
			(net "PD_FRU_WC_N")
		)
		(pad "8" smd rect
			(at -2.970022 -0.975106 270)
			(size 0.4318 1.778)
			(layers "B.Cu" "B.Mask" "B.Paste")
			(net "P3V3_AUX")
		)
	)
	(footprint ""
		(layer "B.Cu")
		(at 39.930832 -47.137828 180)
		(property "Reference" "R267"
			(at 0 0 0)
			(layer "B.SilkS")
			(hide yes)
			(effects
				(font
					(size 1.27 1.27)
				)
				(justify mirror)
			)
		)
		(property "Value" ""
			(at 0 0 0)
			(layer "B.Fab")
			(effects
				(font
					(size 1.27 1.27)
				)
				(justify mirror)
			)
		)
		(duplicate_pad_numbers_are_jumpers no)
		(fp_line
			(start 0.7874 0.4064)
			(end 0.7874 -0.4064)
			(stroke
				(width 0.1524)
				(type default)
			)
			(layer "B.SilkS")
		)
		(fp_line
			(start 0.7874 -0.4064)
			(end -0.7874 -0.4064)
			(stroke
				(width 0.1524)
				(type default)
			)
			(layer "B.SilkS")
		)
		(fp_line
			(start -0.7874 0.4064)
			(end 0.7874 0.4064)
			(stroke
				(width 0.1524)
				(type default)
			)
			(layer "B.SilkS")
		)
		(fp_line
			(start -0.7874 -0.4064)
			(end -0.7874 0.4064)
			(stroke
				(width 0.1524)
				(type default)
			)
			(layer "B.SilkS")
		)
		(fp_line
			(start 0.67945 0.3048)
			(end 0.67945 -0.305054)
			(stroke
				(width 0.1)
				(type default)
			)
			(layer "B.Fab")
		)
		(fp_line
			(start 0.67945 -0.305054)
			(end 0.12065 -0.305054)
			(stroke
				(width 0.1)
				(type default)
			)
			(layer "B.Fab")
		)
		(fp_line
			(start 0.12065 0.3048)
			(end 0.67945 0.3048)
			(stroke
				(width 0.1)
				(type default)
			)
			(layer "B.Fab")
		)
		(fp_line
			(start 0.12065 0.2794)
			(end 0.12065 0.3048)
			(stroke
				(width 0.1)
				(type default)
			)
			(layer "B.Fab")
		)
		(fp_line
			(start 0.12065 -0.2794)
			(end -0.12065 -0.2794)
			(stroke
				(width 0.1)
				(type default)
			)
			(layer "B.Fab")
		)
		(fp_line
			(start 0.12065 -0.305054)
			(end 0.12065 -0.2794)
			(stroke
				(width 0.1)
				(type default)
			)
			(layer "B.Fab")
		)
		(fp_line
			(start -0.120396 0.3048)
			(end -0.120396 0.2794)
			(stroke
				(width 0.1)
				(type default)
			)
			(layer "B.Fab")
		)
		(fp_line
			(start -0.120396 0.2794)
			(end 0.12065 0.2794)
			(stroke
				(width 0.1)
				(type default)
			)
			(layer "B.Fab")
		)
		(fp_line
			(start -0.12065 -0.2794)
			(end -0.12065 -0.3048)
			(stroke
				(width 0.1)
				(type default)
			)
			(layer "B.Fab")
		)
		(fp_line
			(start -0.12065 -0.3048)
			(end -0.67945 -0.3048)
			(stroke
				(width 0.1)
				(type default)
			)
			(layer "B.Fab")
		)
		(fp_line
			(start -0.67945 0.3048)
			(end -0.120396 0.3048)
			(stroke
				(width 0.1)
				(type default)
			)
			(layer "B.Fab")
		)
		(fp_line
			(start -0.67945 -0.3048)
			(end -0.67945 0.3048)
			(stroke
				(width 0.1)
				(type default)
			)
			(layer "B.Fab")
		)
		(pad "1" smd circle
			(at 0.40005 0)
			(size 0 0)
			(layers "B.Cu" "B.Mask" "B.Paste")
			(net "P3V3_AUX")
		)
		(pad "2" smd circle
			(at -0.40005 0)
			(size 0 0)
			(layers "B.Cu" "B.Mask" "B.Paste")
			(net "VOL_SEN_ALERT_R")
		)
	)
	(footprint ""
		(layer "B.Cu")
		(at 46.0502 -61.976 90)
		(property "Reference" "C134"
			(at 0 0 90)
			(layer "B.SilkS")
			(hide yes)
			(effects
				(font
					(size 1.27 1.27)
				)
				(justify mirror)
			)
		)
		(property "Value" ""
			(at 0 0 90)
			(layer "B.Fab")
			(effects
				(font
					(size 1.27 1.27)
				)
				(justify mirror)
			)
		)
		(duplicate_pad_numbers_are_jumpers no)
		(fp_line
			(start 0.7874 -0.4064)
			(end -0.7874 -0.4064)
			(stroke
				(width 0.1524)
				(type default)
			)
			(layer "B.SilkS")
		)
		(fp_line
			(start -0.7874 -0.4064)
			(end -0.7874 0.4064)
			(stroke
				(width 0.1524)
				(type default)
			)
			(layer "B.SilkS")
		)
		(fp_line
			(start 0.7874 0.4064)
			(end 0.7874 -0.4064)
			(stroke
				(width 0.1524)
				(type default)
			)
			(layer "B.SilkS")
		)
		(fp_line
			(start -0.7874 0.4064)
			(end 0.7874 0.4064)
			(stroke
				(width 0.1524)
				(type default)
			)
			(layer "B.SilkS")
		)
		(fp_line
			(start 0.67945 -0.305054)
			(end 0.12065 -0.305054)
			(stroke
				(width 0.1)
				(type default)
			)
			(layer "B.Fab")
		)
		(fp_line
			(start 0.12065 -0.305054)
			(end 0.12065 -0.2794)
			(stroke
				(width 0.1)
				(type default)
			)
			(layer "B.Fab")
		)
		(fp_line
			(start -0.12065 -0.3048)
			(end -0.67945 -0.3048)
			(stroke
				(width 0.1)
				(type default)
			)
			(layer "B.Fab")
		)
		(fp_line
			(start -0.67945 -0.3048)
			(end -0.67945 0.3048)
			(stroke
				(width 0.1)
				(type default)
			)
			(layer "B.Fab")
		)
		(fp_line
			(start 0.12065 -0.2794)
			(end -0.12065 -0.2794)
			(stroke
				(width 0.1)
				(type default)
			)
			(layer "B.Fab")
		)
		(fp_line
			(start -0.12065 -0.2794)
			(end -0.12065 -0.3048)
			(stroke
				(width 0.1)
				(type default)
			)
			(layer "B.Fab")
		)
		(fp_line
			(start 0.12065 0.2794)
			(end 0.12065 0.3048)
			(stroke
				(width 0.1)
				(type default)
			)
			(layer "B.Fab")
		)
		(fp_line
			(start -0.120396 0.2794)
			(end 0.12065 0.2794)
			(stroke
				(width 0.1)
				(type default)
			)
			(layer "B.Fab")
		)
		(fp_line
			(start 0.67945 0.3048)
			(end 0.67945 -0.305054)
			(stroke
				(width 0.1)
				(type default)
			)
			(layer "B.Fab")
		)
		(fp_line
			(start 0.12065 0.3048)
			(end 0.67945 0.3048)
			(stroke
				(width 0.1)
				(type default)
			)
			(layer "B.Fab")
		)
		(fp_line
			(start -0.120396 0.3048)
			(end -0.120396 0.2794)
			(stroke
				(width 0.1)
				(type default)
			)
			(layer "B.Fab")
		)
		(fp_line
			(start -0.67945 0.3048)
			(end -0.120396 0.3048)
			(stroke
				(width 0.1)
				(type default)
			)
			(layer "B.Fab")
		)
		(pad "1" smd circle
			(at 0.40005 0 270)
			(size 0 0)
			(layers "B.Cu" "B.Mask" "B.Paste")
			(net "GND")
		)
		(pad "2" smd circle
			(at -0.40005 0 270)
			(size 0 0)
			(layers "B.Cu" "B.Mask" "B.Paste")
			(net "A_BMC_ADCVREFN0")
		)
	)
	(footprint ""
		(layer "B.Cu")
		(at 15.748 -100.711 135)
		(property "Reference" "C163"
			(at 0 0 135)
			(layer "B.SilkS")
			(hide yes)
			(effects
				(font
					(size 1.27 1.27)
				)
				(justify mirror)
			)
		)
		(property "Value" ""
			(at 0 0 135)
			(layer "B.Fab")
			(effects
				(font
					(size 1.27 1.27)
				)
				(justify mirror)
			)
		)
		(duplicate_pad_numbers_are_jumpers no)
		(fp_line
			(start 1.295492 -0.584255)
			(end -1.295492 -0.584255)
			(stroke
				(width 0.1524)
				(type default)
			)
			(layer "B.SilkS")
		)
		(fp_line
			(start 1.295492 0.584255)
			(end 1.295492 -0.584255)
			(stroke
				(width 0.1524)
				(type default)
			)
			(layer "B.SilkS")
		)
		(fp_line
			(start 0 -0.584076)
			(end 0 0.584076)
			(stroke
				(width 0.1524)
				(type default)
			)
			(layer "B.SilkS")
		)
		(fp_line
			(start -1.295492 -0.584255)
			(end -1.295492 0.584255)
			(stroke
				(width 0.1524)
				(type default)
			)
			(layer "B.SilkS")
		)
		(fp_line
			(start -1.295492 0.584255)
			(end 1.295492 0.584255)
			(stroke
				(width 0.1524)
				(type default)
			)
			(layer "B.SilkS")
		)
		(fp_line
			(start 1.193835 -0.406446)
			(end 0.863721 -0.406446)
			(stroke
				(width 0.1)
				(type default)
			)
			(layer "B.Fab")
		)
		(fp_line
			(start 0.863541 -0.457275)
			(end -0.863541 -0.457275)
			(stroke
				(width 0.1)
				(type default)
			)
			(layer "B.Fab")
		)
		(fp_line
			(start 0.863721 -0.406446)
			(end 0.863541 -0.457275)
			(stroke
				(width 0.1)
				(type default)
			)
			(layer "B.Fab")
		)
		(fp_line
			(start 1.193835 0.406446)
			(end 1.193835 -0.406446)
			(stroke
				(width 0.1)
				(type default)
			)
			(layer "B.Fab")
		)
		(fp_line
			(start 0.863721 0.406446)
			(end 1.193835 0.406446)
			(stroke
				(width 0.1)
				(type default)
			)
			(layer "B.Fab")
		)
		(fp_line
			(start 0.863541 0.457275)
			(end 0.863721 0.406446)
			(stroke
				(width 0.1)
				(type default)
			)
			(layer "B.Fab")
		)
		(fp_line
			(start -0.863541 -0.457275)
			(end -0.863721 -0.406446)
			(stroke
				(width 0.1)
				(type default)
			)
			(layer "B.Fab")
		)
		(fp_line
			(start -0.863721 -0.406446)
			(end -1.193835 -0.406446)
			(stroke
				(width 0.1)
				(type default)
			)
			(layer "B.Fab")
		)
		(fp_line
			(start -1.193835 -0.406446)
			(end -1.193835 0.406446)
			(stroke
				(width 0.1)
				(type default)
			)
			(layer "B.Fab")
		)
		(fp_line
			(start -0.863721 0.406446)
			(end -0.863541 0.457275)
			(stroke
				(width 0.1)
				(type default)
			)
			(layer "B.Fab")
		)
		(fp_line
			(start -0.863541 0.457275)
			(end 0.863541 0.457275)
			(stroke
				(width 0.1)
				(type default)
			)
			(layer "B.Fab")
		)
		(fp_line
			(start -1.193835 0.406446)
			(end -0.863721 0.406446)
			(stroke
				(width 0.1)
				(type default)
			)
			(layer "B.Fab")
		)
		(pad "1" smd rect
			(at 0.7366 0 45)
			(size 0.7112 0.8128)
			(layers "B.Cu" "B.Mask" "B.Paste")
			(net "PVCCA_AUX_PLD")
		)
		(pad "2" smd rect
			(at -0.7366 0 45)
			(size 0.7112 0.8128)
			(layers "B.Cu" "B.Mask" "B.Paste")
			(net "GND")
		)
	)
	(footprint ""
		(layer "B.Cu")
		(at 34.8488 -63.6778)
		(property "Reference" "R618"
			(at 0 0 0)
			(layer "B.SilkS")
			(hide yes)
			(effects
				(font
					(size 1.27 1.27)
				)
				(justify mirror)
			)
		)
		(property "Value" ""
			(at 0 0 0)
			(layer "B.Fab")
			(effects
				(font
					(size 1.27 1.27)
				)
				(justify mirror)
			)
		)
		(duplicate_pad_numbers_are_jumpers no)
		(fp_line
			(start -0.7874 -0.4064)
			(end -0.7874 0.4064)
			(stroke
				(width 0.1524)
				(type default)
			)
			(layer "B.SilkS")
		)
		(fp_line
			(start -0.7874 0.4064)
			(end 0.7874 0.4064)
			(stroke
				(width 0.1524)
				(type default)
			)
			(layer "B.SilkS")
		)
		(fp_line
			(start 0.7874 -0.4064)
			(end -0.7874 -0.4064)
			(stroke
				(width 0.1524)
				(type default)
			)
			(layer "B.SilkS")
		)
		(fp_line
			(start 0.7874 0.4064)
			(end 0.7874 -0.4064)
			(stroke
				(width 0.1524)
				(type default)
			)
			(layer "B.SilkS")
		)
		(fp_line
			(start -0.67945 -0.3048)
			(end -0.67945 0.3048)
			(stroke
				(width 0.1)
				(type default)
			)
			(layer "B.Fab")
		)
		(fp_line
			(start -0.67945 0.3048)
			(end -0.120396 0.3048)
			(stroke
				(width 0.1)
				(type default)
			)
			(layer "B.Fab")
		)
		(fp_line
			(start -0.12065 -0.3048)
			(end -0.67945 -0.3048)
			(stroke
				(width 0.1)
				(type default)
			)
			(layer "B.Fab")
		)
		(fp_line
			(start -0.12065 -0.2794)
			(end -0.12065 -0.3048)
			(stroke
				(width 0.1)
				(type default)
			)
			(layer "B.Fab")
		)
		(fp_line
			(start -0.120396 0.2794)
			(end 0.12065 0.2794)
			(stroke
				(width 0.1)
				(type default)
			)
			(layer "B.Fab")
		)
		(fp_line
			(start -0.120396 0.3048)
			(end -0.120396 0.2794)
			(stroke
				(width 0.1)
				(type default)
			)
			(layer "B.Fab")
		)
		(fp_line
			(start 0.12065 -0.305054)
			(end 0.12065 -0.2794)
			(stroke
				(width 0.1)
				(type default)
			)
			(layer "B.Fab")
		)
		(fp_line
			(start 0.12065 -0.2794)
			(end -0.12065 -0.2794)
			(stroke
				(width 0.1)
				(type default)
			)
			(layer "B.Fab")
		)
		(fp_line
			(start 0.12065 0.2794)
			(end 0.12065 0.3048)
			(stroke
				(width 0.1)
				(type default)
			)
			(layer "B.Fab")
		)
		(fp_line
			(start 0.12065 0.3048)
			(end 0.67945 0.3048)
			(stroke
				(width 0.1)
				(type default)
			)
			(layer "B.Fab")
		)
		(fp_line
			(start 0.67945 -0.305054)
			(end 0.12065 -0.305054)
			(stroke
				(width 0.1)
				(type default)
			)
			(layer "B.Fab")
		)
		(fp_line
			(start 0.67945 0.3048)
			(end 0.67945 -0.305054)
			(stroke
				(width 0.1)
				(type default)
			)
			(layer "B.Fab")
		)
		(pad "1" smd circle
			(at 0.40005 0 180)
			(size 0 0)
			(layers "B.Cu" "B.Mask" "B.Paste")
			(net "UART_SYS_DBG_RX")
		)
		(pad "2" smd circle
			(at -0.40005 0 180)
			(size 0 0)
			(layers "B.Cu" "B.Mask" "B.Paste")
			(net "UART_SYS_DBG_RX_R")
		)
	)
	(footprint ""
		(layer "B.Cu")
		(at 55.123334 -54.87162)
		(property "Reference" "C106"
			(at 0 0 0)
			(layer "B.SilkS")
			(hide yes)
			(effects
				(font
					(size 1.27 1.27)
				)
				(justify mirror)
			)
		)
		(property "Value" ""
			(at 0 0 0)
			(layer "B.Fab")
			(effects
				(font
					(size 1.27 1.27)
				)
				(justify mirror)
			)
		)
		(duplicate_pad_numbers_are_jumpers no)
		(fp_line
			(start -0.7874 -0.4064)
			(end -0.7874 0.4064)
			(stroke
				(width 0.1524)
				(type default)
			)
			(layer "B.SilkS")
		)
		(fp_line
			(start -0.7874 0.4064)
			(end 0.7874 0.4064)
			(stroke
				(width 0.1524)
				(type default)
			)
			(layer "B.SilkS")
		)
		(fp_line
			(start 0.7874 -0.4064)
			(end -0.7874 -0.4064)
			(stroke
				(width 0.1524)
				(type default)
			)
			(layer "B.SilkS")
		)
		(fp_line
			(start 0.7874 0.4064)
			(end 0.7874 -0.4064)
			(stroke
				(width 0.1524)
				(type default)
			)
			(layer "B.SilkS")
		)
		(fp_line
			(start -0.67945 -0.3048)
			(end -0.67945 0.3048)
			(stroke
				(width 0.1)
				(type default)
			)
			(layer "B.Fab")
		)
		(fp_line
			(start -0.67945 0.3048)
			(end -0.120396 0.3048)
			(stroke
				(width 0.1)
				(type default)
			)
			(layer "B.Fab")
		)
		(fp_line
			(start -0.12065 -0.3048)
			(end -0.67945 -0.3048)
			(stroke
				(width 0.1)
				(type default)
			)
			(layer "B.Fab")
		)
		(fp_line
			(start -0.12065 -0.2794)
			(end -0.12065 -0.3048)
			(stroke
				(width 0.1)
				(type default)
			)
			(layer "B.Fab")
		)
		(fp_line
			(start -0.120396 0.2794)
			(end 0.12065 0.2794)
			(stroke
				(width 0.1)
				(type default)
			)
			(layer "B.Fab")
		)
		(fp_line
			(start -0.120396 0.3048)
			(end -0.120396 0.2794)
			(stroke
				(width 0.1)
				(type default)
			)
			(layer "B.Fab")
		)
		(fp_line
			(start 0.12065 -0.305054)
			(end 0.12065 -0.2794)
			(stroke
				(width 0.1)
				(type default)
			)
			(layer "B.Fab")
		)
		(fp_line
			(start 0.12065 -0.2794)
			(end -0.12065 -0.2794)
			(stroke
				(width 0.1)
				(type default)
			)
			(layer "B.Fab")
		)
		(fp_line
			(start 0.12065 0.2794)
			(end 0.12065 0.3048)
			(stroke
				(width 0.1)
				(type default)
			)
			(layer "B.Fab")
		)
		(fp_line
			(start 0.12065 0.3048)
			(end 0.67945 0.3048)
			(stroke
				(width 0.1)
				(type default)
			)
			(layer "B.Fab")
		)
		(fp_line
			(start 0.67945 -0.305054)
			(end 0.12065 -0.305054)
			(stroke
				(width 0.1)
				(type default)
			)
			(layer "B.Fab")
		)
		(fp_line
			(start 0.67945 0.3048)
			(end 0.67945 -0.305054)
			(stroke
				(width 0.1)
				(type default)
			)
			(layer "B.Fab")
		)
		(pad "1" smd circle
			(at 0.40005 0 180)
			(size 0 0)
			(layers "B.Cu" "B.Mask" "B.Paste")
			(net "P1V8_AUX")
		)
		(pad "2" smd circle
			(at -0.40005 0 180)
			(size 0 0)
			(layers "B.Cu" "B.Mask" "B.Paste")
			(net "GND")
		)
	)
	(footprint ""
		(layer "B.Cu")
		(at 74.810112 -56.937656 -90)
		(property "Reference" "C118"
			(at 0 0 90)
			(layer "B.SilkS")
			(hide yes)
			(effects
				(font
					(size 1.27 1.27)
				)
				(justify mirror)
			)
		)
		(property "Value" ""
			(at 0 0 90)
			(layer "B.Fab")
			(effects
				(font
					(size 1.27 1.27)
				)
				(justify mirror)
			)
		)
		(duplicate_pad_numbers_are_jumpers no)
		(fp_line
			(start -1.2954 0.5842)
			(end 1.2954 0.5842)
			(stroke
				(width 0.1524)
				(type default)
			)
			(layer "B.SilkS")
		)
		(fp_line
			(start 1.2954 0.5842)
			(end 1.2954 -0.5842)
			(stroke
				(width 0.1524)
				(type default)
			)
			(layer "B.SilkS")
		)
		(fp_line
			(start -1.2954 -0.5842)
			(end -1.2954 0.5842)
			(stroke
				(width 0.1524)
				(type default)
			)
			(layer "B.SilkS")
		)
		(fp_line
			(start 0 -0.5842)
			(end 0 0.5842)
			(stroke
				(width 0.1524)
				(type default)
			)
			(layer "B.SilkS")
		)
		(fp_line
			(start 1.2954 -0.5842)
			(end -1.2954 -0.5842)
			(stroke
				(width 0.1524)
				(type default)
			)
			(layer "B.SilkS")
		)
		(fp_line
			(start -0.8636 0.4572)
			(end 0.8636 0.4572)
			(stroke
				(width 0.1)
				(type default)
			)
			(layer "B.Fab")
		)
		(fp_line
			(start 0.8636 0.4572)
			(end 0.8636 0.4064)
			(stroke
				(width 0.1)
				(type default)
			)
			(layer "B.Fab")
		)
		(fp_line
			(start -1.1938 0.4064)
			(end -0.8636 0.4064)
			(stroke
				(width 0.1)
				(type default)
			)
			(layer "B.Fab")
		)
		(fp_line
			(start -0.8636 0.4064)
			(end -0.8636 0.4572)
			(stroke
				(width 0.1)
				(type default)
			)
			(layer "B.Fab")
		)
		(fp_line
			(start 0.8636 0.4064)
			(end 1.1938 0.4064)
			(stroke
				(width 0.1)
				(type default)
			)
			(layer "B.Fab")
		)
		(fp_line
			(start 1.1938 0.4064)
			(end 1.1938 -0.4064)
			(stroke
				(width 0.1)
				(type default)
			)
			(layer "B.Fab")
		)
		(fp_line
			(start -1.1938 -0.4064)
			(end -1.1938 0.4064)
			(stroke
				(width 0.1)
				(type default)
			)
			(layer "B.Fab")
		)
		(fp_line
			(start -0.8636 -0.4064)
			(end -1.1938 -0.4064)
			(stroke
				(width 0.1)
				(type default)
			)
			(layer "B.Fab")
		)
		(fp_line
			(start 0.8636 -0.4064)
			(end 0.8636 -0.4572)
			(stroke
				(width 0.1)
				(type default)
			)
			(layer "B.Fab")
		)
		(fp_line
			(start 1.1938 -0.4064)
			(end 0.8636 -0.4064)
			(stroke
				(width 0.1)
				(type default)
			)
			(layer "B.Fab")
		)
		(fp_line
			(start -0.8636 -0.4572)
			(end -0.8636 -0.4064)
			(stroke
				(width 0.1)
				(type default)
			)
			(layer "B.Fab")
		)
		(fp_line
			(start 0.8636 -0.4572)
			(end -0.8636 -0.4572)
			(stroke
				(width 0.1)
				(type default)
			)
			(layer "B.Fab")
		)
		(pad "1" smd rect
			(at 0.7366 0 180)
			(size 0.7112 0.8128)
			(layers "B.Cu" "B.Mask" "B.Paste")
			(net "P1V0_AUX")
		)
		(pad "2" smd rect
			(at -0.7366 0 180)
			(size 0.7112 0.8128)
			(layers "B.Cu" "B.Mask" "B.Paste")
			(net "GND")
		)
	)
	(footprint ""
		(layer "B.Cu")
		(at 39.414958 -83.861656 180)
		(property "Reference" "R821"
			(at 0 0 0)
			(layer "B.SilkS")
			(hide yes)
			(effects
				(font
					(size 1.27 1.27)
				)
				(justify mirror)
			)
		)
		(property "Value" ""
			(at 0 0 0)
			(layer "B.Fab")
			(effects
				(font
					(size 1.27 1.27)
				)
				(justify mirror)
			)
		)
		(duplicate_pad_numbers_are_jumpers no)
		(fp_line
			(start 0.7874 0.4064)
			(end 0.7874 -0.4064)
			(stroke
				(width 0.1524)
				(type default)
			)
			(layer "B.SilkS")
		)
		(fp_line
			(start 0.7874 -0.4064)
			(end -0.7874 -0.4064)
			(stroke
				(width 0.1524)
				(type default)
			)
			(layer "B.SilkS")
		)
		(fp_line
			(start -0.7874 0.4064)
			(end 0.7874 0.4064)
			(stroke
				(width 0.1524)
				(type default)
			)
			(layer "B.SilkS")
		)
		(fp_line
			(start -0.7874 -0.4064)
			(end -0.7874 0.4064)
			(stroke
				(width 0.1524)
				(type default)
			)
			(layer "B.SilkS")
		)
		(fp_line
			(start 0.67945 0.3048)
			(end 0.67945 -0.305054)
			(stroke
				(width 0.1)
				(type default)
			)
			(layer "B.Fab")
		)
		(fp_line
			(start 0.67945 -0.305054)
			(end 0.12065 -0.305054)
			(stroke
				(width 0.1)
				(type default)
			)
			(layer "B.Fab")
		)
		(fp_line
			(start 0.12065 0.3048)
			(end 0.67945 0.3048)
			(stroke
				(width 0.1)
				(type default)
			)
			(layer "B.Fab")
		)
		(fp_line
			(start 0.12065 0.2794)
			(end 0.12065 0.3048)
			(stroke
				(width 0.1)
				(type default)
			)
			(layer "B.Fab")
		)
		(fp_line
			(start 0.12065 -0.2794)
			(end -0.12065 -0.2794)
			(stroke
				(width 0.1)
				(type default)
			)
			(layer "B.Fab")
		)
		(fp_line
			(start 0.12065 -0.305054)
			(end 0.12065 -0.2794)
			(stroke
				(width 0.1)
				(type default)
			)
			(layer "B.Fab")
		)
		(fp_line
			(start -0.120396 0.3048)
			(end -0.120396 0.2794)
			(stroke
				(width 0.1)
				(type default)
			)
			(layer "B.Fab")
		)
		(fp_line
			(start -0.120396 0.2794)
			(end 0.12065 0.2794)
			(stroke
				(width 0.1)
				(type default)
			)
			(layer "B.Fab")
		)
		(fp_line
			(start -0.12065 -0.2794)
			(end -0.12065 -0.3048)
			(stroke
				(width 0.1)
				(type default)
			)
			(layer "B.Fab")
		)
		(fp_line
			(start -0.12065 -0.3048)
			(end -0.67945 -0.3048)
			(stroke
				(width 0.1)
				(type default)
			)
			(layer "B.Fab")
		)
		(fp_line
			(start -0.67945 0.3048)
			(end -0.120396 0.3048)
			(stroke
				(width 0.1)
				(type default)
			)
			(layer "B.Fab")
		)
		(fp_line
			(start -0.67945 -0.3048)
			(end -0.67945 0.3048)
			(stroke
				(width 0.1)
				(type default)
			)
			(layer "B.Fab")
		)
		(pad "1" smd circle
			(at 0.40005 0)
			(size 0 0)
			(layers "B.Cu" "B.Mask" "B.Paste")
			(net "P3V3_AUX")
		)
		(pad "2" smd circle
			(at -0.40005 0)
			(size 0 0)
			(layers "B.Cu" "B.Mask" "B.Paste")
			(net "FM_BMC_ONCTL_R_N")
		)
	)
	(footprint ""
		(layer "B.Cu")
		(at 63.964058 -70.296024 180)
		(property "Reference" "R117"
			(at 0 0 0)
			(layer "B.SilkS")
			(hide yes)
			(effects
				(font
					(size 1.27 1.27)
				)
				(justify mirror)
			)
		)
		(property "Value" ""
			(at 0 0 0)
			(layer "B.Fab")
			(effects
				(font
					(size 1.27 1.27)
				)
				(justify mirror)
			)
		)
		(duplicate_pad_numbers_are_jumpers no)
		(fp_line
			(start 0.7874 0.4064)
			(end 0.7874 -0.4064)
			(stroke
				(width 0.1524)
				(type default)
			)
			(layer "B.SilkS")
		)
		(fp_line
			(start 0.7874 -0.4064)
			(end -0.7874 -0.4064)
			(stroke
				(width 0.1524)
				(type default)
			)
			(layer "B.SilkS")
		)
		(fp_line
			(start -0.7874 0.4064)
			(end 0.7874 0.4064)
			(stroke
				(width 0.1524)
				(type default)
			)
			(layer "B.SilkS")
		)
		(fp_line
			(start -0.7874 -0.4064)
			(end -0.7874 0.4064)
			(stroke
				(width 0.1524)
				(type default)
			)
			(layer "B.SilkS")
		)
		(fp_line
			(start 0.67945 0.3048)
			(end 0.67945 -0.305054)
			(stroke
				(width 0.1)
				(type default)
			)
			(layer "B.Fab")
		)
		(fp_line
			(start 0.67945 -0.305054)
			(end 0.12065 -0.305054)
			(stroke
				(width 0.1)
				(type default)
			)
			(layer "B.Fab")
		)
		(fp_line
			(start 0.12065 0.3048)
			(end 0.67945 0.3048)
			(stroke
				(width 0.1)
				(type default)
			)
			(layer "B.Fab")
		)
		(fp_line
			(start 0.12065 0.2794)
			(end 0.12065 0.3048)
			(stroke
				(width 0.1)
				(type default)
			)
			(layer "B.Fab")
		)
		(fp_line
			(start 0.12065 -0.2794)
			(end -0.12065 -0.2794)
			(stroke
				(width 0.1)
				(type default)
			)
			(layer "B.Fab")
		)
		(fp_line
			(start 0.12065 -0.305054)
			(end 0.12065 -0.2794)
			(stroke
				(width 0.1)
				(type default)
			)
			(layer "B.Fab")
		)
		(fp_line
			(start -0.120396 0.3048)
			(end -0.120396 0.2794)
			(stroke
				(width 0.1)
				(type default)
			)
			(layer "B.Fab")
		)
		(fp_line
			(start -0.120396 0.2794)
			(end 0.12065 0.2794)
			(stroke
				(width 0.1)
				(type default)
			)
			(layer "B.Fab")
		)
		(fp_line
			(start -0.12065 -0.2794)
			(end -0.12065 -0.3048)
			(stroke
				(width 0.1)
				(type default)
			)
			(layer "B.Fab")
		)
		(fp_line
			(start -0.12065 -0.3048)
			(end -0.67945 -0.3048)
			(stroke
				(width 0.1)
				(type default)
			)
			(layer "B.Fab")
		)
		(fp_line
			(start -0.67945 0.3048)
			(end -0.120396 0.3048)
			(stroke
				(width 0.1)
				(type default)
			)
			(layer "B.Fab")
		)
		(fp_line
			(start -0.67945 -0.3048)
			(end -0.67945 0.3048)
			(stroke
				(width 0.1)
				(type default)
			)
			(layer "B.Fab")
		)
		(pad "1" smd circle
			(at 0.40005 0)
			(size 0 0)
			(layers "B.Cu" "B.Mask" "B.Paste")
			(net "PGPPA_BMC_AUX")
		)
		(pad "2" smd circle
			(at -0.40005 0)
			(size 0 0)
			(layers "B.Cu" "B.Mask" "B.Paste")
			(net "RST_BMC_LPC_ESPI_N")
		)
	)
	(footprint ""
		(layer "B.Cu")
		(at 54.684676 -30.867604 -90)
		(property "Reference" "R262"
			(at 0 0 90)
			(layer "B.SilkS")
			(hide yes)
			(effects
				(font
					(size 1.27 1.27)
				)
				(justify mirror)
			)
		)
		(property "Value" ""
			(at 0 0 90)
			(layer "B.Fab")
			(effects
				(font
					(size 1.27 1.27)
				)
				(justify mirror)
			)
		)
		(duplicate_pad_numbers_are_jumpers no)
		(fp_line
			(start -0.7874 0.4064)
			(end 0.7874 0.4064)
			(stroke
				(width 0.1524)
				(type default)
			)
			(layer "B.SilkS")
		)
		(fp_line
			(start 0.7874 0.4064)
			(end 0.7874 -0.4064)
			(stroke
				(width 0.1524)
				(type default)
			)
			(layer "B.SilkS")
		)
		(fp_line
			(start -0.7874 -0.4064)
			(end -0.7874 0.4064)
			(stroke
				(width 0.1524)
				(type default)
			)
			(layer "B.SilkS")
		)
		(fp_line
			(start 0.7874 -0.4064)
			(end -0.7874 -0.4064)
			(stroke
				(width 0.1524)
				(type default)
			)
			(layer "B.SilkS")
		)
		(fp_line
			(start -0.67945 0.3048)
			(end -0.120396 0.3048)
			(stroke
				(width 0.1)
				(type default)
			)
			(layer "B.Fab")
		)
		(fp_line
			(start -0.120396 0.3048)
			(end -0.120396 0.2794)
			(stroke
				(width 0.1)
				(type default)
			)
			(layer "B.Fab")
		)
		(fp_line
			(start 0.12065 0.3048)
			(end 0.67945 0.3048)
			(stroke
				(width 0.1)
				(type default)
			)
			(layer "B.Fab")
		)
		(fp_line
			(start 0.67945 0.3048)
			(end 0.67945 -0.305054)
			(stroke
				(width 0.1)
				(type default)
			)
			(layer "B.Fab")
		)
		(fp_line
			(start -0.120396 0.2794)
			(end 0.12065 0.2794)
			(stroke
				(width 0.1)
				(type default)
			)
			(layer "B.Fab")
		)
		(fp_line
			(start 0.12065 0.2794)
			(end 0.12065 0.3048)
			(stroke
				(width 0.1)
				(type default)
			)
			(layer "B.Fab")
		)
		(fp_line
			(start -0.12065 -0.2794)
			(end -0.12065 -0.3048)
			(stroke
				(width 0.1)
				(type default)
			)
			(layer "B.Fab")
		)
		(fp_line
			(start 0.12065 -0.2794)
			(end -0.12065 -0.2794)
			(stroke
				(width 0.1)
				(type default)
			)
			(layer "B.Fab")
		)
		(fp_line
			(start -0.67945 -0.3048)
			(end -0.67945 0.3048)
			(stroke
				(width 0.1)
				(type default)
			)
			(layer "B.Fab")
		)
		(fp_line
			(start -0.12065 -0.3048)
			(end -0.67945 -0.3048)
			(stroke
				(width 0.1)
				(type default)
			)
			(layer "B.Fab")
		)
		(fp_line
			(start 0.12065 -0.305054)
			(end 0.12065 -0.2794)
			(stroke
				(width 0.1)
				(type default)
			)
			(layer "B.Fab")
		)
		(fp_line
			(start 0.67945 -0.305054)
			(end 0.12065 -0.305054)
			(stroke
				(width 0.1)
				(type default)
			)
			(layer "B.Fab")
		)
		(pad "1" smd circle
			(at 0.40005 0 90)
			(size 0 0)
			(layers "B.Cu" "B.Mask" "B.Paste")
			(net "P3V3_AUX")
		)
		(pad "2" smd circle
			(at -0.40005 0 90)
			(size 0 0)
			(layers "B.Cu" "B.Mask" "B.Paste")
			(net "SMB_BMC_MM10_SCL")
		)
	)
	(footprint ""
		(layer "B.Cu")
		(at 85.29955 -46.463204 180)
		(property "Reference" "R372"
			(at 0 0 0)
			(layer "B.SilkS")
			(hide yes)
			(effects
				(font
					(size 1.27 1.27)
				)
				(justify mirror)
			)
		)
		(property "Value" ""
			(at 0 0 0)
			(layer "B.Fab")
			(effects
				(font
					(size 1.27 1.27)
				)
				(justify mirror)
			)
		)
		(duplicate_pad_numbers_are_jumpers no)
		(fp_line
			(start 0.7874 0.4064)
			(end 0.7874 -0.4064)
			(stroke
				(width 0.1524)
				(type default)
			)
			(layer "B.SilkS")
		)
		(fp_line
			(start 0.7874 -0.4064)
			(end -0.7874 -0.4064)
			(stroke
				(width 0.1524)
				(type default)
			)
			(layer "B.SilkS")
		)
		(fp_line
			(start -0.7874 0.4064)
			(end 0.7874 0.4064)
			(stroke
				(width 0.1524)
				(type default)
			)
			(layer "B.SilkS")
		)
		(fp_line
			(start -0.7874 -0.4064)
			(end -0.7874 0.4064)
			(stroke
				(width 0.1524)
				(type default)
			)
			(layer "B.SilkS")
		)
		(fp_line
			(start 0.67945 0.3048)
			(end 0.67945 -0.305054)
			(stroke
				(width 0.1)
				(type default)
			)
			(layer "B.Fab")
		)
		(fp_line
			(start 0.67945 -0.305054)
			(end 0.12065 -0.305054)
			(stroke
				(width 0.1)
				(type default)
			)
			(layer "B.Fab")
		)
		(fp_line
			(start 0.12065 0.3048)
			(end 0.67945 0.3048)
			(stroke
				(width 0.1)
				(type default)
			)
			(layer "B.Fab")
		)
		(fp_line
			(start 0.12065 0.2794)
			(end 0.12065 0.3048)
			(stroke
				(width 0.1)
				(type default)
			)
			(layer "B.Fab")
		)
		(fp_line
			(start 0.12065 -0.2794)
			(end -0.12065 -0.2794)
			(stroke
				(width 0.1)
				(type default)
			)
			(layer "B.Fab")
		)
		(fp_line
			(start 0.12065 -0.305054)
			(end 0.12065 -0.2794)
			(stroke
				(width 0.1)
				(type default)
			)
			(layer "B.Fab")
		)
		(fp_line
			(start -0.120396 0.3048)
			(end -0.120396 0.2794)
			(stroke
				(width 0.1)
				(type default)
			)
			(layer "B.Fab")
		)
		(fp_line
			(start -0.120396 0.2794)
			(end 0.12065 0.2794)
			(stroke
				(width 0.1)
				(type default)
			)
			(layer "B.Fab")
		)
		(fp_line
			(start -0.12065 -0.2794)
			(end -0.12065 -0.3048)
			(stroke
				(width 0.1)
				(type default)
			)
			(layer "B.Fab")
		)
		(fp_line
			(start -0.12065 -0.3048)
			(end -0.67945 -0.3048)
			(stroke
				(width 0.1)
				(type default)
			)
			(layer "B.Fab")
		)
		(fp_line
			(start -0.67945 0.3048)
			(end -0.120396 0.3048)
			(stroke
				(width 0.1)
				(type default)
			)
			(layer "B.Fab")
		)
		(fp_line
			(start -0.67945 -0.3048)
			(end -0.67945 0.3048)
			(stroke
				(width 0.1)
				(type default)
			)
			(layer "B.Fab")
		)
		(pad "1" smd circle
			(at 0.40005 0)
			(size 0 0)
			(layers "B.Cu" "B.Mask" "B.Paste")
			(net "M_BMC_DDR4_MBA1")
		)
		(pad "2" smd circle
			(at -0.40005 0)
			(size 0 0)
			(layers "B.Cu" "B.Mask" "B.Paste")
			(net "P1V2_AUX")
		)
	)
	(footprint ""
		(layer "B.Cu")
		(at 41.91 -42.037 180)
		(property "Reference" "R689"
			(at 0 0 0)
			(layer "B.SilkS")
			(hide yes)
			(effects
				(font
					(size 1.27 1.27)
				)
				(justify mirror)
			)
		)
		(property "Value" ""
			(at 0 0 0)
			(layer "B.Fab")
			(effects
				(font
					(size 1.27 1.27)
				)
				(justify mirror)
			)
		)
		(duplicate_pad_numbers_are_jumpers no)
		(fp_line
			(start 0.7874 0.4064)
			(end 0.7874 -0.4064)
			(stroke
				(width 0.1524)
				(type default)
			)
			(layer "B.SilkS")
		)
		(fp_line
			(start 0.7874 -0.4064)
			(end -0.7874 -0.4064)
			(stroke
				(width 0.1524)
				(type default)
			)
			(layer "B.SilkS")
		)
		(fp_line
			(start -0.7874 0.4064)
			(end 0.7874 0.4064)
			(stroke
				(width 0.1524)
				(type default)
			)
			(layer "B.SilkS")
		)
		(fp_line
			(start -0.7874 -0.4064)
			(end -0.7874 0.4064)
			(stroke
				(width 0.1524)
				(type default)
			)
			(layer "B.SilkS")
		)
		(fp_line
			(start 0.67945 0.3048)
			(end 0.67945 -0.305054)
			(stroke
				(width 0.1)
				(type default)
			)
			(layer "B.Fab")
		)
		(fp_line
			(start 0.67945 -0.305054)
			(end 0.12065 -0.305054)
			(stroke
				(width 0.1)
				(type default)
			)
			(layer "B.Fab")
		)
		(fp_line
			(start 0.12065 0.3048)
			(end 0.67945 0.3048)
			(stroke
				(width 0.1)
				(type default)
			)
			(layer "B.Fab")
		)
		(fp_line
			(start 0.12065 0.2794)
			(end 0.12065 0.3048)
			(stroke
				(width 0.1)
				(type default)
			)
			(layer "B.Fab")
		)
		(fp_line
			(start 0.12065 -0.2794)
			(end -0.12065 -0.2794)
			(stroke
				(width 0.1)
				(type default)
			)
			(layer "B.Fab")
		)
		(fp_line
			(start 0.12065 -0.305054)
			(end 0.12065 -0.2794)
			(stroke
				(width 0.1)
				(type default)
			)
			(layer "B.Fab")
		)
		(fp_line
			(start -0.120396 0.3048)
			(end -0.120396 0.2794)
			(stroke
				(width 0.1)
				(type default)
			)
			(layer "B.Fab")
		)
		(fp_line
			(start -0.120396 0.2794)
			(end 0.12065 0.2794)
			(stroke
				(width 0.1)
				(type default)
			)
			(layer "B.Fab")
		)
		(fp_line
			(start -0.12065 -0.2794)
			(end -0.12065 -0.3048)
			(stroke
				(width 0.1)
				(type default)
			)
			(layer "B.Fab")
		)
		(fp_line
			(start -0.12065 -0.3048)
			(end -0.67945 -0.3048)
			(stroke
				(width 0.1)
				(type default)
			)
			(layer "B.Fab")
		)
		(fp_line
			(start -0.67945 0.3048)
			(end -0.120396 0.3048)
			(stroke
				(width 0.1)
				(type default)
			)
			(layer "B.Fab")
		)
		(fp_line
			(start -0.67945 -0.3048)
			(end -0.67945 0.3048)
			(stroke
				(width 0.1)
				(type default)
			)
			(layer "B.Fab")
		)
		(pad "1" smd circle
			(at 0.40005 0)
			(size 0 0)
			(layers "B.Cu" "B.Mask" "B.Paste")
			(net "IRQ_SGPIO_N")
		)
		(pad "2" smd circle
			(at -0.40005 0)
			(size 0 0)
			(layers "B.Cu" "B.Mask" "B.Paste")
			(net "IRQ_SGPIO_BMC_N")
		)
	)
	(footprint ""
		(layer "B.Cu")
		(at 68.6308 -93.7514 90)
		(property "Reference" "R645"
			(at 0 0 90)
			(layer "B.SilkS")
			(hide yes)
			(effects
				(font
					(size 1.27 1.27)
				)
				(justify mirror)
			)
		)
		(property "Value" ""
			(at 0 0 90)
			(layer "B.Fab")
			(effects
				(font
					(size 1.27 1.27)
				)
				(justify mirror)
			)
		)
		(duplicate_pad_numbers_are_jumpers no)
		(fp_line
			(start 1.2954 -0.5842)
			(end -1.2954 -0.5842)
			(stroke
				(width 0.1524)
				(type default)
			)
			(layer "B.SilkS")
		)
		(fp_line
			(start -1.2954 -0.5842)
			(end -1.2954 0.5842)
			(stroke
				(width 0.1524)
				(type default)
			)
			(layer "B.SilkS")
		)
		(fp_line
			(start 1.2954 0.5842)
			(end 1.2954 -0.5842)
			(stroke
				(width 0.1524)
				(type default)
			)
			(layer "B.SilkS")
		)
		(fp_line
			(start -1.2954 0.5842)
			(end 1.2954 0.5842)
			(stroke
				(width 0.1524)
				(type default)
			)
			(layer "B.SilkS")
		)
		(fp_line
			(start 0.8636 -0.4572)
			(end -0.8636 -0.4572)
			(stroke
				(width 0.1)
				(type default)
			)
			(layer "B.Fab")
		)
		(fp_line
			(start -0.8636 -0.4572)
			(end -0.8636 -0.406654)
			(stroke
				(width 0.1)
				(type default)
			)
			(layer "B.Fab")
		)
		(fp_line
			(start 1.1938 -0.406654)
			(end 0.8636 -0.406654)
			(stroke
				(width 0.1)
				(type default)
			)
			(layer "B.Fab")
		)
		(fp_line
			(start 0.8636 -0.406654)
			(end 0.8636 -0.4572)
			(stroke
				(width 0.1)
				(type default)
			)
			(layer "B.Fab")
		)
		(fp_line
			(start -0.8636 -0.406654)
			(end -1.1938 -0.406654)
			(stroke
				(width 0.1)
				(type default)
			)
			(layer "B.Fab")
		)
		(fp_line
			(start -1.1938 -0.406654)
			(end -1.1938 0.4064)
			(stroke
				(width 0.1)
				(type default)
			)
			(layer "B.Fab")
		)
		(fp_line
			(start 1.1938 0.4064)
			(end 1.1938 -0.406654)
			(stroke
				(width 0.1)
				(type default)
			)
			(layer "B.Fab")
		)
		(fp_line
			(start 0.8636 0.4064)
			(end 1.1938 0.4064)
			(stroke
				(width 0.1)
				(type default)
			)
			(layer "B.Fab")
		)
		(fp_line
			(start -0.8636 0.4064)
			(end -0.8636 0.4572)
			(stroke
				(width 0.1)
				(type default)
			)
			(layer "B.Fab")
		)
		(fp_line
			(start -1.1938 0.4064)
			(end -0.8636 0.4064)
			(stroke
				(width 0.1)
				(type default)
			)
			(layer "B.Fab")
		)
		(fp_line
			(start 0.8636 0.4318)
			(end 0.8636 0.4064)
			(stroke
				(width 0.1)
				(type default)
			)
			(layer "B.Fab")
		)
		(fp_line
			(start 0.8636 0.4572)
			(end 0.8636 0.4318)
			(stroke
				(width 0.1)
				(type default)
			)
			(layer "B.Fab")
		)
		(fp_line
			(start -0.8636 0.4572)
			(end 0.8636 0.4572)
			(stroke
				(width 0.1)
				(type default)
			)
			(layer "B.Fab")
		)
		(pad "1" smd rect
			(at 0.7366 0)
			(size 0.7112 0.8128)
			(layers "B.Cu" "B.Mask" "B.Paste")
			(net "P1V8_AUX")
		)
		(pad "2" smd rect
			(at -0.7366 0)
			(size 0.7112 0.8128)
			(layers "B.Cu" "B.Mask" "B.Paste")
			(net "PGPPA_BMC_AUX_L")
		)
	)
	(footprint ""
		(layer "B.Cu")
		(at 114.554 34.6964 -90)
		(property "Reference" "X20"
			(at 2.04597 1.2065 0)
			(unlocked yes)
			(layer "B.SilkS")
			(effects
				(font
					(size 0.7874 0.5842)
					(thickness 0.1524)
				)
				(justify left mirror)
			)
		)
		(property "Value" ""
			(at 0 0 90)
			(layer "B.Fab")
			(effects
				(font
					(size 1.27 1.27)
				)
				(justify mirror)
			)
		)
		(property "Device Type" "TP_TDR_4P_FTS_TH-TP_TDR_4P_DIPA"
			(at -1.30175 1.27 180)
			(unlocked yes)
			(layer "B.Fab")
			(hide yes)
			(effects
				(font
					(size 0.635 0.4064)
					(thickness 0.1524)
				)
				(justify mirror)
			)
		)
		(property "User Part Number" "N_A"
			(at -1.30175 1.27 180)
			(unlocked yes)
			(layer "Cmts.User")
			(hide yes)
			(effects
				(font
					(size 0.635 0.4064)
					(thickness 0.1524)
				)
				(justify mirror)
			)
		)
		(duplicate_pad_numbers_are_jumpers no)
		(fp_line
			(start -2.54 3.81)
			(end -2.54 3.6703)
			(stroke
				(width 0.1524)
				(type default)
			)
			(layer "B.SilkS")
		)
		(fp_line
			(start 0 3.81)
			(end -2.54 3.81)
			(stroke
				(width 0.1524)
				(type default)
			)
			(layer "B.SilkS")
		)
		(fp_line
			(start 0 3.175)
			(end 0 3.81)
			(stroke
				(width 0.1524)
				(type default)
			)
			(layer "B.SilkS")
		)
		(fp_line
			(start -2.54 1.4097)
			(end -2.54 1.1303)
			(stroke
				(width 0.1524)
				(type default)
			)
			(layer "B.SilkS")
		)
		(fp_line
			(start 0 0.635)
			(end 0 1.905)
			(stroke
				(width 0.1524)
				(type default)
			)
			(layer "B.SilkS")
		)
		(fp_line
			(start -2.54 -1.1303)
			(end -2.54 -1.27)
			(stroke
				(width 0.1524)
				(type default)
			)
			(layer "B.SilkS")
		)
		(fp_line
			(start -2.54 -1.27)
			(end 0 -1.27)
			(stroke
				(width 0.1524)
				(type default)
			)
			(layer "B.SilkS")
		)
		(fp_line
			(start 0 -1.27)
			(end 0 -0.635)
			(stroke
				(width 0.1524)
				(type default)
			)
			(layer "B.SilkS")
		)
		(fp_poly
			(pts
				(xy 0.761746 0) (xy 2.285746 -0.762) (xy 2.285746 0.762)
			)
			(stroke
				(width 0)
				(type default)
			)
			(fill yes)
			(layer "B.SilkS")
		)
		(fp_line
			(start -2.54 3.81)
			(end -2.54 -1.27)
			(stroke
				(width 0.1)
				(type default)
			)
			(layer "B.Fab")
		)
		(fp_line
			(start 0 3.81)
			(end -2.54 3.81)
			(stroke
				(width 0.1)
				(type default)
			)
			(layer "B.Fab")
		)
		(fp_line
			(start -2.54 -1.27)
			(end 0 -1.27)
			(stroke
				(width 0.1)
				(type default)
			)
			(layer "B.Fab")
		)
		(fp_line
			(start 0 -1.27)
			(end 0 3.81)
			(stroke
				(width 0.1)
				(type default)
			)
			(layer "B.Fab")
		)
		(fp_poly
			(pts
				(xy 0.761746 0) (xy 2.285746 -0.762) (xy 2.285746 0.762)
			)
			(stroke
				(width 0)
				(type default)
			)
			(fill yes)
			(layer "B.Fab")
		)
		(pad "1" thru_hole circle
			(at 0 0 90)
			(size 1.0033 1.0033)
			(drill 0.249936)
			(layers "*.Cu" "*.Mask")
			(remove_unused_layers no)
			(net "TDR_DIFF_100_IN1_DN")
			(clearance 0.10795)
			(padstack
				(mode front_inner_back)
				(layer "Inner"
					(shape circle)
					(size 0.8001 0.8001)
					(clearance 0.1524)
				)
				(layer "B.Cu"
					(shape circle)
					(size 1.0033 1.0033)
					(thermal_gap 0.10795)
					(clearance 0.10795)
				)
			)
		)
		(pad "2" thru_hole circle
			(at -2.54 0 90)
			(size 1.9939 1.9939)
			(drill 0.249936)
			(layers "*.Cu" "*.Mask")
			(remove_unused_layers no)
			(net "GND_P1")
			(clearance 0.10795)
			(padstack
				(mode front_inner_back)
				(layer "Inner"
					(shape circle)
					(size 0.8001 0.8001)
					(clearance 0.1524)
				)
				(layer "B.Cu"
					(shape circle)
					(size 1.9939 1.9939)
					(thermal_gap 0.10795)
					(clearance 0.10795)
				)
			)
		)
		(pad "3" thru_hole circle
			(at -2.54 2.54 90)
			(size 1.9939 1.9939)
			(drill 0.249936)
			(layers "*.Cu" "*.Mask")
			(remove_unused_layers no)
			(net "GND_P1")
			(clearance 0.10795)
			(padstack
				(mode front_inner_back)
				(layer "Inner"
					(shape circle)
					(size 0.8001 0.8001)
					(clearance 0.1524)
				)
				(layer "B.Cu"
					(shape circle)
					(size 1.9939 1.9939)
					(thermal_gap 0.10795)
					(clearance 0.10795)
				)
			)
		)
		(pad "4" thru_hole circle
			(at 0 2.54 90)
			(size 1.0033 1.0033)
			(drill 0.249936)
			(layers "*.Cu" "*.Mask")
			(remove_unused_layers no)
			(net "TDR_DIFF_100_IN1_DP")
			(clearance 0.10795)
			(padstack
				(mode front_inner_back)
				(layer "Inner"
					(shape circle)
					(size 0.8001 0.8001)
					(clearance 0.1524)
				)
				(layer "B.Cu"
					(shape circle)
					(size 1.0033 1.0033)
					(thermal_gap 0.10795)
					(clearance 0.10795)
				)
			)
		)
	)
	(footprint ""
		(layer "B.Cu")
		(at 22.65934 -91.187016 90)
		(property "Reference" "C166"
			(at 0 0 90)
			(layer "B.SilkS")
			(hide yes)
			(effects
				(font
					(size 1.27 1.27)
				)
				(justify mirror)
			)
		)
		(property "Value" ""
			(at 0 0 90)
			(layer "B.Fab")
			(effects
				(font
					(size 1.27 1.27)
				)
				(justify mirror)
			)
		)
		(duplicate_pad_numbers_are_jumpers no)
		(fp_line
			(start 0.69215 -0.2921)
			(end -0.69215 -0.2921)
			(stroke
				(width 0.1524)
				(type default)
			)
			(layer "B.SilkS")
		)
		(fp_line
			(start -0.69215 -0.2921)
			(end -0.69215 0.2921)
			(stroke
				(width 0.1524)
				(type default)
			)
			(layer "B.SilkS")
		)
		(fp_line
			(start 0.69215 0.2921)
			(end 0.69215 -0.2921)
			(stroke
				(width 0.1524)
				(type default)
			)
			(layer "B.SilkS")
		)
		(fp_line
			(start -0.69215 0.2921)
			(end 0.69215 0.2921)
			(stroke
				(width 0.1524)
				(type default)
			)
			(layer "B.SilkS")
		)
		(fp_line
			(start 0.51435 -0.2794)
			(end -0.51435 -0.2794)
			(stroke
				(width 0.1)
				(type default)
			)
			(layer "B.Fab")
		)
		(fp_line
			(start -0.51435 -0.2794)
			(end -0.51435 0.2794)
			(stroke
				(width 0.1)
				(type default)
			)
			(layer "B.Fab")
		)
		(fp_line
			(start 0.51435 0.2794)
			(end 0.51435 -0.2794)
			(stroke
				(width 0.1)
				(type default)
			)
			(layer "B.Fab")
		)
		(fp_line
			(start -0.51435 0.2794)
			(end 0.51435 0.2794)
			(stroke
				(width 0.1)
				(type default)
			)
			(layer "B.Fab")
		)
		(pad "1" smd circle
			(at 0.40005 0 270)
			(size 0 0)
			(layers "B.Cu" "B.Mask" "B.Paste")
			(net "VCCIO0")
		)
		(pad "2" smd circle
			(at -0.40005 0 270)
			(size 0 0)
			(layers "B.Cu" "B.Mask" "B.Paste")
			(net "GND")
		)
		(zone
			(layer "B.Cu")
			(hatch none 0.5)
			(connect_pads
				(clearance 0)
			)
			(min_thickness 0.25)
			(keepout
				(tracks not_allowed)
				(vias allowed)
				(pads allowed)
				(copperpour not_allowed)
				(footprints allowed)
			)
			(placement
				(enabled no)
				(sheetname "")
			)
			(fill
				(thermal_gap 0.5)
				(thermal_bridge_width 0.5)
				(island_removal_mode 0)
			)
			(polygon
				(pts
					(xy 22.74697 -91.377516) (xy 22.805136 -91.286076) (xy 22.805136 -91.086686) (xy 22.74697 -90.996516)
					(xy 22.57171 -90.996516) (xy 22.51329 -91.086686) (xy 22.51329 -91.286076) (xy 22.571456 -91.377516)
				)
			)
		)
	)
	(footprint ""
		(layer "B.Cu")
		(at 27.682444 -99.448112 45)
		(property "Reference" "C266"
			(at 0 0 45)
			(layer "B.SilkS")
			(hide yes)
			(effects
				(font
					(size 1.27 1.27)
				)
				(justify mirror)
			)
		)
		(property "Value" ""
			(at 0 0 45)
			(layer "B.Fab")
			(effects
				(font
					(size 1.27 1.27)
				)
				(justify mirror)
			)
		)
		(duplicate_pad_numbers_are_jumpers no)
		(fp_line
			(start -0.787389 -0.406267)
			(end -0.787389 0.406267)
			(stroke
				(width 0.1524)
				(type default)
			)
			(layer "B.SilkS")
		)
		(fp_line
			(start -0.787389 0.406267)
			(end 0.787389 0.406267)
			(stroke
				(width 0.1524)
				(type default)
			)
			(layer "B.SilkS")
		)
		(fp_line
			(start 0.787389 -0.406267)
			(end -0.787389 -0.406267)
			(stroke
				(width 0.1524)
				(type default)
			)
			(layer "B.SilkS")
		)
		(fp_line
			(start 0.787389 0.406267)
			(end 0.787389 -0.406267)
			(stroke
				(width 0.1524)
				(type default)
			)
			(layer "B.SilkS")
		)
		(fp_line
			(start -0.679446 -0.30479)
			(end -0.679446 0.30479)
			(stroke
				(width 0.1)
				(type default)
			)
			(layer "B.Fab")
		)
		(fp_line
			(start -0.120515 -0.30479)
			(end -0.679446 -0.30479)
			(stroke
				(width 0.1)
				(type default)
			)
			(layer "B.Fab")
		)
		(fp_line
			(start -0.120695 -0.279466)
			(end -0.120515 -0.30479)
			(stroke
				(width 0.1)
				(type default)
			)
			(layer "B.Fab")
		)
		(fp_line
			(start -0.679446 0.30479)
			(end -0.120515 0.30479)
			(stroke
				(width 0.1)
				(type default)
			)
			(layer "B.Fab")
		)
		(fp_line
			(start 0.120695 -0.304969)
			(end 0.120695 -0.279466)
			(stroke
				(width 0.1)
				(type default)
			)
			(layer "B.Fab")
		)
		(fp_line
			(start 0.120695 -0.279466)
			(end -0.120695 -0.279466)
			(stroke
				(width 0.1)
				(type default)
			)
			(layer "B.Fab")
		)
		(fp_line
			(start -0.120335 0.279466)
			(end 0.120695 0.279466)
			(stroke
				(width 0.1)
				(type default)
			)
			(layer "B.Fab")
		)
		(fp_line
			(start -0.120515 0.30479)
			(end -0.120335 0.279466)
			(stroke
				(width 0.1)
				(type default)
			)
			(layer "B.Fab")
		)
		(fp_line
			(start 0.679446 -0.305149)
			(end 0.120695 -0.304969)
			(stroke
				(width 0.1)
				(type default)
			)
			(layer "B.Fab")
		)
		(fp_line
			(start 0.120695 0.279466)
			(end 0.120515 0.30479)
			(stroke
				(width 0.1)
				(type default)
			)
			(layer "B.Fab")
		)
		(fp_line
			(start 0.120515 0.30479)
			(end 0.679446 0.30479)
			(stroke
				(width 0.1)
				(type default)
			)
			(layer "B.Fab")
		)
		(fp_line
			(start 0.679446 0.30479)
			(end 0.679446 -0.305149)
			(stroke
				(width 0.1)
				(type default)
			)
			(layer "B.Fab")
		)
		(pad "1" smd circle
			(at 0.40005 0 225)
			(size 0 0)
			(layers "B.Cu" "B.Mask" "B.Paste")
			(net "PVCCA_AUX_PLD")
		)
		(pad "2" smd circle
			(at -0.40005 0 225)
			(size 0 0)
			(layers "B.Cu" "B.Mask" "B.Paste")
			(net "GND")
		)
	)
	(footprint ""
		(layer "B.Cu")
		(at 24.384 -93.345 180)
		(property "Reference" "C220"
			(at 0 0 0)
			(layer "B.SilkS")
			(hide yes)
			(effects
				(font
					(size 1.27 1.27)
				)
				(justify mirror)
			)
		)
		(property "Value" ""
			(at 0 0 0)
			(layer "B.Fab")
			(effects
				(font
					(size 1.27 1.27)
				)
				(justify mirror)
			)
		)
		(duplicate_pad_numbers_are_jumpers no)
		(fp_line
			(start 0.69215 0.2921)
			(end 0.69215 -0.2921)
			(stroke
				(width 0.1524)
				(type default)
			)
			(layer "B.SilkS")
		)
		(fp_line
			(start 0.69215 -0.2921)
			(end -0.69215 -0.2921)
			(stroke
				(width 0.1524)
				(type default)
			)
			(layer "B.SilkS")
		)
		(fp_line
			(start -0.69215 0.2921)
			(end 0.69215 0.2921)
			(stroke
				(width 0.1524)
				(type default)
			)
			(layer "B.SilkS")
		)
		(fp_line
			(start -0.69215 -0.2921)
			(end -0.69215 0.2921)
			(stroke
				(width 0.1524)
				(type default)
			)
			(layer "B.SilkS")
		)
		(fp_line
			(start 0.51435 0.2794)
			(end 0.51435 -0.2794)
			(stroke
				(width 0.1)
				(type default)
			)
			(layer "B.Fab")
		)
		(fp_line
			(start 0.51435 -0.2794)
			(end -0.51435 -0.2794)
			(stroke
				(width 0.1)
				(type default)
			)
			(layer "B.Fab")
		)
		(fp_line
			(start -0.51435 0.2794)
			(end 0.51435 0.2794)
			(stroke
				(width 0.1)
				(type default)
			)
			(layer "B.Fab")
		)
		(fp_line
			(start -0.51435 -0.2794)
			(end -0.51435 0.2794)
			(stroke
				(width 0.1)
				(type default)
			)
			(layer "B.Fab")
		)
		(pad "1" smd circle
			(at 0.40005 0)
			(size 0 0)
			(layers "B.Cu" "B.Mask" "B.Paste")
			(net "VCCIO4")
		)
		(pad "2" smd circle
			(at -0.40005 0)
			(size 0 0)
			(layers "B.Cu" "B.Mask" "B.Paste")
			(net "GND")
		)
		(zone
			(layer "B.Cu")
			(hatch none 0.5)
			(connect_pads
				(clearance 0)
			)
			(min_thickness 0.25)
			(keepout
				(tracks not_allowed)
				(vias allowed)
				(pads allowed)
				(copperpour not_allowed)
				(footprints allowed)
			)
			(placement
				(enabled no)
				(sheetname "")
			)
			(fill
				(thermal_gap 0.5)
				(thermal_bridge_width 0.5)
				(island_removal_mode 0)
			)
			(polygon
				(pts
					(xy 24.1935 -93.43263) (xy 24.28494 -93.490796) (xy 24.48433 -93.490796) (xy 24.5745 -93.43263)
					(xy 24.5745 -93.25737) (xy 24.48433 -93.19895) (xy 24.28494 -93.19895) (xy 24.1935 -93.257116)
				)
			)
		)
	)
	(footprint ""
		(layer "B.Cu")
		(at 12.192 -24.384 -90)
		(property "Reference" "R306"
			(at 0 0 90)
			(layer "B.SilkS")
			(hide yes)
			(effects
				(font
					(size 1.27 1.27)
				)
				(justify mirror)
			)
		)
		(property "Value" ""
			(at 0 0 90)
			(layer "B.Fab")
			(effects
				(font
					(size 1.27 1.27)
				)
				(justify mirror)
			)
		)
		(duplicate_pad_numbers_are_jumpers no)
		(fp_line
			(start -0.7874 0.4064)
			(end 0.7874 0.4064)
			(stroke
				(width 0.1524)
				(type default)
			)
			(layer "B.SilkS")
		)
		(fp_line
			(start 0.7874 0.4064)
			(end 0.7874 -0.4064)
			(stroke
				(width 0.1524)
				(type default)
			)
			(layer "B.SilkS")
		)
		(fp_line
			(start -0.7874 -0.4064)
			(end -0.7874 0.4064)
			(stroke
				(width 0.1524)
				(type default)
			)
			(layer "B.SilkS")
		)
		(fp_line
			(start 0.7874 -0.4064)
			(end -0.7874 -0.4064)
			(stroke
				(width 0.1524)
				(type default)
			)
			(layer "B.SilkS")
		)
		(fp_line
			(start -0.67945 0.3048)
			(end -0.120396 0.3048)
			(stroke
				(width 0.1)
				(type default)
			)
			(layer "B.Fab")
		)
		(fp_line
			(start -0.120396 0.3048)
			(end -0.120396 0.2794)
			(stroke
				(width 0.1)
				(type default)
			)
			(layer "B.Fab")
		)
		(fp_line
			(start 0.12065 0.3048)
			(end 0.67945 0.3048)
			(stroke
				(width 0.1)
				(type default)
			)
			(layer "B.Fab")
		)
		(fp_line
			(start 0.67945 0.3048)
			(end 0.67945 -0.305054)
			(stroke
				(width 0.1)
				(type default)
			)
			(layer "B.Fab")
		)
		(fp_line
			(start -0.120396 0.2794)
			(end 0.12065 0.2794)
			(stroke
				(width 0.1)
				(type default)
			)
			(layer "B.Fab")
		)
		(fp_line
			(start 0.12065 0.2794)
			(end 0.12065 0.3048)
			(stroke
				(width 0.1)
				(type default)
			)
			(layer "B.Fab")
		)
		(fp_line
			(start -0.12065 -0.2794)
			(end -0.12065 -0.3048)
			(stroke
				(width 0.1)
				(type default)
			)
			(layer "B.Fab")
		)
		(fp_line
			(start 0.12065 -0.2794)
			(end -0.12065 -0.2794)
			(stroke
				(width 0.1)
				(type default)
			)
			(layer "B.Fab")
		)
		(fp_line
			(start -0.67945 -0.3048)
			(end -0.67945 0.3048)
			(stroke
				(width 0.1)
				(type default)
			)
			(layer "B.Fab")
		)
		(fp_line
			(start -0.12065 -0.3048)
			(end -0.67945 -0.3048)
			(stroke
				(width 0.1)
				(type default)
			)
			(layer "B.Fab")
		)
		(fp_line
			(start 0.12065 -0.305054)
			(end 0.12065 -0.2794)
			(stroke
				(width 0.1)
				(type default)
			)
			(layer "B.Fab")
		)
		(fp_line
			(start 0.67945 -0.305054)
			(end 0.12065 -0.305054)
			(stroke
				(width 0.1)
				(type default)
			)
			(layer "B.Fab")
		)
		(pad "1" smd circle
			(at 0.40005 0 90)
			(size 0 0)
			(layers "B.Cu" "B.Mask" "B.Paste")
			(net "BEEP_LED")
		)
		(pad "2" smd circle
			(at -0.40005 0 90)
			(size 0 0)
			(layers "B.Cu" "B.Mask" "B.Paste")
			(net "GND")
		)
	)
	(footprint ""
		(layer "B.Cu")
		(at 58.092848 -49.54778 -90)
		(property "Reference" "C93"
			(at 0 0 90)
			(layer "B.SilkS")
			(hide yes)
			(effects
				(font
					(size 1.27 1.27)
				)
				(justify mirror)
			)
		)
		(property "Value" ""
			(at 0 0 90)
			(layer "B.Fab")
			(effects
				(font
					(size 1.27 1.27)
				)
				(justify mirror)
			)
		)
		(duplicate_pad_numbers_are_jumpers no)
		(fp_line
			(start -0.7874 0.4064)
			(end 0.7874 0.4064)
			(stroke
				(width 0.1524)
				(type default)
			)
			(layer "B.SilkS")
		)
		(fp_line
			(start 0.7874 0.4064)
			(end 0.7874 -0.4064)
			(stroke
				(width 0.1524)
				(type default)
			)
			(layer "B.SilkS")
		)
		(fp_line
			(start -0.7874 -0.4064)
			(end -0.7874 0.4064)
			(stroke
				(width 0.1524)
				(type default)
			)
			(layer "B.SilkS")
		)
		(fp_line
			(start 0.7874 -0.4064)
			(end -0.7874 -0.4064)
			(stroke
				(width 0.1524)
				(type default)
			)
			(layer "B.SilkS")
		)
		(fp_line
			(start -0.67945 0.3048)
			(end -0.120396 0.3048)
			(stroke
				(width 0.1)
				(type default)
			)
			(layer "B.Fab")
		)
		(fp_line
			(start -0.120396 0.3048)
			(end -0.120396 0.2794)
			(stroke
				(width 0.1)
				(type default)
			)
			(layer "B.Fab")
		)
		(fp_line
			(start 0.12065 0.3048)
			(end 0.67945 0.3048)
			(stroke
				(width 0.1)
				(type default)
			)
			(layer "B.Fab")
		)
		(fp_line
			(start 0.67945 0.3048)
			(end 0.67945 -0.305054)
			(stroke
				(width 0.1)
				(type default)
			)
			(layer "B.Fab")
		)
		(fp_line
			(start -0.120396 0.2794)
			(end 0.12065 0.2794)
			(stroke
				(width 0.1)
				(type default)
			)
			(layer "B.Fab")
		)
		(fp_line
			(start 0.12065 0.2794)
			(end 0.12065 0.3048)
			(stroke
				(width 0.1)
				(type default)
			)
			(layer "B.Fab")
		)
		(fp_line
			(start -0.12065 -0.2794)
			(end -0.12065 -0.3048)
			(stroke
				(width 0.1)
				(type default)
			)
			(layer "B.Fab")
		)
		(fp_line
			(start 0.12065 -0.2794)
			(end -0.12065 -0.2794)
			(stroke
				(width 0.1)
				(type default)
			)
			(layer "B.Fab")
		)
		(fp_line
			(start -0.67945 -0.3048)
			(end -0.67945 0.3048)
			(stroke
				(width 0.1)
				(type default)
			)
			(layer "B.Fab")
		)
		(fp_line
			(start -0.12065 -0.3048)
			(end -0.67945 -0.3048)
			(stroke
				(width 0.1)
				(type default)
			)
			(layer "B.Fab")
		)
		(fp_line
			(start 0.12065 -0.305054)
			(end 0.12065 -0.2794)
			(stroke
				(width 0.1)
				(type default)
			)
			(layer "B.Fab")
		)
		(fp_line
			(start 0.67945 -0.305054)
			(end 0.12065 -0.305054)
			(stroke
				(width 0.1)
				(type default)
			)
			(layer "B.Fab")
		)
		(pad "1" smd circle
			(at 0.40005 0 90)
			(size 0 0)
			(layers "B.Cu" "B.Mask" "B.Paste")
			(net "P1V8_AUX")
		)
		(pad "2" smd circle
			(at -0.40005 0 90)
			(size 0 0)
			(layers "B.Cu" "B.Mask" "B.Paste")
			(net "GND")
		)
	)
	(footprint ""
		(layer "B.Cu")
		(at 43.5356 -4.1148 -90)
		(property "Reference" "U26"
			(at -2.047748 -2.3876 0)
			(unlocked yes)
			(layer "B.SilkS")
			(effects
				(font
					(size 0.7874 0.5842)
					(thickness 0.1524)
				)
				(justify left mirror)
			)
		)
		(property "Value" ""
			(at 0 0 90)
			(layer "B.Fab")
			(effects
				(font
					(size 1.27 1.27)
				)
				(justify mirror)
			)
		)
		(duplicate_pad_numbers_are_jumpers no)
		(fp_line
			(start -1.3462 1.1938)
			(end -1.3462 -1.1938)
			(stroke
				(width 0.1524)
				(type default)
			)
			(layer "B.SilkS")
		)
		(fp_line
			(start 1.3462 1.1938)
			(end -1.3462 1.1938)
			(stroke
				(width 0.1524)
				(type default)
			)
			(layer "B.SilkS")
		)
		(fp_line
			(start -1.3462 -1.1938)
			(end 1.3462 -1.1938)
			(stroke
				(width 0.1524)
				(type default)
			)
			(layer "B.SilkS")
		)
		(fp_line
			(start 1.3462 -1.1938)
			(end 1.3462 1.1684)
			(stroke
				(width 0.1524)
				(type default)
			)
			(layer "B.SilkS")
		)
		(fp_poly
			(pts
				(xy 1.447038 -0.760476) (xy 2.052066 -0.457962) (xy 2.052066 -1.06299)
			)
			(stroke
				(width 0)
				(type default)
			)
			(fill yes)
			(layer "B.SilkS")
		)
		(fp_line
			(start -0.674878 1.124966)
			(end -0.674878 -1.124966)
			(stroke
				(width 0.1)
				(type default)
			)
			(layer "B.Fab")
		)
		(fp_line
			(start 0.674878 1.124966)
			(end -0.674878 1.124966)
			(stroke
				(width 0.1)
				(type default)
			)
			(layer "B.Fab")
		)
		(fp_line
			(start -0.674878 -1.124966)
			(end 0.674878 -1.124966)
			(stroke
				(width 0.1)
				(type default)
			)
			(layer "B.Fab")
		)
		(fp_line
			(start 0.674878 -1.124966)
			(end 0.674878 1.124966)
			(stroke
				(width 0.1)
				(type default)
			)
			(layer "B.Fab")
		)
		(fp_poly
			(pts
				(xy 1.447038 -0.760476) (xy 2.052066 -0.457962) (xy 2.052066 -1.06299)
			)
			(stroke
				(width 0)
				(type default)
			)
			(fill yes)
			(layer "B.Fab")
		)
		(pad "1" smd rect
			(at 0.899922 -0.750062 90)
			(size 0.6096 0.6096)
			(layers "B.Cu" "B.Mask" "B.Paste")
			(net "BMC_DDC_BUF_EN")
		)
		(pad "2" smd rect
			(at 0.899922 0)
			(size 0.4064 0.6096)
			(layers "B.Cu" "B.Mask" "B.Paste")
			(net "V_VGAVS")
		)
		(pad "3" smd rect
			(at 0.899922 0.750062 90)
			(size 0.6096 0.6096)
			(layers "B.Cu" "B.Mask" "B.Paste")
			(net "GND")
		)
		(pad "4" smd rect
			(at -0.899922 0.750062 90)
			(size 0.6096 0.6096)
			(layers "B.Cu" "B.Mask" "B.Paste")
			(net "V_VGAVS_BUF_R")
		)
		(pad "5" smd rect
			(at -0.899922 -0.750062 90)
			(size 0.6096 0.6096)
			(layers "B.Cu" "B.Mask" "B.Paste")
			(net "BMC_DDC_BUF_PWR")
		)
	)
	(footprint ""
		(layer "B.Cu")
		(at 50.508662 -46.220126 180)
		(property "Reference" "C32"
			(at 0 0 0)
			(layer "B.SilkS")
			(hide yes)
			(effects
				(font
					(size 1.27 1.27)
				)
				(justify mirror)
			)
		)
		(property "Value" ""
			(at 0 0 0)
			(layer "B.Fab")
			(effects
				(font
					(size 1.27 1.27)
				)
				(justify mirror)
			)
		)
		(duplicate_pad_numbers_are_jumpers no)
		(fp_line
			(start 0.7874 0.4064)
			(end 0.7874 -0.4064)
			(stroke
				(width 0.1524)
				(type default)
			)
			(layer "B.SilkS")
		)
		(fp_line
			(start 0.7874 -0.4064)
			(end -0.7874 -0.4064)
			(stroke
				(width 0.1524)
				(type default)
			)
			(layer "B.SilkS")
		)
		(fp_line
			(start -0.7874 0.4064)
			(end 0.7874 0.4064)
			(stroke
				(width 0.1524)
				(type default)
			)
			(layer "B.SilkS")
		)
		(fp_line
			(start -0.7874 -0.4064)
			(end -0.7874 0.4064)
			(stroke
				(width 0.1524)
				(type default)
			)
			(layer "B.SilkS")
		)
		(fp_line
			(start 0.67945 0.3048)
			(end 0.67945 -0.305054)
			(stroke
				(width 0.1)
				(type default)
			)
			(layer "B.Fab")
		)
		(fp_line
			(start 0.67945 -0.305054)
			(end 0.12065 -0.305054)
			(stroke
				(width 0.1)
				(type default)
			)
			(layer "B.Fab")
		)
		(fp_line
			(start 0.12065 0.3048)
			(end 0.67945 0.3048)
			(stroke
				(width 0.1)
				(type default)
			)
			(layer "B.Fab")
		)
		(fp_line
			(start 0.12065 0.2794)
			(end 0.12065 0.3048)
			(stroke
				(width 0.1)
				(type default)
			)
			(layer "B.Fab")
		)
		(fp_line
			(start 0.12065 -0.2794)
			(end -0.12065 -0.2794)
			(stroke
				(width 0.1)
				(type default)
			)
			(layer "B.Fab")
		)
		(fp_line
			(start 0.12065 -0.305054)
			(end 0.12065 -0.2794)
			(stroke
				(width 0.1)
				(type default)
			)
			(layer "B.Fab")
		)
		(fp_line
			(start -0.120396 0.3048)
			(end -0.120396 0.2794)
			(stroke
				(width 0.1)
				(type default)
			)
			(layer "B.Fab")
		)
		(fp_line
			(start -0.120396 0.2794)
			(end 0.12065 0.2794)
			(stroke
				(width 0.1)
				(type default)
			)
			(layer "B.Fab")
		)
		(fp_line
			(start -0.12065 -0.2794)
			(end -0.12065 -0.3048)
			(stroke
				(width 0.1)
				(type default)
			)
			(layer "B.Fab")
		)
		(fp_line
			(start -0.12065 -0.3048)
			(end -0.67945 -0.3048)
			(stroke
				(width 0.1)
				(type default)
			)
			(layer "B.Fab")
		)
		(fp_line
			(start -0.67945 0.3048)
			(end -0.120396 0.3048)
			(stroke
				(width 0.1)
				(type default)
			)
			(layer "B.Fab")
		)
		(fp_line
			(start -0.67945 -0.3048)
			(end -0.67945 0.3048)
			(stroke
				(width 0.1)
				(type default)
			)
			(layer "B.Fab")
		)
		(pad "1" smd circle
			(at 0.40005 0)
			(size 0 0)
			(layers "B.Cu" "B.Mask" "B.Paste")
			(net "P3V3_P2V5_P1V8_RVDD")
		)
		(pad "2" smd circle
			(at -0.40005 0)
			(size 0 0)
			(layers "B.Cu" "B.Mask" "B.Paste")
			(net "GND")
		)
	)
	(footprint ""
		(layer "B.Cu")
		(at 56.256174 -44.791884)
		(property "Reference" "C95"
			(at 0 0 0)
			(layer "B.SilkS")
			(hide yes)
			(effects
				(font
					(size 1.27 1.27)
				)
				(justify mirror)
			)
		)
		(property "Value" ""
			(at 0 0 0)
			(layer "B.Fab")
			(effects
				(font
					(size 1.27 1.27)
				)
				(justify mirror)
			)
		)
		(duplicate_pad_numbers_are_jumpers no)
		(fp_line
			(start -0.7874 -0.4064)
			(end -0.7874 0.4064)
			(stroke
				(width 0.1524)
				(type default)
			)
			(layer "B.SilkS")
		)
		(fp_line
			(start -0.7874 0.4064)
			(end 0.7874 0.4064)
			(stroke
				(width 0.1524)
				(type default)
			)
			(layer "B.SilkS")
		)
		(fp_line
			(start 0.7874 -0.4064)
			(end -0.7874 -0.4064)
			(stroke
				(width 0.1524)
				(type default)
			)
			(layer "B.SilkS")
		)
		(fp_line
			(start 0.7874 0.4064)
			(end 0.7874 -0.4064)
			(stroke
				(width 0.1524)
				(type default)
			)
			(layer "B.SilkS")
		)
		(fp_line
			(start -0.67945 -0.3048)
			(end -0.67945 0.3048)
			(stroke
				(width 0.1)
				(type default)
			)
			(layer "B.Fab")
		)
		(fp_line
			(start -0.67945 0.3048)
			(end -0.120396 0.3048)
			(stroke
				(width 0.1)
				(type default)
			)
			(layer "B.Fab")
		)
		(fp_line
			(start -0.12065 -0.3048)
			(end -0.67945 -0.3048)
			(stroke
				(width 0.1)
				(type default)
			)
			(layer "B.Fab")
		)
		(fp_line
			(start -0.12065 -0.2794)
			(end -0.12065 -0.3048)
			(stroke
				(width 0.1)
				(type default)
			)
			(layer "B.Fab")
		)
		(fp_line
			(start -0.120396 0.2794)
			(end 0.12065 0.2794)
			(stroke
				(width 0.1)
				(type default)
			)
			(layer "B.Fab")
		)
		(fp_line
			(start -0.120396 0.3048)
			(end -0.120396 0.2794)
			(stroke
				(width 0.1)
				(type default)
			)
			(layer "B.Fab")
		)
		(fp_line
			(start 0.12065 -0.305054)
			(end 0.12065 -0.2794)
			(stroke
				(width 0.1)
				(type default)
			)
			(layer "B.Fab")
		)
		(fp_line
			(start 0.12065 -0.2794)
			(end -0.12065 -0.2794)
			(stroke
				(width 0.1)
				(type default)
			)
			(layer "B.Fab")
		)
		(fp_line
			(start 0.12065 0.2794)
			(end 0.12065 0.3048)
			(stroke
				(width 0.1)
				(type default)
			)
			(layer "B.Fab")
		)
		(fp_line
			(start 0.12065 0.3048)
			(end 0.67945 0.3048)
			(stroke
				(width 0.1)
				(type default)
			)
			(layer "B.Fab")
		)
		(fp_line
			(start 0.67945 -0.305054)
			(end 0.12065 -0.305054)
			(stroke
				(width 0.1)
				(type default)
			)
			(layer "B.Fab")
		)
		(fp_line
			(start 0.67945 0.3048)
			(end 0.67945 -0.305054)
			(stroke
				(width 0.1)
				(type default)
			)
			(layer "B.Fab")
		)
		(pad "1" smd circle
			(at 0.40005 0 180)
			(size 0 0)
			(layers "B.Cu" "B.Mask" "B.Paste")
			(net "P1V8_AUX")
		)
		(pad "2" smd circle
			(at -0.40005 0 180)
			(size 0 0)
			(layers "B.Cu" "B.Mask" "B.Paste")
			(net "GND")
		)
	)
	(footprint ""
		(layer "B.Cu")
		(at 42.350182 -30.816804 -90)
		(property "Reference" "R246"
			(at 0 0 90)
			(layer "B.SilkS")
			(hide yes)
			(effects
				(font
					(size 1.27 1.27)
				)
				(justify mirror)
			)
		)
		(property "Value" ""
			(at 0 0 90)
			(layer "B.Fab")
			(effects
				(font
					(size 1.27 1.27)
				)
				(justify mirror)
			)
		)
		(duplicate_pad_numbers_are_jumpers no)
		(fp_line
			(start -0.7874 0.4064)
			(end 0.7874 0.4064)
			(stroke
				(width 0.1524)
				(type default)
			)
			(layer "B.SilkS")
		)
		(fp_line
			(start 0.7874 0.4064)
			(end 0.7874 -0.4064)
			(stroke
				(width 0.1524)
				(type default)
			)
			(layer "B.SilkS")
		)
		(fp_line
			(start -0.7874 -0.4064)
			(end -0.7874 0.4064)
			(stroke
				(width 0.1524)
				(type default)
			)
			(layer "B.SilkS")
		)
		(fp_line
			(start 0.7874 -0.4064)
			(end -0.7874 -0.4064)
			(stroke
				(width 0.1524)
				(type default)
			)
			(layer "B.SilkS")
		)
		(fp_line
			(start -0.67945 0.3048)
			(end -0.120396 0.3048)
			(stroke
				(width 0.1)
				(type default)
			)
			(layer "B.Fab")
		)
		(fp_line
			(start -0.120396 0.3048)
			(end -0.120396 0.2794)
			(stroke
				(width 0.1)
				(type default)
			)
			(layer "B.Fab")
		)
		(fp_line
			(start 0.12065 0.3048)
			(end 0.67945 0.3048)
			(stroke
				(width 0.1)
				(type default)
			)
			(layer "B.Fab")
		)
		(fp_line
			(start 0.67945 0.3048)
			(end 0.67945 -0.305054)
			(stroke
				(width 0.1)
				(type default)
			)
			(layer "B.Fab")
		)
		(fp_line
			(start -0.120396 0.2794)
			(end 0.12065 0.2794)
			(stroke
				(width 0.1)
				(type default)
			)
			(layer "B.Fab")
		)
		(fp_line
			(start 0.12065 0.2794)
			(end 0.12065 0.3048)
			(stroke
				(width 0.1)
				(type default)
			)
			(layer "B.Fab")
		)
		(fp_line
			(start -0.12065 -0.2794)
			(end -0.12065 -0.3048)
			(stroke
				(width 0.1)
				(type default)
			)
			(layer "B.Fab")
		)
		(fp_line
			(start 0.12065 -0.2794)
			(end -0.12065 -0.2794)
			(stroke
				(width 0.1)
				(type default)
			)
			(layer "B.Fab")
		)
		(fp_line
			(start -0.67945 -0.3048)
			(end -0.67945 0.3048)
			(stroke
				(width 0.1)
				(type default)
			)
			(layer "B.Fab")
		)
		(fp_line
			(start -0.12065 -0.3048)
			(end -0.67945 -0.3048)
			(stroke
				(width 0.1)
				(type default)
			)
			(layer "B.Fab")
		)
		(fp_line
			(start 0.12065 -0.305054)
			(end 0.12065 -0.2794)
			(stroke
				(width 0.1)
				(type default)
			)
			(layer "B.Fab")
		)
		(fp_line
			(start 0.67945 -0.305054)
			(end 0.12065 -0.305054)
			(stroke
				(width 0.1)
				(type default)
			)
			(layer "B.Fab")
		)
		(pad "1" smd circle
			(at 0.40005 0 90)
			(size 0 0)
			(layers "B.Cu" "B.Mask" "B.Paste")
			(net "P3V3_AUX")
		)
		(pad "2" smd circle
			(at -0.40005 0 90)
			(size 0 0)
			(layers "B.Cu" "B.Mask" "B.Paste")
			(net "SMB_BMC_MM2_SCL")
		)
	)
	(footprint ""
		(layer "B.Cu")
		(at 65.405 -69.977 90)
		(property "Reference" "R312"
			(at 0 0 90)
			(layer "B.SilkS")
			(hide yes)
			(effects
				(font
					(size 1.27 1.27)
				)
				(justify mirror)
			)
		)
		(property "Value" ""
			(at 0 0 90)
			(layer "B.Fab")
			(effects
				(font
					(size 1.27 1.27)
				)
				(justify mirror)
			)
		)
		(duplicate_pad_numbers_are_jumpers no)
		(fp_line
			(start 0.7874 -0.4064)
			(end -0.7874 -0.4064)
			(stroke
				(width 0.1524)
				(type default)
			)
			(layer "B.SilkS")
		)
		(fp_line
			(start -0.7874 -0.4064)
			(end -0.7874 0.4064)
			(stroke
				(width 0.1524)
				(type default)
			)
			(layer "B.SilkS")
		)
		(fp_line
			(start 0.7874 0.4064)
			(end 0.7874 -0.4064)
			(stroke
				(width 0.1524)
				(type default)
			)
			(layer "B.SilkS")
		)
		(fp_line
			(start -0.7874 0.4064)
			(end 0.7874 0.4064)
			(stroke
				(width 0.1524)
				(type default)
			)
			(layer "B.SilkS")
		)
		(fp_line
			(start 0.67945 -0.305054)
			(end 0.12065 -0.305054)
			(stroke
				(width 0.1)
				(type default)
			)
			(layer "B.Fab")
		)
		(fp_line
			(start 0.12065 -0.305054)
			(end 0.12065 -0.2794)
			(stroke
				(width 0.1)
				(type default)
			)
			(layer "B.Fab")
		)
		(fp_line
			(start -0.12065 -0.3048)
			(end -0.67945 -0.3048)
			(stroke
				(width 0.1)
				(type default)
			)
			(layer "B.Fab")
		)
		(fp_line
			(start -0.67945 -0.3048)
			(end -0.67945 0.3048)
			(stroke
				(width 0.1)
				(type default)
			)
			(layer "B.Fab")
		)
		(fp_line
			(start 0.12065 -0.2794)
			(end -0.12065 -0.2794)
			(stroke
				(width 0.1)
				(type default)
			)
			(layer "B.Fab")
		)
		(fp_line
			(start -0.12065 -0.2794)
			(end -0.12065 -0.3048)
			(stroke
				(width 0.1)
				(type default)
			)
			(layer "B.Fab")
		)
		(fp_line
			(start 0.12065 0.2794)
			(end 0.12065 0.3048)
			(stroke
				(width 0.1)
				(type default)
			)
			(layer "B.Fab")
		)
		(fp_line
			(start -0.120396 0.2794)
			(end 0.12065 0.2794)
			(stroke
				(width 0.1)
				(type default)
			)
			(layer "B.Fab")
		)
		(fp_line
			(start 0.67945 0.3048)
			(end 0.67945 -0.305054)
			(stroke
				(width 0.1)
				(type default)
			)
			(layer "B.Fab")
		)
		(fp_line
			(start 0.12065 0.3048)
			(end 0.67945 0.3048)
			(stroke
				(width 0.1)
				(type default)
			)
			(layer "B.Fab")
		)
		(fp_line
			(start -0.120396 0.3048)
			(end -0.120396 0.2794)
			(stroke
				(width 0.1)
				(type default)
			)
			(layer "B.Fab")
		)
		(fp_line
			(start -0.67945 0.3048)
			(end -0.120396 0.3048)
			(stroke
				(width 0.1)
				(type default)
			)
			(layer "B.Fab")
		)
		(pad "1" smd circle
			(at 0.40005 0 270)
			(size 0 0)
			(layers "B.Cu" "B.Mask" "B.Paste")
			(net "RST_BMC_LPC_ESPI_N")
		)
		(pad "2" smd circle
			(at -0.40005 0 270)
			(size 0 0)
			(layers "B.Cu" "B.Mask" "B.Paste")
			(net "GND")
		)
	)
	(footprint ""
		(layer "B.Cu")
		(at 59.662822 -72.113394)
		(property "Reference" "R797"
			(at 0 0 0)
			(layer "B.SilkS")
			(hide yes)
			(effects
				(font
					(size 1.27 1.27)
				)
				(justify mirror)
			)
		)
		(property "Value" ""
			(at 0 0 0)
			(layer "B.Fab")
			(effects
				(font
					(size 1.27 1.27)
				)
				(justify mirror)
			)
		)
		(duplicate_pad_numbers_are_jumpers no)
		(fp_line
			(start -0.7874 -0.4064)
			(end -0.7874 0.4064)
			(stroke
				(width 0.1524)
				(type default)
			)
			(layer "B.SilkS")
		)
		(fp_line
			(start -0.7874 0.4064)
			(end 0.7874 0.4064)
			(stroke
				(width 0.1524)
				(type default)
			)
			(layer "B.SilkS")
		)
		(fp_line
			(start 0.7874 -0.4064)
			(end -0.7874 -0.4064)
			(stroke
				(width 0.1524)
				(type default)
			)
			(layer "B.SilkS")
		)
		(fp_line
			(start 0.7874 0.4064)
			(end 0.7874 -0.4064)
			(stroke
				(width 0.1524)
				(type default)
			)
			(layer "B.SilkS")
		)
		(fp_line
			(start -0.67945 -0.3048)
			(end -0.67945 0.3048)
			(stroke
				(width 0.1)
				(type default)
			)
			(layer "B.Fab")
		)
		(fp_line
			(start -0.67945 0.3048)
			(end -0.120396 0.3048)
			(stroke
				(width 0.1)
				(type default)
			)
			(layer "B.Fab")
		)
		(fp_line
			(start -0.12065 -0.3048)
			(end -0.67945 -0.3048)
			(stroke
				(width 0.1)
				(type default)
			)
			(layer "B.Fab")
		)
		(fp_line
			(start -0.12065 -0.2794)
			(end -0.12065 -0.3048)
			(stroke
				(width 0.1)
				(type default)
			)
			(layer "B.Fab")
		)
		(fp_line
			(start -0.120396 0.2794)
			(end 0.12065 0.2794)
			(stroke
				(width 0.1)
				(type default)
			)
			(layer "B.Fab")
		)
		(fp_line
			(start -0.120396 0.3048)
			(end -0.120396 0.2794)
			(stroke
				(width 0.1)
				(type default)
			)
			(layer "B.Fab")
		)
		(fp_line
			(start 0.12065 -0.305054)
			(end 0.12065 -0.2794)
			(stroke
				(width 0.1)
				(type default)
			)
			(layer "B.Fab")
		)
		(fp_line
			(start 0.12065 -0.2794)
			(end -0.12065 -0.2794)
			(stroke
				(width 0.1)
				(type default)
			)
			(layer "B.Fab")
		)
		(fp_line
			(start 0.12065 0.2794)
			(end 0.12065 0.3048)
			(stroke
				(width 0.1)
				(type default)
			)
			(layer "B.Fab")
		)
		(fp_line
			(start 0.12065 0.3048)
			(end 0.67945 0.3048)
			(stroke
				(width 0.1)
				(type default)
			)
			(layer "B.Fab")
		)
		(fp_line
			(start 0.67945 -0.305054)
			(end 0.12065 -0.305054)
			(stroke
				(width 0.1)
				(type default)
			)
			(layer "B.Fab")
		)
		(fp_line
			(start 0.67945 0.3048)
			(end 0.67945 -0.305054)
			(stroke
				(width 0.1)
				(type default)
			)
			(layer "B.Fab")
		)
		(pad "1" smd circle
			(at 0.40005 0 180)
			(size 0 0)
			(layers "B.Cu" "B.Mask" "B.Paste")
			(net "PGPPA_BMC_AUX")
		)
		(pad "2" smd circle
			(at -0.40005 0 180)
			(size 0 0)
			(layers "B.Cu" "B.Mask" "B.Paste")
			(net "PGPPA_BMC_AUX_SENSOR")
		)
	)
	(footprint ""
		(layer "B.Cu")
		(at 85.29955 -40.363394 180)
		(property "Reference" "R352"
			(at 0 0 0)
			(layer "B.SilkS")
			(hide yes)
			(effects
				(font
					(size 1.27 1.27)
				)
				(justify mirror)
			)
		)
		(property "Value" ""
			(at 0 0 0)
			(layer "B.Fab")
			(effects
				(font
					(size 1.27 1.27)
				)
				(justify mirror)
			)
		)
		(duplicate_pad_numbers_are_jumpers no)
		(fp_line
			(start 0.7874 0.4064)
			(end 0.7874 -0.4064)
			(stroke
				(width 0.1524)
				(type default)
			)
			(layer "B.SilkS")
		)
		(fp_line
			(start 0.7874 -0.4064)
			(end -0.7874 -0.4064)
			(stroke
				(width 0.1524)
				(type default)
			)
			(layer "B.SilkS")
		)
		(fp_line
			(start -0.7874 0.4064)
			(end 0.7874 0.4064)
			(stroke
				(width 0.1524)
				(type default)
			)
			(layer "B.SilkS")
		)
		(fp_line
			(start -0.7874 -0.4064)
			(end -0.7874 0.4064)
			(stroke
				(width 0.1524)
				(type default)
			)
			(layer "B.SilkS")
		)
		(fp_line
			(start 0.67945 0.3048)
			(end 0.67945 -0.305054)
			(stroke
				(width 0.1)
				(type default)
			)
			(layer "B.Fab")
		)
		(fp_line
			(start 0.67945 -0.305054)
			(end 0.12065 -0.305054)
			(stroke
				(width 0.1)
				(type default)
			)
			(layer "B.Fab")
		)
		(fp_line
			(start 0.12065 0.3048)
			(end 0.67945 0.3048)
			(stroke
				(width 0.1)
				(type default)
			)
			(layer "B.Fab")
		)
		(fp_line
			(start 0.12065 0.2794)
			(end 0.12065 0.3048)
			(stroke
				(width 0.1)
				(type default)
			)
			(layer "B.Fab")
		)
		(fp_line
			(start 0.12065 -0.2794)
			(end -0.12065 -0.2794)
			(stroke
				(width 0.1)
				(type default)
			)
			(layer "B.Fab")
		)
		(fp_line
			(start 0.12065 -0.305054)
			(end 0.12065 -0.2794)
			(stroke
				(width 0.1)
				(type default)
			)
			(layer "B.Fab")
		)
		(fp_line
			(start -0.120396 0.3048)
			(end -0.120396 0.2794)
			(stroke
				(width 0.1)
				(type default)
			)
			(layer "B.Fab")
		)
		(fp_line
			(start -0.120396 0.2794)
			(end 0.12065 0.2794)
			(stroke
				(width 0.1)
				(type default)
			)
			(layer "B.Fab")
		)
		(fp_line
			(start -0.12065 -0.2794)
			(end -0.12065 -0.3048)
			(stroke
				(width 0.1)
				(type default)
			)
			(layer "B.Fab")
		)
		(fp_line
			(start -0.12065 -0.3048)
			(end -0.67945 -0.3048)
			(stroke
				(width 0.1)
				(type default)
			)
			(layer "B.Fab")
		)
		(fp_line
			(start -0.67945 0.3048)
			(end -0.120396 0.3048)
			(stroke
				(width 0.1)
				(type default)
			)
			(layer "B.Fab")
		)
		(fp_line
			(start -0.67945 -0.3048)
			(end -0.67945 0.3048)
			(stroke
				(width 0.1)
				(type default)
			)
			(layer "B.Fab")
		)
		(pad "1" smd circle
			(at 0.40005 0)
			(size 0 0)
			(layers "B.Cu" "B.Mask" "B.Paste")
			(net "M_BMC_DDR4_MA<1>")
		)
		(pad "2" smd circle
			(at -0.40005 0)
			(size 0 0)
			(layers "B.Cu" "B.Mask" "B.Paste")
			(net "P1V2_AUX")
		)
	)
	(footprint ""
		(layer "B.Cu")
		(at 43.163236 -65.743582 -90)
		(property "Reference" "R191"
			(at 0 0 90)
			(layer "B.SilkS")
			(hide yes)
			(effects
				(font
					(size 1.27 1.27)
				)
				(justify mirror)
			)
		)
		(property "Value" ""
			(at 0 0 90)
			(layer "B.Fab")
			(effects
				(font
					(size 1.27 1.27)
				)
				(justify mirror)
			)
		)
		(duplicate_pad_numbers_are_jumpers no)
		(fp_line
			(start -0.7874 0.4064)
			(end 0.7874 0.4064)
			(stroke
				(width 0.1524)
				(type default)
			)
			(layer "B.SilkS")
		)
		(fp_line
			(start 0.7874 0.4064)
			(end 0.7874 -0.4064)
			(stroke
				(width 0.1524)
				(type default)
			)
			(layer "B.SilkS")
		)
		(fp_line
			(start -0.7874 -0.4064)
			(end -0.7874 0.4064)
			(stroke
				(width 0.1524)
				(type default)
			)
			(layer "B.SilkS")
		)
		(fp_line
			(start 0.7874 -0.4064)
			(end -0.7874 -0.4064)
			(stroke
				(width 0.1524)
				(type default)
			)
			(layer "B.SilkS")
		)
		(fp_line
			(start -0.67945 0.3048)
			(end -0.120396 0.3048)
			(stroke
				(width 0.1)
				(type default)
			)
			(layer "B.Fab")
		)
		(fp_line
			(start -0.120396 0.3048)
			(end -0.120396 0.2794)
			(stroke
				(width 0.1)
				(type default)
			)
			(layer "B.Fab")
		)
		(fp_line
			(start 0.12065 0.3048)
			(end 0.67945 0.3048)
			(stroke
				(width 0.1)
				(type default)
			)
			(layer "B.Fab")
		)
		(fp_line
			(start 0.67945 0.3048)
			(end 0.67945 -0.305054)
			(stroke
				(width 0.1)
				(type default)
			)
			(layer "B.Fab")
		)
		(fp_line
			(start -0.120396 0.2794)
			(end 0.12065 0.2794)
			(stroke
				(width 0.1)
				(type default)
			)
			(layer "B.Fab")
		)
		(fp_line
			(start 0.12065 0.2794)
			(end 0.12065 0.3048)
			(stroke
				(width 0.1)
				(type default)
			)
			(layer "B.Fab")
		)
		(fp_line
			(start -0.12065 -0.2794)
			(end -0.12065 -0.3048)
			(stroke
				(width 0.1)
				(type default)
			)
			(layer "B.Fab")
		)
		(fp_line
			(start 0.12065 -0.2794)
			(end -0.12065 -0.2794)
			(stroke
				(width 0.1)
				(type default)
			)
			(layer "B.Fab")
		)
		(fp_line
			(start -0.67945 -0.3048)
			(end -0.67945 0.3048)
			(stroke
				(width 0.1)
				(type default)
			)
			(layer "B.Fab")
		)
		(fp_line
			(start -0.12065 -0.3048)
			(end -0.67945 -0.3048)
			(stroke
				(width 0.1)
				(type default)
			)
			(layer "B.Fab")
		)
		(fp_line
			(start 0.12065 -0.305054)
			(end 0.12065 -0.2794)
			(stroke
				(width 0.1)
				(type default)
			)
			(layer "B.Fab")
		)
		(fp_line
			(start 0.67945 -0.305054)
			(end 0.12065 -0.305054)
			(stroke
				(width 0.1)
				(type default)
			)
			(layer "B.Fab")
		)
		(pad "1" smd circle
			(at 0.40005 0 90)
			(size 0 0)
			(layers "B.Cu" "B.Mask" "B.Paste")
			(net "P1V2_P1V0_I3C_VDDL1")
		)
		(pad "2" smd circle
			(at -0.40005 0 90)
			(size 0 0)
			(layers "B.Cu" "B.Mask" "B.Paste")
			(net "I3C2_SPD_SDA")
		)
	)
	(footprint ""
		(layer "B.Cu")
		(at 39.80053 -65.77965 -90)
		(property "Reference" "R189"
			(at 0 0 90)
			(layer "B.SilkS")
			(hide yes)
			(effects
				(font
					(size 1.27 1.27)
				)
				(justify mirror)
			)
		)
		(property "Value" ""
			(at 0 0 90)
			(layer "B.Fab")
			(effects
				(font
					(size 1.27 1.27)
				)
				(justify mirror)
			)
		)
		(duplicate_pad_numbers_are_jumpers no)
		(fp_line
			(start -0.7874 0.4064)
			(end 0.7874 0.4064)
			(stroke
				(width 0.1524)
				(type default)
			)
			(layer "B.SilkS")
		)
		(fp_line
			(start 0.7874 0.4064)
			(end 0.7874 -0.4064)
			(stroke
				(width 0.1524)
				(type default)
			)
			(layer "B.SilkS")
		)
		(fp_line
			(start -0.7874 -0.4064)
			(end -0.7874 0.4064)
			(stroke
				(width 0.1524)
				(type default)
			)
			(layer "B.SilkS")
		)
		(fp_line
			(start 0.7874 -0.4064)
			(end -0.7874 -0.4064)
			(stroke
				(width 0.1524)
				(type default)
			)
			(layer "B.SilkS")
		)
		(fp_line
			(start -0.67945 0.3048)
			(end -0.120396 0.3048)
			(stroke
				(width 0.1)
				(type default)
			)
			(layer "B.Fab")
		)
		(fp_line
			(start -0.120396 0.3048)
			(end -0.120396 0.2794)
			(stroke
				(width 0.1)
				(type default)
			)
			(layer "B.Fab")
		)
		(fp_line
			(start 0.12065 0.3048)
			(end 0.67945 0.3048)
			(stroke
				(width 0.1)
				(type default)
			)
			(layer "B.Fab")
		)
		(fp_line
			(start 0.67945 0.3048)
			(end 0.67945 -0.305054)
			(stroke
				(width 0.1)
				(type default)
			)
			(layer "B.Fab")
		)
		(fp_line
			(start -0.120396 0.2794)
			(end 0.12065 0.2794)
			(stroke
				(width 0.1)
				(type default)
			)
			(layer "B.Fab")
		)
		(fp_line
			(start 0.12065 0.2794)
			(end 0.12065 0.3048)
			(stroke
				(width 0.1)
				(type default)
			)
			(layer "B.Fab")
		)
		(fp_line
			(start -0.12065 -0.2794)
			(end -0.12065 -0.3048)
			(stroke
				(width 0.1)
				(type default)
			)
			(layer "B.Fab")
		)
		(fp_line
			(start 0.12065 -0.2794)
			(end -0.12065 -0.2794)
			(stroke
				(width 0.1)
				(type default)
			)
			(layer "B.Fab")
		)
		(fp_line
			(start -0.67945 -0.3048)
			(end -0.67945 0.3048)
			(stroke
				(width 0.1)
				(type default)
			)
			(layer "B.Fab")
		)
		(fp_line
			(start -0.12065 -0.3048)
			(end -0.67945 -0.3048)
			(stroke
				(width 0.1)
				(type default)
			)
			(layer "B.Fab")
		)
		(fp_line
			(start 0.12065 -0.305054)
			(end 0.12065 -0.2794)
			(stroke
				(width 0.1)
				(type default)
			)
			(layer "B.Fab")
		)
		(fp_line
			(start 0.67945 -0.305054)
			(end 0.12065 -0.305054)
			(stroke
				(width 0.1)
				(type default)
			)
			(layer "B.Fab")
		)
		(pad "1" smd circle
			(at 0.40005 0 90)
			(size 0 0)
			(layers "B.Cu" "B.Mask" "B.Paste")
			(net "P1V2_P1V0_I3C_VDDL1")
		)
		(pad "2" smd circle
			(at -0.40005 0 90)
			(size 0 0)
			(layers "B.Cu" "B.Mask" "B.Paste")
			(net "I3C3_SPD_SDA")
		)
	)
	(footprint ""
		(layer "B.Cu")
		(at 83.16722 -44.554394 180)
		(property "Reference" "R363"
			(at 0 0 0)
			(layer "B.SilkS")
			(hide yes)
			(effects
				(font
					(size 1.27 1.27)
				)
				(justify mirror)
			)
		)
		(property "Value" ""
			(at 0 0 0)
			(layer "B.Fab")
			(effects
				(font
					(size 1.27 1.27)
				)
				(justify mirror)
			)
		)
		(duplicate_pad_numbers_are_jumpers no)
		(fp_line
			(start 0.7874 0.4064)
			(end 0.7874 -0.4064)
			(stroke
				(width 0.1524)
				(type default)
			)
			(layer "B.SilkS")
		)
		(fp_line
			(start 0.7874 -0.4064)
			(end -0.7874 -0.4064)
			(stroke
				(width 0.1524)
				(type default)
			)
			(layer "B.SilkS")
		)
		(fp_line
			(start -0.7874 0.4064)
			(end 0.7874 0.4064)
			(stroke
				(width 0.1524)
				(type default)
			)
			(layer "B.SilkS")
		)
		(fp_line
			(start -0.7874 -0.4064)
			(end -0.7874 0.4064)
			(stroke
				(width 0.1524)
				(type default)
			)
			(layer "B.SilkS")
		)
		(fp_line
			(start 0.67945 0.3048)
			(end 0.67945 -0.305054)
			(stroke
				(width 0.1)
				(type default)
			)
			(layer "B.Fab")
		)
		(fp_line
			(start 0.67945 -0.305054)
			(end 0.12065 -0.305054)
			(stroke
				(width 0.1)
				(type default)
			)
			(layer "B.Fab")
		)
		(fp_line
			(start 0.12065 0.3048)
			(end 0.67945 0.3048)
			(stroke
				(width 0.1)
				(type default)
			)
			(layer "B.Fab")
		)
		(fp_line
			(start 0.12065 0.2794)
			(end 0.12065 0.3048)
			(stroke
				(width 0.1)
				(type default)
			)
			(layer "B.Fab")
		)
		(fp_line
			(start 0.12065 -0.2794)
			(end -0.12065 -0.2794)
			(stroke
				(width 0.1)
				(type default)
			)
			(layer "B.Fab")
		)
		(fp_line
			(start 0.12065 -0.305054)
			(end 0.12065 -0.2794)
			(stroke
				(width 0.1)
				(type default)
			)
			(layer "B.Fab")
		)
		(fp_line
			(start -0.120396 0.3048)
			(end -0.120396 0.2794)
			(stroke
				(width 0.1)
				(type default)
			)
			(layer "B.Fab")
		)
		(fp_line
			(start -0.120396 0.2794)
			(end 0.12065 0.2794)
			(stroke
				(width 0.1)
				(type default)
			)
			(layer "B.Fab")
		)
		(fp_line
			(start -0.12065 -0.2794)
			(end -0.12065 -0.3048)
			(stroke
				(width 0.1)
				(type default)
			)
			(layer "B.Fab")
		)
		(fp_line
			(start -0.12065 -0.3048)
			(end -0.67945 -0.3048)
			(stroke
				(width 0.1)
				(type default)
			)
			(layer "B.Fab")
		)
		(fp_line
			(start -0.67945 0.3048)
			(end -0.120396 0.3048)
			(stroke
				(width 0.1)
				(type default)
			)
			(layer "B.Fab")
		)
		(fp_line
			(start -0.67945 -0.3048)
			(end -0.67945 0.3048)
			(stroke
				(width 0.1)
				(type default)
			)
			(layer "B.Fab")
		)
		(pad "1" smd circle
			(at 0.40005 0)
			(size 0 0)
			(layers "B.Cu" "B.Mask" "B.Paste")
			(net "M_BMC_DDR4_MA<12>")
		)
		(pad "2" smd circle
			(at -0.40005 0)
			(size 0 0)
			(layers "B.Cu" "B.Mask" "B.Paste")
			(net "P1V2_AUX")
		)
	)
	(footprint ""
		(layer "B.Cu")
		(at 46.609 -107.3912)
		(property "Reference" "R79"
			(at 0 0 0)
			(layer "B.SilkS")
			(hide yes)
			(effects
				(font
					(size 1.27 1.27)
				)
				(justify mirror)
			)
		)
		(property "Value" ""
			(at 0 0 0)
			(layer "B.Fab")
			(effects
				(font
					(size 1.27 1.27)
				)
				(justify mirror)
			)
		)
		(duplicate_pad_numbers_are_jumpers no)
		(fp_line
			(start -0.7874 -0.4064)
			(end -0.7874 0.4064)
			(stroke
				(width 0.1524)
				(type default)
			)
			(layer "B.SilkS")
		)
		(fp_line
			(start -0.7874 0.4064)
			(end 0.7874 0.4064)
			(stroke
				(width 0.1524)
				(type default)
			)
			(layer "B.SilkS")
		)
		(fp_line
			(start 0.7874 -0.4064)
			(end -0.7874 -0.4064)
			(stroke
				(width 0.1524)
				(type default)
			)
			(layer "B.SilkS")
		)
		(fp_line
			(start 0.7874 0.4064)
			(end 0.7874 -0.4064)
			(stroke
				(width 0.1524)
				(type default)
			)
			(layer "B.SilkS")
		)
		(fp_line
			(start -0.67945 -0.3048)
			(end -0.67945 0.3048)
			(stroke
				(width 0.1)
				(type default)
			)
			(layer "B.Fab")
		)
		(fp_line
			(start -0.67945 0.3048)
			(end -0.120396 0.3048)
			(stroke
				(width 0.1)
				(type default)
			)
			(layer "B.Fab")
		)
		(fp_line
			(start -0.12065 -0.3048)
			(end -0.67945 -0.3048)
			(stroke
				(width 0.1)
				(type default)
			)
			(layer "B.Fab")
		)
		(fp_line
			(start -0.12065 -0.2794)
			(end -0.12065 -0.3048)
			(stroke
				(width 0.1)
				(type default)
			)
			(layer "B.Fab")
		)
		(fp_line
			(start -0.120396 0.2794)
			(end 0.12065 0.2794)
			(stroke
				(width 0.1)
				(type default)
			)
			(layer "B.Fab")
		)
		(fp_line
			(start -0.120396 0.3048)
			(end -0.120396 0.2794)
			(stroke
				(width 0.1)
				(type default)
			)
			(layer "B.Fab")
		)
		(fp_line
			(start 0.12065 -0.305054)
			(end 0.12065 -0.2794)
			(stroke
				(width 0.1)
				(type default)
			)
			(layer "B.Fab")
		)
		(fp_line
			(start 0.12065 -0.2794)
			(end -0.12065 -0.2794)
			(stroke
				(width 0.1)
				(type default)
			)
			(layer "B.Fab")
		)
		(fp_line
			(start 0.12065 0.2794)
			(end 0.12065 0.3048)
			(stroke
				(width 0.1)
				(type default)
			)
			(layer "B.Fab")
		)
		(fp_line
			(start 0.12065 0.3048)
			(end 0.67945 0.3048)
			(stroke
				(width 0.1)
				(type default)
			)
			(layer "B.Fab")
		)
		(fp_line
			(start 0.67945 -0.305054)
			(end 0.12065 -0.305054)
			(stroke
				(width 0.1)
				(type default)
			)
			(layer "B.Fab")
		)
		(fp_line
			(start 0.67945 0.3048)
			(end 0.67945 -0.305054)
			(stroke
				(width 0.1)
				(type default)
			)
			(layer "B.Fab")
		)
		(pad "1" smd circle
			(at 0.40005 0 180)
			(size 0 0)
			(layers "B.Cu" "B.Mask" "B.Paste")
			(net "P3V3_AUX")
		)
		(pad "2" smd circle
			(at -0.40005 0 180)
			(size 0 0)
			(layers "B.Cu" "B.Mask" "B.Paste")
			(net "SGPIO_DO_0")
		)
	)
	(footprint ""
		(layer "B.Cu")
		(at 80.546194 -53.342286 90)
		(property "Reference" "C9"
			(at 0 0 90)
			(layer "B.SilkS")
			(hide yes)
			(effects
				(font
					(size 1.27 1.27)
				)
				(justify mirror)
			)
		)
		(property "Value" ""
			(at 0 0 90)
			(layer "B.Fab")
			(effects
				(font
					(size 1.27 1.27)
				)
				(justify mirror)
			)
		)
		(duplicate_pad_numbers_are_jumpers no)
		(fp_line
			(start 0.7874 -0.4064)
			(end -0.7874 -0.4064)
			(stroke
				(width 0.1524)
				(type default)
			)
			(layer "B.SilkS")
		)
		(fp_line
			(start -0.7874 -0.4064)
			(end -0.7874 0.4064)
			(stroke
				(width 0.1524)
				(type default)
			)
			(layer "B.SilkS")
		)
		(fp_line
			(start 0.7874 0.4064)
			(end 0.7874 -0.4064)
			(stroke
				(width 0.1524)
				(type default)
			)
			(layer "B.SilkS")
		)
		(fp_line
			(start -0.7874 0.4064)
			(end 0.7874 0.4064)
			(stroke
				(width 0.1524)
				(type default)
			)
			(layer "B.SilkS")
		)
		(fp_line
			(start 0.67945 -0.305054)
			(end 0.12065 -0.305054)
			(stroke
				(width 0.1)
				(type default)
			)
			(layer "B.Fab")
		)
		(fp_line
			(start 0.12065 -0.305054)
			(end 0.12065 -0.2794)
			(stroke
				(width 0.1)
				(type default)
			)
			(layer "B.Fab")
		)
		(fp_line
			(start -0.12065 -0.3048)
			(end -0.67945 -0.3048)
			(stroke
				(width 0.1)
				(type default)
			)
			(layer "B.Fab")
		)
		(fp_line
			(start -0.67945 -0.3048)
			(end -0.67945 0.3048)
			(stroke
				(width 0.1)
				(type default)
			)
			(layer "B.Fab")
		)
		(fp_line
			(start 0.12065 -0.2794)
			(end -0.12065 -0.2794)
			(stroke
				(width 0.1)
				(type default)
			)
			(layer "B.Fab")
		)
		(fp_line
			(start -0.12065 -0.2794)
			(end -0.12065 -0.3048)
			(stroke
				(width 0.1)
				(type default)
			)
			(layer "B.Fab")
		)
		(fp_line
			(start 0.12065 0.2794)
			(end 0.12065 0.3048)
			(stroke
				(width 0.1)
				(type default)
			)
			(layer "B.Fab")
		)
		(fp_line
			(start -0.120396 0.2794)
			(end 0.12065 0.2794)
			(stroke
				(width 0.1)
				(type default)
			)
			(layer "B.Fab")
		)
		(fp_line
			(start 0.67945 0.3048)
			(end 0.67945 -0.305054)
			(stroke
				(width 0.1)
				(type default)
			)
			(layer "B.Fab")
		)
		(fp_line
			(start 0.12065 0.3048)
			(end 0.67945 0.3048)
			(stroke
				(width 0.1)
				(type default)
			)
			(layer "B.Fab")
		)
		(fp_line
			(start -0.120396 0.3048)
			(end -0.120396 0.2794)
			(stroke
				(width 0.1)
				(type default)
			)
			(layer "B.Fab")
		)
		(fp_line
			(start -0.67945 0.3048)
			(end -0.120396 0.3048)
			(stroke
				(width 0.1)
				(type default)
			)
			(layer "B.Fab")
		)
		(pad "1" smd circle
			(at 0.40005 0 270)
			(size 0 0)
			(layers "B.Cu" "B.Mask" "B.Paste")
			(net "P1V2_AUX")
		)
		(pad "2" smd circle
			(at -0.40005 0 270)
			(size 0 0)
			(layers "B.Cu" "B.Mask" "B.Paste")
			(net "GND")
		)
	)
	(footprint ""
		(layer "B.Cu")
		(at 43.890184 -101.70287)
		(property "Reference" "U21"
			(at 0.369316 3.44424 0)
			(unlocked yes)
			(layer "B.SilkS")
			(effects
				(font
					(size 0.7874 0.5842)
					(thickness 0.1524)
				)
				(justify left mirror)
			)
		)
		(property "Value" ""
			(at 0 0 0)
			(layer "B.Fab")
			(effects
				(font
					(size 1.27 1.27)
				)
				(justify mirror)
			)
		)
		(duplicate_pad_numbers_are_jumpers no)
		(fp_line
			(start -2.0066 -2.5654)
			(end -2.0066 2.5654)
			(stroke
				(width 0.1524)
				(type default)
			)
			(layer "B.SilkS")
		)
		(fp_line
			(start -2.0066 2.5654)
			(end 2.0066 2.5654)
			(stroke
				(width 0.1524)
				(type default)
			)
			(layer "B.SilkS")
		)
		(fp_line
			(start -0.5842 -2.5654)
			(end -2.0066 -2.5654)
			(stroke
				(width 0.1524)
				(type default)
			)
			(layer "B.SilkS")
		)
		(fp_line
			(start 0 -1.9812)
			(end -0.5842 -2.5654)
			(stroke
				(width 0.1524)
				(type default)
			)
			(layer "B.SilkS")
		)
		(fp_line
			(start 0.5842 -2.5654)
			(end 0 -1.9812)
			(stroke
				(width 0.1524)
				(type default)
			)
			(layer "B.SilkS")
		)
		(fp_line
			(start 2.0066 -2.5654)
			(end 0.5842 -2.5654)
			(stroke
				(width 0.1524)
				(type default)
			)
			(layer "B.SilkS")
		)
		(fp_line
			(start 2.0066 2.5654)
			(end 2.0066 -2.5654)
			(stroke
				(width 0.1524)
				(type default)
			)
			(layer "B.SilkS")
		)
		(fp_poly
			(pts
				(xy 3.853688 -2.300478) (xy 4.869688 -2.808478) (xy 4.869688 -1.792478)
			)
			(stroke
				(width 0)
				(type default)
			)
			(fill yes)
			(layer "B.SilkS")
		)
		(fp_line
			(start -3.7338 -2.5654)
			(end -3.6703 -2.5654)
			(stroke
				(width 0.1)
				(type default)
			)
			(layer "B.Fab")
		)
		(fp_line
			(start -3.7338 2.5654)
			(end -3.7338 -2.5654)
			(stroke
				(width 0.1)
				(type default)
			)
			(layer "B.Fab")
		)
		(fp_line
			(start -3.6703 -2.5654)
			(end 3.6703 -2.5654)
			(stroke
				(width 0.1)
				(type default)
			)
			(layer "B.Fab")
		)
		(fp_line
			(start -3.6703 2.5654)
			(end -3.7338 2.5654)
			(stroke
				(width 0.1)
				(type default)
			)
			(layer "B.Fab")
		)
		(fp_line
			(start 3.6703 -2.5654)
			(end 3.7338 -2.5654)
			(stroke
				(width 0.1)
				(type default)
			)
			(layer "B.Fab")
		)
		(fp_line
			(start 3.6703 2.5654)
			(end -3.6703 2.5654)
			(stroke
				(width 0.1)
				(type default)
			)
			(layer "B.Fab")
		)
		(fp_line
			(start 3.7338 -2.5654)
			(end 3.7338 2.5654)
			(stroke
				(width 0.1)
				(type default)
			)
			(layer "B.Fab")
		)
		(fp_line
			(start 3.7338 2.5654)
			(end 3.6703 2.5654)
			(stroke
				(width 0.1)
				(type default)
			)
			(layer "B.Fab")
		)
		(fp_poly
			(pts
				(xy 3.955288 -2.275078) (xy 4.971288 -2.783078) (xy 4.971288 -1.767078)
			)
			(stroke
				(width 0)
				(type default)
			)
			(fill yes)
			(layer "B.Fab")
		)
		(pad "1" smd rect
			(at 2.921 -2.275078 270)
			(size 0.3556 1.4986)
			(layers "B.Cu" "B.Mask" "B.Paste")
			(net "FM_BMC_BIOS_MUX_CS_SPI_R_SEL_0")
		)
		(pad "2" smd rect
			(at 2.921 -1.625092 270)
			(size 0.3556 1.4986)
			(layers "B.Cu" "B.Mask" "B.Paste")
			(net "SPI_SYS_MUX_WP_IO2")
		)
		(pad "3" smd rect
			(at 2.921 -0.975106 270)
			(size 0.3556 1.4986)
			(layers "B.Cu" "B.Mask" "B.Paste")
			(net "SPI_BMC_BIOS_ROM_R_IO2")
		)
		(pad "4" smd rect
			(at 2.921 -0.32512 270)
			(size 0.3556 1.4986)
			(layers "B.Cu" "B.Mask" "B.Paste")
			(net "SPI_PCH_MUXED_IO2")
		)
		(pad "5" smd rect
			(at 2.921 0.32512 270)
			(size 0.3556 1.4986)
			(layers "B.Cu" "B.Mask" "B.Paste")
			(net "SPI_SYS_MUX_MISO")
		)
		(pad "6" smd rect
			(at 2.921 0.975106 270)
			(size 0.3556 1.4986)
			(layers "B.Cu" "B.Mask" "B.Paste")
			(net "SPI_BMC_BIOS_ROM_R_MISO")
		)
		(pad "7" smd rect
			(at 2.921 1.625092 270)
			(size 0.3556 1.4986)
			(layers "B.Cu" "B.Mask" "B.Paste")
			(net "SPI_PCH_MUXED_IO1")
		)
		(pad "8" smd rect
			(at 2.921 2.275078 270)
			(size 0.3556 1.4986)
			(layers "B.Cu" "B.Mask" "B.Paste")
			(net "GND")
		)
		(pad "9" smd rect
			(at -2.921 2.275078 270)
			(size 0.3556 1.4986)
			(layers "B.Cu" "B.Mask" "B.Paste")
			(net "SPI_PCH_MUXED_CS0_N")
		)
		(pad "10" smd rect
			(at -2.921 1.625092 270)
			(size 0.3556 1.4986)
			(layers "B.Cu" "B.Mask" "B.Paste")
			(net "SPI_BMC_BIOS_SOURCE_CS0_N")
		)
		(pad "11" smd rect
			(at -2.921 0.975106 270)
			(size 0.3556 1.4986)
			(layers "B.Cu" "B.Mask" "B.Paste")
			(net "SPI_PCH_SECURE_CS0_N")
		)
		(pad "12" smd rect
			(at -2.921 0.32512 270)
			(size 0.3556 1.4986)
			(layers "B.Cu" "B.Mask" "B.Paste")
			(net "TP_BIOS_MUX1_PIN12")
		)
		(pad "13" smd rect
			(at -2.921 -0.32512 270)
			(size 0.3556 1.4986)
			(layers "B.Cu" "B.Mask" "B.Paste")
			(net "TP_BIOS_MUX1_PIN13")
		)
		(pad "14" smd rect
			(at -2.921 -0.975106 270)
			(size 0.3556 1.4986)
			(layers "B.Cu" "B.Mask" "B.Paste")
			(net "TP_BIOS_MUX1_PIN14")
		)
		(pad "15" smd rect
			(at -2.921 -1.625092 270)
			(size 0.3556 1.4986)
			(layers "B.Cu" "B.Mask" "B.Paste")
			(net "PD_BIOS_MUX_EN_N")
		)
		(pad "16" smd rect
			(at -2.921 -2.275078 270)
			(size 0.3556 1.4986)
			(layers "B.Cu" "B.Mask" "B.Paste")
			(net "P3V3_AUX")
		)
	)
	(footprint ""
		(layer "B.Cu")
		(at 53.532024 -45.280326)
		(property "Reference" "C60"
			(at 0 0 0)
			(layer "B.SilkS")
			(hide yes)
			(effects
				(font
					(size 1.27 1.27)
				)
				(justify mirror)
			)
		)
		(property "Value" ""
			(at 0 0 0)
			(layer "B.Fab")
			(effects
				(font
					(size 1.27 1.27)
				)
				(justify mirror)
			)
		)
		(duplicate_pad_numbers_are_jumpers no)
		(fp_line
			(start -0.7874 -0.4064)
			(end -0.7874 0.4064)
			(stroke
				(width 0.1524)
				(type default)
			)
			(layer "B.SilkS")
		)
		(fp_line
			(start -0.7874 0.4064)
			(end 0.7874 0.4064)
			(stroke
				(width 0.1524)
				(type default)
			)
			(layer "B.SilkS")
		)
		(fp_line
			(start 0.7874 -0.4064)
			(end -0.7874 -0.4064)
			(stroke
				(width 0.1524)
				(type default)
			)
			(layer "B.SilkS")
		)
		(fp_line
			(start 0.7874 0.4064)
			(end 0.7874 -0.4064)
			(stroke
				(width 0.1524)
				(type default)
			)
			(layer "B.SilkS")
		)
		(fp_line
			(start -0.67945 -0.3048)
			(end -0.67945 0.3048)
			(stroke
				(width 0.1)
				(type default)
			)
			(layer "B.Fab")
		)
		(fp_line
			(start -0.67945 0.3048)
			(end -0.120396 0.3048)
			(stroke
				(width 0.1)
				(type default)
			)
			(layer "B.Fab")
		)
		(fp_line
			(start -0.12065 -0.3048)
			(end -0.67945 -0.3048)
			(stroke
				(width 0.1)
				(type default)
			)
			(layer "B.Fab")
		)
		(fp_line
			(start -0.12065 -0.2794)
			(end -0.12065 -0.3048)
			(stroke
				(width 0.1)
				(type default)
			)
			(layer "B.Fab")
		)
		(fp_line
			(start -0.120396 0.2794)
			(end 0.12065 0.2794)
			(stroke
				(width 0.1)
				(type default)
			)
			(layer "B.Fab")
		)
		(fp_line
			(start -0.120396 0.3048)
			(end -0.120396 0.2794)
			(stroke
				(width 0.1)
				(type default)
			)
			(layer "B.Fab")
		)
		(fp_line
			(start 0.12065 -0.305054)
			(end 0.12065 -0.2794)
			(stroke
				(width 0.1)
				(type default)
			)
			(layer "B.Fab")
		)
		(fp_line
			(start 0.12065 -0.2794)
			(end -0.12065 -0.2794)
			(stroke
				(width 0.1)
				(type default)
			)
			(layer "B.Fab")
		)
		(fp_line
			(start 0.12065 0.2794)
			(end 0.12065 0.3048)
			(stroke
				(width 0.1)
				(type default)
			)
			(layer "B.Fab")
		)
		(fp_line
			(start 0.12065 0.3048)
			(end 0.67945 0.3048)
			(stroke
				(width 0.1)
				(type default)
			)
			(layer "B.Fab")
		)
		(fp_line
			(start 0.67945 -0.305054)
			(end 0.12065 -0.305054)
			(stroke
				(width 0.1)
				(type default)
			)
			(layer "B.Fab")
		)
		(fp_line
			(start 0.67945 0.3048)
			(end 0.67945 -0.305054)
			(stroke
				(width 0.1)
				(type default)
			)
			(layer "B.Fab")
		)
		(pad "1" smd circle
			(at 0.40005 0 180)
			(size 0 0)
			(layers "B.Cu" "B.Mask" "B.Paste")
			(net "P3V3_STBY_PLLAHVDD")
		)
		(pad "2" smd circle
			(at -0.40005 0 180)
			(size 0 0)
			(layers "B.Cu" "B.Mask" "B.Paste")
			(net "GND")
		)
	)
	(footprint ""
		(layer "B.Cu")
		(at 82.804 -32.766 -90)
		(property "Reference" "C120"
			(at 0 0 90)
			(layer "B.SilkS")
			(hide yes)
			(effects
				(font
					(size 1.27 1.27)
				)
				(justify mirror)
			)
		)
		(property "Value" ""
			(at 0 0 90)
			(layer "B.Fab")
			(effects
				(font
					(size 1.27 1.27)
				)
				(justify mirror)
			)
		)
		(duplicate_pad_numbers_are_jumpers no)
		(fp_line
			(start -1.2954 0.5842)
			(end 1.2954 0.5842)
			(stroke
				(width 0.1524)
				(type default)
			)
			(layer "B.SilkS")
		)
		(fp_line
			(start 1.2954 0.5842)
			(end 1.2954 -0.5842)
			(stroke
				(width 0.1524)
				(type default)
			)
			(layer "B.SilkS")
		)
		(fp_line
			(start -1.2954 -0.5842)
			(end -1.2954 0.5842)
			(stroke
				(width 0.1524)
				(type default)
			)
			(layer "B.SilkS")
		)
		(fp_line
			(start 0 -0.5842)
			(end 0 0.5842)
			(stroke
				(width 0.1524)
				(type default)
			)
			(layer "B.SilkS")
		)
		(fp_line
			(start 1.2954 -0.5842)
			(end -1.2954 -0.5842)
			(stroke
				(width 0.1524)
				(type default)
			)
			(layer "B.SilkS")
		)
		(fp_line
			(start -0.8636 0.4572)
			(end 0.8636 0.4572)
			(stroke
				(width 0.1)
				(type default)
			)
			(layer "B.Fab")
		)
		(fp_line
			(start 0.8636 0.4572)
			(end 0.8636 0.4064)
			(stroke
				(width 0.1)
				(type default)
			)
			(layer "B.Fab")
		)
		(fp_line
			(start -1.1938 0.4064)
			(end -0.8636 0.4064)
			(stroke
				(width 0.1)
				(type default)
			)
			(layer "B.Fab")
		)
		(fp_line
			(start -0.8636 0.4064)
			(end -0.8636 0.4572)
			(stroke
				(width 0.1)
				(type default)
			)
			(layer "B.Fab")
		)
		(fp_line
			(start 0.8636 0.4064)
			(end 1.1938 0.4064)
			(stroke
				(width 0.1)
				(type default)
			)
			(layer "B.Fab")
		)
		(fp_line
			(start 1.1938 0.4064)
			(end 1.1938 -0.4064)
			(stroke
				(width 0.1)
				(type default)
			)
			(layer "B.Fab")
		)
		(fp_line
			(start -1.1938 -0.4064)
			(end -1.1938 0.4064)
			(stroke
				(width 0.1)
				(type default)
			)
			(layer "B.Fab")
		)
		(fp_line
			(start -0.8636 -0.4064)
			(end -1.1938 -0.4064)
			(stroke
				(width 0.1)
				(type default)
			)
			(layer "B.Fab")
		)
		(fp_line
			(start 0.8636 -0.4064)
			(end 0.8636 -0.4572)
			(stroke
				(width 0.1)
				(type default)
			)
			(layer "B.Fab")
		)
		(fp_line
			(start 1.1938 -0.4064)
			(end 0.8636 -0.4064)
			(stroke
				(width 0.1)
				(type default)
			)
			(layer "B.Fab")
		)
		(fp_line
			(start -0.8636 -0.4572)
			(end -0.8636 -0.4064)
			(stroke
				(width 0.1)
				(type default)
			)
			(layer "B.Fab")
		)
		(fp_line
			(start 0.8636 -0.4572)
			(end -0.8636 -0.4572)
			(stroke
				(width 0.1)
				(type default)
			)
			(layer "B.Fab")
		)
		(pad "1" smd rect
			(at 0.7366 0 180)
			(size 0.7112 0.8128)
			(layers "B.Cu" "B.Mask" "B.Paste")
			(net "P3V3_AUX")
		)
		(pad "2" smd rect
			(at -0.7366 0 180)
			(size 0.7112 0.8128)
			(layers "B.Cu" "B.Mask" "B.Paste")
			(net "GND")
		)
	)
	(footprint ""
		(layer "B.Cu")
		(at 49.2252 -88.1126 -90)
		(property "Reference" "R34"
			(at 0 0 90)
			(layer "B.SilkS")
			(hide yes)
			(effects
				(font
					(size 1.27 1.27)
				)
				(justify mirror)
			)
		)
		(property "Value" ""
			(at 0 0 90)
			(layer "B.Fab")
			(effects
				(font
					(size 1.27 1.27)
				)
				(justify mirror)
			)
		)
		(duplicate_pad_numbers_are_jumpers no)
		(fp_line
			(start -0.7874 0.4064)
			(end 0.7874 0.4064)
			(stroke
				(width 0.1524)
				(type default)
			)
			(layer "B.SilkS")
		)
		(fp_line
			(start 0.7874 0.4064)
			(end 0.7874 -0.4064)
			(stroke
				(width 0.1524)
				(type default)
			)
			(layer "B.SilkS")
		)
		(fp_line
			(start -0.7874 -0.4064)
			(end -0.7874 0.4064)
			(stroke
				(width 0.1524)
				(type default)
			)
			(layer "B.SilkS")
		)
		(fp_line
			(start 0.7874 -0.4064)
			(end -0.7874 -0.4064)
			(stroke
				(width 0.1524)
				(type default)
			)
			(layer "B.SilkS")
		)
		(fp_line
			(start -0.67945 0.3048)
			(end -0.120396 0.3048)
			(stroke
				(width 0.1)
				(type default)
			)
			(layer "B.Fab")
		)
		(fp_line
			(start -0.120396 0.3048)
			(end -0.120396 0.2794)
			(stroke
				(width 0.1)
				(type default)
			)
			(layer "B.Fab")
		)
		(fp_line
			(start 0.12065 0.3048)
			(end 0.67945 0.3048)
			(stroke
				(width 0.1)
				(type default)
			)
			(layer "B.Fab")
		)
		(fp_line
			(start 0.67945 0.3048)
			(end 0.67945 -0.305054)
			(stroke
				(width 0.1)
				(type default)
			)
			(layer "B.Fab")
		)
		(fp_line
			(start -0.120396 0.2794)
			(end 0.12065 0.2794)
			(stroke
				(width 0.1)
				(type default)
			)
			(layer "B.Fab")
		)
		(fp_line
			(start 0.12065 0.2794)
			(end 0.12065 0.3048)
			(stroke
				(width 0.1)
				(type default)
			)
			(layer "B.Fab")
		)
		(fp_line
			(start -0.12065 -0.2794)
			(end -0.12065 -0.3048)
			(stroke
				(width 0.1)
				(type default)
			)
			(layer "B.Fab")
		)
		(fp_line
			(start 0.12065 -0.2794)
			(end -0.12065 -0.2794)
			(stroke
				(width 0.1)
				(type default)
			)
			(layer "B.Fab")
		)
		(fp_line
			(start -0.67945 -0.3048)
			(end -0.67945 0.3048)
			(stroke
				(width 0.1)
				(type default)
			)
			(layer "B.Fab")
		)
		(fp_line
			(start -0.12065 -0.3048)
			(end -0.67945 -0.3048)
			(stroke
				(width 0.1)
				(type default)
			)
			(layer "B.Fab")
		)
		(fp_line
			(start 0.12065 -0.305054)
			(end 0.12065 -0.2794)
			(stroke
				(width 0.1)
				(type default)
			)
			(layer "B.Fab")
		)
		(fp_line
			(start 0.67945 -0.305054)
			(end 0.12065 -0.305054)
			(stroke
				(width 0.1)
				(type default)
			)
			(layer "B.Fab")
		)
		(pad "1" smd circle
			(at 0.40005 0 90)
			(size 0 0)
			(layers "B.Cu" "B.Mask" "B.Paste")
			(net "P3V3_RGM")
		)
		(pad "2" smd circle
			(at -0.40005 0 90)
			(size 0 0)
			(layers "B.Cu" "B.Mask" "B.Paste")
			(net "RST_PLTRST_N")
		)
	)
	(footprint ""
		(layer "B.Cu")
		(at 39.80815 -59.0042)
		(property "Reference" "R717"
			(at 0 0 0)
			(layer "B.SilkS")
			(hide yes)
			(effects
				(font
					(size 1.27 1.27)
				)
				(justify mirror)
			)
		)
		(property "Value" ""
			(at 0 0 0)
			(layer "B.Fab")
			(effects
				(font
					(size 1.27 1.27)
				)
				(justify mirror)
			)
		)
		(duplicate_pad_numbers_are_jumpers no)
		(fp_line
			(start -0.7874 -0.4064)
			(end -0.7874 0.4064)
			(stroke
				(width 0.1524)
				(type default)
			)
			(layer "B.SilkS")
		)
		(fp_line
			(start -0.7874 0.4064)
			(end 0.7874 0.4064)
			(stroke
				(width 0.1524)
				(type default)
			)
			(layer "B.SilkS")
		)
		(fp_line
			(start 0.7874 -0.4064)
			(end -0.7874 -0.4064)
			(stroke
				(width 0.1524)
				(type default)
			)
			(layer "B.SilkS")
		)
		(fp_line
			(start 0.7874 0.4064)
			(end 0.7874 -0.4064)
			(stroke
				(width 0.1524)
				(type default)
			)
			(layer "B.SilkS")
		)
		(fp_line
			(start -0.67945 -0.3048)
			(end -0.67945 0.3048)
			(stroke
				(width 0.1)
				(type default)
			)
			(layer "B.Fab")
		)
		(fp_line
			(start -0.67945 0.3048)
			(end -0.120396 0.3048)
			(stroke
				(width 0.1)
				(type default)
			)
			(layer "B.Fab")
		)
		(fp_line
			(start -0.12065 -0.3048)
			(end -0.67945 -0.3048)
			(stroke
				(width 0.1)
				(type default)
			)
			(layer "B.Fab")
		)
		(fp_line
			(start -0.12065 -0.2794)
			(end -0.12065 -0.3048)
			(stroke
				(width 0.1)
				(type default)
			)
			(layer "B.Fab")
		)
		(fp_line
			(start -0.120396 0.2794)
			(end 0.12065 0.2794)
			(stroke
				(width 0.1)
				(type default)
			)
			(layer "B.Fab")
		)
		(fp_line
			(start -0.120396 0.3048)
			(end -0.120396 0.2794)
			(stroke
				(width 0.1)
				(type default)
			)
			(layer "B.Fab")
		)
		(fp_line
			(start 0.12065 -0.305054)
			(end 0.12065 -0.2794)
			(stroke
				(width 0.1)
				(type default)
			)
			(layer "B.Fab")
		)
		(fp_line
			(start 0.12065 -0.2794)
			(end -0.12065 -0.2794)
			(stroke
				(width 0.1)
				(type default)
			)
			(layer "B.Fab")
		)
		(fp_line
			(start 0.12065 0.2794)
			(end 0.12065 0.3048)
			(stroke
				(width 0.1)
				(type default)
			)
			(layer "B.Fab")
		)
		(fp_line
			(start 0.12065 0.3048)
			(end 0.67945 0.3048)
			(stroke
				(width 0.1)
				(type default)
			)
			(layer "B.Fab")
		)
		(fp_line
			(start 0.67945 -0.305054)
			(end 0.12065 -0.305054)
			(stroke
				(width 0.1)
				(type default)
			)
			(layer "B.Fab")
		)
		(fp_line
			(start 0.67945 0.3048)
			(end 0.67945 -0.305054)
			(stroke
				(width 0.1)
				(type default)
			)
			(layer "B.Fab")
		)
		(pad "1" smd circle
			(at 0.40005 0 180)
			(size 0 0)
			(layers "B.Cu" "B.Mask" "B.Paste")
			(net "P3V3_AUX")
		)
		(pad "2" smd circle
			(at -0.40005 0 180)
			(size 0 0)
			(layers "B.Cu" "B.Mask" "B.Paste")
			(net "RST_BMC_RSTBTN_OUT_N")
		)
	)
	(footprint ""
		(layer "B.Cu")
		(at 18.259552 -90.786966 180)
		(property "Reference" "C167"
			(at 0 0 0)
			(layer "B.SilkS")
			(hide yes)
			(effects
				(font
					(size 1.27 1.27)
				)
				(justify mirror)
			)
		)
		(property "Value" ""
			(at 0 0 0)
			(layer "B.Fab")
			(effects
				(font
					(size 1.27 1.27)
				)
				(justify mirror)
			)
		)
		(duplicate_pad_numbers_are_jumpers no)
		(fp_line
			(start 0.69215 0.2921)
			(end 0.69215 -0.2921)
			(stroke
				(width 0.1524)
				(type default)
			)
			(layer "B.SilkS")
		)
		(fp_line
			(start 0.69215 -0.2921)
			(end -0.69215 -0.2921)
			(stroke
				(width 0.1524)
				(type default)
			)
			(layer "B.SilkS")
		)
		(fp_line
			(start -0.69215 0.2921)
			(end 0.69215 0.2921)
			(stroke
				(width 0.1524)
				(type default)
			)
			(layer "B.SilkS")
		)
		(fp_line
			(start -0.69215 -0.2921)
			(end -0.69215 0.2921)
			(stroke
				(width 0.1524)
				(type default)
			)
			(layer "B.SilkS")
		)
		(fp_line
			(start 0.51435 0.2794)
			(end 0.51435 -0.2794)
			(stroke
				(width 0.1)
				(type default)
			)
			(layer "B.Fab")
		)
		(fp_line
			(start 0.51435 -0.2794)
			(end -0.51435 -0.2794)
			(stroke
				(width 0.1)
				(type default)
			)
			(layer "B.Fab")
		)
		(fp_line
			(start -0.51435 0.2794)
			(end 0.51435 0.2794)
			(stroke
				(width 0.1)
				(type default)
			)
			(layer "B.Fab")
		)
		(fp_line
			(start -0.51435 -0.2794)
			(end -0.51435 0.2794)
			(stroke
				(width 0.1)
				(type default)
			)
			(layer "B.Fab")
		)
		(pad "1" smd circle
			(at 0.40005 0)
			(size 0 0)
			(layers "B.Cu" "B.Mask" "B.Paste")
			(net "VCCIO1")
		)
		(pad "2" smd circle
			(at -0.40005 0)
			(size 0 0)
			(layers "B.Cu" "B.Mask" "B.Paste")
			(net "GND")
		)
		(zone
			(layer "B.Cu")
			(hatch none 0.5)
			(connect_pads
				(clearance 0)
			)
			(min_thickness 0.25)
			(keepout
				(tracks not_allowed)
				(vias allowed)
				(pads allowed)
				(copperpour not_allowed)
				(footprints allowed)
			)
			(placement
				(enabled no)
				(sheetname "")
			)
			(fill
				(thermal_gap 0.5)
				(thermal_bridge_width 0.5)
				(island_removal_mode 0)
			)
			(polygon
				(pts
					(xy 18.069052 -90.874596) (xy 18.160492 -90.932762) (xy 18.359882 -90.932762) (xy 18.450052 -90.874596)
					(xy 18.450052 -90.699336) (xy 18.359882 -90.640916) (xy 18.160492 -90.640916) (xy 18.069052 -90.699082)
				)
			)
		)
	)
	(footprint ""
		(layer "B.Cu")
		(at 81.129886 -42.006012)
		(property "Reference" "R329"
			(at 0 0 0)
			(layer "B.SilkS")
			(hide yes)
			(effects
				(font
					(size 1.27 1.27)
				)
				(justify mirror)
			)
		)
		(property "Value" ""
			(at 0 0 0)
			(layer "B.Fab")
			(effects
				(font
					(size 1.27 1.27)
				)
				(justify mirror)
			)
		)
		(duplicate_pad_numbers_are_jumpers no)
		(fp_line
			(start -0.7874 -0.4064)
			(end -0.7874 0.4064)
			(stroke
				(width 0.1524)
				(type default)
			)
			(layer "B.SilkS")
		)
		(fp_line
			(start -0.7874 0.4064)
			(end 0.7874 0.4064)
			(stroke
				(width 0.1524)
				(type default)
			)
			(layer "B.SilkS")
		)
		(fp_line
			(start 0.7874 -0.4064)
			(end -0.7874 -0.4064)
			(stroke
				(width 0.1524)
				(type default)
			)
			(layer "B.SilkS")
		)
		(fp_line
			(start 0.7874 0.4064)
			(end 0.7874 -0.4064)
			(stroke
				(width 0.1524)
				(type default)
			)
			(layer "B.SilkS")
		)
		(fp_line
			(start -0.67945 -0.3048)
			(end -0.67945 0.3048)
			(stroke
				(width 0.1)
				(type default)
			)
			(layer "B.Fab")
		)
		(fp_line
			(start -0.67945 0.3048)
			(end -0.120396 0.3048)
			(stroke
				(width 0.1)
				(type default)
			)
			(layer "B.Fab")
		)
		(fp_line
			(start -0.12065 -0.3048)
			(end -0.67945 -0.3048)
			(stroke
				(width 0.1)
				(type default)
			)
			(layer "B.Fab")
		)
		(fp_line
			(start -0.12065 -0.2794)
			(end -0.12065 -0.3048)
			(stroke
				(width 0.1)
				(type default)
			)
			(layer "B.Fab")
		)
		(fp_line
			(start -0.120396 0.2794)
			(end 0.12065 0.2794)
			(stroke
				(width 0.1)
				(type default)
			)
			(layer "B.Fab")
		)
		(fp_line
			(start -0.120396 0.3048)
			(end -0.120396 0.2794)
			(stroke
				(width 0.1)
				(type default)
			)
			(layer "B.Fab")
		)
		(fp_line
			(start 0.12065 -0.305054)
			(end 0.12065 -0.2794)
			(stroke
				(width 0.1)
				(type default)
			)
			(layer "B.Fab")
		)
		(fp_line
			(start 0.12065 -0.2794)
			(end -0.12065 -0.2794)
			(stroke
				(width 0.1)
				(type default)
			)
			(layer "B.Fab")
		)
		(fp_line
			(start 0.12065 0.2794)
			(end 0.12065 0.3048)
			(stroke
				(width 0.1)
				(type default)
			)
			(layer "B.Fab")
		)
		(fp_line
			(start 0.12065 0.3048)
			(end 0.67945 0.3048)
			(stroke
				(width 0.1)
				(type default)
			)
			(layer "B.Fab")
		)
		(fp_line
			(start 0.67945 -0.305054)
			(end 0.12065 -0.305054)
			(stroke
				(width 0.1)
				(type default)
			)
			(layer "B.Fab")
		)
		(fp_line
			(start 0.67945 0.3048)
			(end 0.67945 -0.305054)
			(stroke
				(width 0.1)
				(type default)
			)
			(layer "B.Fab")
		)
		(pad "1" smd circle
			(at 0.40005 0 180)
			(size 0 0)
			(layers "B.Cu" "B.Mask" "B.Paste")
			(net "GND")
		)
		(pad "2" smd circle
			(at -0.40005 0 180)
			(size 0 0)
			(layers "B.Cu" "B.Mask" "B.Paste")
			(net "M_BMC_DDR4_MA<3>")
		)
	)
	(footprint ""
		(layer "B.Cu")
		(at 13.335 -106.426 90)
		(property "Reference" "R898"
			(at 0 0 90)
			(layer "B.SilkS")
			(hide yes)
			(effects
				(font
					(size 1.27 1.27)
				)
				(justify mirror)
			)
		)
		(property "Value" ""
			(at 0 0 90)
			(layer "B.Fab")
			(effects
				(font
					(size 1.27 1.27)
				)
				(justify mirror)
			)
		)
		(duplicate_pad_numbers_are_jumpers no)
		(fp_line
			(start 0.7874 -0.4064)
			(end -0.7874 -0.4064)
			(stroke
				(width 0.1524)
				(type default)
			)
			(layer "B.SilkS")
		)
		(fp_line
			(start -0.7874 -0.4064)
			(end -0.7874 0.4064)
			(stroke
				(width 0.1524)
				(type default)
			)
			(layer "B.SilkS")
		)
		(fp_line
			(start 0.7874 0.4064)
			(end 0.7874 -0.4064)
			(stroke
				(width 0.1524)
				(type default)
			)
			(layer "B.SilkS")
		)
		(fp_line
			(start -0.7874 0.4064)
			(end 0.7874 0.4064)
			(stroke
				(width 0.1524)
				(type default)
			)
			(layer "B.SilkS")
		)
		(fp_line
			(start 0.67945 -0.305054)
			(end 0.12065 -0.305054)
			(stroke
				(width 0.1)
				(type default)
			)
			(layer "B.Fab")
		)
		(fp_line
			(start 0.12065 -0.305054)
			(end 0.12065 -0.2794)
			(stroke
				(width 0.1)
				(type default)
			)
			(layer "B.Fab")
		)
		(fp_line
			(start -0.12065 -0.3048)
			(end -0.67945 -0.3048)
			(stroke
				(width 0.1)
				(type default)
			)
			(layer "B.Fab")
		)
		(fp_line
			(start -0.67945 -0.3048)
			(end -0.67945 0.3048)
			(stroke
				(width 0.1)
				(type default)
			)
			(layer "B.Fab")
		)
		(fp_line
			(start 0.12065 -0.2794)
			(end -0.12065 -0.2794)
			(stroke
				(width 0.1)
				(type default)
			)
			(layer "B.Fab")
		)
		(fp_line
			(start -0.12065 -0.2794)
			(end -0.12065 -0.3048)
			(stroke
				(width 0.1)
				(type default)
			)
			(layer "B.Fab")
		)
		(fp_line
			(start 0.12065 0.2794)
			(end 0.12065 0.3048)
			(stroke
				(width 0.1)
				(type default)
			)
			(layer "B.Fab")
		)
		(fp_line
			(start -0.120396 0.2794)
			(end 0.12065 0.2794)
			(stroke
				(width 0.1)
				(type default)
			)
			(layer "B.Fab")
		)
		(fp_line
			(start 0.67945 0.3048)
			(end 0.67945 -0.305054)
			(stroke
				(width 0.1)
				(type default)
			)
			(layer "B.Fab")
		)
		(fp_line
			(start 0.12065 0.3048)
			(end 0.67945 0.3048)
			(stroke
				(width 0.1)
				(type default)
			)
			(layer "B.Fab")
		)
		(fp_line
			(start -0.120396 0.3048)
			(end -0.120396 0.2794)
			(stroke
				(width 0.1)
				(type default)
			)
			(layer "B.Fab")
		)
		(fp_line
			(start -0.67945 0.3048)
			(end -0.120396 0.3048)
			(stroke
				(width 0.1)
				(type default)
			)
			(layer "B.Fab")
		)
		(pad "1" smd circle
			(at 0.40005 0 270)
			(size 0 0)
			(layers "B.Cu" "B.Mask" "B.Paste")
			(net "FM_UARTSW_LSB_R_N")
		)
		(pad "2" smd circle
			(at -0.40005 0 270)
			(size 0 0)
			(layers "B.Cu" "B.Mask" "B.Paste")
			(net "FM_UARTSW_LSB_N")
		)
	)
	(footprint ""
		(layer "B.Cu")
		(at 37.4015 -99.568 180)
		(property "Reference" "R728"
			(at 0 0 0)
			(layer "B.SilkS")
			(hide yes)
			(effects
				(font
					(size 1.27 1.27)
				)
				(justify mirror)
			)
		)
		(property "Value" ""
			(at 0 0 0)
			(layer "B.Fab")
			(effects
				(font
					(size 1.27 1.27)
				)
				(justify mirror)
			)
		)
		(duplicate_pad_numbers_are_jumpers no)
		(fp_line
			(start 0.7874 0.4064)
			(end 0.7874 -0.4064)
			(stroke
				(width 0.1524)
				(type default)
			)
			(layer "B.SilkS")
		)
		(fp_line
			(start 0.7874 -0.4064)
			(end -0.7874 -0.4064)
			(stroke
				(width 0.1524)
				(type default)
			)
			(layer "B.SilkS")
		)
		(fp_line
			(start -0.7874 0.4064)
			(end 0.7874 0.4064)
			(stroke
				(width 0.1524)
				(type default)
			)
			(layer "B.SilkS")
		)
		(fp_line
			(start -0.7874 -0.4064)
			(end -0.7874 0.4064)
			(stroke
				(width 0.1524)
				(type default)
			)
			(layer "B.SilkS")
		)
		(fp_line
			(start 0.67945 0.3048)
			(end 0.67945 -0.305054)
			(stroke
				(width 0.1)
				(type default)
			)
			(layer "B.Fab")
		)
		(fp_line
			(start 0.67945 -0.305054)
			(end 0.12065 -0.305054)
			(stroke
				(width 0.1)
				(type default)
			)
			(layer "B.Fab")
		)
		(fp_line
			(start 0.12065 0.3048)
			(end 0.67945 0.3048)
			(stroke
				(width 0.1)
				(type default)
			)
			(layer "B.Fab")
		)
		(fp_line
			(start 0.12065 0.2794)
			(end 0.12065 0.3048)
			(stroke
				(width 0.1)
				(type default)
			)
			(layer "B.Fab")
		)
		(fp_line
			(start 0.12065 -0.2794)
			(end -0.12065 -0.2794)
			(stroke
				(width 0.1)
				(type default)
			)
			(layer "B.Fab")
		)
		(fp_line
			(start 0.12065 -0.305054)
			(end 0.12065 -0.2794)
			(stroke
				(width 0.1)
				(type default)
			)
			(layer "B.Fab")
		)
		(fp_line
			(start -0.120396 0.3048)
			(end -0.120396 0.2794)
			(stroke
				(width 0.1)
				(type default)
			)
			(layer "B.Fab")
		)
		(fp_line
			(start -0.120396 0.2794)
			(end 0.12065 0.2794)
			(stroke
				(width 0.1)
				(type default)
			)
			(layer "B.Fab")
		)
		(fp_line
			(start -0.12065 -0.2794)
			(end -0.12065 -0.3048)
			(stroke
				(width 0.1)
				(type default)
			)
			(layer "B.Fab")
		)
		(fp_line
			(start -0.12065 -0.3048)
			(end -0.67945 -0.3048)
			(stroke
				(width 0.1)
				(type default)
			)
			(layer "B.Fab")
		)
		(fp_line
			(start -0.67945 0.3048)
			(end -0.120396 0.3048)
			(stroke
				(width 0.1)
				(type default)
			)
			(layer "B.Fab")
		)
		(fp_line
			(start -0.67945 -0.3048)
			(end -0.67945 0.3048)
			(stroke
				(width 0.1)
				(type default)
			)
			(layer "B.Fab")
		)
		(pad "1" smd circle
			(at 0.40005 0)
			(size 0 0)
			(layers "B.Cu" "B.Mask" "B.Paste")
			(net "SPI_BMC_BIOS_CS0_N")
		)
		(pad "2" smd circle
			(at -0.40005 0)
			(size 0 0)
			(layers "B.Cu" "B.Mask" "B.Paste")
			(net "SPI_BMC_BIOS_SOURCE_CS0_N")
		)
	)
	(footprint ""
		(layer "B.Cu")
		(at 57.906666 -74.66584 180)
		(property "Reference" "R787"
			(at 0 0 0)
			(layer "B.SilkS")
			(hide yes)
			(effects
				(font
					(size 1.27 1.27)
				)
				(justify mirror)
			)
		)
		(property "Value" ""
			(at 0 0 0)
			(layer "B.Fab")
			(effects
				(font
					(size 1.27 1.27)
				)
				(justify mirror)
			)
		)
		(duplicate_pad_numbers_are_jumpers no)
		(fp_line
			(start 0.7874 0.4064)
			(end 0.7874 -0.4064)
			(stroke
				(width 0.1524)
				(type default)
			)
			(layer "B.SilkS")
		)
		(fp_line
			(start 0.7874 -0.4064)
			(end -0.7874 -0.4064)
			(stroke
				(width 0.1524)
				(type default)
			)
			(layer "B.SilkS")
		)
		(fp_line
			(start -0.7874 0.4064)
			(end 0.7874 0.4064)
			(stroke
				(width 0.1524)
				(type default)
			)
			(layer "B.SilkS")
		)
		(fp_line
			(start -0.7874 -0.4064)
			(end -0.7874 0.4064)
			(stroke
				(width 0.1524)
				(type default)
			)
			(layer "B.SilkS")
		)
		(fp_line
			(start 0.67945 0.3048)
			(end 0.67945 -0.305054)
			(stroke
				(width 0.1)
				(type default)
			)
			(layer "B.Fab")
		)
		(fp_line
			(start 0.67945 -0.305054)
			(end 0.12065 -0.305054)
			(stroke
				(width 0.1)
				(type default)
			)
			(layer "B.Fab")
		)
		(fp_line
			(start 0.12065 0.3048)
			(end 0.67945 0.3048)
			(stroke
				(width 0.1)
				(type default)
			)
			(layer "B.Fab")
		)
		(fp_line
			(start 0.12065 0.2794)
			(end 0.12065 0.3048)
			(stroke
				(width 0.1)
				(type default)
			)
			(layer "B.Fab")
		)
		(fp_line
			(start 0.12065 -0.2794)
			(end -0.12065 -0.2794)
			(stroke
				(width 0.1)
				(type default)
			)
			(layer "B.Fab")
		)
		(fp_line
			(start 0.12065 -0.305054)
			(end 0.12065 -0.2794)
			(stroke
				(width 0.1)
				(type default)
			)
			(layer "B.Fab")
		)
		(fp_line
			(start -0.120396 0.3048)
			(end -0.120396 0.2794)
			(stroke
				(width 0.1)
				(type default)
			)
			(layer "B.Fab")
		)
		(fp_line
			(start -0.120396 0.2794)
			(end 0.12065 0.2794)
			(stroke
				(width 0.1)
				(type default)
			)
			(layer "B.Fab")
		)
		(fp_line
			(start -0.12065 -0.2794)
			(end -0.12065 -0.3048)
			(stroke
				(width 0.1)
				(type default)
			)
			(layer "B.Fab")
		)
		(fp_line
			(start -0.12065 -0.3048)
			(end -0.67945 -0.3048)
			(stroke
				(width 0.1)
				(type default)
			)
			(layer "B.Fab")
		)
		(fp_line
			(start -0.67945 0.3048)
			(end -0.120396 0.3048)
			(stroke
				(width 0.1)
				(type default)
			)
			(layer "B.Fab")
		)
		(fp_line
			(start -0.67945 -0.3048)
			(end -0.67945 0.3048)
			(stroke
				(width 0.1)
				(type default)
			)
			(layer "B.Fab")
		)
		(pad "1" smd circle
			(at 0.40005 0)
			(size 0 0)
			(layers "B.Cu" "B.Mask" "B.Paste")
			(net "P5V_AUX")
		)
		(pad "2" smd circle
			(at -0.40005 0)
			(size 0 0)
			(layers "B.Cu" "B.Mask" "B.Paste")
			(net "P5V_SENSOR")
		)
	)
	(footprint ""
		(layer "B.Cu")
		(at 50.858674 -70.800722 180)
		(property "Reference" "R794"
			(at 0 0 0)
			(layer "B.SilkS")
			(hide yes)
			(effects
				(font
					(size 1.27 1.27)
				)
				(justify mirror)
			)
		)
		(property "Value" ""
			(at 0 0 0)
			(layer "B.Fab")
			(effects
				(font
					(size 1.27 1.27)
				)
				(justify mirror)
			)
		)
		(duplicate_pad_numbers_are_jumpers no)
		(fp_line
			(start 0.7874 0.4064)
			(end 0.7874 -0.4064)
			(stroke
				(width 0.1524)
				(type default)
			)
			(layer "B.SilkS")
		)
		(fp_line
			(start 0.7874 -0.4064)
			(end -0.7874 -0.4064)
			(stroke
				(width 0.1524)
				(type default)
			)
			(layer "B.SilkS")
		)
		(fp_line
			(start -0.7874 0.4064)
			(end 0.7874 0.4064)
			(stroke
				(width 0.1524)
				(type default)
			)
			(layer "B.SilkS")
		)
		(fp_line
			(start -0.7874 -0.4064)
			(end -0.7874 0.4064)
			(stroke
				(width 0.1524)
				(type default)
			)
			(layer "B.SilkS")
		)
		(fp_line
			(start 0.67945 0.3048)
			(end 0.67945 -0.305054)
			(stroke
				(width 0.1)
				(type default)
			)
			(layer "B.Fab")
		)
		(fp_line
			(start 0.67945 -0.305054)
			(end 0.12065 -0.305054)
			(stroke
				(width 0.1)
				(type default)
			)
			(layer "B.Fab")
		)
		(fp_line
			(start 0.12065 0.3048)
			(end 0.67945 0.3048)
			(stroke
				(width 0.1)
				(type default)
			)
			(layer "B.Fab")
		)
		(fp_line
			(start 0.12065 0.2794)
			(end 0.12065 0.3048)
			(stroke
				(width 0.1)
				(type default)
			)
			(layer "B.Fab")
		)
		(fp_line
			(start 0.12065 -0.2794)
			(end -0.12065 -0.2794)
			(stroke
				(width 0.1)
				(type default)
			)
			(layer "B.Fab")
		)
		(fp_line
			(start 0.12065 -0.305054)
			(end 0.12065 -0.2794)
			(stroke
				(width 0.1)
				(type default)
			)
			(layer "B.Fab")
		)
		(fp_line
			(start -0.120396 0.3048)
			(end -0.120396 0.2794)
			(stroke
				(width 0.1)
				(type default)
			)
			(layer "B.Fab")
		)
		(fp_line
			(start -0.120396 0.2794)
			(end 0.12065 0.2794)
			(stroke
				(width 0.1)
				(type default)
			)
			(layer "B.Fab")
		)
		(fp_line
			(start -0.12065 -0.2794)
			(end -0.12065 -0.3048)
			(stroke
				(width 0.1)
				(type default)
			)
			(layer "B.Fab")
		)
		(fp_line
			(start -0.12065 -0.3048)
			(end -0.67945 -0.3048)
			(stroke
				(width 0.1)
				(type default)
			)
			(layer "B.Fab")
		)
		(fp_line
			(start -0.67945 0.3048)
			(end -0.120396 0.3048)
			(stroke
				(width 0.1)
				(type default)
			)
			(layer "B.Fab")
		)
		(fp_line
			(start -0.67945 -0.3048)
			(end -0.67945 0.3048)
			(stroke
				(width 0.1)
				(type default)
			)
			(layer "B.Fab")
		)
		(pad "1" smd circle
			(at 0.40005 0)
			(size 0 0)
			(layers "B.Cu" "B.Mask" "B.Paste")
			(net "P1V8_SENSOR")
		)
		(pad "2" smd circle
			(at -0.40005 0)
			(size 0 0)
			(layers "B.Cu" "B.Mask" "B.Paste")
			(net "GND")
		)
	)
	(footprint ""
		(layer "B.Cu")
		(at 60.85586 -30.867604 -90)
		(property "Reference" "R427"
			(at 0 0 90)
			(layer "B.SilkS")
			(hide yes)
			(effects
				(font
					(size 1.27 1.27)
				)
				(justify mirror)
			)
		)
		(property "Value" ""
			(at 0 0 90)
			(layer "B.Fab")
			(effects
				(font
					(size 1.27 1.27)
				)
				(justify mirror)
			)
		)
		(duplicate_pad_numbers_are_jumpers no)
		(fp_line
			(start -0.7874 0.4064)
			(end 0.7874 0.4064)
			(stroke
				(width 0.1524)
				(type default)
			)
			(layer "B.SilkS")
		)
		(fp_line
			(start 0.7874 0.4064)
			(end 0.7874 -0.4064)
			(stroke
				(width 0.1524)
				(type default)
			)
			(layer "B.SilkS")
		)
		(fp_line
			(start -0.7874 -0.4064)
			(end -0.7874 0.4064)
			(stroke
				(width 0.1524)
				(type default)
			)
			(layer "B.SilkS")
		)
		(fp_line
			(start 0.7874 -0.4064)
			(end -0.7874 -0.4064)
			(stroke
				(width 0.1524)
				(type default)
			)
			(layer "B.SilkS")
		)
		(fp_line
			(start -0.67945 0.3048)
			(end -0.120396 0.3048)
			(stroke
				(width 0.1)
				(type default)
			)
			(layer "B.Fab")
		)
		(fp_line
			(start -0.120396 0.3048)
			(end -0.120396 0.2794)
			(stroke
				(width 0.1)
				(type default)
			)
			(layer "B.Fab")
		)
		(fp_line
			(start 0.12065 0.3048)
			(end 0.67945 0.3048)
			(stroke
				(width 0.1)
				(type default)
			)
			(layer "B.Fab")
		)
		(fp_line
			(start 0.67945 0.3048)
			(end 0.67945 -0.305054)
			(stroke
				(width 0.1)
				(type default)
			)
			(layer "B.Fab")
		)
		(fp_line
			(start -0.120396 0.2794)
			(end 0.12065 0.2794)
			(stroke
				(width 0.1)
				(type default)
			)
			(layer "B.Fab")
		)
		(fp_line
			(start 0.12065 0.2794)
			(end 0.12065 0.3048)
			(stroke
				(width 0.1)
				(type default)
			)
			(layer "B.Fab")
		)
		(fp_line
			(start -0.12065 -0.2794)
			(end -0.12065 -0.3048)
			(stroke
				(width 0.1)
				(type default)
			)
			(layer "B.Fab")
		)
		(fp_line
			(start 0.12065 -0.2794)
			(end -0.12065 -0.2794)
			(stroke
				(width 0.1)
				(type default)
			)
			(layer "B.Fab")
		)
		(fp_line
			(start -0.67945 -0.3048)
			(end -0.67945 0.3048)
			(stroke
				(width 0.1)
				(type default)
			)
			(layer "B.Fab")
		)
		(fp_line
			(start -0.12065 -0.3048)
			(end -0.67945 -0.3048)
			(stroke
				(width 0.1)
				(type default)
			)
			(layer "B.Fab")
		)
		(fp_line
			(start 0.12065 -0.305054)
			(end 0.12065 -0.2794)
			(stroke
				(width 0.1)
				(type default)
			)
			(layer "B.Fab")
		)
		(fp_line
			(start 0.67945 -0.305054)
			(end 0.12065 -0.305054)
			(stroke
				(width 0.1)
				(type default)
			)
			(layer "B.Fab")
		)
		(pad "1" smd circle
			(at 0.40005 0 90)
			(size 0 0)
			(layers "B.Cu" "B.Mask" "B.Paste")
			(net "UART_BMC_1_RXD_R")
		)
		(pad "2" smd circle
			(at -0.40005 0 90)
			(size 0 0)
			(layers "B.Cu" "B.Mask" "B.Paste")
			(net "UART_BMC_1_RXD")
		)
	)
	(footprint ""
		(layer "B.Cu")
		(at 53.006498 -49.3903)
		(property "Reference" "C117"
			(at 0 0 0)
			(layer "B.SilkS")
			(hide yes)
			(effects
				(font
					(size 1.27 1.27)
				)
				(justify mirror)
			)
		)
		(property "Value" ""
			(at 0 0 0)
			(layer "B.Fab")
			(effects
				(font
					(size 1.27 1.27)
				)
				(justify mirror)
			)
		)
		(duplicate_pad_numbers_are_jumpers no)
		(fp_line
			(start -0.7874 -0.4064)
			(end -0.7874 0.4064)
			(stroke
				(width 0.1524)
				(type default)
			)
			(layer "B.SilkS")
		)
		(fp_line
			(start -0.7874 0.4064)
			(end 0.7874 0.4064)
			(stroke
				(width 0.1524)
				(type default)
			)
			(layer "B.SilkS")
		)
		(fp_line
			(start 0.7874 -0.4064)
			(end -0.7874 -0.4064)
			(stroke
				(width 0.1524)
				(type default)
			)
			(layer "B.SilkS")
		)
		(fp_line
			(start 0.7874 0.4064)
			(end 0.7874 -0.4064)
			(stroke
				(width 0.1524)
				(type default)
			)
			(layer "B.SilkS")
		)
		(fp_line
			(start -0.67945 -0.3048)
			(end -0.67945 0.3048)
			(stroke
				(width 0.1)
				(type default)
			)
			(layer "B.Fab")
		)
		(fp_line
			(start -0.67945 0.3048)
			(end -0.120396 0.3048)
			(stroke
				(width 0.1)
				(type default)
			)
			(layer "B.Fab")
		)
		(fp_line
			(start -0.12065 -0.3048)
			(end -0.67945 -0.3048)
			(stroke
				(width 0.1)
				(type default)
			)
			(layer "B.Fab")
		)
		(fp_line
			(start -0.12065 -0.2794)
			(end -0.12065 -0.3048)
			(stroke
				(width 0.1)
				(type default)
			)
			(layer "B.Fab")
		)
		(fp_line
			(start -0.120396 0.2794)
			(end 0.12065 0.2794)
			(stroke
				(width 0.1)
				(type default)
			)
			(layer "B.Fab")
		)
		(fp_line
			(start -0.120396 0.3048)
			(end -0.120396 0.2794)
			(stroke
				(width 0.1)
				(type default)
			)
			(layer "B.Fab")
		)
		(fp_line
			(start 0.12065 -0.305054)
			(end 0.12065 -0.2794)
			(stroke
				(width 0.1)
				(type default)
			)
			(layer "B.Fab")
		)
		(fp_line
			(start 0.12065 -0.2794)
			(end -0.12065 -0.2794)
			(stroke
				(width 0.1)
				(type default)
			)
			(layer "B.Fab")
		)
		(fp_line
			(start 0.12065 0.2794)
			(end 0.12065 0.3048)
			(stroke
				(width 0.1)
				(type default)
			)
			(layer "B.Fab")
		)
		(fp_line
			(start 0.12065 0.3048)
			(end 0.67945 0.3048)
			(stroke
				(width 0.1)
				(type default)
			)
			(layer "B.Fab")
		)
		(fp_line
			(start 0.67945 -0.305054)
			(end 0.12065 -0.305054)
			(stroke
				(width 0.1)
				(type default)
			)
			(layer "B.Fab")
		)
		(fp_line
			(start 0.67945 0.3048)
			(end 0.67945 -0.305054)
			(stroke
				(width 0.1)
				(type default)
			)
			(layer "B.Fab")
		)
		(pad "1" smd circle
			(at 0.40005 0 180)
			(size 0 0)
			(layers "B.Cu" "B.Mask" "B.Paste")
			(net "P1V2_AUX")
		)
		(pad "2" smd circle
			(at -0.40005 0 180)
			(size 0 0)
			(layers "B.Cu" "B.Mask" "B.Paste")
			(net "GND")
		)
	)
	(footprint ""
		(layer "B.Cu")
		(at 11.2776 -106.3752 -90)
		(property "Reference" "R847"
			(at 0 0 90)
			(layer "B.SilkS")
			(hide yes)
			(effects
				(font
					(size 1.27 1.27)
				)
				(justify mirror)
			)
		)
		(property "Value" ""
			(at 0 0 90)
			(layer "B.Fab")
			(effects
				(font
					(size 1.27 1.27)
				)
				(justify mirror)
			)
		)
		(duplicate_pad_numbers_are_jumpers no)
		(fp_line
			(start -0.7874 0.4064)
			(end 0.7874 0.4064)
			(stroke
				(width 0.1524)
				(type default)
			)
			(layer "B.SilkS")
		)
		(fp_line
			(start 0.7874 0.4064)
			(end 0.7874 -0.4064)
			(stroke
				(width 0.1524)
				(type default)
			)
			(layer "B.SilkS")
		)
		(fp_line
			(start -0.7874 -0.4064)
			(end -0.7874 0.4064)
			(stroke
				(width 0.1524)
				(type default)
			)
			(layer "B.SilkS")
		)
		(fp_line
			(start 0.7874 -0.4064)
			(end -0.7874 -0.4064)
			(stroke
				(width 0.1524)
				(type default)
			)
			(layer "B.SilkS")
		)
		(fp_line
			(start -0.67945 0.3048)
			(end -0.120396 0.3048)
			(stroke
				(width 0.1)
				(type default)
			)
			(layer "B.Fab")
		)
		(fp_line
			(start -0.120396 0.3048)
			(end -0.120396 0.2794)
			(stroke
				(width 0.1)
				(type default)
			)
			(layer "B.Fab")
		)
		(fp_line
			(start 0.12065 0.3048)
			(end 0.67945 0.3048)
			(stroke
				(width 0.1)
				(type default)
			)
			(layer "B.Fab")
		)
		(fp_line
			(start 0.67945 0.3048)
			(end 0.67945 -0.305054)
			(stroke
				(width 0.1)
				(type default)
			)
			(layer "B.Fab")
		)
		(fp_line
			(start -0.120396 0.2794)
			(end 0.12065 0.2794)
			(stroke
				(width 0.1)
				(type default)
			)
			(layer "B.Fab")
		)
		(fp_line
			(start 0.12065 0.2794)
			(end 0.12065 0.3048)
			(stroke
				(width 0.1)
				(type default)
			)
			(layer "B.Fab")
		)
		(fp_line
			(start -0.12065 -0.2794)
			(end -0.12065 -0.3048)
			(stroke
				(width 0.1)
				(type default)
			)
			(layer "B.Fab")
		)
		(fp_line
			(start 0.12065 -0.2794)
			(end -0.12065 -0.2794)
			(stroke
				(width 0.1)
				(type default)
			)
			(layer "B.Fab")
		)
		(fp_line
			(start -0.67945 -0.3048)
			(end -0.67945 0.3048)
			(stroke
				(width 0.1)
				(type default)
			)
			(layer "B.Fab")
		)
		(fp_line
			(start -0.12065 -0.3048)
			(end -0.67945 -0.3048)
			(stroke
				(width 0.1)
				(type default)
			)
			(layer "B.Fab")
		)
		(fp_line
			(start 0.12065 -0.305054)
			(end 0.12065 -0.2794)
			(stroke
				(width 0.1)
				(type default)
			)
			(layer "B.Fab")
		)
		(fp_line
			(start 0.67945 -0.305054)
			(end 0.12065 -0.305054)
			(stroke
				(width 0.1)
				(type default)
			)
			(layer "B.Fab")
		)
		(pad "1" smd circle
			(at 0.40005 0 90)
			(size 0 0)
			(layers "B.Cu" "B.Mask" "B.Paste")
			(net "PCH_BEEP_LED")
		)
		(pad "2" smd circle
			(at -0.40005 0 90)
			(size 0 0)
			(layers "B.Cu" "B.Mask" "B.Paste")
			(net "FM_PCH_BEEP_LED")
		)
	)
	(footprint ""
		(layer "B.Cu")
		(at 29.464 -91.059 180)
		(property "Reference" "R586"
			(at 0 0 0)
			(layer "B.SilkS")
			(hide yes)
			(effects
				(font
					(size 1.27 1.27)
				)
				(justify mirror)
			)
		)
		(property "Value" ""
			(at 0 0 0)
			(layer "B.Fab")
			(effects
				(font
					(size 1.27 1.27)
				)
				(justify mirror)
			)
		)
		(duplicate_pad_numbers_are_jumpers no)
		(fp_line
			(start 0.7874 0.4064)
			(end 0.7874 -0.4064)
			(stroke
				(width 0.1524)
				(type default)
			)
			(layer "B.SilkS")
		)
		(fp_line
			(start 0.7874 -0.4064)
			(end -0.7874 -0.4064)
			(stroke
				(width 0.1524)
				(type default)
			)
			(layer "B.SilkS")
		)
		(fp_line
			(start -0.7874 0.4064)
			(end 0.7874 0.4064)
			(stroke
				(width 0.1524)
				(type default)
			)
			(layer "B.SilkS")
		)
		(fp_line
			(start -0.7874 -0.4064)
			(end -0.7874 0.4064)
			(stroke
				(width 0.1524)
				(type default)
			)
			(layer "B.SilkS")
		)
		(fp_line
			(start 0.67945 0.3048)
			(end 0.67945 -0.305054)
			(stroke
				(width 0.1)
				(type default)
			)
			(layer "B.Fab")
		)
		(fp_line
			(start 0.67945 -0.305054)
			(end 0.12065 -0.305054)
			(stroke
				(width 0.1)
				(type default)
			)
			(layer "B.Fab")
		)
		(fp_line
			(start 0.12065 0.3048)
			(end 0.67945 0.3048)
			(stroke
				(width 0.1)
				(type default)
			)
			(layer "B.Fab")
		)
		(fp_line
			(start 0.12065 0.2794)
			(end 0.12065 0.3048)
			(stroke
				(width 0.1)
				(type default)
			)
			(layer "B.Fab")
		)
		(fp_line
			(start 0.12065 -0.2794)
			(end -0.12065 -0.2794)
			(stroke
				(width 0.1)
				(type default)
			)
			(layer "B.Fab")
		)
		(fp_line
			(start 0.12065 -0.305054)
			(end 0.12065 -0.2794)
			(stroke
				(width 0.1)
				(type default)
			)
			(layer "B.Fab")
		)
		(fp_line
			(start -0.120396 0.3048)
			(end -0.120396 0.2794)
			(stroke
				(width 0.1)
				(type default)
			)
			(layer "B.Fab")
		)
		(fp_line
			(start -0.120396 0.2794)
			(end 0.12065 0.2794)
			(stroke
				(width 0.1)
				(type default)
			)
			(layer "B.Fab")
		)
		(fp_line
			(start -0.12065 -0.2794)
			(end -0.12065 -0.3048)
			(stroke
				(width 0.1)
				(type default)
			)
			(layer "B.Fab")
		)
		(fp_line
			(start -0.12065 -0.3048)
			(end -0.67945 -0.3048)
			(stroke
				(width 0.1)
				(type default)
			)
			(layer "B.Fab")
		)
		(fp_line
			(start -0.67945 0.3048)
			(end -0.120396 0.3048)
			(stroke
				(width 0.1)
				(type default)
			)
			(layer "B.Fab")
		)
		(fp_line
			(start -0.67945 -0.3048)
			(end -0.67945 0.3048)
			(stroke
				(width 0.1)
				(type default)
			)
			(layer "B.Fab")
		)
		(pad "1" smd circle
			(at 0.40005 0)
			(size 0 0)
			(layers "B.Cu" "B.Mask" "B.Paste")
			(net "P3V3_AUX")
		)
		(pad "2" smd circle
			(at -0.40005 0)
			(size 0 0)
			(layers "B.Cu" "B.Mask" "B.Paste")
			(net "BMC_CPLD_GPIO_2")
		)
	)
	(footprint ""
		(layer "B.Cu")
		(at 55.8546 -66.0146 -90)
		(property "Reference" "R180"
			(at 0 0 90)
			(layer "B.SilkS")
			(hide yes)
			(effects
				(font
					(size 1.27 1.27)
				)
				(justify mirror)
			)
		)
		(property "Value" ""
			(at 0 0 90)
			(layer "B.Fab")
			(effects
				(font
					(size 1.27 1.27)
				)
				(justify mirror)
			)
		)
		(duplicate_pad_numbers_are_jumpers no)
		(fp_line
			(start -0.7874 0.4064)
			(end 0.7874 0.4064)
			(stroke
				(width 0.1524)
				(type default)
			)
			(layer "B.SilkS")
		)
		(fp_line
			(start 0.7874 0.4064)
			(end 0.7874 -0.4064)
			(stroke
				(width 0.1524)
				(type default)
			)
			(layer "B.SilkS")
		)
		(fp_line
			(start -0.7874 -0.4064)
			(end -0.7874 0.4064)
			(stroke
				(width 0.1524)
				(type default)
			)
			(layer "B.SilkS")
		)
		(fp_line
			(start 0.7874 -0.4064)
			(end -0.7874 -0.4064)
			(stroke
				(width 0.1524)
				(type default)
			)
			(layer "B.SilkS")
		)
		(fp_line
			(start -0.67945 0.3048)
			(end -0.120396 0.3048)
			(stroke
				(width 0.1)
				(type default)
			)
			(layer "B.Fab")
		)
		(fp_line
			(start -0.120396 0.3048)
			(end -0.120396 0.2794)
			(stroke
				(width 0.1)
				(type default)
			)
			(layer "B.Fab")
		)
		(fp_line
			(start 0.12065 0.3048)
			(end 0.67945 0.3048)
			(stroke
				(width 0.1)
				(type default)
			)
			(layer "B.Fab")
		)
		(fp_line
			(start 0.67945 0.3048)
			(end 0.67945 -0.305054)
			(stroke
				(width 0.1)
				(type default)
			)
			(layer "B.Fab")
		)
		(fp_line
			(start -0.120396 0.2794)
			(end 0.12065 0.2794)
			(stroke
				(width 0.1)
				(type default)
			)
			(layer "B.Fab")
		)
		(fp_line
			(start 0.12065 0.2794)
			(end 0.12065 0.3048)
			(stroke
				(width 0.1)
				(type default)
			)
			(layer "B.Fab")
		)
		(fp_line
			(start -0.12065 -0.2794)
			(end -0.12065 -0.3048)
			(stroke
				(width 0.1)
				(type default)
			)
			(layer "B.Fab")
		)
		(fp_line
			(start 0.12065 -0.2794)
			(end -0.12065 -0.2794)
			(stroke
				(width 0.1)
				(type default)
			)
			(layer "B.Fab")
		)
		(fp_line
			(start -0.67945 -0.3048)
			(end -0.67945 0.3048)
			(stroke
				(width 0.1)
				(type default)
			)
			(layer "B.Fab")
		)
		(fp_line
			(start -0.12065 -0.3048)
			(end -0.67945 -0.3048)
			(stroke
				(width 0.1)
				(type default)
			)
			(layer "B.Fab")
		)
		(fp_line
			(start 0.12065 -0.305054)
			(end 0.12065 -0.2794)
			(stroke
				(width 0.1)
				(type default)
			)
			(layer "B.Fab")
		)
		(fp_line
			(start 0.67945 -0.305054)
			(end 0.12065 -0.305054)
			(stroke
				(width 0.1)
				(type default)
			)
			(layer "B.Fab")
		)
		(pad "1" smd circle
			(at 0.40005 0 90)
			(size 0 0)
			(layers "B.Cu" "B.Mask" "B.Paste")
			(net "SPI_BMC_MISO_IO1_R")
		)
		(pad "2" smd circle
			(at -0.40005 0 90)
			(size 0 0)
			(layers "B.Cu" "B.Mask" "B.Paste")
			(net "SPI_BMC_BOOT_MISO")
		)
	)
	(footprint ""
		(layer "B.Cu")
		(at 85.281262 -44.427394 180)
		(property "Reference" "R358"
			(at 0 0 0)
			(layer "B.SilkS")
			(hide yes)
			(effects
				(font
					(size 1.27 1.27)
				)
				(justify mirror)
			)
		)
		(property "Value" ""
			(at 0 0 0)
			(layer "B.Fab")
			(effects
				(font
					(size 1.27 1.27)
				)
				(justify mirror)
			)
		)
		(duplicate_pad_numbers_are_jumpers no)
		(fp_line
			(start 0.7874 0.4064)
			(end 0.7874 -0.4064)
			(stroke
				(width 0.1524)
				(type default)
			)
			(layer "B.SilkS")
		)
		(fp_line
			(start 0.7874 -0.4064)
			(end -0.7874 -0.4064)
			(stroke
				(width 0.1524)
				(type default)
			)
			(layer "B.SilkS")
		)
		(fp_line
			(start -0.7874 0.4064)
			(end 0.7874 0.4064)
			(stroke
				(width 0.1524)
				(type default)
			)
			(layer "B.SilkS")
		)
		(fp_line
			(start -0.7874 -0.4064)
			(end -0.7874 0.4064)
			(stroke
				(width 0.1524)
				(type default)
			)
			(layer "B.SilkS")
		)
		(fp_line
			(start 0.67945 0.3048)
			(end 0.67945 -0.305054)
			(stroke
				(width 0.1)
				(type default)
			)
			(layer "B.Fab")
		)
		(fp_line
			(start 0.67945 -0.305054)
			(end 0.12065 -0.305054)
			(stroke
				(width 0.1)
				(type default)
			)
			(layer "B.Fab")
		)
		(fp_line
			(start 0.12065 0.3048)
			(end 0.67945 0.3048)
			(stroke
				(width 0.1)
				(type default)
			)
			(layer "B.Fab")
		)
		(fp_line
			(start 0.12065 0.2794)
			(end 0.12065 0.3048)
			(stroke
				(width 0.1)
				(type default)
			)
			(layer "B.Fab")
		)
		(fp_line
			(start 0.12065 -0.2794)
			(end -0.12065 -0.2794)
			(stroke
				(width 0.1)
				(type default)
			)
			(layer "B.Fab")
		)
		(fp_line
			(start 0.12065 -0.305054)
			(end 0.12065 -0.2794)
			(stroke
				(width 0.1)
				(type default)
			)
			(layer "B.Fab")
		)
		(fp_line
			(start -0.120396 0.3048)
			(end -0.120396 0.2794)
			(stroke
				(width 0.1)
				(type default)
			)
			(layer "B.Fab")
		)
		(fp_line
			(start -0.120396 0.2794)
			(end 0.12065 0.2794)
			(stroke
				(width 0.1)
				(type default)
			)
			(layer "B.Fab")
		)
		(fp_line
			(start -0.12065 -0.2794)
			(end -0.12065 -0.3048)
			(stroke
				(width 0.1)
				(type default)
			)
			(layer "B.Fab")
		)
		(fp_line
			(start -0.12065 -0.3048)
			(end -0.67945 -0.3048)
			(stroke
				(width 0.1)
				(type default)
			)
			(layer "B.Fab")
		)
		(fp_line
			(start -0.67945 0.3048)
			(end -0.120396 0.3048)
			(stroke
				(width 0.1)
				(type default)
			)
			(layer "B.Fab")
		)
		(fp_line
			(start -0.67945 -0.3048)
			(end -0.67945 0.3048)
			(stroke
				(width 0.1)
				(type default)
			)
			(layer "B.Fab")
		)
		(pad "1" smd circle
			(at 0.40005 0)
			(size 0 0)
			(layers "B.Cu" "B.Mask" "B.Paste")
			(net "M_BMC_DDR4_MA<7>")
		)
		(pad "2" smd circle
			(at -0.40005 0)
			(size 0 0)
			(layers "B.Cu" "B.Mask" "B.Paste")
			(net "P1V2_AUX")
		)
	)
	(footprint ""
		(layer "B.Cu")
		(at 85.29955 -45.443394 180)
		(property "Reference" "R356"
			(at 0 0 0)
			(layer "B.SilkS")
			(hide yes)
			(effects
				(font
					(size 1.27 1.27)
				)
				(justify mirror)
			)
		)
		(property "Value" ""
			(at 0 0 0)
			(layer "B.Fab")
			(effects
				(font
					(size 1.27 1.27)
				)
				(justify mirror)
			)
		)
		(duplicate_pad_numbers_are_jumpers no)
		(fp_line
			(start 0.7874 0.4064)
			(end 0.7874 -0.4064)
			(stroke
				(width 0.1524)
				(type default)
			)
			(layer "B.SilkS")
		)
		(fp_line
			(start 0.7874 -0.4064)
			(end -0.7874 -0.4064)
			(stroke
				(width 0.1524)
				(type default)
			)
			(layer "B.SilkS")
		)
		(fp_line
			(start -0.7874 0.4064)
			(end 0.7874 0.4064)
			(stroke
				(width 0.1524)
				(type default)
			)
			(layer "B.SilkS")
		)
		(fp_line
			(start -0.7874 -0.4064)
			(end -0.7874 0.4064)
			(stroke
				(width 0.1524)
				(type default)
			)
			(layer "B.SilkS")
		)
		(fp_line
			(start 0.67945 0.3048)
			(end 0.67945 -0.305054)
			(stroke
				(width 0.1)
				(type default)
			)
			(layer "B.Fab")
		)
		(fp_line
			(start 0.67945 -0.305054)
			(end 0.12065 -0.305054)
			(stroke
				(width 0.1)
				(type default)
			)
			(layer "B.Fab")
		)
		(fp_line
			(start 0.12065 0.3048)
			(end 0.67945 0.3048)
			(stroke
				(width 0.1)
				(type default)
			)
			(layer "B.Fab")
		)
		(fp_line
			(start 0.12065 0.2794)
			(end 0.12065 0.3048)
			(stroke
				(width 0.1)
				(type default)
			)
			(layer "B.Fab")
		)
		(fp_line
			(start 0.12065 -0.2794)
			(end -0.12065 -0.2794)
			(stroke
				(width 0.1)
				(type default)
			)
			(layer "B.Fab")
		)
		(fp_line
			(start 0.12065 -0.305054)
			(end 0.12065 -0.2794)
			(stroke
				(width 0.1)
				(type default)
			)
			(layer "B.Fab")
		)
		(fp_line
			(start -0.120396 0.3048)
			(end -0.120396 0.2794)
			(stroke
				(width 0.1)
				(type default)
			)
			(layer "B.Fab")
		)
		(fp_line
			(start -0.120396 0.2794)
			(end 0.12065 0.2794)
			(stroke
				(width 0.1)
				(type default)
			)
			(layer "B.Fab")
		)
		(fp_line
			(start -0.12065 -0.2794)
			(end -0.12065 -0.3048)
			(stroke
				(width 0.1)
				(type default)
			)
			(layer "B.Fab")
		)
		(fp_line
			(start -0.12065 -0.3048)
			(end -0.67945 -0.3048)
			(stroke
				(width 0.1)
				(type default)
			)
			(layer "B.Fab")
		)
		(fp_line
			(start -0.67945 0.3048)
			(end -0.120396 0.3048)
			(stroke
				(width 0.1)
				(type default)
			)
			(layer "B.Fab")
		)
		(fp_line
			(start -0.67945 -0.3048)
			(end -0.67945 0.3048)
			(stroke
				(width 0.1)
				(type default)
			)
			(layer "B.Fab")
		)
		(pad "1" smd circle
			(at 0.40005 0)
			(size 0 0)
			(layers "B.Cu" "B.Mask" "B.Paste")
			(net "M_BMC_DDR4_MA<5>")
		)
		(pad "2" smd circle
			(at -0.40005 0)
			(size 0 0)
			(layers "B.Cu" "B.Mask" "B.Paste")
			(net "P1V2_AUX")
		)
	)
	(footprint ""
		(layer "B.Cu")
		(at 27.31135 -86.778846)
		(property "Reference" "R459"
			(at 0 0 0)
			(layer "B.SilkS")
			(hide yes)
			(effects
				(font
					(size 1.27 1.27)
				)
				(justify mirror)
			)
		)
		(property "Value" ""
			(at 0 0 0)
			(layer "B.Fab")
			(effects
				(font
					(size 1.27 1.27)
				)
				(justify mirror)
			)
		)
		(duplicate_pad_numbers_are_jumpers no)
		(fp_line
			(start -0.7874 -0.4064)
			(end -0.7874 0.4064)
			(stroke
				(width 0.1524)
				(type default)
			)
			(layer "B.SilkS")
		)
		(fp_line
			(start -0.7874 0.4064)
			(end 0.7874 0.4064)
			(stroke
				(width 0.1524)
				(type default)
			)
			(layer "B.SilkS")
		)
		(fp_line
			(start 0.7874 -0.4064)
			(end -0.7874 -0.4064)
			(stroke
				(width 0.1524)
				(type default)
			)
			(layer "B.SilkS")
		)
		(fp_line
			(start 0.7874 0.4064)
			(end 0.7874 -0.4064)
			(stroke
				(width 0.1524)
				(type default)
			)
			(layer "B.SilkS")
		)
		(fp_line
			(start -0.67945 -0.3048)
			(end -0.67945 0.3048)
			(stroke
				(width 0.1)
				(type default)
			)
			(layer "B.Fab")
		)
		(fp_line
			(start -0.67945 0.3048)
			(end -0.120396 0.3048)
			(stroke
				(width 0.1)
				(type default)
			)
			(layer "B.Fab")
		)
		(fp_line
			(start -0.12065 -0.3048)
			(end -0.67945 -0.3048)
			(stroke
				(width 0.1)
				(type default)
			)
			(layer "B.Fab")
		)
		(fp_line
			(start -0.12065 -0.2794)
			(end -0.12065 -0.3048)
			(stroke
				(width 0.1)
				(type default)
			)
			(layer "B.Fab")
		)
		(fp_line
			(start -0.120396 0.2794)
			(end 0.12065 0.2794)
			(stroke
				(width 0.1)
				(type default)
			)
			(layer "B.Fab")
		)
		(fp_line
			(start -0.120396 0.3048)
			(end -0.120396 0.2794)
			(stroke
				(width 0.1)
				(type default)
			)
			(layer "B.Fab")
		)
		(fp_line
			(start 0.12065 -0.305054)
			(end 0.12065 -0.2794)
			(stroke
				(width 0.1)
				(type default)
			)
			(layer "B.Fab")
		)
		(fp_line
			(start 0.12065 -0.2794)
			(end -0.12065 -0.2794)
			(stroke
				(width 0.1)
				(type default)
			)
			(layer "B.Fab")
		)
		(fp_line
			(start 0.12065 0.2794)
			(end 0.12065 0.3048)
			(stroke
				(width 0.1)
				(type default)
			)
			(layer "B.Fab")
		)
		(fp_line
			(start 0.12065 0.3048)
			(end 0.67945 0.3048)
			(stroke
				(width 0.1)
				(type default)
			)
			(layer "B.Fab")
		)
		(fp_line
			(start 0.67945 -0.305054)
			(end 0.12065 -0.305054)
			(stroke
				(width 0.1)
				(type default)
			)
			(layer "B.Fab")
		)
		(fp_line
			(start 0.67945 0.3048)
			(end 0.67945 -0.305054)
			(stroke
				(width 0.1)
				(type default)
			)
			(layer "B.Fab")
		)
		(pad "1" smd circle
			(at 0.40005 0 180)
			(size 0 0)
			(layers "B.Cu" "B.Mask" "B.Paste")
			(net "BSM_PRSNT_R_N")
		)
		(pad "2" smd circle
			(at -0.40005 0 180)
			(size 0 0)
			(layers "B.Cu" "B.Mask" "B.Paste")
			(net "BSM_PRSNT_R1_N")
		)
	)
	(footprint ""
		(layer "B.Cu")
		(at 80.772 -33.4645 -90)
		(property "Reference" "R403"
			(at 0 0 90)
			(layer "B.SilkS")
			(hide yes)
			(effects
				(font
					(size 1.27 1.27)
				)
				(justify mirror)
			)
		)
		(property "Value" ""
			(at 0 0 90)
			(layer "B.Fab")
			(effects
				(font
					(size 1.27 1.27)
				)
				(justify mirror)
			)
		)
		(duplicate_pad_numbers_are_jumpers no)
		(fp_line
			(start -0.7874 0.4064)
			(end 0.7874 0.4064)
			(stroke
				(width 0.1524)
				(type default)
			)
			(layer "B.SilkS")
		)
		(fp_line
			(start 0.7874 0.4064)
			(end 0.7874 -0.4064)
			(stroke
				(width 0.1524)
				(type default)
			)
			(layer "B.SilkS")
		)
		(fp_line
			(start -0.7874 -0.4064)
			(end -0.7874 0.4064)
			(stroke
				(width 0.1524)
				(type default)
			)
			(layer "B.SilkS")
		)
		(fp_line
			(start 0.7874 -0.4064)
			(end -0.7874 -0.4064)
			(stroke
				(width 0.1524)
				(type default)
			)
			(layer "B.SilkS")
		)
		(fp_line
			(start -0.67945 0.3048)
			(end -0.120396 0.3048)
			(stroke
				(width 0.1)
				(type default)
			)
			(layer "B.Fab")
		)
		(fp_line
			(start -0.120396 0.3048)
			(end -0.120396 0.2794)
			(stroke
				(width 0.1)
				(type default)
			)
			(layer "B.Fab")
		)
		(fp_line
			(start 0.12065 0.3048)
			(end 0.67945 0.3048)
			(stroke
				(width 0.1)
				(type default)
			)
			(layer "B.Fab")
		)
		(fp_line
			(start 0.67945 0.3048)
			(end 0.67945 -0.305054)
			(stroke
				(width 0.1)
				(type default)
			)
			(layer "B.Fab")
		)
		(fp_line
			(start -0.120396 0.2794)
			(end 0.12065 0.2794)
			(stroke
				(width 0.1)
				(type default)
			)
			(layer "B.Fab")
		)
		(fp_line
			(start 0.12065 0.2794)
			(end 0.12065 0.3048)
			(stroke
				(width 0.1)
				(type default)
			)
			(layer "B.Fab")
		)
		(fp_line
			(start -0.12065 -0.2794)
			(end -0.12065 -0.3048)
			(stroke
				(width 0.1)
				(type default)
			)
			(layer "B.Fab")
		)
		(fp_line
			(start 0.12065 -0.2794)
			(end -0.12065 -0.2794)
			(stroke
				(width 0.1)
				(type default)
			)
			(layer "B.Fab")
		)
		(fp_line
			(start -0.67945 -0.3048)
			(end -0.67945 0.3048)
			(stroke
				(width 0.1)
				(type default)
			)
			(layer "B.Fab")
		)
		(fp_line
			(start -0.12065 -0.3048)
			(end -0.67945 -0.3048)
			(stroke
				(width 0.1)
				(type default)
			)
			(layer "B.Fab")
		)
		(fp_line
			(start 0.12065 -0.305054)
			(end 0.12065 -0.2794)
			(stroke
				(width 0.1)
				(type default)
			)
			(layer "B.Fab")
		)
		(fp_line
			(start 0.67945 -0.305054)
			(end 0.12065 -0.305054)
			(stroke
				(width 0.1)
				(type default)
			)
			(layer "B.Fab")
		)
		(pad "1" smd circle
			(at 0.40005 0 90)
			(size 0 0)
			(layers "B.Cu" "B.Mask" "B.Paste")
			(net "P3V3_AUX")
		)
		(pad "2" smd circle
			(at -0.40005 0 90)
			(size 0 0)
			(layers "B.Cu" "B.Mask" "B.Paste")
			(net "PWRGD_P2V5_AUX_R")
		)
	)
	(footprint ""
		(layer "B.Cu")
		(at 35.8902 -19.9898 180)
		(property "Reference" "C211"
			(at 0 0 0)
			(layer "B.SilkS")
			(hide yes)
			(effects
				(font
					(size 1.27 1.27)
				)
				(justify mirror)
			)
		)
		(property "Value" ""
			(at 0 0 0)
			(layer "B.Fab")
			(effects
				(font
					(size 1.27 1.27)
				)
				(justify mirror)
			)
		)
		(duplicate_pad_numbers_are_jumpers no)
		(fp_line
			(start 0.7874 0.4064)
			(end 0.7874 -0.4064)
			(stroke
				(width 0.1524)
				(type default)
			)
			(layer "B.SilkS")
		)
		(fp_line
			(start 0.7874 -0.4064)
			(end -0.7874 -0.4064)
			(stroke
				(width 0.1524)
				(type default)
			)
			(layer "B.SilkS")
		)
		(fp_line
			(start -0.7874 0.4064)
			(end 0.7874 0.4064)
			(stroke
				(width 0.1524)
				(type default)
			)
			(layer "B.SilkS")
		)
		(fp_line
			(start -0.7874 -0.4064)
			(end -0.7874 0.4064)
			(stroke
				(width 0.1524)
				(type default)
			)
			(layer "B.SilkS")
		)
		(fp_line
			(start 0.67945 0.3048)
			(end 0.67945 -0.305054)
			(stroke
				(width 0.1)
				(type default)
			)
			(layer "B.Fab")
		)
		(fp_line
			(start 0.67945 -0.305054)
			(end 0.12065 -0.305054)
			(stroke
				(width 0.1)
				(type default)
			)
			(layer "B.Fab")
		)
		(fp_line
			(start 0.12065 0.3048)
			(end 0.67945 0.3048)
			(stroke
				(width 0.1)
				(type default)
			)
			(layer "B.Fab")
		)
		(fp_line
			(start 0.12065 0.2794)
			(end 0.12065 0.3048)
			(stroke
				(width 0.1)
				(type default)
			)
			(layer "B.Fab")
		)
		(fp_line
			(start 0.12065 -0.2794)
			(end -0.12065 -0.2794)
			(stroke
				(width 0.1)
				(type default)
			)
			(layer "B.Fab")
		)
		(fp_line
			(start 0.12065 -0.305054)
			(end 0.12065 -0.2794)
			(stroke
				(width 0.1)
				(type default)
			)
			(layer "B.Fab")
		)
		(fp_line
			(start -0.120396 0.3048)
			(end -0.120396 0.2794)
			(stroke
				(width 0.1)
				(type default)
			)
			(layer "B.Fab")
		)
		(fp_line
			(start -0.120396 0.2794)
			(end 0.12065 0.2794)
			(stroke
				(width 0.1)
				(type default)
			)
			(layer "B.Fab")
		)
		(fp_line
			(start -0.12065 -0.2794)
			(end -0.12065 -0.3048)
			(stroke
				(width 0.1)
				(type default)
			)
			(layer "B.Fab")
		)
		(fp_line
			(start -0.12065 -0.3048)
			(end -0.67945 -0.3048)
			(stroke
				(width 0.1)
				(type default)
			)
			(layer "B.Fab")
		)
		(fp_line
			(start -0.67945 0.3048)
			(end -0.120396 0.3048)
			(stroke
				(width 0.1)
				(type default)
			)
			(layer "B.Fab")
		)
		(fp_line
			(start -0.67945 -0.3048)
			(end -0.67945 0.3048)
			(stroke
				(width 0.1)
				(type default)
			)
			(layer "B.Fab")
		)
		(pad "1" smd circle
			(at 0.40005 0)
			(size 0 0)
			(layers "B.Cu" "B.Mask" "B.Paste")
			(net "V_VGAHS_BUF")
		)
		(pad "2" smd circle
			(at -0.40005 0)
			(size 0 0)
			(layers "B.Cu" "B.Mask" "B.Paste")
			(net "GND")
		)
	)
	(footprint ""
		(layer "B.Cu")
		(at 47.4218 -76.2762)
		(property "Reference" "R111"
			(at 0 0 0)
			(layer "B.SilkS")
			(hide yes)
			(effects
				(font
					(size 1.27 1.27)
				)
				(justify mirror)
			)
		)
		(property "Value" ""
			(at 0 0 0)
			(layer "B.Fab")
			(effects
				(font
					(size 1.27 1.27)
				)
				(justify mirror)
			)
		)
		(duplicate_pad_numbers_are_jumpers no)
		(fp_line
			(start -0.7874 -0.4064)
			(end -0.7874 0.4064)
			(stroke
				(width 0.1524)
				(type default)
			)
			(layer "B.SilkS")
		)
		(fp_line
			(start -0.7874 0.4064)
			(end 0.7874 0.4064)
			(stroke
				(width 0.1524)
				(type default)
			)
			(layer "B.SilkS")
		)
		(fp_line
			(start 0.7874 -0.4064)
			(end -0.7874 -0.4064)
			(stroke
				(width 0.1524)
				(type default)
			)
			(layer "B.SilkS")
		)
		(fp_line
			(start 0.7874 0.4064)
			(end 0.7874 -0.4064)
			(stroke
				(width 0.1524)
				(type default)
			)
			(layer "B.SilkS")
		)
		(fp_line
			(start -0.67945 -0.3048)
			(end -0.67945 0.3048)
			(stroke
				(width 0.1)
				(type default)
			)
			(layer "B.Fab")
		)
		(fp_line
			(start -0.67945 0.3048)
			(end -0.120396 0.3048)
			(stroke
				(width 0.1)
				(type default)
			)
			(layer "B.Fab")
		)
		(fp_line
			(start -0.12065 -0.3048)
			(end -0.67945 -0.3048)
			(stroke
				(width 0.1)
				(type default)
			)
			(layer "B.Fab")
		)
		(fp_line
			(start -0.12065 -0.2794)
			(end -0.12065 -0.3048)
			(stroke
				(width 0.1)
				(type default)
			)
			(layer "B.Fab")
		)
		(fp_line
			(start -0.120396 0.2794)
			(end 0.12065 0.2794)
			(stroke
				(width 0.1)
				(type default)
			)
			(layer "B.Fab")
		)
		(fp_line
			(start -0.120396 0.3048)
			(end -0.120396 0.2794)
			(stroke
				(width 0.1)
				(type default)
			)
			(layer "B.Fab")
		)
		(fp_line
			(start 0.12065 -0.305054)
			(end 0.12065 -0.2794)
			(stroke
				(width 0.1)
				(type default)
			)
			(layer "B.Fab")
		)
		(fp_line
			(start 0.12065 -0.2794)
			(end -0.12065 -0.2794)
			(stroke
				(width 0.1)
				(type default)
			)
			(layer "B.Fab")
		)
		(fp_line
			(start 0.12065 0.2794)
			(end 0.12065 0.3048)
			(stroke
				(width 0.1)
				(type default)
			)
			(layer "B.Fab")
		)
		(fp_line
			(start 0.12065 0.3048)
			(end 0.67945 0.3048)
			(stroke
				(width 0.1)
				(type default)
			)
			(layer "B.Fab")
		)
		(fp_line
			(start 0.67945 -0.305054)
			(end 0.12065 -0.305054)
			(stroke
				(width 0.1)
				(type default)
			)
			(layer "B.Fab")
		)
		(fp_line
			(start 0.67945 0.3048)
			(end 0.67945 -0.305054)
			(stroke
				(width 0.1)
				(type default)
			)
			(layer "B.Fab")
		)
		(pad "1" smd circle
			(at 0.40005 0 180)
			(size 0 0)
			(layers "B.Cu" "B.Mask" "B.Paste")
			(net "FM_BMC_READY_R_PLD_N")
		)
		(pad "2" smd circle
			(at -0.40005 0 180)
			(size 0 0)
			(layers "B.Cu" "B.Mask" "B.Paste")
			(net "FM_BMC_READY_PLD_N")
		)
	)
	(footprint ""
		(layer "B.Cu")
		(at 24.202644 -95.130112 180)
		(property "Reference" "C263"
			(at 0 0 0)
			(layer "B.SilkS")
			(hide yes)
			(effects
				(font
					(size 1.27 1.27)
				)
				(justify mirror)
			)
		)
		(property "Value" ""
			(at 0 0 0)
			(layer "B.Fab")
			(effects
				(font
					(size 1.27 1.27)
				)
				(justify mirror)
			)
		)
		(duplicate_pad_numbers_are_jumpers no)
		(fp_line
			(start 0.69215 0.2921)
			(end 0.69215 -0.2921)
			(stroke
				(width 0.1524)
				(type default)
			)
			(layer "B.SilkS")
		)
		(fp_line
			(start 0.69215 -0.2921)
			(end -0.69215 -0.2921)
			(stroke
				(width 0.1524)
				(type default)
			)
			(layer "B.SilkS")
		)
		(fp_line
			(start -0.69215 0.2921)
			(end 0.69215 0.2921)
			(stroke
				(width 0.1524)
				(type default)
			)
			(layer "B.SilkS")
		)
		(fp_line
			(start -0.69215 -0.2921)
			(end -0.69215 0.2921)
			(stroke
				(width 0.1524)
				(type default)
			)
			(layer "B.SilkS")
		)
		(fp_line
			(start 0.51435 0.2794)
			(end 0.51435 -0.2794)
			(stroke
				(width 0.1)
				(type default)
			)
			(layer "B.Fab")
		)
		(fp_line
			(start 0.51435 -0.2794)
			(end -0.51435 -0.2794)
			(stroke
				(width 0.1)
				(type default)
			)
			(layer "B.Fab")
		)
		(fp_line
			(start -0.51435 0.2794)
			(end 0.51435 0.2794)
			(stroke
				(width 0.1)
				(type default)
			)
			(layer "B.Fab")
		)
		(fp_line
			(start -0.51435 -0.2794)
			(end -0.51435 0.2794)
			(stroke
				(width 0.1)
				(type default)
			)
			(layer "B.Fab")
		)
		(pad "1" smd circle
			(at 0.40005 0)
			(size 0 0)
			(layers "B.Cu" "B.Mask" "B.Paste")
			(net "PVCCA_AUX_PLD")
		)
		(pad "2" smd circle
			(at -0.40005 0)
			(size 0 0)
			(layers "B.Cu" "B.Mask" "B.Paste")
			(net "GND")
		)
		(zone
			(layer "B.Cu")
			(hatch none 0.5)
			(connect_pads
				(clearance 0)
			)
			(min_thickness 0.25)
			(keepout
				(tracks not_allowed)
				(vias allowed)
				(pads allowed)
				(copperpour not_allowed)
				(footprints allowed)
			)
			(placement
				(enabled no)
				(sheetname "")
			)
			(fill
				(thermal_gap 0.5)
				(thermal_bridge_width 0.5)
				(island_removal_mode 0)
			)
			(polygon
				(pts
					(xy 24.012144 -95.217742) (xy 24.103584 -95.275908) (xy 24.302974 -95.275908) (xy 24.393144 -95.217742)
					(xy 24.393144 -95.042482) (xy 24.302974 -94.984062) (xy 24.103584 -94.984062) (xy 24.012144 -95.042228)
				)
			)
		)
	)
	(footprint ""
		(layer "B.Cu")
		(at 56.861964 -70.046342)
		(property "Reference" "R783"
			(at 0 0 0)
			(layer "B.SilkS")
			(hide yes)
			(effects
				(font
					(size 1.27 1.27)
				)
				(justify mirror)
			)
		)
		(property "Value" ""
			(at 0 0 0)
			(layer "B.Fab")
			(effects
				(font
					(size 1.27 1.27)
				)
				(justify mirror)
			)
		)
		(duplicate_pad_numbers_are_jumpers no)
		(fp_line
			(start -0.7874 -0.4064)
			(end -0.7874 0.4064)
			(stroke
				(width 0.1524)
				(type default)
			)
			(layer "B.SilkS")
		)
		(fp_line
			(start -0.7874 0.4064)
			(end 0.7874 0.4064)
			(stroke
				(width 0.1524)
				(type default)
			)
			(layer "B.SilkS")
		)
		(fp_line
			(start 0.7874 -0.4064)
			(end -0.7874 -0.4064)
			(stroke
				(width 0.1524)
				(type default)
			)
			(layer "B.SilkS")
		)
		(fp_line
			(start 0.7874 0.4064)
			(end 0.7874 -0.4064)
			(stroke
				(width 0.1524)
				(type default)
			)
			(layer "B.SilkS")
		)
		(fp_line
			(start -0.67945 -0.3048)
			(end -0.67945 0.3048)
			(stroke
				(width 0.1)
				(type default)
			)
			(layer "B.Fab")
		)
		(fp_line
			(start -0.67945 0.3048)
			(end -0.120396 0.3048)
			(stroke
				(width 0.1)
				(type default)
			)
			(layer "B.Fab")
		)
		(fp_line
			(start -0.12065 -0.3048)
			(end -0.67945 -0.3048)
			(stroke
				(width 0.1)
				(type default)
			)
			(layer "B.Fab")
		)
		(fp_line
			(start -0.12065 -0.2794)
			(end -0.12065 -0.3048)
			(stroke
				(width 0.1)
				(type default)
			)
			(layer "B.Fab")
		)
		(fp_line
			(start -0.120396 0.2794)
			(end 0.12065 0.2794)
			(stroke
				(width 0.1)
				(type default)
			)
			(layer "B.Fab")
		)
		(fp_line
			(start -0.120396 0.3048)
			(end -0.120396 0.2794)
			(stroke
				(width 0.1)
				(type default)
			)
			(layer "B.Fab")
		)
		(fp_line
			(start 0.12065 -0.305054)
			(end 0.12065 -0.2794)
			(stroke
				(width 0.1)
				(type default)
			)
			(layer "B.Fab")
		)
		(fp_line
			(start 0.12065 -0.2794)
			(end -0.12065 -0.2794)
			(stroke
				(width 0.1)
				(type default)
			)
			(layer "B.Fab")
		)
		(fp_line
			(start 0.12065 0.2794)
			(end 0.12065 0.3048)
			(stroke
				(width 0.1)
				(type default)
			)
			(layer "B.Fab")
		)
		(fp_line
			(start 0.12065 0.3048)
			(end 0.67945 0.3048)
			(stroke
				(width 0.1)
				(type default)
			)
			(layer "B.Fab")
		)
		(fp_line
			(start 0.67945 -0.305054)
			(end 0.12065 -0.305054)
			(stroke
				(width 0.1)
				(type default)
			)
			(layer "B.Fab")
		)
		(fp_line
			(start 0.67945 0.3048)
			(end 0.67945 -0.305054)
			(stroke
				(width 0.1)
				(type default)
			)
			(layer "B.Fab")
		)
		(pad "1" smd circle
			(at 0.40005 0 180)
			(size 0 0)
			(layers "B.Cu" "B.Mask" "B.Paste")
			(net "P1V8_AUX")
		)
		(pad "2" smd circle
			(at -0.40005 0 180)
			(size 0 0)
			(layers "B.Cu" "B.Mask" "B.Paste")
			(net "ADCVREFEXT0")
		)
	)
	(footprint ""
		(layer "B.Cu")
		(at 82.933794 -49.907444 180)
		(property "Reference" "C1"
			(at 0 0 0)
			(layer "B.SilkS")
			(hide yes)
			(effects
				(font
					(size 1.27 1.27)
				)
				(justify mirror)
			)
		)
		(property "Value" ""
			(at 0 0 0)
			(layer "B.Fab")
			(effects
				(font
					(size 1.27 1.27)
				)
				(justify mirror)
			)
		)
		(duplicate_pad_numbers_are_jumpers no)
		(fp_line
			(start 1.2954 0.5842)
			(end 1.2954 -0.5842)
			(stroke
				(width 0.1524)
				(type default)
			)
			(layer "B.SilkS")
		)
		(fp_line
			(start 1.2954 -0.5842)
			(end -1.2954 -0.5842)
			(stroke
				(width 0.1524)
				(type default)
			)
			(layer "B.SilkS")
		)
		(fp_line
			(start 0 -0.5842)
			(end 0 0.5842)
			(stroke
				(width 0.1524)
				(type default)
			)
			(layer "B.SilkS")
		)
		(fp_line
			(start -1.2954 0.5842)
			(end 1.2954 0.5842)
			(stroke
				(width 0.1524)
				(type default)
			)
			(layer "B.SilkS")
		)
		(fp_line
			(start -1.2954 -0.5842)
			(end -1.2954 0.5842)
			(stroke
				(width 0.1524)
				(type default)
			)
			(layer "B.SilkS")
		)
		(fp_line
			(start 1.1938 0.4064)
			(end 1.1938 -0.4064)
			(stroke
				(width 0.1)
				(type default)
			)
			(layer "B.Fab")
		)
		(fp_line
			(start 1.1938 -0.4064)
			(end 0.8636 -0.4064)
			(stroke
				(width 0.1)
				(type default)
			)
			(layer "B.Fab")
		)
		(fp_line
			(start 0.8636 0.4572)
			(end 0.8636 0.4064)
			(stroke
				(width 0.1)
				(type default)
			)
			(layer "B.Fab")
		)
		(fp_line
			(start 0.8636 0.4064)
			(end 1.1938 0.4064)
			(stroke
				(width 0.1)
				(type default)
			)
			(layer "B.Fab")
		)
		(fp_line
			(start 0.8636 -0.4064)
			(end 0.8636 -0.4572)
			(stroke
				(width 0.1)
				(type default)
			)
			(layer "B.Fab")
		)
		(fp_line
			(start 0.8636 -0.4572)
			(end -0.8636 -0.4572)
			(stroke
				(width 0.1)
				(type default)
			)
			(layer "B.Fab")
		)
		(fp_line
			(start -0.8636 0.4572)
			(end 0.8636 0.4572)
			(stroke
				(width 0.1)
				(type default)
			)
			(layer "B.Fab")
		)
		(fp_line
			(start -0.8636 0.4064)
			(end -0.8636 0.4572)
			(stroke
				(width 0.1)
				(type default)
			)
			(layer "B.Fab")
		)
		(fp_line
			(start -0.8636 -0.4064)
			(end -1.1938 -0.4064)
			(stroke
				(width 0.1)
				(type default)
			)
			(layer "B.Fab")
		)
		(fp_line
			(start -0.8636 -0.4572)
			(end -0.8636 -0.4064)
			(stroke
				(width 0.1)
				(type default)
			)
			(layer "B.Fab")
		)
		(fp_line
			(start -1.1938 0.4064)
			(end -0.8636 0.4064)
			(stroke
				(width 0.1)
				(type default)
			)
			(layer "B.Fab")
		)
		(fp_line
			(start -1.1938 -0.4064)
			(end -1.1938 0.4064)
			(stroke
				(width 0.1)
				(type default)
			)
			(layer "B.Fab")
		)
		(pad "1" smd rect
			(at 0.7366 0 90)
			(size 0.7112 0.8128)
			(layers "B.Cu" "B.Mask" "B.Paste")
			(net "P1V2_AUX")
		)
		(pad "2" smd rect
			(at -0.7366 0 90)
			(size 0.7112 0.8128)
			(layers "B.Cu" "B.Mask" "B.Paste")
			(net "GND")
		)
	)
	(footprint ""
		(layer "B.Cu")
		(at 56.7436 -67.818 -90)
		(property "Reference" "R402"
			(at 0 0 90)
			(layer "B.SilkS")
			(hide yes)
			(effects
				(font
					(size 1.27 1.27)
				)
				(justify mirror)
			)
		)
		(property "Value" ""
			(at 0 0 90)
			(layer "B.Fab")
			(effects
				(font
					(size 1.27 1.27)
				)
				(justify mirror)
			)
		)
		(duplicate_pad_numbers_are_jumpers no)
		(fp_line
			(start -0.7874 0.4064)
			(end 0.7874 0.4064)
			(stroke
				(width 0.1524)
				(type default)
			)
			(layer "B.SilkS")
		)
		(fp_line
			(start 0.7874 0.4064)
			(end 0.7874 -0.4064)
			(stroke
				(width 0.1524)
				(type default)
			)
			(layer "B.SilkS")
		)
		(fp_line
			(start -0.7874 -0.4064)
			(end -0.7874 0.4064)
			(stroke
				(width 0.1524)
				(type default)
			)
			(layer "B.SilkS")
		)
		(fp_line
			(start 0.7874 -0.4064)
			(end -0.7874 -0.4064)
			(stroke
				(width 0.1524)
				(type default)
			)
			(layer "B.SilkS")
		)
		(fp_line
			(start -0.67945 0.3048)
			(end -0.120396 0.3048)
			(stroke
				(width 0.1)
				(type default)
			)
			(layer "B.Fab")
		)
		(fp_line
			(start -0.120396 0.3048)
			(end -0.120396 0.2794)
			(stroke
				(width 0.1)
				(type default)
			)
			(layer "B.Fab")
		)
		(fp_line
			(start 0.12065 0.3048)
			(end 0.67945 0.3048)
			(stroke
				(width 0.1)
				(type default)
			)
			(layer "B.Fab")
		)
		(fp_line
			(start 0.67945 0.3048)
			(end 0.67945 -0.305054)
			(stroke
				(width 0.1)
				(type default)
			)
			(layer "B.Fab")
		)
		(fp_line
			(start -0.120396 0.2794)
			(end 0.12065 0.2794)
			(stroke
				(width 0.1)
				(type default)
			)
			(layer "B.Fab")
		)
		(fp_line
			(start 0.12065 0.2794)
			(end 0.12065 0.3048)
			(stroke
				(width 0.1)
				(type default)
			)
			(layer "B.Fab")
		)
		(fp_line
			(start -0.12065 -0.2794)
			(end -0.12065 -0.3048)
			(stroke
				(width 0.1)
				(type default)
			)
			(layer "B.Fab")
		)
		(fp_line
			(start 0.12065 -0.2794)
			(end -0.12065 -0.2794)
			(stroke
				(width 0.1)
				(type default)
			)
			(layer "B.Fab")
		)
		(fp_line
			(start -0.67945 -0.3048)
			(end -0.67945 0.3048)
			(stroke
				(width 0.1)
				(type default)
			)
			(layer "B.Fab")
		)
		(fp_line
			(start -0.12065 -0.3048)
			(end -0.67945 -0.3048)
			(stroke
				(width 0.1)
				(type default)
			)
			(layer "B.Fab")
		)
		(fp_line
			(start 0.12065 -0.305054)
			(end 0.12065 -0.2794)
			(stroke
				(width 0.1)
				(type default)
			)
			(layer "B.Fab")
		)
		(fp_line
			(start 0.67945 -0.305054)
			(end 0.12065 -0.305054)
			(stroke
				(width 0.1)
				(type default)
			)
			(layer "B.Fab")
		)
		(pad "1" smd circle
			(at 0.40005 0 90)
			(size 0 0)
			(layers "B.Cu" "B.Mask" "B.Paste")
			(net "PU_FWSPIWP_N")
		)
		(pad "2" smd circle
			(at -0.40005 0 90)
			(size 0 0)
			(layers "B.Cu" "B.Mask" "B.Paste")
			(net "PU_FWSPIWP_N_R")
		)
	)
	(footprint ""
		(layer "B.Cu")
		(at 39.742618 -52.779676 -90)
		(property "Reference" "R279"
			(at 0 0 90)
			(layer "B.SilkS")
			(hide yes)
			(effects
				(font
					(size 1.27 1.27)
				)
				(justify mirror)
			)
		)
		(property "Value" ""
			(at 0 0 90)
			(layer "B.Fab")
			(effects
				(font
					(size 1.27 1.27)
				)
				(justify mirror)
			)
		)
		(duplicate_pad_numbers_are_jumpers no)
		(fp_line
			(start -0.7874 0.4064)
			(end 0.7874 0.4064)
			(stroke
				(width 0.1524)
				(type default)
			)
			(layer "B.SilkS")
		)
		(fp_line
			(start 0.7874 0.4064)
			(end 0.7874 -0.4064)
			(stroke
				(width 0.1524)
				(type default)
			)
			(layer "B.SilkS")
		)
		(fp_line
			(start -0.7874 -0.4064)
			(end -0.7874 0.4064)
			(stroke
				(width 0.1524)
				(type default)
			)
			(layer "B.SilkS")
		)
		(fp_line
			(start 0.7874 -0.4064)
			(end -0.7874 -0.4064)
			(stroke
				(width 0.1524)
				(type default)
			)
			(layer "B.SilkS")
		)
		(fp_line
			(start -0.67945 0.3048)
			(end -0.120396 0.3048)
			(stroke
				(width 0.1)
				(type default)
			)
			(layer "B.Fab")
		)
		(fp_line
			(start -0.120396 0.3048)
			(end -0.120396 0.2794)
			(stroke
				(width 0.1)
				(type default)
			)
			(layer "B.Fab")
		)
		(fp_line
			(start 0.12065 0.3048)
			(end 0.67945 0.3048)
			(stroke
				(width 0.1)
				(type default)
			)
			(layer "B.Fab")
		)
		(fp_line
			(start 0.67945 0.3048)
			(end 0.67945 -0.305054)
			(stroke
				(width 0.1)
				(type default)
			)
			(layer "B.Fab")
		)
		(fp_line
			(start -0.120396 0.2794)
			(end 0.12065 0.2794)
			(stroke
				(width 0.1)
				(type default)
			)
			(layer "B.Fab")
		)
		(fp_line
			(start 0.12065 0.2794)
			(end 0.12065 0.3048)
			(stroke
				(width 0.1)
				(type default)
			)
			(layer "B.Fab")
		)
		(fp_line
			(start -0.12065 -0.2794)
			(end -0.12065 -0.3048)
			(stroke
				(width 0.1)
				(type default)
			)
			(layer "B.Fab")
		)
		(fp_line
			(start 0.12065 -0.2794)
			(end -0.12065 -0.2794)
			(stroke
				(width 0.1)
				(type default)
			)
			(layer "B.Fab")
		)
		(fp_line
			(start -0.67945 -0.3048)
			(end -0.67945 0.3048)
			(stroke
				(width 0.1)
				(type default)
			)
			(layer "B.Fab")
		)
		(fp_line
			(start -0.12065 -0.3048)
			(end -0.67945 -0.3048)
			(stroke
				(width 0.1)
				(type default)
			)
			(layer "B.Fab")
		)
		(fp_line
			(start 0.12065 -0.305054)
			(end 0.12065 -0.2794)
			(stroke
				(width 0.1)
				(type default)
			)
			(layer "B.Fab")
		)
		(fp_line
			(start 0.67945 -0.305054)
			(end 0.12065 -0.305054)
			(stroke
				(width 0.1)
				(type default)
			)
			(layer "B.Fab")
		)
		(pad "1" smd circle
			(at 0.40005 0 90)
			(size 0 0)
			(layers "B.Cu" "B.Mask" "B.Paste")
			(net "P1V0_AUX")
		)
		(pad "2" smd circle
			(at -0.40005 0 90)
			(size 0 0)
			(layers "B.Cu" "B.Mask" "B.Paste")
			(net "P1V2_P1V0_I3C_VDDL1")
		)
	)
	(footprint ""
		(layer "B.Cu")
		(at 62.992 -24.257 -90)
		(property "Reference" "C149"
			(at 0 0 90)
			(layer "B.SilkS")
			(hide yes)
			(effects
				(font
					(size 1.27 1.27)
				)
				(justify mirror)
			)
		)
		(property "Value" ""
			(at 0 0 90)
			(layer "B.Fab")
			(effects
				(font
					(size 1.27 1.27)
				)
				(justify mirror)
			)
		)
		(duplicate_pad_numbers_are_jumpers no)
		(fp_line
			(start -0.7874 0.4064)
			(end 0.7874 0.4064)
			(stroke
				(width 0.1524)
				(type default)
			)
			(layer "B.SilkS")
		)
		(fp_line
			(start 0.7874 0.4064)
			(end 0.7874 -0.4064)
			(stroke
				(width 0.1524)
				(type default)
			)
			(layer "B.SilkS")
		)
		(fp_line
			(start -0.7874 -0.4064)
			(end -0.7874 0.4064)
			(stroke
				(width 0.1524)
				(type default)
			)
			(layer "B.SilkS")
		)
		(fp_line
			(start 0.7874 -0.4064)
			(end -0.7874 -0.4064)
			(stroke
				(width 0.1524)
				(type default)
			)
			(layer "B.SilkS")
		)
		(fp_line
			(start -0.67945 0.3048)
			(end -0.120396 0.3048)
			(stroke
				(width 0.1)
				(type default)
			)
			(layer "B.Fab")
		)
		(fp_line
			(start -0.120396 0.3048)
			(end -0.120396 0.2794)
			(stroke
				(width 0.1)
				(type default)
			)
			(layer "B.Fab")
		)
		(fp_line
			(start 0.12065 0.3048)
			(end 0.67945 0.3048)
			(stroke
				(width 0.1)
				(type default)
			)
			(layer "B.Fab")
		)
		(fp_line
			(start 0.67945 0.3048)
			(end 0.67945 -0.305054)
			(stroke
				(width 0.1)
				(type default)
			)
			(layer "B.Fab")
		)
		(fp_line
			(start -0.120396 0.2794)
			(end 0.12065 0.2794)
			(stroke
				(width 0.1)
				(type default)
			)
			(layer "B.Fab")
		)
		(fp_line
			(start 0.12065 0.2794)
			(end 0.12065 0.3048)
			(stroke
				(width 0.1)
				(type default)
			)
			(layer "B.Fab")
		)
		(fp_line
			(start -0.12065 -0.2794)
			(end -0.12065 -0.3048)
			(stroke
				(width 0.1)
				(type default)
			)
			(layer "B.Fab")
		)
		(fp_line
			(start 0.12065 -0.2794)
			(end -0.12065 -0.2794)
			(stroke
				(width 0.1)
				(type default)
			)
			(layer "B.Fab")
		)
		(fp_line
			(start -0.67945 -0.3048)
			(end -0.67945 0.3048)
			(stroke
				(width 0.1)
				(type default)
			)
			(layer "B.Fab")
		)
		(fp_line
			(start -0.12065 -0.3048)
			(end -0.67945 -0.3048)
			(stroke
				(width 0.1)
				(type default)
			)
			(layer "B.Fab")
		)
		(fp_line
			(start 0.12065 -0.305054)
			(end 0.12065 -0.2794)
			(stroke
				(width 0.1)
				(type default)
			)
			(layer "B.Fab")
		)
		(fp_line
			(start 0.67945 -0.305054)
			(end 0.12065 -0.305054)
			(stroke
				(width 0.1)
				(type default)
			)
			(layer "B.Fab")
		)
		(pad "1" smd circle
			(at 0.40005 0 90)
			(size 0 0)
			(layers "B.Cu" "B.Mask" "B.Paste")
			(net "P3V3_AUX")
		)
		(pad "2" smd circle
			(at -0.40005 0 90)
			(size 0 0)
			(layers "B.Cu" "B.Mask" "B.Paste")
			(net "GND")
		)
	)
	(footprint ""
		(layer "B.Cu")
		(at 43.942 -19.431 90)
		(property "Reference" "R693"
			(at 0 0 90)
			(layer "B.SilkS")
			(hide yes)
			(effects
				(font
					(size 1.27 1.27)
				)
				(justify mirror)
			)
		)
		(property "Value" ""
			(at 0 0 90)
			(layer "B.Fab")
			(effects
				(font
					(size 1.27 1.27)
				)
				(justify mirror)
			)
		)
		(duplicate_pad_numbers_are_jumpers no)
		(fp_line
			(start 0.7874 -0.4064)
			(end -0.7874 -0.4064)
			(stroke
				(width 0.1524)
				(type default)
			)
			(layer "B.SilkS")
		)
		(fp_line
			(start -0.7874 -0.4064)
			(end -0.7874 0.4064)
			(stroke
				(width 0.1524)
				(type default)
			)
			(layer "B.SilkS")
		)
		(fp_line
			(start 0.7874 0.4064)
			(end 0.7874 -0.4064)
			(stroke
				(width 0.1524)
				(type default)
			)
			(layer "B.SilkS")
		)
		(fp_line
			(start -0.7874 0.4064)
			(end 0.7874 0.4064)
			(stroke
				(width 0.1524)
				(type default)
			)
			(layer "B.SilkS")
		)
		(fp_line
			(start 0.67945 -0.305054)
			(end 0.12065 -0.305054)
			(stroke
				(width 0.1)
				(type default)
			)
			(layer "B.Fab")
		)
		(fp_line
			(start 0.12065 -0.305054)
			(end 0.12065 -0.2794)
			(stroke
				(width 0.1)
				(type default)
			)
			(layer "B.Fab")
		)
		(fp_line
			(start -0.12065 -0.3048)
			(end -0.67945 -0.3048)
			(stroke
				(width 0.1)
				(type default)
			)
			(layer "B.Fab")
		)
		(fp_line
			(start -0.67945 -0.3048)
			(end -0.67945 0.3048)
			(stroke
				(width 0.1)
				(type default)
			)
			(layer "B.Fab")
		)
		(fp_line
			(start 0.12065 -0.2794)
			(end -0.12065 -0.2794)
			(stroke
				(width 0.1)
				(type default)
			)
			(layer "B.Fab")
		)
		(fp_line
			(start -0.12065 -0.2794)
			(end -0.12065 -0.3048)
			(stroke
				(width 0.1)
				(type default)
			)
			(layer "B.Fab")
		)
		(fp_line
			(start 0.12065 0.2794)
			(end 0.12065 0.3048)
			(stroke
				(width 0.1)
				(type default)
			)
			(layer "B.Fab")
		)
		(fp_line
			(start -0.120396 0.2794)
			(end 0.12065 0.2794)
			(stroke
				(width 0.1)
				(type default)
			)
			(layer "B.Fab")
		)
		(fp_line
			(start 0.67945 0.3048)
			(end 0.67945 -0.305054)
			(stroke
				(width 0.1)
				(type default)
			)
			(layer "B.Fab")
		)
		(fp_line
			(start 0.12065 0.3048)
			(end 0.67945 0.3048)
			(stroke
				(width 0.1)
				(type default)
			)
			(layer "B.Fab")
		)
		(fp_line
			(start -0.120396 0.3048)
			(end -0.120396 0.2794)
			(stroke
				(width 0.1)
				(type default)
			)
			(layer "B.Fab")
		)
		(fp_line
			(start -0.67945 0.3048)
			(end -0.120396 0.3048)
			(stroke
				(width 0.1)
				(type default)
			)
			(layer "B.Fab")
		)
		(pad "1" smd circle
			(at 0.40005 0 270)
			(size 0 0)
			(layers "B.Cu" "B.Mask" "B.Paste")
			(net "DEBUG_PORT_PRSNT")
		)
		(pad "2" smd circle
			(at -0.40005 0 270)
			(size 0 0)
			(layers "B.Cu" "B.Mask" "B.Paste")
			(net "DEBUG_PORT_PRSNT_R")
		)
	)
	(footprint ""
		(layer "B.Cu")
		(at 41.966134 -48.44415)
		(property "Reference" "R819"
			(at 0 0 0)
			(layer "B.SilkS")
			(hide yes)
			(effects
				(font
					(size 1.27 1.27)
				)
				(justify mirror)
			)
		)
		(property "Value" ""
			(at 0 0 0)
			(layer "B.Fab")
			(effects
				(font
					(size 1.27 1.27)
				)
				(justify mirror)
			)
		)
		(duplicate_pad_numbers_are_jumpers no)
		(fp_line
			(start -0.7874 -0.4064)
			(end -0.7874 0.4064)
			(stroke
				(width 0.1524)
				(type default)
			)
			(layer "B.SilkS")
		)
		(fp_line
			(start -0.7874 0.4064)
			(end 0.7874 0.4064)
			(stroke
				(width 0.1524)
				(type default)
			)
			(layer "B.SilkS")
		)
		(fp_line
			(start 0.7874 -0.4064)
			(end -0.7874 -0.4064)
			(stroke
				(width 0.1524)
				(type default)
			)
			(layer "B.SilkS")
		)
		(fp_line
			(start 0.7874 0.4064)
			(end 0.7874 -0.4064)
			(stroke
				(width 0.1524)
				(type default)
			)
			(layer "B.SilkS")
		)
		(fp_line
			(start -0.67945 -0.3048)
			(end -0.67945 0.3048)
			(stroke
				(width 0.1)
				(type default)
			)
			(layer "B.Fab")
		)
		(fp_line
			(start -0.67945 0.3048)
			(end -0.120396 0.3048)
			(stroke
				(width 0.1)
				(type default)
			)
			(layer "B.Fab")
		)
		(fp_line
			(start -0.12065 -0.3048)
			(end -0.67945 -0.3048)
			(stroke
				(width 0.1)
				(type default)
			)
			(layer "B.Fab")
		)
		(fp_line
			(start -0.12065 -0.2794)
			(end -0.12065 -0.3048)
			(stroke
				(width 0.1)
				(type default)
			)
			(layer "B.Fab")
		)
		(fp_line
			(start -0.120396 0.2794)
			(end 0.12065 0.2794)
			(stroke
				(width 0.1)
				(type default)
			)
			(layer "B.Fab")
		)
		(fp_line
			(start -0.120396 0.3048)
			(end -0.120396 0.2794)
			(stroke
				(width 0.1)
				(type default)
			)
			(layer "B.Fab")
		)
		(fp_line
			(start 0.12065 -0.305054)
			(end 0.12065 -0.2794)
			(stroke
				(width 0.1)
				(type default)
			)
			(layer "B.Fab")
		)
		(fp_line
			(start 0.12065 -0.2794)
			(end -0.12065 -0.2794)
			(stroke
				(width 0.1)
				(type default)
			)
			(layer "B.Fab")
		)
		(fp_line
			(start 0.12065 0.2794)
			(end 0.12065 0.3048)
			(stroke
				(width 0.1)
				(type default)
			)
			(layer "B.Fab")
		)
		(fp_line
			(start 0.12065 0.3048)
			(end 0.67945 0.3048)
			(stroke
				(width 0.1)
				(type default)
			)
			(layer "B.Fab")
		)
		(fp_line
			(start 0.67945 -0.305054)
			(end 0.12065 -0.305054)
			(stroke
				(width 0.1)
				(type default)
			)
			(layer "B.Fab")
		)
		(fp_line
			(start 0.67945 0.3048)
			(end 0.67945 -0.305054)
			(stroke
				(width 0.1)
				(type default)
			)
			(layer "B.Fab")
		)
		(pad "1" smd circle
			(at 0.40005 0 180)
			(size 0 0)
			(layers "B.Cu" "B.Mask" "B.Paste")
			(net "SMB_BMC_MM14_R_SCL")
		)
		(pad "2" smd circle
			(at -0.40005 0 180)
			(size 0 0)
			(layers "B.Cu" "B.Mask" "B.Paste")
			(net "GND")
		)
	)
	(footprint ""
		(layer "B.Cu")
		(at 43.88866 -76.4286 180)
		(property "Reference" "R852"
			(at 0 0 0)
			(layer "B.SilkS")
			(hide yes)
			(effects
				(font
					(size 1.27 1.27)
				)
				(justify mirror)
			)
		)
		(property "Value" ""
			(at 0 0 0)
			(layer "B.Fab")
			(effects
				(font
					(size 1.27 1.27)
				)
				(justify mirror)
			)
		)
		(duplicate_pad_numbers_are_jumpers no)
		(fp_line
			(start 0.7874 0.4064)
			(end 0.7874 -0.4064)
			(stroke
				(width 0.1524)
				(type default)
			)
			(layer "B.SilkS")
		)
		(fp_line
			(start 0.7874 -0.4064)
			(end -0.7874 -0.4064)
			(stroke
				(width 0.1524)
				(type default)
			)
			(layer "B.SilkS")
		)
		(fp_line
			(start -0.7874 0.4064)
			(end 0.7874 0.4064)
			(stroke
				(width 0.1524)
				(type default)
			)
			(layer "B.SilkS")
		)
		(fp_line
			(start -0.7874 -0.4064)
			(end -0.7874 0.4064)
			(stroke
				(width 0.1524)
				(type default)
			)
			(layer "B.SilkS")
		)
		(fp_line
			(start 0.67945 0.3048)
			(end 0.67945 -0.305054)
			(stroke
				(width 0.1)
				(type default)
			)
			(layer "B.Fab")
		)
		(fp_line
			(start 0.67945 -0.305054)
			(end 0.12065 -0.305054)
			(stroke
				(width 0.1)
				(type default)
			)
			(layer "B.Fab")
		)
		(fp_line
			(start 0.12065 0.3048)
			(end 0.67945 0.3048)
			(stroke
				(width 0.1)
				(type default)
			)
			(layer "B.Fab")
		)
		(fp_line
			(start 0.12065 0.2794)
			(end 0.12065 0.3048)
			(stroke
				(width 0.1)
				(type default)
			)
			(layer "B.Fab")
		)
		(fp_line
			(start 0.12065 -0.2794)
			(end -0.12065 -0.2794)
			(stroke
				(width 0.1)
				(type default)
			)
			(layer "B.Fab")
		)
		(fp_line
			(start 0.12065 -0.305054)
			(end 0.12065 -0.2794)
			(stroke
				(width 0.1)
				(type default)
			)
			(layer "B.Fab")
		)
		(fp_line
			(start -0.120396 0.3048)
			(end -0.120396 0.2794)
			(stroke
				(width 0.1)
				(type default)
			)
			(layer "B.Fab")
		)
		(fp_line
			(start -0.120396 0.2794)
			(end 0.12065 0.2794)
			(stroke
				(width 0.1)
				(type default)
			)
			(layer "B.Fab")
		)
		(fp_line
			(start -0.12065 -0.2794)
			(end -0.12065 -0.3048)
			(stroke
				(width 0.1)
				(type default)
			)
			(layer "B.Fab")
		)
		(fp_line
			(start -0.12065 -0.3048)
			(end -0.67945 -0.3048)
			(stroke
				(width 0.1)
				(type default)
			)
			(layer "B.Fab")
		)
		(fp_line
			(start -0.67945 0.3048)
			(end -0.120396 0.3048)
			(stroke
				(width 0.1)
				(type default)
			)
			(layer "B.Fab")
		)
		(fp_line
			(start -0.67945 -0.3048)
			(end -0.67945 0.3048)
			(stroke
				(width 0.1)
				(type default)
			)
			(layer "B.Fab")
		)
		(pad "1" smd circle
			(at 0.40005 0)
			(size 0 0)
			(layers "B.Cu" "B.Mask" "B.Paste")
			(net "FM_BMC_MUX_CS_SPI_SEL_0")
		)
		(pad "2" smd circle
			(at -0.40005 0)
			(size 0 0)
			(layers "B.Cu" "B.Mask" "B.Paste")
			(net "FM_BMC_BIOS_MUX_CS_SPI_R_SEL_0")
		)
	)
	(footprint ""
		(layer "B.Cu")
		(at 47.850044 -74.954384)
		(property "Reference" "R775"
			(at 0 0 0)
			(layer "B.SilkS")
			(hide yes)
			(effects
				(font
					(size 1.27 1.27)
				)
				(justify mirror)
			)
		)
		(property "Value" ""
			(at 0 0 0)
			(layer "B.Fab")
			(effects
				(font
					(size 1.27 1.27)
				)
				(justify mirror)
			)
		)
		(duplicate_pad_numbers_are_jumpers no)
		(fp_line
			(start -0.7874 -0.4064)
			(end -0.7874 0.4064)
			(stroke
				(width 0.1524)
				(type default)
			)
			(layer "B.SilkS")
		)
		(fp_line
			(start -0.7874 0.4064)
			(end 0.7874 0.4064)
			(stroke
				(width 0.1524)
				(type default)
			)
			(layer "B.SilkS")
		)
		(fp_line
			(start 0.7874 -0.4064)
			(end -0.7874 -0.4064)
			(stroke
				(width 0.1524)
				(type default)
			)
			(layer "B.SilkS")
		)
		(fp_line
			(start 0.7874 0.4064)
			(end 0.7874 -0.4064)
			(stroke
				(width 0.1524)
				(type default)
			)
			(layer "B.SilkS")
		)
		(fp_line
			(start -0.67945 -0.3048)
			(end -0.67945 0.3048)
			(stroke
				(width 0.1)
				(type default)
			)
			(layer "B.Fab")
		)
		(fp_line
			(start -0.67945 0.3048)
			(end -0.120396 0.3048)
			(stroke
				(width 0.1)
				(type default)
			)
			(layer "B.Fab")
		)
		(fp_line
			(start -0.12065 -0.3048)
			(end -0.67945 -0.3048)
			(stroke
				(width 0.1)
				(type default)
			)
			(layer "B.Fab")
		)
		(fp_line
			(start -0.12065 -0.2794)
			(end -0.12065 -0.3048)
			(stroke
				(width 0.1)
				(type default)
			)
			(layer "B.Fab")
		)
		(fp_line
			(start -0.120396 0.2794)
			(end 0.12065 0.2794)
			(stroke
				(width 0.1)
				(type default)
			)
			(layer "B.Fab")
		)
		(fp_line
			(start -0.120396 0.3048)
			(end -0.120396 0.2794)
			(stroke
				(width 0.1)
				(type default)
			)
			(layer "B.Fab")
		)
		(fp_line
			(start 0.12065 -0.305054)
			(end 0.12065 -0.2794)
			(stroke
				(width 0.1)
				(type default)
			)
			(layer "B.Fab")
		)
		(fp_line
			(start 0.12065 -0.2794)
			(end -0.12065 -0.2794)
			(stroke
				(width 0.1)
				(type default)
			)
			(layer "B.Fab")
		)
		(fp_line
			(start 0.12065 0.2794)
			(end 0.12065 0.3048)
			(stroke
				(width 0.1)
				(type default)
			)
			(layer "B.Fab")
		)
		(fp_line
			(start 0.12065 0.3048)
			(end 0.67945 0.3048)
			(stroke
				(width 0.1)
				(type default)
			)
			(layer "B.Fab")
		)
		(fp_line
			(start 0.67945 -0.305054)
			(end 0.12065 -0.305054)
			(stroke
				(width 0.1)
				(type default)
			)
			(layer "B.Fab")
		)
		(fp_line
			(start 0.67945 0.3048)
			(end 0.67945 -0.305054)
			(stroke
				(width 0.1)
				(type default)
			)
			(layer "B.Fab")
		)
		(pad "1" smd circle
			(at 0.40005 0 180)
			(size 0 0)
			(layers "B.Cu" "B.Mask" "B.Paste")
			(net "BATTERY_DETECT")
		)
		(pad "2" smd circle
			(at -0.40005 0 180)
			(size 0 0)
			(layers "B.Cu" "B.Mask" "B.Paste")
			(net "BATTERY_DETECT_R")
		)
	)
	(footprint ""
		(layer "B.Cu")
		(at 41.9989 -40.9321)
		(property "Reference" "R172"
			(at 0 0 0)
			(layer "B.SilkS")
			(hide yes)
			(effects
				(font
					(size 1.27 1.27)
				)
				(justify mirror)
			)
		)
		(property "Value" ""
			(at 0 0 0)
			(layer "B.Fab")
			(effects
				(font
					(size 1.27 1.27)
				)
				(justify mirror)
			)
		)
		(duplicate_pad_numbers_are_jumpers no)
		(fp_line
			(start -0.7874 -0.4064)
			(end -0.7874 0.4064)
			(stroke
				(width 0.1524)
				(type default)
			)
			(layer "B.SilkS")
		)
		(fp_line
			(start -0.7874 0.4064)
			(end 0.7874 0.4064)
			(stroke
				(width 0.1524)
				(type default)
			)
			(layer "B.SilkS")
		)
		(fp_line
			(start 0.7874 -0.4064)
			(end -0.7874 -0.4064)
			(stroke
				(width 0.1524)
				(type default)
			)
			(layer "B.SilkS")
		)
		(fp_line
			(start 0.7874 0.4064)
			(end 0.7874 -0.4064)
			(stroke
				(width 0.1524)
				(type default)
			)
			(layer "B.SilkS")
		)
		(fp_line
			(start -0.67945 -0.3048)
			(end -0.67945 0.3048)
			(stroke
				(width 0.1)
				(type default)
			)
			(layer "B.Fab")
		)
		(fp_line
			(start -0.67945 0.3048)
			(end -0.120396 0.3048)
			(stroke
				(width 0.1)
				(type default)
			)
			(layer "B.Fab")
		)
		(fp_line
			(start -0.12065 -0.3048)
			(end -0.67945 -0.3048)
			(stroke
				(width 0.1)
				(type default)
			)
			(layer "B.Fab")
		)
		(fp_line
			(start -0.12065 -0.2794)
			(end -0.12065 -0.3048)
			(stroke
				(width 0.1)
				(type default)
			)
			(layer "B.Fab")
		)
		(fp_line
			(start -0.120396 0.2794)
			(end 0.12065 0.2794)
			(stroke
				(width 0.1)
				(type default)
			)
			(layer "B.Fab")
		)
		(fp_line
			(start -0.120396 0.3048)
			(end -0.120396 0.2794)
			(stroke
				(width 0.1)
				(type default)
			)
			(layer "B.Fab")
		)
		(fp_line
			(start 0.12065 -0.305054)
			(end 0.12065 -0.2794)
			(stroke
				(width 0.1)
				(type default)
			)
			(layer "B.Fab")
		)
		(fp_line
			(start 0.12065 -0.2794)
			(end -0.12065 -0.2794)
			(stroke
				(width 0.1)
				(type default)
			)
			(layer "B.Fab")
		)
		(fp_line
			(start 0.12065 0.2794)
			(end 0.12065 0.3048)
			(stroke
				(width 0.1)
				(type default)
			)
			(layer "B.Fab")
		)
		(fp_line
			(start 0.12065 0.3048)
			(end 0.67945 0.3048)
			(stroke
				(width 0.1)
				(type default)
			)
			(layer "B.Fab")
		)
		(fp_line
			(start 0.67945 -0.305054)
			(end 0.12065 -0.305054)
			(stroke
				(width 0.1)
				(type default)
			)
			(layer "B.Fab")
		)
		(fp_line
			(start 0.67945 0.3048)
			(end 0.67945 -0.305054)
			(stroke
				(width 0.1)
				(type default)
			)
			(layer "B.Fab")
		)
		(pad "1" smd circle
			(at 0.40005 0 180)
			(size 0 0)
			(layers "B.Cu" "B.Mask" "B.Paste")
			(net "RMII_TXD0_R")
		)
		(pad "2" smd circle
			(at -0.40005 0 180)
			(size 0 0)
			(layers "B.Cu" "B.Mask" "B.Paste")
			(net "RMII_TXD0")
		)
	)
	(footprint ""
		(layer "B.Cu")
		(at 56.515 -34.671 90)
		(property "Reference" "R146"
			(at 0 0 90)
			(layer "B.SilkS")
			(hide yes)
			(effects
				(font
					(size 1.27 1.27)
				)
				(justify mirror)
			)
		)
		(property "Value" ""
			(at 0 0 90)
			(layer "B.Fab")
			(effects
				(font
					(size 1.27 1.27)
				)
				(justify mirror)
			)
		)
		(duplicate_pad_numbers_are_jumpers no)
		(fp_line
			(start 0.7874 -0.4064)
			(end -0.7874 -0.4064)
			(stroke
				(width 0.1524)
				(type default)
			)
			(layer "B.SilkS")
		)
		(fp_line
			(start -0.7874 -0.4064)
			(end -0.7874 0.4064)
			(stroke
				(width 0.1524)
				(type default)
			)
			(layer "B.SilkS")
		)
		(fp_line
			(start 0.7874 0.4064)
			(end 0.7874 -0.4064)
			(stroke
				(width 0.1524)
				(type default)
			)
			(layer "B.SilkS")
		)
		(fp_line
			(start -0.7874 0.4064)
			(end 0.7874 0.4064)
			(stroke
				(width 0.1524)
				(type default)
			)
			(layer "B.SilkS")
		)
		(fp_line
			(start 0.67945 -0.305054)
			(end 0.12065 -0.305054)
			(stroke
				(width 0.1)
				(type default)
			)
			(layer "B.Fab")
		)
		(fp_line
			(start 0.12065 -0.305054)
			(end 0.12065 -0.2794)
			(stroke
				(width 0.1)
				(type default)
			)
			(layer "B.Fab")
		)
		(fp_line
			(start -0.12065 -0.3048)
			(end -0.67945 -0.3048)
			(stroke
				(width 0.1)
				(type default)
			)
			(layer "B.Fab")
		)
		(fp_line
			(start -0.67945 -0.3048)
			(end -0.67945 0.3048)
			(stroke
				(width 0.1)
				(type default)
			)
			(layer "B.Fab")
		)
		(fp_line
			(start 0.12065 -0.2794)
			(end -0.12065 -0.2794)
			(stroke
				(width 0.1)
				(type default)
			)
			(layer "B.Fab")
		)
		(fp_line
			(start -0.12065 -0.2794)
			(end -0.12065 -0.3048)
			(stroke
				(width 0.1)
				(type default)
			)
			(layer "B.Fab")
		)
		(fp_line
			(start 0.12065 0.2794)
			(end 0.12065 0.3048)
			(stroke
				(width 0.1)
				(type default)
			)
			(layer "B.Fab")
		)
		(fp_line
			(start -0.120396 0.2794)
			(end 0.12065 0.2794)
			(stroke
				(width 0.1)
				(type default)
			)
			(layer "B.Fab")
		)
		(fp_line
			(start 0.67945 0.3048)
			(end 0.67945 -0.305054)
			(stroke
				(width 0.1)
				(type default)
			)
			(layer "B.Fab")
		)
		(fp_line
			(start 0.12065 0.3048)
			(end 0.67945 0.3048)
			(stroke
				(width 0.1)
				(type default)
			)
			(layer "B.Fab")
		)
		(fp_line
			(start -0.120396 0.3048)
			(end -0.120396 0.2794)
			(stroke
				(width 0.1)
				(type default)
			)
			(layer "B.Fab")
		)
		(fp_line
			(start -0.67945 0.3048)
			(end -0.120396 0.3048)
			(stroke
				(width 0.1)
				(type default)
			)
			(layer "B.Fab")
		)
		(pad "1" smd circle
			(at 0.40005 0 270)
			(size 0 0)
			(layers "B.Cu" "B.Mask" "B.Paste")
			(net "SMB_BMC_MM8_R_SCL")
		)
		(pad "2" smd circle
			(at -0.40005 0 270)
			(size 0 0)
			(layers "B.Cu" "B.Mask" "B.Paste")
			(net "SMB_BMC_MM8_SCL")
		)
	)
	(footprint ""
		(layer "B.Cu")
		(at 51.2445 -91.3765 180)
		(property "Reference" "R735"
			(at 0 0 0)
			(layer "B.SilkS")
			(hide yes)
			(effects
				(font
					(size 1.27 1.27)
				)
				(justify mirror)
			)
		)
		(property "Value" ""
			(at 0 0 0)
			(layer "B.Fab")
			(effects
				(font
					(size 1.27 1.27)
				)
				(justify mirror)
			)
		)
		(duplicate_pad_numbers_are_jumpers no)
		(fp_line
			(start 0.7874 0.4064)
			(end 0.7874 -0.4064)
			(stroke
				(width 0.1524)
				(type default)
			)
			(layer "B.SilkS")
		)
		(fp_line
			(start 0.7874 -0.4064)
			(end -0.7874 -0.4064)
			(stroke
				(width 0.1524)
				(type default)
			)
			(layer "B.SilkS")
		)
		(fp_line
			(start -0.7874 0.4064)
			(end 0.7874 0.4064)
			(stroke
				(width 0.1524)
				(type default)
			)
			(layer "B.SilkS")
		)
		(fp_line
			(start -0.7874 -0.4064)
			(end -0.7874 0.4064)
			(stroke
				(width 0.1524)
				(type default)
			)
			(layer "B.SilkS")
		)
		(fp_line
			(start 0.67945 0.3048)
			(end 0.67945 -0.305054)
			(stroke
				(width 0.1)
				(type default)
			)
			(layer "B.Fab")
		)
		(fp_line
			(start 0.67945 -0.305054)
			(end 0.12065 -0.305054)
			(stroke
				(width 0.1)
				(type default)
			)
			(layer "B.Fab")
		)
		(fp_line
			(start 0.12065 0.3048)
			(end 0.67945 0.3048)
			(stroke
				(width 0.1)
				(type default)
			)
			(layer "B.Fab")
		)
		(fp_line
			(start 0.12065 0.2794)
			(end 0.12065 0.3048)
			(stroke
				(width 0.1)
				(type default)
			)
			(layer "B.Fab")
		)
		(fp_line
			(start 0.12065 -0.2794)
			(end -0.12065 -0.2794)
			(stroke
				(width 0.1)
				(type default)
			)
			(layer "B.Fab")
		)
		(fp_line
			(start 0.12065 -0.305054)
			(end 0.12065 -0.2794)
			(stroke
				(width 0.1)
				(type default)
			)
			(layer "B.Fab")
		)
		(fp_line
			(start -0.120396 0.3048)
			(end -0.120396 0.2794)
			(stroke
				(width 0.1)
				(type default)
			)
			(layer "B.Fab")
		)
		(fp_line
			(start -0.120396 0.2794)
			(end 0.12065 0.2794)
			(stroke
				(width 0.1)
				(type default)
			)
			(layer "B.Fab")
		)
		(fp_line
			(start -0.12065 -0.2794)
			(end -0.12065 -0.3048)
			(stroke
				(width 0.1)
				(type default)
			)
			(layer "B.Fab")
		)
		(fp_line
			(start -0.12065 -0.3048)
			(end -0.67945 -0.3048)
			(stroke
				(width 0.1)
				(type default)
			)
			(layer "B.Fab")
		)
		(fp_line
			(start -0.67945 0.3048)
			(end -0.120396 0.3048)
			(stroke
				(width 0.1)
				(type default)
			)
			(layer "B.Fab")
		)
		(fp_line
			(start -0.67945 -0.3048)
			(end -0.67945 0.3048)
			(stroke
				(width 0.1)
				(type default)
			)
			(layer "B.Fab")
		)
		(pad "1" smd circle
			(at 0.40005 0)
			(size 0 0)
			(layers "B.Cu" "B.Mask" "B.Paste")
			(net "P3V3_AUX")
		)
		(pad "2" smd circle
			(at -0.40005 0)
			(size 0 0)
			(layers "B.Cu" "B.Mask" "B.Paste")
			(net "FM_UART_SWITCH_N")
		)
	)
	(footprint ""
		(layer "B.Cu")
		(at 53.5432 -34.637726 90)
		(property "Reference" "R826"
			(at 0 0 90)
			(layer "B.SilkS")
			(hide yes)
			(effects
				(font
					(size 1.27 1.27)
				)
				(justify mirror)
			)
		)
		(property "Value" ""
			(at 0 0 90)
			(layer "B.Fab")
			(effects
				(font
					(size 1.27 1.27)
				)
				(justify mirror)
			)
		)
		(duplicate_pad_numbers_are_jumpers no)
		(fp_line
			(start 0.7874 -0.4064)
			(end -0.7874 -0.4064)
			(stroke
				(width 0.1524)
				(type default)
			)
			(layer "B.SilkS")
		)
		(fp_line
			(start -0.7874 -0.4064)
			(end -0.7874 0.4064)
			(stroke
				(width 0.1524)
				(type default)
			)
			(layer "B.SilkS")
		)
		(fp_line
			(start 0.7874 0.4064)
			(end 0.7874 -0.4064)
			(stroke
				(width 0.1524)
				(type default)
			)
			(layer "B.SilkS")
		)
		(fp_line
			(start -0.7874 0.4064)
			(end 0.7874 0.4064)
			(stroke
				(width 0.1524)
				(type default)
			)
			(layer "B.SilkS")
		)
		(fp_line
			(start 0.67945 -0.305054)
			(end 0.12065 -0.305054)
			(stroke
				(width 0.1)
				(type default)
			)
			(layer "B.Fab")
		)
		(fp_line
			(start 0.12065 -0.305054)
			(end 0.12065 -0.2794)
			(stroke
				(width 0.1)
				(type default)
			)
			(layer "B.Fab")
		)
		(fp_line
			(start -0.12065 -0.3048)
			(end -0.67945 -0.3048)
			(stroke
				(width 0.1)
				(type default)
			)
			(layer "B.Fab")
		)
		(fp_line
			(start -0.67945 -0.3048)
			(end -0.67945 0.3048)
			(stroke
				(width 0.1)
				(type default)
			)
			(layer "B.Fab")
		)
		(fp_line
			(start 0.12065 -0.2794)
			(end -0.12065 -0.2794)
			(stroke
				(width 0.1)
				(type default)
			)
			(layer "B.Fab")
		)
		(fp_line
			(start -0.12065 -0.2794)
			(end -0.12065 -0.3048)
			(stroke
				(width 0.1)
				(type default)
			)
			(layer "B.Fab")
		)
		(fp_line
			(start 0.12065 0.2794)
			(end 0.12065 0.3048)
			(stroke
				(width 0.1)
				(type default)
			)
			(layer "B.Fab")
		)
		(fp_line
			(start -0.120396 0.2794)
			(end 0.12065 0.2794)
			(stroke
				(width 0.1)
				(type default)
			)
			(layer "B.Fab")
		)
		(fp_line
			(start 0.67945 0.3048)
			(end 0.67945 -0.305054)
			(stroke
				(width 0.1)
				(type default)
			)
			(layer "B.Fab")
		)
		(fp_line
			(start 0.12065 0.3048)
			(end 0.67945 0.3048)
			(stroke
				(width 0.1)
				(type default)
			)
			(layer "B.Fab")
		)
		(fp_line
			(start -0.120396 0.3048)
			(end -0.120396 0.2794)
			(stroke
				(width 0.1)
				(type default)
			)
			(layer "B.Fab")
		)
		(fp_line
			(start -0.67945 0.3048)
			(end -0.120396 0.3048)
			(stroke
				(width 0.1)
				(type default)
			)
			(layer "B.Fab")
		)
		(pad "1" smd circle
			(at 0.40005 0 270)
			(size 0 0)
			(layers "B.Cu" "B.Mask" "B.Paste")
			(net "IRQ_PCH_SCI_WHEA_R_N")
		)
		(pad "2" smd circle
			(at -0.40005 0 270)
			(size 0 0)
			(layers "B.Cu" "B.Mask" "B.Paste")
			(net "IRQ_PCH_SCI_WHEA_N")
		)
	)
	(footprint ""
		(layer "B.Cu")
		(at 45.0342 -55.4482 90)
		(property "Reference" "R489"
			(at 0 0 90)
			(layer "B.SilkS")
			(hide yes)
			(effects
				(font
					(size 1.27 1.27)
				)
				(justify mirror)
			)
		)
		(property "Value" ""
			(at 0 0 90)
			(layer "B.Fab")
			(effects
				(font
					(size 1.27 1.27)
				)
				(justify mirror)
			)
		)
		(duplicate_pad_numbers_are_jumpers no)
		(fp_line
			(start 0.7874 -0.4064)
			(end -0.7874 -0.4064)
			(stroke
				(width 0.1524)
				(type default)
			)
			(layer "B.SilkS")
		)
		(fp_line
			(start -0.7874 -0.4064)
			(end -0.7874 0.4064)
			(stroke
				(width 0.1524)
				(type default)
			)
			(layer "B.SilkS")
		)
		(fp_line
			(start 0.7874 0.4064)
			(end 0.7874 -0.4064)
			(stroke
				(width 0.1524)
				(type default)
			)
			(layer "B.SilkS")
		)
		(fp_line
			(start -0.7874 0.4064)
			(end 0.7874 0.4064)
			(stroke
				(width 0.1524)
				(type default)
			)
			(layer "B.SilkS")
		)
		(fp_line
			(start 0.67945 -0.305054)
			(end 0.12065 -0.305054)
			(stroke
				(width 0.1)
				(type default)
			)
			(layer "B.Fab")
		)
		(fp_line
			(start 0.12065 -0.305054)
			(end 0.12065 -0.2794)
			(stroke
				(width 0.1)
				(type default)
			)
			(layer "B.Fab")
		)
		(fp_line
			(start -0.12065 -0.3048)
			(end -0.67945 -0.3048)
			(stroke
				(width 0.1)
				(type default)
			)
			(layer "B.Fab")
		)
		(fp_line
			(start -0.67945 -0.3048)
			(end -0.67945 0.3048)
			(stroke
				(width 0.1)
				(type default)
			)
			(layer "B.Fab")
		)
		(fp_line
			(start 0.12065 -0.2794)
			(end -0.12065 -0.2794)
			(stroke
				(width 0.1)
				(type default)
			)
			(layer "B.Fab")
		)
		(fp_line
			(start -0.12065 -0.2794)
			(end -0.12065 -0.3048)
			(stroke
				(width 0.1)
				(type default)
			)
			(layer "B.Fab")
		)
		(fp_line
			(start 0.12065 0.2794)
			(end 0.12065 0.3048)
			(stroke
				(width 0.1)
				(type default)
			)
			(layer "B.Fab")
		)
		(fp_line
			(start -0.120396 0.2794)
			(end 0.12065 0.2794)
			(stroke
				(width 0.1)
				(type default)
			)
			(layer "B.Fab")
		)
		(fp_line
			(start 0.67945 0.3048)
			(end 0.67945 -0.305054)
			(stroke
				(width 0.1)
				(type default)
			)
			(layer "B.Fab")
		)
		(fp_line
			(start 0.12065 0.3048)
			(end 0.67945 0.3048)
			(stroke
				(width 0.1)
				(type default)
			)
			(layer "B.Fab")
		)
		(fp_line
			(start -0.120396 0.3048)
			(end -0.120396 0.2794)
			(stroke
				(width 0.1)
				(type default)
			)
			(layer "B.Fab")
		)
		(fp_line
			(start -0.67945 0.3048)
			(end -0.120396 0.3048)
			(stroke
				(width 0.1)
				(type default)
			)
			(layer "B.Fab")
		)
		(pad "1" smd circle
			(at 0.40005 0 270)
			(size 0 0)
			(layers "B.Cu" "B.Mask" "B.Paste")
			(net "FM_SOL_UART_CH_SEL")
		)
		(pad "2" smd circle
			(at -0.40005 0 270)
			(size 0 0)
			(layers "B.Cu" "B.Mask" "B.Paste")
			(net "FM_SOL_UART_CH_SEL_R1")
		)
	)
	(footprint ""
		(layer "B.Cu")
		(at 59.109102 -50.71364 90)
		(property "Reference" "C79"
			(at 0 0 90)
			(layer "B.SilkS")
			(hide yes)
			(effects
				(font
					(size 1.27 1.27)
				)
				(justify mirror)
			)
		)
		(property "Value" ""
			(at 0 0 90)
			(layer "B.Fab")
			(effects
				(font
					(size 1.27 1.27)
				)
				(justify mirror)
			)
		)
		(duplicate_pad_numbers_are_jumpers no)
		(fp_line
			(start 0.7874 -0.4064)
			(end -0.7874 -0.4064)
			(stroke
				(width 0.1524)
				(type default)
			)
			(layer "B.SilkS")
		)
		(fp_line
			(start -0.7874 -0.4064)
			(end -0.7874 0.4064)
			(stroke
				(width 0.1524)
				(type default)
			)
			(layer "B.SilkS")
		)
		(fp_line
			(start 0.7874 0.4064)
			(end 0.7874 -0.4064)
			(stroke
				(width 0.1524)
				(type default)
			)
			(layer "B.SilkS")
		)
		(fp_line
			(start -0.7874 0.4064)
			(end 0.7874 0.4064)
			(stroke
				(width 0.1524)
				(type default)
			)
			(layer "B.SilkS")
		)
		(fp_line
			(start 0.67945 -0.305054)
			(end 0.12065 -0.305054)
			(stroke
				(width 0.1)
				(type default)
			)
			(layer "B.Fab")
		)
		(fp_line
			(start 0.12065 -0.305054)
			(end 0.12065 -0.2794)
			(stroke
				(width 0.1)
				(type default)
			)
			(layer "B.Fab")
		)
		(fp_line
			(start -0.12065 -0.3048)
			(end -0.67945 -0.3048)
			(stroke
				(width 0.1)
				(type default)
			)
			(layer "B.Fab")
		)
		(fp_line
			(start -0.67945 -0.3048)
			(end -0.67945 0.3048)
			(stroke
				(width 0.1)
				(type default)
			)
			(layer "B.Fab")
		)
		(fp_line
			(start 0.12065 -0.2794)
			(end -0.12065 -0.2794)
			(stroke
				(width 0.1)
				(type default)
			)
			(layer "B.Fab")
		)
		(fp_line
			(start -0.12065 -0.2794)
			(end -0.12065 -0.3048)
			(stroke
				(width 0.1)
				(type default)
			)
			(layer "B.Fab")
		)
		(fp_line
			(start 0.12065 0.2794)
			(end 0.12065 0.3048)
			(stroke
				(width 0.1)
				(type default)
			)
			(layer "B.Fab")
		)
		(fp_line
			(start -0.120396 0.2794)
			(end 0.12065 0.2794)
			(stroke
				(width 0.1)
				(type default)
			)
			(layer "B.Fab")
		)
		(fp_line
			(start 0.67945 0.3048)
			(end 0.67945 -0.305054)
			(stroke
				(width 0.1)
				(type default)
			)
			(layer "B.Fab")
		)
		(fp_line
			(start 0.12065 0.3048)
			(end 0.67945 0.3048)
			(stroke
				(width 0.1)
				(type default)
			)
			(layer "B.Fab")
		)
		(fp_line
			(start -0.120396 0.3048)
			(end -0.120396 0.2794)
			(stroke
				(width 0.1)
				(type default)
			)
			(layer "B.Fab")
		)
		(fp_line
			(start -0.67945 0.3048)
			(end -0.120396 0.3048)
			(stroke
				(width 0.1)
				(type default)
			)
			(layer "B.Fab")
		)
		(pad "1" smd circle
			(at 0.40005 0 270)
			(size 0 0)
			(layers "B.Cu" "B.Mask" "B.Paste")
			(net "P1V0_STBY_PE_VCC10A")
		)
		(pad "2" smd circle
			(at -0.40005 0 270)
			(size 0 0)
			(layers "B.Cu" "B.Mask" "B.Paste")
			(net "GND")
		)
	)
	(footprint ""
		(layer "B.Cu")
		(at 81.788 -59.055 90)
		(property "Reference" "C131"
			(at 0 0 90)
			(layer "B.SilkS")
			(hide yes)
			(effects
				(font
					(size 1.27 1.27)
				)
				(justify mirror)
			)
		)
		(property "Value" ""
			(at 0 0 90)
			(layer "B.Fab")
			(effects
				(font
					(size 1.27 1.27)
				)
				(justify mirror)
			)
		)
		(duplicate_pad_numbers_are_jumpers no)
		(fp_line
			(start 1.2954 -0.5842)
			(end -1.2954 -0.5842)
			(stroke
				(width 0.1524)
				(type default)
			)
			(layer "B.SilkS")
		)
		(fp_line
			(start 0 -0.5842)
			(end 0 0.5842)
			(stroke
				(width 0.1524)
				(type default)
			)
			(layer "B.SilkS")
		)
		(fp_line
			(start -1.2954 -0.5842)
			(end -1.2954 0.5842)
			(stroke
				(width 0.1524)
				(type default)
			)
			(layer "B.SilkS")
		)
		(fp_line
			(start 1.2954 0.5842)
			(end 1.2954 -0.5842)
			(stroke
				(width 0.1524)
				(type default)
			)
			(layer "B.SilkS")
		)
		(fp_line
			(start -1.2954 0.5842)
			(end 1.2954 0.5842)
			(stroke
				(width 0.1524)
				(type default)
			)
			(layer "B.SilkS")
		)
		(fp_line
			(start 0.8636 -0.4572)
			(end -0.8636 -0.4572)
			(stroke
				(width 0.1)
				(type default)
			)
			(layer "B.Fab")
		)
		(fp_line
			(start -0.8636 -0.4572)
			(end -0.8636 -0.4064)
			(stroke
				(width 0.1)
				(type default)
			)
			(layer "B.Fab")
		)
		(fp_line
			(start 1.1938 -0.4064)
			(end 0.8636 -0.4064)
			(stroke
				(width 0.1)
				(type default)
			)
			(layer "B.Fab")
		)
		(fp_line
			(start 0.8636 -0.4064)
			(end 0.8636 -0.4572)
			(stroke
				(width 0.1)
				(type default)
			)
			(layer "B.Fab")
		)
		(fp_line
			(start -0.8636 -0.4064)
			(end -1.1938 -0.4064)
			(stroke
				(width 0.1)
				(type default)
			)
			(layer "B.Fab")
		)
		(fp_line
			(start -1.1938 -0.4064)
			(end -1.1938 0.4064)
			(stroke
				(width 0.1)
				(type default)
			)
			(layer "B.Fab")
		)
		(fp_line
			(start 1.1938 0.4064)
			(end 1.1938 -0.4064)
			(stroke
				(width 0.1)
				(type default)
			)
			(layer "B.Fab")
		)
		(fp_line
			(start 0.8636 0.4064)
			(end 1.1938 0.4064)
			(stroke
				(width 0.1)
				(type default)
			)
			(layer "B.Fab")
		)
		(fp_line
			(start -0.8636 0.4064)
			(end -0.8636 0.4572)
			(stroke
				(width 0.1)
				(type default)
			)
			(layer "B.Fab")
		)
		(fp_line
			(start -1.1938 0.4064)
			(end -0.8636 0.4064)
			(stroke
				(width 0.1)
				(type default)
			)
			(layer "B.Fab")
		)
		(fp_line
			(start 0.8636 0.4572)
			(end 0.8636 0.4064)
			(stroke
				(width 0.1)
				(type default)
			)
			(layer "B.Fab")
		)
		(fp_line
			(start -0.8636 0.4572)
			(end 0.8636 0.4572)
			(stroke
				(width 0.1)
				(type default)
			)
			(layer "B.Fab")
		)
		(pad "1" smd rect
			(at 0.7366 0)
			(size 0.7112 0.8128)
			(layers "B.Cu" "B.Mask" "B.Paste")
			(net "P1V2_AUX")
		)
		(pad "2" smd rect
			(at -0.7366 0)
			(size 0.7112 0.8128)
			(layers "B.Cu" "B.Mask" "B.Paste")
			(net "GND")
		)
	)
	(footprint ""
		(layer "B.Cu")
		(at 70.650862 -65.406016 90)
		(property "Reference" "L10"
			(at 0 0 90)
			(layer "B.SilkS")
			(hide yes)
			(effects
				(font
					(size 1.27 1.27)
				)
				(justify mirror)
			)
		)
		(property "Value" ""
			(at 0 0 90)
			(layer "B.Fab")
			(effects
				(font
					(size 1.27 1.27)
				)
				(justify mirror)
			)
		)
		(duplicate_pad_numbers_are_jumpers no)
		(fp_line
			(start 1.27 -0.5842)
			(end -1.27 -0.5842)
			(stroke
				(width 0.1524)
				(type default)
			)
			(layer "B.SilkS")
		)
		(fp_line
			(start 1.27 -0.5588)
			(end 1.27 -0.5842)
			(stroke
				(width 0.1524)
				(type default)
			)
			(layer "B.SilkS")
		)
		(fp_line
			(start 1.27 0.5842)
			(end 1.27 -0.5842)
			(stroke
				(width 0.1524)
				(type default)
			)
			(layer "B.SilkS")
		)
		(fp_line
			(start 0.127 0.5842)
			(end 0.127 -0.5842)
			(stroke
				(width 0.1524)
				(type default)
			)
			(layer "B.SilkS")
		)
		(fp_line
			(start -0.127 0.5842)
			(end -0.127 -0.5842)
			(stroke
				(width 0.1524)
				(type default)
			)
			(layer "B.SilkS")
		)
		(fp_line
			(start -1.27 0.5842)
			(end -1.27 -0.5842)
			(stroke
				(width 0.1524)
				(type default)
			)
			(layer "B.SilkS")
		)
		(fp_line
			(start -1.27 0.5842)
			(end 1.27 0.5842)
			(stroke
				(width 0.1524)
				(type default)
			)
			(layer "B.SilkS")
		)
		(fp_line
			(start 0.9144 -0.508)
			(end -0.9144 -0.508)
			(stroke
				(width 0.1)
				(type default)
			)
			(layer "B.Fab")
		)
		(fp_line
			(start -0.9144 -0.508)
			(end -0.9144 -0.406654)
			(stroke
				(width 0.1)
				(type default)
			)
			(layer "B.Fab")
		)
		(fp_line
			(start 1.194308 -0.406654)
			(end 0.9144 -0.406654)
			(stroke
				(width 0.1)
				(type default)
			)
			(layer "B.Fab")
		)
		(fp_line
			(start 0.9144 -0.406654)
			(end 0.9144 -0.508)
			(stroke
				(width 0.1)
				(type default)
			)
			(layer "B.Fab")
		)
		(fp_line
			(start -0.9144 -0.406654)
			(end -1.1938 -0.406654)
			(stroke
				(width 0.1)
				(type default)
			)
			(layer "B.Fab")
		)
		(fp_line
			(start -1.1938 -0.406654)
			(end -1.1938 0.4064)
			(stroke
				(width 0.1)
				(type default)
			)
			(layer "B.Fab")
		)
		(fp_line
			(start -0.9144 0.4064)
			(end -0.9144 0.508)
			(stroke
				(width 0.1)
				(type default)
			)
			(layer "B.Fab")
		)
		(fp_line
			(start -1.1938 0.4064)
			(end -0.9144 0.4064)
			(stroke
				(width 0.1)
				(type default)
			)
			(layer "B.Fab")
		)
		(fp_line
			(start 1.194308 0.406654)
			(end 1.194308 -0.406654)
			(stroke
				(width 0.1)
				(type default)
			)
			(layer "B.Fab")
		)
		(fp_line
			(start 0.9144 0.406654)
			(end 1.194308 0.406654)
			(stroke
				(width 0.1)
				(type default)
			)
			(layer "B.Fab")
		)
		(fp_line
			(start 0.9144 0.508)
			(end 0.9144 0.406654)
			(stroke
				(width 0.1)
				(type default)
			)
			(layer "B.Fab")
		)
		(fp_line
			(start -0.9144 0.508)
			(end 0.9144 0.508)
			(stroke
				(width 0.1)
				(type default)
			)
			(layer "B.Fab")
		)
		(pad "1" smd rect
			(at 0.7366 0)
			(size 0.7112 0.8128)
			(layers "B.Cu" "B.Mask" "B.Paste")
			(net "P1V8_AUX")
		)
		(pad "2" smd rect
			(at -0.7366 0)
			(size 0.7112 0.8128)
			(layers "B.Cu" "B.Mask" "B.Paste")
			(net "P1V8_STBY_PE_VCC18A")
		)
	)
	(footprint ""
		(layer "B.Cu")
		(at 85.32241 -28.627832)
		(property "Reference" "R12"
			(at 0 0 0)
			(layer "B.SilkS")
			(hide yes)
			(effects
				(font
					(size 1.27 1.27)
				)
				(justify mirror)
			)
		)
		(property "Value" ""
			(at 0 0 0)
			(layer "B.Fab")
			(effects
				(font
					(size 1.27 1.27)
				)
				(justify mirror)
			)
		)
		(duplicate_pad_numbers_are_jumpers no)
		(fp_line
			(start -0.7874 -0.4064)
			(end -0.7874 0.4064)
			(stroke
				(width 0.1524)
				(type default)
			)
			(layer "B.SilkS")
		)
		(fp_line
			(start -0.7874 0.4064)
			(end 0.7874 0.4064)
			(stroke
				(width 0.1524)
				(type default)
			)
			(layer "B.SilkS")
		)
		(fp_line
			(start 0.7874 -0.4064)
			(end -0.7874 -0.4064)
			(stroke
				(width 0.1524)
				(type default)
			)
			(layer "B.SilkS")
		)
		(fp_line
			(start 0.7874 0.4064)
			(end 0.7874 -0.4064)
			(stroke
				(width 0.1524)
				(type default)
			)
			(layer "B.SilkS")
		)
		(fp_line
			(start -0.67945 -0.3048)
			(end -0.67945 0.3048)
			(stroke
				(width 0.1)
				(type default)
			)
			(layer "B.Fab")
		)
		(fp_line
			(start -0.67945 0.3048)
			(end -0.120396 0.3048)
			(stroke
				(width 0.1)
				(type default)
			)
			(layer "B.Fab")
		)
		(fp_line
			(start -0.12065 -0.3048)
			(end -0.67945 -0.3048)
			(stroke
				(width 0.1)
				(type default)
			)
			(layer "B.Fab")
		)
		(fp_line
			(start -0.12065 -0.2794)
			(end -0.12065 -0.3048)
			(stroke
				(width 0.1)
				(type default)
			)
			(layer "B.Fab")
		)
		(fp_line
			(start -0.120396 0.2794)
			(end 0.12065 0.2794)
			(stroke
				(width 0.1)
				(type default)
			)
			(layer "B.Fab")
		)
		(fp_line
			(start -0.120396 0.3048)
			(end -0.120396 0.2794)
			(stroke
				(width 0.1)
				(type default)
			)
			(layer "B.Fab")
		)
		(fp_line
			(start 0.12065 -0.305054)
			(end 0.12065 -0.2794)
			(stroke
				(width 0.1)
				(type default)
			)
			(layer "B.Fab")
		)
		(fp_line
			(start 0.12065 -0.2794)
			(end -0.12065 -0.2794)
			(stroke
				(width 0.1)
				(type default)
			)
			(layer "B.Fab")
		)
		(fp_line
			(start 0.12065 0.2794)
			(end 0.12065 0.3048)
			(stroke
				(width 0.1)
				(type default)
			)
			(layer "B.Fab")
		)
		(fp_line
			(start 0.12065 0.3048)
			(end 0.67945 0.3048)
			(stroke
				(width 0.1)
				(type default)
			)
			(layer "B.Fab")
		)
		(fp_line
			(start 0.67945 -0.305054)
			(end 0.12065 -0.305054)
			(stroke
				(width 0.1)
				(type default)
			)
			(layer "B.Fab")
		)
		(fp_line
			(start 0.67945 0.3048)
			(end 0.67945 -0.305054)
			(stroke
				(width 0.1)
				(type default)
			)
			(layer "B.Fab")
		)
		(pad "1" smd circle
			(at 0.40005 0 180)
			(size 0 0)
			(layers "B.Cu" "B.Mask" "B.Paste")
			(net "P3V3_AUX")
		)
		(pad "2" smd circle
			(at -0.40005 0 180)
			(size 0 0)
			(layers "B.Cu" "B.Mask" "B.Paste")
			(net "FRU_E0")
		)
	)
	(footprint ""
		(layer "B.Cu")
		(at 56.861964 -71.064882 180)
		(property "Reference" "C282"
			(at 0 0 0)
			(layer "B.SilkS")
			(hide yes)
			(effects
				(font
					(size 1.27 1.27)
				)
				(justify mirror)
			)
		)
		(property "Value" ""
			(at 0 0 0)
			(layer "B.Fab")
			(effects
				(font
					(size 1.27 1.27)
				)
				(justify mirror)
			)
		)
		(duplicate_pad_numbers_are_jumpers no)
		(fp_line
			(start 0.7874 0.4064)
			(end 0.7874 -0.4064)
			(stroke
				(width 0.1524)
				(type default)
			)
			(layer "B.SilkS")
		)
		(fp_line
			(start 0.7874 -0.4064)
			(end -0.7874 -0.4064)
			(stroke
				(width 0.1524)
				(type default)
			)
			(layer "B.SilkS")
		)
		(fp_line
			(start -0.7874 0.4064)
			(end 0.7874 0.4064)
			(stroke
				(width 0.1524)
				(type default)
			)
			(layer "B.SilkS")
		)
		(fp_line
			(start -0.7874 -0.4064)
			(end -0.7874 0.4064)
			(stroke
				(width 0.1524)
				(type default)
			)
			(layer "B.SilkS")
		)
		(fp_line
			(start 0.67945 0.3048)
			(end 0.67945 -0.305054)
			(stroke
				(width 0.1)
				(type default)
			)
			(layer "B.Fab")
		)
		(fp_line
			(start 0.67945 -0.305054)
			(end 0.12065 -0.305054)
			(stroke
				(width 0.1)
				(type default)
			)
			(layer "B.Fab")
		)
		(fp_line
			(start 0.12065 0.3048)
			(end 0.67945 0.3048)
			(stroke
				(width 0.1)
				(type default)
			)
			(layer "B.Fab")
		)
		(fp_line
			(start 0.12065 0.2794)
			(end 0.12065 0.3048)
			(stroke
				(width 0.1)
				(type default)
			)
			(layer "B.Fab")
		)
		(fp_line
			(start 0.12065 -0.2794)
			(end -0.12065 -0.2794)
			(stroke
				(width 0.1)
				(type default)
			)
			(layer "B.Fab")
		)
		(fp_line
			(start 0.12065 -0.305054)
			(end 0.12065 -0.2794)
			(stroke
				(width 0.1)
				(type default)
			)
			(layer "B.Fab")
		)
		(fp_line
			(start -0.120396 0.3048)
			(end -0.120396 0.2794)
			(stroke
				(width 0.1)
				(type default)
			)
			(layer "B.Fab")
		)
		(fp_line
			(start -0.120396 0.2794)
			(end 0.12065 0.2794)
			(stroke
				(width 0.1)
				(type default)
			)
			(layer "B.Fab")
		)
		(fp_line
			(start -0.12065 -0.2794)
			(end -0.12065 -0.3048)
			(stroke
				(width 0.1)
				(type default)
			)
			(layer "B.Fab")
		)
		(fp_line
			(start -0.12065 -0.3048)
			(end -0.67945 -0.3048)
			(stroke
				(width 0.1)
				(type default)
			)
			(layer "B.Fab")
		)
		(fp_line
			(start -0.67945 0.3048)
			(end -0.120396 0.3048)
			(stroke
				(width 0.1)
				(type default)
			)
			(layer "B.Fab")
		)
		(fp_line
			(start -0.67945 -0.3048)
			(end -0.67945 0.3048)
			(stroke
				(width 0.1)
				(type default)
			)
			(layer "B.Fab")
		)
		(pad "1" smd circle
			(at 0.40005 0)
			(size 0 0)
			(layers "B.Cu" "B.Mask" "B.Paste")
			(net "ADCVREFEXT0")
		)
		(pad "2" smd circle
			(at -0.40005 0)
			(size 0 0)
			(layers "B.Cu" "B.Mask" "B.Paste")
			(net "GND")
		)
	)
	(footprint ""
		(layer "B.Cu")
		(at 80.755744 -37.559488 90)
		(property "Reference" "R351"
			(at 0 0 90)
			(layer "B.SilkS")
			(hide yes)
			(effects
				(font
					(size 1.27 1.27)
				)
				(justify mirror)
			)
		)
		(property "Value" ""
			(at 0 0 90)
			(layer "B.Fab")
			(effects
				(font
					(size 1.27 1.27)
				)
				(justify mirror)
			)
		)
		(duplicate_pad_numbers_are_jumpers no)
		(fp_line
			(start 0.7874 -0.4064)
			(end -0.7874 -0.4064)
			(stroke
				(width 0.1524)
				(type default)
			)
			(layer "B.SilkS")
		)
		(fp_line
			(start -0.7874 -0.4064)
			(end -0.7874 0.4064)
			(stroke
				(width 0.1524)
				(type default)
			)
			(layer "B.SilkS")
		)
		(fp_line
			(start 0.7874 0.4064)
			(end 0.7874 -0.4064)
			(stroke
				(width 0.1524)
				(type default)
			)
			(layer "B.SilkS")
		)
		(fp_line
			(start -0.7874 0.4064)
			(end 0.7874 0.4064)
			(stroke
				(width 0.1524)
				(type default)
			)
			(layer "B.SilkS")
		)
		(fp_line
			(start 0.67945 -0.305054)
			(end 0.12065 -0.305054)
			(stroke
				(width 0.1)
				(type default)
			)
			(layer "B.Fab")
		)
		(fp_line
			(start 0.12065 -0.305054)
			(end 0.12065 -0.2794)
			(stroke
				(width 0.1)
				(type default)
			)
			(layer "B.Fab")
		)
		(fp_line
			(start -0.12065 -0.3048)
			(end -0.67945 -0.3048)
			(stroke
				(width 0.1)
				(type default)
			)
			(layer "B.Fab")
		)
		(fp_line
			(start -0.67945 -0.3048)
			(end -0.67945 0.3048)
			(stroke
				(width 0.1)
				(type default)
			)
			(layer "B.Fab")
		)
		(fp_line
			(start 0.12065 -0.2794)
			(end -0.12065 -0.2794)
			(stroke
				(width 0.1)
				(type default)
			)
			(layer "B.Fab")
		)
		(fp_line
			(start -0.12065 -0.2794)
			(end -0.12065 -0.3048)
			(stroke
				(width 0.1)
				(type default)
			)
			(layer "B.Fab")
		)
		(fp_line
			(start 0.12065 0.2794)
			(end 0.12065 0.3048)
			(stroke
				(width 0.1)
				(type default)
			)
			(layer "B.Fab")
		)
		(fp_line
			(start -0.120396 0.2794)
			(end 0.12065 0.2794)
			(stroke
				(width 0.1)
				(type default)
			)
			(layer "B.Fab")
		)
		(fp_line
			(start 0.67945 0.3048)
			(end 0.67945 -0.305054)
			(stroke
				(width 0.1)
				(type default)
			)
			(layer "B.Fab")
		)
		(fp_line
			(start 0.12065 0.3048)
			(end 0.67945 0.3048)
			(stroke
				(width 0.1)
				(type default)
			)
			(layer "B.Fab")
		)
		(fp_line
			(start -0.120396 0.3048)
			(end -0.120396 0.2794)
			(stroke
				(width 0.1)
				(type default)
			)
			(layer "B.Fab")
		)
		(fp_line
			(start -0.67945 0.3048)
			(end -0.120396 0.3048)
			(stroke
				(width 0.1)
				(type default)
			)
			(layer "B.Fab")
		)
		(pad "1" smd circle
			(at 0.40005 0 270)
			(size 0 0)
			(layers "B.Cu" "B.Mask" "B.Paste")
			(net "M_BMC_DDR4_MA<0>")
		)
		(pad "2" smd circle
			(at -0.40005 0 270)
			(size 0 0)
			(layers "B.Cu" "B.Mask" "B.Paste")
			(net "P1V2_AUX")
		)
	)
	(footprint ""
		(layer "B.Cu")
		(at 29.1846 -27.7622)
		(property "Reference" "C212"
			(at 0 0 0)
			(layer "B.SilkS")
			(hide yes)
			(effects
				(font
					(size 1.27 1.27)
				)
				(justify mirror)
			)
		)
		(property "Value" ""
			(at 0 0 0)
			(layer "B.Fab")
			(effects
				(font
					(size 1.27 1.27)
				)
				(justify mirror)
			)
		)
		(duplicate_pad_numbers_are_jumpers no)
		(fp_line
			(start -0.7874 -0.4064)
			(end -0.7874 0.4064)
			(stroke
				(width 0.1524)
				(type default)
			)
			(layer "B.SilkS")
		)
		(fp_line
			(start -0.7874 0.4064)
			(end 0.7874 0.4064)
			(stroke
				(width 0.1524)
				(type default)
			)
			(layer "B.SilkS")
		)
		(fp_line
			(start 0.7874 -0.4064)
			(end -0.7874 -0.4064)
			(stroke
				(width 0.1524)
				(type default)
			)
			(layer "B.SilkS")
		)
		(fp_line
			(start 0.7874 0.4064)
			(end 0.7874 -0.4064)
			(stroke
				(width 0.1524)
				(type default)
			)
			(layer "B.SilkS")
		)
		(fp_line
			(start -0.67945 -0.3048)
			(end -0.67945 0.3048)
			(stroke
				(width 0.1)
				(type default)
			)
			(layer "B.Fab")
		)
		(fp_line
			(start -0.67945 0.3048)
			(end -0.120396 0.3048)
			(stroke
				(width 0.1)
				(type default)
			)
			(layer "B.Fab")
		)
		(fp_line
			(start -0.12065 -0.3048)
			(end -0.67945 -0.3048)
			(stroke
				(width 0.1)
				(type default)
			)
			(layer "B.Fab")
		)
		(fp_line
			(start -0.12065 -0.2794)
			(end -0.12065 -0.3048)
			(stroke
				(width 0.1)
				(type default)
			)
			(layer "B.Fab")
		)
		(fp_line
			(start -0.120396 0.2794)
			(end 0.12065 0.2794)
			(stroke
				(width 0.1)
				(type default)
			)
			(layer "B.Fab")
		)
		(fp_line
			(start -0.120396 0.3048)
			(end -0.120396 0.2794)
			(stroke
				(width 0.1)
				(type default)
			)
			(layer "B.Fab")
		)
		(fp_line
			(start 0.12065 -0.305054)
			(end 0.12065 -0.2794)
			(stroke
				(width 0.1)
				(type default)
			)
			(layer "B.Fab")
		)
		(fp_line
			(start 0.12065 -0.2794)
			(end -0.12065 -0.2794)
			(stroke
				(width 0.1)
				(type default)
			)
			(layer "B.Fab")
		)
		(fp_line
			(start 0.12065 0.2794)
			(end 0.12065 0.3048)
			(stroke
				(width 0.1)
				(type default)
			)
			(layer "B.Fab")
		)
		(fp_line
			(start 0.12065 0.3048)
			(end 0.67945 0.3048)
			(stroke
				(width 0.1)
				(type default)
			)
			(layer "B.Fab")
		)
		(fp_line
			(start 0.67945 -0.305054)
			(end 0.12065 -0.305054)
			(stroke
				(width 0.1)
				(type default)
			)
			(layer "B.Fab")
		)
		(fp_line
			(start 0.67945 0.3048)
			(end 0.67945 -0.305054)
			(stroke
				(width 0.1)
				(type default)
			)
			(layer "B.Fab")
		)
		(pad "1" smd circle
			(at 0.40005 0 180)
			(size 0 0)
			(layers "B.Cu" "B.Mask" "B.Paste")
			(net "V_VGAVS_BUF")
		)
		(pad "2" smd circle
			(at -0.40005 0 180)
			(size 0 0)
			(layers "B.Cu" "B.Mask" "B.Paste")
			(net "GND")
		)
	)
	(footprint ""
		(layer "B.Cu")
		(at 61.996828 -27.875992 90)
		(property "Reference" "R851"
			(at 0 0 90)
			(layer "B.SilkS")
			(hide yes)
			(effects
				(font
					(size 1.27 1.27)
				)
				(justify mirror)
			)
		)
		(property "Value" ""
			(at 0 0 90)
			(layer "B.Fab")
			(effects
				(font
					(size 1.27 1.27)
				)
				(justify mirror)
			)
		)
		(duplicate_pad_numbers_are_jumpers no)
		(fp_line
			(start 0.7874 -0.4064)
			(end -0.7874 -0.4064)
			(stroke
				(width 0.1524)
				(type default)
			)
			(layer "B.SilkS")
		)
		(fp_line
			(start -0.7874 -0.4064)
			(end -0.7874 0.4064)
			(stroke
				(width 0.1524)
				(type default)
			)
			(layer "B.SilkS")
		)
		(fp_line
			(start 0.7874 0.4064)
			(end 0.7874 -0.4064)
			(stroke
				(width 0.1524)
				(type default)
			)
			(layer "B.SilkS")
		)
		(fp_line
			(start -0.7874 0.4064)
			(end 0.7874 0.4064)
			(stroke
				(width 0.1524)
				(type default)
			)
			(layer "B.SilkS")
		)
		(fp_line
			(start 0.67945 -0.305054)
			(end 0.12065 -0.305054)
			(stroke
				(width 0.1)
				(type default)
			)
			(layer "B.Fab")
		)
		(fp_line
			(start 0.12065 -0.305054)
			(end 0.12065 -0.2794)
			(stroke
				(width 0.1)
				(type default)
			)
			(layer "B.Fab")
		)
		(fp_line
			(start -0.12065 -0.3048)
			(end -0.67945 -0.3048)
			(stroke
				(width 0.1)
				(type default)
			)
			(layer "B.Fab")
		)
		(fp_line
			(start -0.67945 -0.3048)
			(end -0.67945 0.3048)
			(stroke
				(width 0.1)
				(type default)
			)
			(layer "B.Fab")
		)
		(fp_line
			(start 0.12065 -0.2794)
			(end -0.12065 -0.2794)
			(stroke
				(width 0.1)
				(type default)
			)
			(layer "B.Fab")
		)
		(fp_line
			(start -0.12065 -0.2794)
			(end -0.12065 -0.3048)
			(stroke
				(width 0.1)
				(type default)
			)
			(layer "B.Fab")
		)
		(fp_line
			(start 0.12065 0.2794)
			(end 0.12065 0.3048)
			(stroke
				(width 0.1)
				(type default)
			)
			(layer "B.Fab")
		)
		(fp_line
			(start -0.120396 0.2794)
			(end 0.12065 0.2794)
			(stroke
				(width 0.1)
				(type default)
			)
			(layer "B.Fab")
		)
		(fp_line
			(start 0.67945 0.3048)
			(end 0.67945 -0.305054)
			(stroke
				(width 0.1)
				(type default)
			)
			(layer "B.Fab")
		)
		(fp_line
			(start 0.12065 0.3048)
			(end 0.67945 0.3048)
			(stroke
				(width 0.1)
				(type default)
			)
			(layer "B.Fab")
		)
		(fp_line
			(start -0.120396 0.3048)
			(end -0.120396 0.2794)
			(stroke
				(width 0.1)
				(type default)
			)
			(layer "B.Fab")
		)
		(fp_line
			(start -0.67945 0.3048)
			(end -0.120396 0.3048)
			(stroke
				(width 0.1)
				(type default)
			)
			(layer "B.Fab")
		)
		(pad "1" smd circle
			(at 0.40005 0 270)
			(size 0 0)
			(layers "B.Cu" "B.Mask" "B.Paste")
			(net "P3V3_AUX")
		)
		(pad "2" smd circle
			(at -0.40005 0 270)
			(size 0 0)
			(layers "B.Cu" "B.Mask" "B.Paste")
			(net "SMB_BMC_ALERT15_N")
		)
	)
	(footprint ""
		(layer "B.Cu")
		(at 59.3852 -77.9526)
		(property "Reference" "R547"
			(at 0 0 0)
			(layer "B.SilkS")
			(hide yes)
			(effects
				(font
					(size 1.27 1.27)
				)
				(justify mirror)
			)
		)
		(property "Value" ""
			(at 0 0 0)
			(layer "B.Fab")
			(effects
				(font
					(size 1.27 1.27)
				)
				(justify mirror)
			)
		)
		(duplicate_pad_numbers_are_jumpers no)
		(fp_line
			(start -0.7874 -0.4064)
			(end -0.7874 0.4064)
			(stroke
				(width 0.1524)
				(type default)
			)
			(layer "B.SilkS")
		)
		(fp_line
			(start -0.7874 0.4064)
			(end 0.7874 0.4064)
			(stroke
				(width 0.1524)
				(type default)
			)
			(layer "B.SilkS")
		)
		(fp_line
			(start 0.7874 -0.4064)
			(end -0.7874 -0.4064)
			(stroke
				(width 0.1524)
				(type default)
			)
			(layer "B.SilkS")
		)
		(fp_line
			(start 0.7874 0.4064)
			(end 0.7874 -0.4064)
			(stroke
				(width 0.1524)
				(type default)
			)
			(layer "B.SilkS")
		)
		(fp_line
			(start -0.67945 -0.3048)
			(end -0.67945 0.3048)
			(stroke
				(width 0.1)
				(type default)
			)
			(layer "B.Fab")
		)
		(fp_line
			(start -0.67945 0.3048)
			(end -0.120396 0.3048)
			(stroke
				(width 0.1)
				(type default)
			)
			(layer "B.Fab")
		)
		(fp_line
			(start -0.12065 -0.3048)
			(end -0.67945 -0.3048)
			(stroke
				(width 0.1)
				(type default)
			)
			(layer "B.Fab")
		)
		(fp_line
			(start -0.12065 -0.2794)
			(end -0.12065 -0.3048)
			(stroke
				(width 0.1)
				(type default)
			)
			(layer "B.Fab")
		)
		(fp_line
			(start -0.120396 0.2794)
			(end 0.12065 0.2794)
			(stroke
				(width 0.1)
				(type default)
			)
			(layer "B.Fab")
		)
		(fp_line
			(start -0.120396 0.3048)
			(end -0.120396 0.2794)
			(stroke
				(width 0.1)
				(type default)
			)
			(layer "B.Fab")
		)
		(fp_line
			(start 0.12065 -0.305054)
			(end 0.12065 -0.2794)
			(stroke
				(width 0.1)
				(type default)
			)
			(layer "B.Fab")
		)
		(fp_line
			(start 0.12065 -0.2794)
			(end -0.12065 -0.2794)
			(stroke
				(width 0.1)
				(type default)
			)
			(layer "B.Fab")
		)
		(fp_line
			(start 0.12065 0.2794)
			(end 0.12065 0.3048)
			(stroke
				(width 0.1)
				(type default)
			)
			(layer "B.Fab")
		)
		(fp_line
			(start 0.12065 0.3048)
			(end 0.67945 0.3048)
			(stroke
				(width 0.1)
				(type default)
			)
			(layer "B.Fab")
		)
		(fp_line
			(start 0.67945 -0.305054)
			(end 0.12065 -0.305054)
			(stroke
				(width 0.1)
				(type default)
			)
			(layer "B.Fab")
		)
		(fp_line
			(start 0.67945 0.3048)
			(end 0.67945 -0.305054)
			(stroke
				(width 0.1)
				(type default)
			)
			(layer "B.Fab")
		)
		(pad "1" smd circle
			(at 0.40005 0 180)
			(size 0 0)
			(layers "B.Cu" "B.Mask" "B.Paste")
			(net "SPI_BMC_CS1_FLASH_R_N")
		)
		(pad "2" smd circle
			(at -0.40005 0 180)
			(size 0 0)
			(layers "B.Cu" "B.Mask" "B.Paste")
			(net "SPI_BMC_BOOT_CS1_R_N")
		)
	)
	(footprint ""
		(layer "B.Cu")
		(at 26.416 -92.075 90)
		(property "Reference" "R301"
			(at 0 0 90)
			(layer "B.SilkS")
			(hide yes)
			(effects
				(font
					(size 1.27 1.27)
				)
				(justify mirror)
			)
		)
		(property "Value" ""
			(at 0 0 90)
			(layer "B.Fab")
			(effects
				(font
					(size 1.27 1.27)
				)
				(justify mirror)
			)
		)
		(duplicate_pad_numbers_are_jumpers no)
		(fp_line
			(start 0.7874 -0.4064)
			(end -0.7874 -0.4064)
			(stroke
				(width 0.1524)
				(type default)
			)
			(layer "B.SilkS")
		)
		(fp_line
			(start -0.7874 -0.4064)
			(end -0.7874 0.4064)
			(stroke
				(width 0.1524)
				(type default)
			)
			(layer "B.SilkS")
		)
		(fp_line
			(start 0.7874 0.4064)
			(end 0.7874 -0.4064)
			(stroke
				(width 0.1524)
				(type default)
			)
			(layer "B.SilkS")
		)
		(fp_line
			(start -0.7874 0.4064)
			(end 0.7874 0.4064)
			(stroke
				(width 0.1524)
				(type default)
			)
			(layer "B.SilkS")
		)
		(fp_line
			(start 0.67945 -0.305054)
			(end 0.12065 -0.305054)
			(stroke
				(width 0.1)
				(type default)
			)
			(layer "B.Fab")
		)
		(fp_line
			(start 0.12065 -0.305054)
			(end 0.12065 -0.2794)
			(stroke
				(width 0.1)
				(type default)
			)
			(layer "B.Fab")
		)
		(fp_line
			(start -0.12065 -0.3048)
			(end -0.67945 -0.3048)
			(stroke
				(width 0.1)
				(type default)
			)
			(layer "B.Fab")
		)
		(fp_line
			(start -0.67945 -0.3048)
			(end -0.67945 0.3048)
			(stroke
				(width 0.1)
				(type default)
			)
			(layer "B.Fab")
		)
		(fp_line
			(start 0.12065 -0.2794)
			(end -0.12065 -0.2794)
			(stroke
				(width 0.1)
				(type default)
			)
			(layer "B.Fab")
		)
		(fp_line
			(start -0.12065 -0.2794)
			(end -0.12065 -0.3048)
			(stroke
				(width 0.1)
				(type default)
			)
			(layer "B.Fab")
		)
		(fp_line
			(start 0.12065 0.2794)
			(end 0.12065 0.3048)
			(stroke
				(width 0.1)
				(type default)
			)
			(layer "B.Fab")
		)
		(fp_line
			(start -0.120396 0.2794)
			(end 0.12065 0.2794)
			(stroke
				(width 0.1)
				(type default)
			)
			(layer "B.Fab")
		)
		(fp_line
			(start 0.67945 0.3048)
			(end 0.67945 -0.305054)
			(stroke
				(width 0.1)
				(type default)
			)
			(layer "B.Fab")
		)
		(fp_line
			(start 0.12065 0.3048)
			(end 0.67945 0.3048)
			(stroke
				(width 0.1)
				(type default)
			)
			(layer "B.Fab")
		)
		(fp_line
			(start -0.120396 0.3048)
			(end -0.120396 0.2794)
			(stroke
				(width 0.1)
				(type default)
			)
			(layer "B.Fab")
		)
		(fp_line
			(start -0.67945 0.3048)
			(end -0.120396 0.3048)
			(stroke
				(width 0.1)
				(type default)
			)
			(layer "B.Fab")
		)
		(pad "1" smd circle
			(at 0.40005 0 270)
			(size 0 0)
			(layers "B.Cu" "B.Mask" "B.Paste")
			(net "P3V3_AUX")
		)
		(pad "2" smd circle
			(at -0.40005 0 270)
			(size 0 0)
			(layers "B.Cu" "B.Mask" "B.Paste")
			(net "VCCIO5")
		)
	)
	(footprint ""
		(layer "B.Cu")
		(at 43.367198 -34.637726 90)
		(property "Reference" "R394"
			(at 0 0 90)
			(layer "B.SilkS")
			(hide yes)
			(effects
				(font
					(size 1.27 1.27)
				)
				(justify mirror)
			)
		)
		(property "Value" ""
			(at 0 0 90)
			(layer "B.Fab")
			(effects
				(font
					(size 1.27 1.27)
				)
				(justify mirror)
			)
		)
		(duplicate_pad_numbers_are_jumpers no)
		(fp_line
			(start 0.7874 -0.4064)
			(end -0.7874 -0.4064)
			(stroke
				(width 0.1524)
				(type default)
			)
			(layer "B.SilkS")
		)
		(fp_line
			(start -0.7874 -0.4064)
			(end -0.7874 0.4064)
			(stroke
				(width 0.1524)
				(type default)
			)
			(layer "B.SilkS")
		)
		(fp_line
			(start 0.7874 0.4064)
			(end 0.7874 -0.4064)
			(stroke
				(width 0.1524)
				(type default)
			)
			(layer "B.SilkS")
		)
		(fp_line
			(start -0.7874 0.4064)
			(end 0.7874 0.4064)
			(stroke
				(width 0.1524)
				(type default)
			)
			(layer "B.SilkS")
		)
		(fp_line
			(start 0.67945 -0.305054)
			(end 0.12065 -0.305054)
			(stroke
				(width 0.1)
				(type default)
			)
			(layer "B.Fab")
		)
		(fp_line
			(start 0.12065 -0.305054)
			(end 0.12065 -0.2794)
			(stroke
				(width 0.1)
				(type default)
			)
			(layer "B.Fab")
		)
		(fp_line
			(start -0.12065 -0.3048)
			(end -0.67945 -0.3048)
			(stroke
				(width 0.1)
				(type default)
			)
			(layer "B.Fab")
		)
		(fp_line
			(start -0.67945 -0.3048)
			(end -0.67945 0.3048)
			(stroke
				(width 0.1)
				(type default)
			)
			(layer "B.Fab")
		)
		(fp_line
			(start 0.12065 -0.2794)
			(end -0.12065 -0.2794)
			(stroke
				(width 0.1)
				(type default)
			)
			(layer "B.Fab")
		)
		(fp_line
			(start -0.12065 -0.2794)
			(end -0.12065 -0.3048)
			(stroke
				(width 0.1)
				(type default)
			)
			(layer "B.Fab")
		)
		(fp_line
			(start 0.12065 0.2794)
			(end 0.12065 0.3048)
			(stroke
				(width 0.1)
				(type default)
			)
			(layer "B.Fab")
		)
		(fp_line
			(start -0.120396 0.2794)
			(end 0.12065 0.2794)
			(stroke
				(width 0.1)
				(type default)
			)
			(layer "B.Fab")
		)
		(fp_line
			(start 0.67945 0.3048)
			(end 0.67945 -0.305054)
			(stroke
				(width 0.1)
				(type default)
			)
			(layer "B.Fab")
		)
		(fp_line
			(start 0.12065 0.3048)
			(end 0.67945 0.3048)
			(stroke
				(width 0.1)
				(type default)
			)
			(layer "B.Fab")
		)
		(fp_line
			(start -0.120396 0.3048)
			(end -0.120396 0.2794)
			(stroke
				(width 0.1)
				(type default)
			)
			(layer "B.Fab")
		)
		(fp_line
			(start -0.67945 0.3048)
			(end -0.120396 0.3048)
			(stroke
				(width 0.1)
				(type default)
			)
			(layer "B.Fab")
		)
		(pad "1" smd circle
			(at 0.40005 0 270)
			(size 0 0)
			(layers "B.Cu" "B.Mask" "B.Paste")
			(net "SMB_BMC_MM2_R_SDA")
		)
		(pad "2" smd circle
			(at -0.40005 0 270)
			(size 0 0)
			(layers "B.Cu" "B.Mask" "B.Paste")
			(net "SMB_BMC_MM2_SDA")
		)
	)
	(footprint ""
		(layer "B.Cu")
		(at 76.691744 -37.559488 90)
		(property "Reference" "R362"
			(at 0 0 90)
			(layer "B.SilkS")
			(hide yes)
			(effects
				(font
					(size 1.27 1.27)
				)
				(justify mirror)
			)
		)
		(property "Value" ""
			(at 0 0 90)
			(layer "B.Fab")
			(effects
				(font
					(size 1.27 1.27)
				)
				(justify mirror)
			)
		)
		(duplicate_pad_numbers_are_jumpers no)
		(fp_line
			(start 0.7874 -0.4064)
			(end -0.7874 -0.4064)
			(stroke
				(width 0.1524)
				(type default)
			)
			(layer "B.SilkS")
		)
		(fp_line
			(start -0.7874 -0.4064)
			(end -0.7874 0.4064)
			(stroke
				(width 0.1524)
				(type default)
			)
			(layer "B.SilkS")
		)
		(fp_line
			(start 0.7874 0.4064)
			(end 0.7874 -0.4064)
			(stroke
				(width 0.1524)
				(type default)
			)
			(layer "B.SilkS")
		)
		(fp_line
			(start -0.7874 0.4064)
			(end 0.7874 0.4064)
			(stroke
				(width 0.1524)
				(type default)
			)
			(layer "B.SilkS")
		)
		(fp_line
			(start 0.67945 -0.305054)
			(end 0.12065 -0.305054)
			(stroke
				(width 0.1)
				(type default)
			)
			(layer "B.Fab")
		)
		(fp_line
			(start 0.12065 -0.305054)
			(end 0.12065 -0.2794)
			(stroke
				(width 0.1)
				(type default)
			)
			(layer "B.Fab")
		)
		(fp_line
			(start -0.12065 -0.3048)
			(end -0.67945 -0.3048)
			(stroke
				(width 0.1)
				(type default)
			)
			(layer "B.Fab")
		)
		(fp_line
			(start -0.67945 -0.3048)
			(end -0.67945 0.3048)
			(stroke
				(width 0.1)
				(type default)
			)
			(layer "B.Fab")
		)
		(fp_line
			(start 0.12065 -0.2794)
			(end -0.12065 -0.2794)
			(stroke
				(width 0.1)
				(type default)
			)
			(layer "B.Fab")
		)
		(fp_line
			(start -0.12065 -0.2794)
			(end -0.12065 -0.3048)
			(stroke
				(width 0.1)
				(type default)
			)
			(layer "B.Fab")
		)
		(fp_line
			(start 0.12065 0.2794)
			(end 0.12065 0.3048)
			(stroke
				(width 0.1)
				(type default)
			)
			(layer "B.Fab")
		)
		(fp_line
			(start -0.120396 0.2794)
			(end 0.12065 0.2794)
			(stroke
				(width 0.1)
				(type default)
			)
			(layer "B.Fab")
		)
		(fp_line
			(start 0.67945 0.3048)
			(end 0.67945 -0.305054)
			(stroke
				(width 0.1)
				(type default)
			)
			(layer "B.Fab")
		)
		(fp_line
			(start 0.12065 0.3048)
			(end 0.67945 0.3048)
			(stroke
				(width 0.1)
				(type default)
			)
			(layer "B.Fab")
		)
		(fp_line
			(start -0.120396 0.3048)
			(end -0.120396 0.2794)
			(stroke
				(width 0.1)
				(type default)
			)
			(layer "B.Fab")
		)
		(fp_line
			(start -0.67945 0.3048)
			(end -0.120396 0.3048)
			(stroke
				(width 0.1)
				(type default)
			)
			(layer "B.Fab")
		)
		(pad "1" smd circle
			(at 0.40005 0 270)
			(size 0 0)
			(layers "B.Cu" "B.Mask" "B.Paste")
			(net "M_BMC_DDR4_MA<11>")
		)
		(pad "2" smd circle
			(at -0.40005 0 270)
			(size 0 0)
			(layers "B.Cu" "B.Mask" "B.Paste")
			(net "P1V2_AUX")
		)
	)
	(footprint ""
		(layer "B.Cu")
		(at 58.55208 -61.0616 90)
		(property "Reference" "R37"
			(at 0 0 90)
			(layer "B.SilkS")
			(hide yes)
			(effects
				(font
					(size 1.27 1.27)
				)
				(justify mirror)
			)
		)
		(property "Value" ""
			(at 0 0 90)
			(layer "B.Fab")
			(effects
				(font
					(size 1.27 1.27)
				)
				(justify mirror)
			)
		)
		(duplicate_pad_numbers_are_jumpers no)
		(fp_line
			(start 0.7874 -0.4064)
			(end -0.7874 -0.4064)
			(stroke
				(width 0.1524)
				(type default)
			)
			(layer "B.SilkS")
		)
		(fp_line
			(start -0.7874 -0.4064)
			(end -0.7874 0.4064)
			(stroke
				(width 0.1524)
				(type default)
			)
			(layer "B.SilkS")
		)
		(fp_line
			(start 0.7874 0.4064)
			(end 0.7874 -0.4064)
			(stroke
				(width 0.1524)
				(type default)
			)
			(layer "B.SilkS")
		)
		(fp_line
			(start -0.7874 0.4064)
			(end 0.7874 0.4064)
			(stroke
				(width 0.1524)
				(type default)
			)
			(layer "B.SilkS")
		)
		(fp_line
			(start 0.67945 -0.305054)
			(end 0.12065 -0.305054)
			(stroke
				(width 0.1)
				(type default)
			)
			(layer "B.Fab")
		)
		(fp_line
			(start 0.12065 -0.305054)
			(end 0.12065 -0.2794)
			(stroke
				(width 0.1)
				(type default)
			)
			(layer "B.Fab")
		)
		(fp_line
			(start -0.12065 -0.3048)
			(end -0.67945 -0.3048)
			(stroke
				(width 0.1)
				(type default)
			)
			(layer "B.Fab")
		)
		(fp_line
			(start -0.67945 -0.3048)
			(end -0.67945 0.3048)
			(stroke
				(width 0.1)
				(type default)
			)
			(layer "B.Fab")
		)
		(fp_line
			(start 0.12065 -0.2794)
			(end -0.12065 -0.2794)
			(stroke
				(width 0.1)
				(type default)
			)
			(layer "B.Fab")
		)
		(fp_line
			(start -0.12065 -0.2794)
			(end -0.12065 -0.3048)
			(stroke
				(width 0.1)
				(type default)
			)
			(layer "B.Fab")
		)
		(fp_line
			(start 0.12065 0.2794)
			(end 0.12065 0.3048)
			(stroke
				(width 0.1)
				(type default)
			)
			(layer "B.Fab")
		)
		(fp_line
			(start -0.120396 0.2794)
			(end 0.12065 0.2794)
			(stroke
				(width 0.1)
				(type default)
			)
			(layer "B.Fab")
		)
		(fp_line
			(start 0.67945 0.3048)
			(end 0.67945 -0.305054)
			(stroke
				(width 0.1)
				(type default)
			)
			(layer "B.Fab")
		)
		(fp_line
			(start 0.12065 0.3048)
			(end 0.67945 0.3048)
			(stroke
				(width 0.1)
				(type default)
			)
			(layer "B.Fab")
		)
		(fp_line
			(start -0.120396 0.3048)
			(end -0.120396 0.2794)
			(stroke
				(width 0.1)
				(type default)
			)
			(layer "B.Fab")
		)
		(fp_line
			(start -0.67945 0.3048)
			(end -0.120396 0.3048)
			(stroke
				(width 0.1)
				(type default)
			)
			(layer "B.Fab")
		)
		(pad "1" smd circle
			(at 0.40005 0 270)
			(size 0 0)
			(layers "B.Cu" "B.Mask" "B.Paste")
			(net "IRQ_SMI_ACTIVE_GF_N")
		)
		(pad "2" smd circle
			(at -0.40005 0 270)
			(size 0 0)
			(layers "B.Cu" "B.Mask" "B.Paste")
			(net "IRQ_SMI_ACTIVE_BMC_N")
		)
	)
	(footprint ""
		(layer "B.Cu")
		(at 21.301456 -92.4306 -90)
		(property "Reference" "C242"
			(at 0 0 90)
			(layer "B.SilkS")
			(hide yes)
			(effects
				(font
					(size 1.27 1.27)
				)
				(justify mirror)
			)
		)
		(property "Value" ""
			(at 0 0 90)
			(layer "B.Fab")
			(effects
				(font
					(size 1.27 1.27)
				)
				(justify mirror)
			)
		)
		(duplicate_pad_numbers_are_jumpers no)
		(fp_line
			(start -0.69215 0.2921)
			(end 0.69215 0.2921)
			(stroke
				(width 0.1524)
				(type default)
			)
			(layer "B.SilkS")
		)
		(fp_line
			(start 0.69215 0.2921)
			(end 0.69215 -0.2921)
			(stroke
				(width 0.1524)
				(type default)
			)
			(layer "B.SilkS")
		)
		(fp_line
			(start -0.69215 -0.2921)
			(end -0.69215 0.2921)
			(stroke
				(width 0.1524)
				(type default)
			)
			(layer "B.SilkS")
		)
		(fp_line
			(start 0.69215 -0.2921)
			(end -0.69215 -0.2921)
			(stroke
				(width 0.1524)
				(type default)
			)
			(layer "B.SilkS")
		)
		(fp_line
			(start -0.51435 0.2794)
			(end 0.51435 0.2794)
			(stroke
				(width 0.1)
				(type default)
			)
			(layer "B.Fab")
		)
		(fp_line
			(start 0.51435 0.2794)
			(end 0.51435 -0.2794)
			(stroke
				(width 0.1)
				(type default)
			)
			(layer "B.Fab")
		)
		(fp_line
			(start -0.51435 -0.2794)
			(end -0.51435 0.2794)
			(stroke
				(width 0.1)
				(type default)
			)
			(layer "B.Fab")
		)
		(fp_line
			(start 0.51435 -0.2794)
			(end -0.51435 -0.2794)
			(stroke
				(width 0.1)
				(type default)
			)
			(layer "B.Fab")
		)
		(pad "1" smd circle
			(at 0.40005 0 90)
			(size 0 0)
			(layers "B.Cu" "B.Mask" "B.Paste")
			(net "VCCIO0")
		)
		(pad "2" smd circle
			(at -0.40005 0 90)
			(size 0 0)
			(layers "B.Cu" "B.Mask" "B.Paste")
			(net "GND")
		)
		(zone
			(layer "B.Cu")
			(hatch none 0.5)
			(connect_pads
				(clearance 0)
			)
			(min_thickness 0.25)
			(keepout
				(tracks not_allowed)
				(vias allowed)
				(pads allowed)
				(copperpour not_allowed)
				(footprints allowed)
			)
			(placement
				(enabled no)
				(sheetname "")
			)
			(fill
				(thermal_gap 0.5)
				(thermal_bridge_width 0.5)
				(island_removal_mode 0)
			)
			(polygon
				(pts
					(xy 21.213826 -92.2401) (xy 21.15566 -92.33154) (xy 21.15566 -92.53093) (xy 21.213826 -92.6211)
					(xy 21.389086 -92.6211) (xy 21.447506 -92.53093) (xy 21.447506 -92.33154) (xy 21.38934 -92.2401)
				)
			)
		)
	)
	(footprint ""
		(layer "B.Cu")
		(at 71.374 -19.685 90)
		(property "Reference" "R857"
			(at 0 0 90)
			(layer "B.SilkS")
			(hide yes)
			(effects
				(font
					(size 1.27 1.27)
				)
				(justify mirror)
			)
		)
		(property "Value" ""
			(at 0 0 90)
			(layer "B.Fab")
			(effects
				(font
					(size 1.27 1.27)
				)
				(justify mirror)
			)
		)
		(duplicate_pad_numbers_are_jumpers no)
		(fp_line
			(start 0.7874 -0.4064)
			(end -0.7874 -0.4064)
			(stroke
				(width 0.1524)
				(type default)
			)
			(layer "B.SilkS")
		)
		(fp_line
			(start -0.7874 -0.4064)
			(end -0.7874 0.4064)
			(stroke
				(width 0.1524)
				(type default)
			)
			(layer "B.SilkS")
		)
		(fp_line
			(start 0.7874 0.4064)
			(end 0.7874 -0.4064)
			(stroke
				(width 0.1524)
				(type default)
			)
			(layer "B.SilkS")
		)
		(fp_line
			(start -0.7874 0.4064)
			(end 0.7874 0.4064)
			(stroke
				(width 0.1524)
				(type default)
			)
			(layer "B.SilkS")
		)
		(fp_line
			(start 0.67945 -0.305054)
			(end 0.12065 -0.305054)
			(stroke
				(width 0.1)
				(type default)
			)
			(layer "B.Fab")
		)
		(fp_line
			(start 0.12065 -0.305054)
			(end 0.12065 -0.2794)
			(stroke
				(width 0.1)
				(type default)
			)
			(layer "B.Fab")
		)
		(fp_line
			(start -0.12065 -0.3048)
			(end -0.67945 -0.3048)
			(stroke
				(width 0.1)
				(type default)
			)
			(layer "B.Fab")
		)
		(fp_line
			(start -0.67945 -0.3048)
			(end -0.67945 0.3048)
			(stroke
				(width 0.1)
				(type default)
			)
			(layer "B.Fab")
		)
		(fp_line
			(start 0.12065 -0.2794)
			(end -0.12065 -0.2794)
			(stroke
				(width 0.1)
				(type default)
			)
			(layer "B.Fab")
		)
		(fp_line
			(start -0.12065 -0.2794)
			(end -0.12065 -0.3048)
			(stroke
				(width 0.1)
				(type default)
			)
			(layer "B.Fab")
		)
		(fp_line
			(start 0.12065 0.2794)
			(end 0.12065 0.3048)
			(stroke
				(width 0.1)
				(type default)
			)
			(layer "B.Fab")
		)
		(fp_line
			(start -0.120396 0.2794)
			(end 0.12065 0.2794)
			(stroke
				(width 0.1)
				(type default)
			)
			(layer "B.Fab")
		)
		(fp_line
			(start 0.67945 0.3048)
			(end 0.67945 -0.305054)
			(stroke
				(width 0.1)
				(type default)
			)
			(layer "B.Fab")
		)
		(fp_line
			(start 0.12065 0.3048)
			(end 0.67945 0.3048)
			(stroke
				(width 0.1)
				(type default)
			)
			(layer "B.Fab")
		)
		(fp_line
			(start -0.120396 0.3048)
			(end -0.120396 0.2794)
			(stroke
				(width 0.1)
				(type default)
			)
			(layer "B.Fab")
		)
		(fp_line
			(start -0.67945 0.3048)
			(end -0.120396 0.3048)
			(stroke
				(width 0.1)
				(type default)
			)
			(layer "B.Fab")
		)
		(pad "1" smd circle
			(at 0.40005 0 270)
			(size 0 0)
			(layers "B.Cu" "B.Mask" "B.Paste")
			(net "FM_BOARD_BMC_REV_ID1")
		)
		(pad "2" smd circle
			(at -0.40005 0 270)
			(size 0 0)
			(layers "B.Cu" "B.Mask" "B.Paste")
			(net "GND")
		)
	)
	(footprint ""
		(layer "B.Cu")
		(at 65.89014 -97.6376 180)
		(property "Reference" "R646"
			(at 0 0 0)
			(layer "B.SilkS")
			(hide yes)
			(effects
				(font
					(size 1.27 1.27)
				)
				(justify mirror)
			)
		)
		(property "Value" ""
			(at 0 0 0)
			(layer "B.Fab")
			(effects
				(font
					(size 1.27 1.27)
				)
				(justify mirror)
			)
		)
		(duplicate_pad_numbers_are_jumpers no)
		(fp_line
			(start 1.2954 0.5842)
			(end 1.2954 -0.5842)
			(stroke
				(width 0.1524)
				(type default)
			)
			(layer "B.SilkS")
		)
		(fp_line
			(start 1.2954 -0.5842)
			(end -1.2954 -0.5842)
			(stroke
				(width 0.1524)
				(type default)
			)
			(layer "B.SilkS")
		)
		(fp_line
			(start -1.2954 0.5842)
			(end 1.2954 0.5842)
			(stroke
				(width 0.1524)
				(type default)
			)
			(layer "B.SilkS")
		)
		(fp_line
			(start -1.2954 -0.5842)
			(end -1.2954 0.5842)
			(stroke
				(width 0.1524)
				(type default)
			)
			(layer "B.SilkS")
		)
		(fp_line
			(start 1.1938 0.4064)
			(end 1.1938 -0.406654)
			(stroke
				(width 0.1)
				(type default)
			)
			(layer "B.Fab")
		)
		(fp_line
			(start 1.1938 -0.406654)
			(end 0.8636 -0.406654)
			(stroke
				(width 0.1)
				(type default)
			)
			(layer "B.Fab")
		)
		(fp_line
			(start 0.8636 0.4572)
			(end 0.8636 0.4318)
			(stroke
				(width 0.1)
				(type default)
			)
			(layer "B.Fab")
		)
		(fp_line
			(start 0.8636 0.4318)
			(end 0.8636 0.4064)
			(stroke
				(width 0.1)
				(type default)
			)
			(layer "B.Fab")
		)
		(fp_line
			(start 0.8636 0.4064)
			(end 1.1938 0.4064)
			(stroke
				(width 0.1)
				(type default)
			)
			(layer "B.Fab")
		)
		(fp_line
			(start 0.8636 -0.406654)
			(end 0.8636 -0.4572)
			(stroke
				(width 0.1)
				(type default)
			)
			(layer "B.Fab")
		)
		(fp_line
			(start 0.8636 -0.4572)
			(end -0.8636 -0.4572)
			(stroke
				(width 0.1)
				(type default)
			)
			(layer "B.Fab")
		)
		(fp_line
			(start -0.8636 0.4572)
			(end 0.8636 0.4572)
			(stroke
				(width 0.1)
				(type default)
			)
			(layer "B.Fab")
		)
		(fp_line
			(start -0.8636 0.4064)
			(end -0.8636 0.4572)
			(stroke
				(width 0.1)
				(type default)
			)
			(layer "B.Fab")
		)
		(fp_line
			(start -0.8636 -0.406654)
			(end -1.1938 -0.406654)
			(stroke
				(width 0.1)
				(type default)
			)
			(layer "B.Fab")
		)
		(fp_line
			(start -0.8636 -0.4572)
			(end -0.8636 -0.406654)
			(stroke
				(width 0.1)
				(type default)
			)
			(layer "B.Fab")
		)
		(fp_line
			(start -1.1938 0.4064)
			(end -0.8636 0.4064)
			(stroke
				(width 0.1)
				(type default)
			)
			(layer "B.Fab")
		)
		(fp_line
			(start -1.1938 -0.406654)
			(end -1.1938 0.4064)
			(stroke
				(width 0.1)
				(type default)
			)
			(layer "B.Fab")
		)
		(pad "1" smd rect
			(at 0.7366 0 90)
			(size 0.7112 0.8128)
			(layers "B.Cu" "B.Mask" "B.Paste")
			(net "PGPPA_BMC_AUX_L")
		)
		(pad "2" smd rect
			(at -0.7366 0 90)
			(size 0.7112 0.8128)
			(layers "B.Cu" "B.Mask" "B.Paste")
			(net "P3V3_AUX")
		)
	)
	(footprint ""
		(layer "B.Cu")
		(at 14.224 -24.13 -90)
		(property "Reference" "U8"
			(at 1.31826 1.352296 0)
			(unlocked yes)
			(layer "B.SilkS")
			(effects
				(font
					(size 0.7874 0.5842)
					(thickness 0.1524)
				)
				(justify left mirror)
			)
		)
		(property "Value" ""
			(at 0 0 90)
			(layer "B.Fab")
			(effects
				(font
					(size 1.27 1.27)
				)
				(justify mirror)
			)
		)
		(duplicate_pad_numbers_are_jumpers no)
		(fp_line
			(start -1.400048 1.100074)
			(end 1.400048 1.100074)
			(stroke
				(width 0.1524)
				(type default)
			)
			(layer "B.SilkS")
		)
		(fp_line
			(start 1.400048 1.100074)
			(end 1.400048 -1.100074)
			(stroke
				(width 0.1524)
				(type default)
			)
			(layer "B.SilkS")
		)
		(fp_line
			(start -1.400048 -1.100074)
			(end -1.400048 1.100074)
			(stroke
				(width 0.1524)
				(type default)
			)
			(layer "B.SilkS")
		)
		(fp_line
			(start -1.400048 -1.100074)
			(end 1.400048 -1.100074)
			(stroke
				(width 0.1524)
				(type default)
			)
			(layer "B.SilkS")
		)
		(fp_poly
			(pts
				(xy 1.029208 -1.283716) (xy 0.521208 -2.299716) (xy 1.537208 -2.299716)
			)
			(stroke
				(width 0)
				(type default)
			)
			(fill yes)
			(layer "B.SilkS")
		)
		(fp_line
			(start -0.674878 1.100074)
			(end 0.674878 1.100074)
			(stroke
				(width 0.1)
				(type default)
			)
			(layer "B.Fab")
		)
		(fp_line
			(start 0.674878 1.100074)
			(end 0.674878 -1.100074)
			(stroke
				(width 0.1)
				(type default)
			)
			(layer "B.Fab")
		)
		(fp_line
			(start -0.674878 -1.100074)
			(end -0.674878 1.100074)
			(stroke
				(width 0.1)
				(type default)
			)
			(layer "B.Fab")
		)
		(fp_line
			(start 0.674878 -1.100074)
			(end -0.674878 -1.100074)
			(stroke
				(width 0.1)
				(type default)
			)
			(layer "B.Fab")
		)
		(fp_poly
			(pts
				(xy 1.590548 -0.649986) (xy 2.606548 -1.157986) (xy 2.606548 -0.141986)
			)
			(stroke
				(width 0)
				(type default)
			)
			(fill yes)
			(layer "B.Fab")
		)
		(pad "1" smd rect
			(at 0.94996 -0.649986 180)
			(size 0.4318 0.6096)
			(layers "B.Cu" "B.Mask" "B.Paste")
			(net "BMC_ID_BEEP_SEL")
		)
		(pad "2" smd rect
			(at 0.94996 0 180)
			(size 0.4318 0.6096)
			(layers "B.Cu" "B.Mask" "B.Paste")
			(net "PCH_BEEP_LED")
		)
		(pad "3" smd rect
			(at 0.94996 0.649986 180)
			(size 0.4318 0.6096)
			(layers "B.Cu" "B.Mask" "B.Paste")
			(net "GND")
		)
		(pad "4" smd rect
			(at -0.94996 0.649986 180)
			(size 0.4318 0.6096)
			(layers "B.Cu" "B.Mask" "B.Paste")
			(net "BEEP_LED")
		)
		(pad "5" smd rect
			(at -0.94996 -0.649986 180)
			(size 0.4318 0.6096)
			(layers "B.Cu" "B.Mask" "B.Paste")
			(net "P3V3_AUX")
		)
	)
	(footprint ""
		(layer "B.Cu")
		(at 38.608 -66.421 90)
		(property "Reference" "R642"
			(at 0 0 90)
			(layer "B.SilkS")
			(hide yes)
			(effects
				(font
					(size 1.27 1.27)
				)
				(justify mirror)
			)
		)
		(property "Value" ""
			(at 0 0 90)
			(layer "B.Fab")
			(effects
				(font
					(size 1.27 1.27)
				)
				(justify mirror)
			)
		)
		(duplicate_pad_numbers_are_jumpers no)
		(fp_line
			(start 0.7874 -0.4064)
			(end -0.7874 -0.4064)
			(stroke
				(width 0.1524)
				(type default)
			)
			(layer "B.SilkS")
		)
		(fp_line
			(start -0.7874 -0.4064)
			(end -0.7874 0.4064)
			(stroke
				(width 0.1524)
				(type default)
			)
			(layer "B.SilkS")
		)
		(fp_line
			(start 0.7874 0.4064)
			(end 0.7874 -0.4064)
			(stroke
				(width 0.1524)
				(type default)
			)
			(layer "B.SilkS")
		)
		(fp_line
			(start -0.7874 0.4064)
			(end 0.7874 0.4064)
			(stroke
				(width 0.1524)
				(type default)
			)
			(layer "B.SilkS")
		)
		(fp_line
			(start 0.67945 -0.305054)
			(end 0.12065 -0.305054)
			(stroke
				(width 0.1)
				(type default)
			)
			(layer "B.Fab")
		)
		(fp_line
			(start 0.12065 -0.305054)
			(end 0.12065 -0.2794)
			(stroke
				(width 0.1)
				(type default)
			)
			(layer "B.Fab")
		)
		(fp_line
			(start -0.12065 -0.3048)
			(end -0.67945 -0.3048)
			(stroke
				(width 0.1)
				(type default)
			)
			(layer "B.Fab")
		)
		(fp_line
			(start -0.67945 -0.3048)
			(end -0.67945 0.3048)
			(stroke
				(width 0.1)
				(type default)
			)
			(layer "B.Fab")
		)
		(fp_line
			(start 0.12065 -0.2794)
			(end -0.12065 -0.2794)
			(stroke
				(width 0.1)
				(type default)
			)
			(layer "B.Fab")
		)
		(fp_line
			(start -0.12065 -0.2794)
			(end -0.12065 -0.3048)
			(stroke
				(width 0.1)
				(type default)
			)
			(layer "B.Fab")
		)
		(fp_line
			(start 0.12065 0.2794)
			(end 0.12065 0.3048)
			(stroke
				(width 0.1)
				(type default)
			)
			(layer "B.Fab")
		)
		(fp_line
			(start -0.120396 0.2794)
			(end 0.12065 0.2794)
			(stroke
				(width 0.1)
				(type default)
			)
			(layer "B.Fab")
		)
		(fp_line
			(start 0.67945 0.3048)
			(end 0.67945 -0.305054)
			(stroke
				(width 0.1)
				(type default)
			)
			(layer "B.Fab")
		)
		(fp_line
			(start 0.12065 0.3048)
			(end 0.67945 0.3048)
			(stroke
				(width 0.1)
				(type default)
			)
			(layer "B.Fab")
		)
		(fp_line
			(start -0.120396 0.3048)
			(end -0.120396 0.2794)
			(stroke
				(width 0.1)
				(type default)
			)
			(layer "B.Fab")
		)
		(fp_line
			(start -0.67945 0.3048)
			(end -0.120396 0.3048)
			(stroke
				(width 0.1)
				(type default)
			)
			(layer "B.Fab")
		)
		(pad "1" smd circle
			(at 0.40005 0 270)
			(size 0 0)
			(layers "B.Cu" "B.Mask" "B.Paste")
			(net "GND")
		)
		(pad "2" smd circle
			(at -0.40005 0 270)
			(size 0 0)
			(layers "B.Cu" "B.Mask" "B.Paste")
			(net "FM_JTAG_BMC_MUX_SEL")
		)
	)
	(footprint ""
		(layer "B.Cu")
		(at 20.80133 -77.50683 90)
		(property "Reference" "OSC2"
			(at -2.07518 2.46507 0)
			(unlocked yes)
			(layer "B.SilkS")
			(effects
				(font
					(size 0.635 0.4064)
					(thickness 0.1524)
				)
				(justify left mirror)
			)
		)
		(property "Value" ""
			(at 0 0 90)
			(layer "B.Fab")
			(effects
				(font
					(size 1.27 1.27)
				)
				(justify mirror)
			)
		)
		(duplicate_pad_numbers_are_jumpers no)
		(fp_line
			(start 1.397 -1.761236)
			(end 1.397 1.761236)
			(stroke
				(width 0.1524)
				(type default)
			)
			(layer "B.SilkS")
		)
		(fp_line
			(start -1.397 -1.761236)
			(end 1.397 -1.761236)
			(stroke
				(width 0.1524)
				(type default)
			)
			(layer "B.SilkS")
		)
		(fp_line
			(start 1.397 1.761236)
			(end -1.397 1.761236)
			(stroke
				(width 0.1524)
				(type default)
			)
			(layer "B.SilkS")
		)
		(fp_line
			(start -1.397 1.761236)
			(end -1.397 -1.761236)
			(stroke
				(width 0.1524)
				(type default)
			)
			(layer "B.SilkS")
		)
		(fp_poly
			(pts
				(xy 1.965706 -0.825246) (xy 3.043428 -0.46609) (xy 2.324862 0.252476)
			)
			(stroke
				(width 0)
				(type default)
			)
			(fill yes)
			(layer "B.SilkS")
		)
		(fp_line
			(start 1.299972 -1.649984)
			(end -1.299972 -1.649984)
			(stroke
				(width 0.1)
				(type default)
			)
			(layer "B.Fab")
		)
		(fp_line
			(start -1.299972 -1.649984)
			(end -1.299972 1.649984)
			(stroke
				(width 0.1)
				(type default)
			)
			(layer "B.Fab")
		)
		(fp_line
			(start 1.299972 1.649984)
			(end 1.299972 -1.649984)
			(stroke
				(width 0.1)
				(type default)
			)
			(layer "B.Fab")
		)
		(fp_line
			(start -1.299972 1.649984)
			(end 1.299972 1.649984)
			(stroke
				(width 0.1)
				(type default)
			)
			(layer "B.Fab")
		)
		(fp_poly
			(pts
				(xy 1.694688 -1.050036) (xy 2.710688 -1.558036) (xy 2.710688 -0.542036)
			)
			(stroke
				(width 0)
				(type default)
			)
			(fill yes)
			(layer "B.Fab")
		)
		(pad "1" smd rect
			(at 0.824992 -1.050036 270)
			(size 0.8636 1.1684)
			(layers "B.Cu" "B.Mask" "B.Paste")
			(net "PU_25M_FPGA_CLK_EN")
		)
		(pad "2" smd rect
			(at 0.824992 1.050036 270)
			(size 0.8636 1.1684)
			(layers "B.Cu" "B.Mask" "B.Paste")
			(net "GND")
		)
		(pad "3" smd rect
			(at -0.824992 1.050036 270)
			(size 0.8636 1.1684)
			(layers "B.Cu" "B.Mask" "B.Paste")
			(net "CLK_25M_OSC_FPGA_R")
		)
		(pad "4" smd rect
			(at -0.824992 -1.050036 270)
			(size 0.8636 1.1684)
			(layers "B.Cu" "B.Mask" "B.Paste")
			(net "P3V3_AUX")
		)
	)
	(footprint ""
		(layer "B.Cu")
		(at 42.183558 -84.33816 90)
		(property "Reference" "U11"
			(at 0.26924 2.303272 270)
			(unlocked yes)
			(layer "B.SilkS")
			(effects
				(font
					(size 0.7874 0.5842)
					(thickness 0.1524)
				)
				(justify mirror)
			)
		)
		(property "Value" ""
			(at 0 0 90)
			(layer "B.Fab")
			(effects
				(font
					(size 1.27 1.27)
				)
				(justify mirror)
			)
		)
		(duplicate_pad_numbers_are_jumpers no)
		(fp_line
			(start 1.905 -1.651)
			(end -1.905 -1.651)
			(stroke
				(width 0.1524)
				(type default)
			)
			(layer "B.SilkS")
		)
		(fp_line
			(start -1.905 -1.651)
			(end -1.905 1.651)
			(stroke
				(width 0.1524)
				(type default)
			)
			(layer "B.SilkS")
		)
		(fp_line
			(start 1.905 1.651)
			(end 1.905 -1.651)
			(stroke
				(width 0.1524)
				(type default)
			)
			(layer "B.SilkS")
		)
		(fp_line
			(start -1.905 1.651)
			(end 1.905 1.651)
			(stroke
				(width 0.1524)
				(type default)
			)
			(layer "B.SilkS")
		)
		(fp_line
			(start 0.649986 -1.524)
			(end -0.6985 -1.524)
			(stroke
				(width 0.1)
				(type default)
			)
			(layer "B.Fab")
		)
		(fp_line
			(start -0.6985 -1.524)
			(end -0.6985 -0.219964)
			(stroke
				(width 0.1)
				(type default)
			)
			(layer "B.Fab")
		)
		(fp_line
			(start 1.249934 -1.169924)
			(end 0.649986 -1.169924)
			(stroke
				(width 0.1)
				(type default)
			)
			(layer "B.Fab")
		)
		(fp_line
			(start 0.649986 -1.169924)
			(end 0.649986 -1.524)
			(stroke
				(width 0.1)
				(type default)
			)
			(layer "B.Fab")
		)
		(fp_line
			(start 1.249934 -0.729996)
			(end 1.249934 -1.169924)
			(stroke
				(width 0.1)
				(type default)
			)
			(layer "B.Fab")
		)
		(fp_line
			(start 0.6985 -0.729996)
			(end 1.249934 -0.729996)
			(stroke
				(width 0.1)
				(type default)
			)
			(layer "B.Fab")
		)
		(fp_line
			(start -0.6985 -0.219964)
			(end -1.249934 -0.219964)
			(stroke
				(width 0.1)
				(type default)
			)
			(layer "B.Fab")
		)
		(fp_line
			(start -1.249934 -0.219964)
			(end -1.249934 0.219964)
			(stroke
				(width 0.1)
				(type default)
			)
			(layer "B.Fab")
		)
		(fp_line
			(start -0.6985 0.219964)
			(end -0.6985 1.524)
			(stroke
				(width 0.1)
				(type default)
			)
			(layer "B.Fab")
		)
		(fp_line
			(start -1.249934 0.219964)
			(end -0.6985 0.219964)
			(stroke
				(width 0.1)
				(type default)
			)
			(layer "B.Fab")
		)
		(fp_line
			(start 1.249934 0.729996)
			(end 0.6985 0.729996)
			(stroke
				(width 0.1)
				(type default)
			)
			(layer "B.Fab")
		)
		(fp_line
			(start 0.6985 0.729996)
			(end 0.6985 -0.729996)
			(stroke
				(width 0.1)
				(type default)
			)
			(layer "B.Fab")
		)
		(fp_line
			(start 1.249934 1.169924)
			(end 1.249934 0.729996)
			(stroke
				(width 0.1)
				(type default)
			)
			(layer "B.Fab")
		)
		(fp_line
			(start 0.649986 1.169924)
			(end 1.249934 1.169924)
			(stroke
				(width 0.1)
				(type default)
			)
			(layer "B.Fab")
		)
		(fp_line
			(start 0.649986 1.524)
			(end 0.649986 1.169924)
			(stroke
				(width 0.1)
				(type default)
			)
			(layer "B.Fab")
		)
		(fp_line
			(start -0.6985 1.524)
			(end 0.649986 1.524)
			(stroke
				(width 0.1)
				(type default)
			)
			(layer "B.Fab")
		)
		(pad "1" smd rect
			(at 1.1176 -1.016)
			(size 1.016 1.27)
			(layers "B.Cu" "B.Mask" "B.Paste")
			(net "FM_BMC_ONCTL_R_N")
		)
		(pad "2" smd rect
			(at 1.1176 1.016)
			(size 1.016 1.27)
			(layers "B.Cu" "B.Mask" "B.Paste")
			(net "UART_BMC_5_TXD_R")
		)
		(pad "3" smd rect
			(at -1.1176 0)
			(size 1.016 1.27)
			(layers "B.Cu" "B.Mask" "B.Paste")
			(net "FM_BMC_DISABLE")
		)
	)
	(footprint ""
		(layer "B.Cu")
		(at 74.095356 -99.906328)
		(property "Reference" "R714"
			(at 0 0 0)
			(layer "B.SilkS")
			(hide yes)
			(effects
				(font
					(size 1.27 1.27)
				)
				(justify mirror)
			)
		)
		(property "Value" ""
			(at 0 0 0)
			(layer "B.Fab")
			(effects
				(font
					(size 1.27 1.27)
				)
				(justify mirror)
			)
		)
		(duplicate_pad_numbers_are_jumpers no)
		(fp_line
			(start -0.7874 -0.4064)
			(end -0.7874 0.4064)
			(stroke
				(width 0.1524)
				(type default)
			)
			(layer "B.SilkS")
		)
		(fp_line
			(start -0.7874 0.4064)
			(end 0.7874 0.4064)
			(stroke
				(width 0.1524)
				(type default)
			)
			(layer "B.SilkS")
		)
		(fp_line
			(start 0.7874 -0.4064)
			(end -0.7874 -0.4064)
			(stroke
				(width 0.1524)
				(type default)
			)
			(layer "B.SilkS")
		)
		(fp_line
			(start 0.7874 0.4064)
			(end 0.7874 -0.4064)
			(stroke
				(width 0.1524)
				(type default)
			)
			(layer "B.SilkS")
		)
		(fp_line
			(start -0.67945 -0.3048)
			(end -0.67945 0.3048)
			(stroke
				(width 0.1)
				(type default)
			)
			(layer "B.Fab")
		)
		(fp_line
			(start -0.67945 0.3048)
			(end -0.120396 0.3048)
			(stroke
				(width 0.1)
				(type default)
			)
			(layer "B.Fab")
		)
		(fp_line
			(start -0.12065 -0.3048)
			(end -0.67945 -0.3048)
			(stroke
				(width 0.1)
				(type default)
			)
			(layer "B.Fab")
		)
		(fp_line
			(start -0.12065 -0.2794)
			(end -0.12065 -0.3048)
			(stroke
				(width 0.1)
				(type default)
			)
			(layer "B.Fab")
		)
		(fp_line
			(start -0.120396 0.2794)
			(end 0.12065 0.2794)
			(stroke
				(width 0.1)
				(type default)
			)
			(layer "B.Fab")
		)
		(fp_line
			(start -0.120396 0.3048)
			(end -0.120396 0.2794)
			(stroke
				(width 0.1)
				(type default)
			)
			(layer "B.Fab")
		)
		(fp_line
			(start 0.12065 -0.305054)
			(end 0.12065 -0.2794)
			(stroke
				(width 0.1)
				(type default)
			)
			(layer "B.Fab")
		)
		(fp_line
			(start 0.12065 -0.2794)
			(end -0.12065 -0.2794)
			(stroke
				(width 0.1)
				(type default)
			)
			(layer "B.Fab")
		)
		(fp_line
			(start 0.12065 0.2794)
			(end 0.12065 0.3048)
			(stroke
				(width 0.1)
				(type default)
			)
			(layer "B.Fab")
		)
		(fp_line
			(start 0.12065 0.3048)
			(end 0.67945 0.3048)
			(stroke
				(width 0.1)
				(type default)
			)
			(layer "B.Fab")
		)
		(fp_line
			(start 0.67945 -0.305054)
			(end 0.12065 -0.305054)
			(stroke
				(width 0.1)
				(type default)
			)
			(layer "B.Fab")
		)
		(fp_line
			(start 0.67945 0.3048)
			(end 0.67945 -0.305054)
			(stroke
				(width 0.1)
				(type default)
			)
			(layer "B.Fab")
		)
		(pad "1" smd circle
			(at 0.40005 0 180)
			(size 0 0)
			(layers "B.Cu" "B.Mask" "B.Paste")
			(net "LPC_ESPI_SEL")
		)
		(pad "2" smd circle
			(at -0.40005 0 180)
			(size 0 0)
			(layers "B.Cu" "B.Mask" "B.Paste")
			(net "LPC_ESPI_SEL_R1")
		)
	)
	(footprint ""
		(layer "B.Cu")
		(at 34.8996 -82.2452)
		(property "Reference" ""
			(at 0 0 0)
			(layer "B.SilkS")
			(hide yes)
			(effects
				(font
					(size 1.27 1.27)
				)
				(justify mirror)
			)
		)
		(property "Value" ""
			(at 0 0 0)
			(layer "B.Fab")
			(effects
				(font
					(size 1.27 1.27)
				)
				(justify mirror)
			)
		)
		(duplicate_pad_numbers_are_jumpers no)
		(pad "1" smd circle
			(at 0 0 180)
			(size 0.9906 0.9906)
			(layers "B.Cu" "B.Mask" "B.Paste")
			(net "Net_595")
		)
		(zone
			(layer "B.Cu")
			(hatch none 0.5)
			(connect_pads
				(clearance 0)
			)
			(min_thickness 0.25)
			(keepout
				(tracks not_allowed)
				(vias allowed)
				(pads allowed)
				(copperpour not_allowed)
				(footprints allowed)
			)
			(placement
				(enabled no)
				(sheetname "")
			)
			(fill
				(thermal_gap 0.5)
				(thermal_bridge_width 0.5)
				(island_removal_mode 0)
			)
			(polygon
				(pts
					(arc
						(start 36.5252 -82.2452)
						(mid 33.274 -82.2452)
						(end 36.5252 -82.2452)
					)
				)
			)
		)
	)
	(footprint ""
		(layer "B.Cu")
		(at 41.9608 -43.9928 180)
		(property "Reference" "R444"
			(at 0 0 0)
			(layer "B.SilkS")
			(hide yes)
			(effects
				(font
					(size 1.27 1.27)
				)
				(justify mirror)
			)
		)
		(property "Value" ""
			(at 0 0 0)
			(layer "B.Fab")
			(effects
				(font
					(size 1.27 1.27)
				)
				(justify mirror)
			)
		)
		(duplicate_pad_numbers_are_jumpers no)
		(fp_line
			(start 0.7874 0.4064)
			(end 0.7874 -0.4064)
			(stroke
				(width 0.1524)
				(type default)
			)
			(layer "B.SilkS")
		)
		(fp_line
			(start 0.7874 -0.4064)
			(end -0.7874 -0.4064)
			(stroke
				(width 0.1524)
				(type default)
			)
			(layer "B.SilkS")
		)
		(fp_line
			(start -0.7874 0.4064)
			(end 0.7874 0.4064)
			(stroke
				(width 0.1524)
				(type default)
			)
			(layer "B.SilkS")
		)
		(fp_line
			(start -0.7874 -0.4064)
			(end -0.7874 0.4064)
			(stroke
				(width 0.1524)
				(type default)
			)
			(layer "B.SilkS")
		)
		(fp_line
			(start 0.67945 0.3048)
			(end 0.67945 -0.305054)
			(stroke
				(width 0.1)
				(type default)
			)
			(layer "B.Fab")
		)
		(fp_line
			(start 0.67945 -0.305054)
			(end 0.12065 -0.305054)
			(stroke
				(width 0.1)
				(type default)
			)
			(layer "B.Fab")
		)
		(fp_line
			(start 0.12065 0.3048)
			(end 0.67945 0.3048)
			(stroke
				(width 0.1)
				(type default)
			)
			(layer "B.Fab")
		)
		(fp_line
			(start 0.12065 0.2794)
			(end 0.12065 0.3048)
			(stroke
				(width 0.1)
				(type default)
			)
			(layer "B.Fab")
		)
		(fp_line
			(start 0.12065 -0.2794)
			(end -0.12065 -0.2794)
			(stroke
				(width 0.1)
				(type default)
			)
			(layer "B.Fab")
		)
		(fp_line
			(start 0.12065 -0.305054)
			(end 0.12065 -0.2794)
			(stroke
				(width 0.1)
				(type default)
			)
			(layer "B.Fab")
		)
		(fp_line
			(start -0.120396 0.3048)
			(end -0.120396 0.2794)
			(stroke
				(width 0.1)
				(type default)
			)
			(layer "B.Fab")
		)
		(fp_line
			(start -0.120396 0.2794)
			(end 0.12065 0.2794)
			(stroke
				(width 0.1)
				(type default)
			)
			(layer "B.Fab")
		)
		(fp_line
			(start -0.12065 -0.2794)
			(end -0.12065 -0.3048)
			(stroke
				(width 0.1)
				(type default)
			)
			(layer "B.Fab")
		)
		(fp_line
			(start -0.12065 -0.3048)
			(end -0.67945 -0.3048)
			(stroke
				(width 0.1)
				(type default)
			)
			(layer "B.Fab")
		)
		(fp_line
			(start -0.67945 0.3048)
			(end -0.120396 0.3048)
			(stroke
				(width 0.1)
				(type default)
			)
			(layer "B.Fab")
		)
		(fp_line
			(start -0.67945 -0.3048)
			(end -0.67945 0.3048)
			(stroke
				(width 0.1)
				(type default)
			)
			(layer "B.Fab")
		)
		(pad "1" smd circle
			(at 0.40005 0)
			(size 0 0)
			(layers "B.Cu" "B.Mask" "B.Paste")
			(net "FM_ESPI_PLD_EN")
		)
		(pad "2" smd circle
			(at -0.40005 0)
			(size 0 0)
			(layers "B.Cu" "B.Mask" "B.Paste")
			(net "FM_ESPI_PLD_R1_EN")
		)
	)
	(footprint ""
		(layer "B.Cu")
		(at 26.035 -101.981 -90)
		(property "Reference" "R627"
			(at 0 0 90)
			(layer "B.SilkS")
			(hide yes)
			(effects
				(font
					(size 1.27 1.27)
				)
				(justify mirror)
			)
		)
		(property "Value" ""
			(at 0 0 90)
			(layer "B.Fab")
			(effects
				(font
					(size 1.27 1.27)
				)
				(justify mirror)
			)
		)
		(duplicate_pad_numbers_are_jumpers no)
		(fp_line
			(start -0.7874 0.4064)
			(end 0.7874 0.4064)
			(stroke
				(width 0.1524)
				(type default)
			)
			(layer "B.SilkS")
		)
		(fp_line
			(start 0.7874 0.4064)
			(end 0.7874 -0.4064)
			(stroke
				(width 0.1524)
				(type default)
			)
			(layer "B.SilkS")
		)
		(fp_line
			(start -0.7874 -0.4064)
			(end -0.7874 0.4064)
			(stroke
				(width 0.1524)
				(type default)
			)
			(layer "B.SilkS")
		)
		(fp_line
			(start 0.7874 -0.4064)
			(end -0.7874 -0.4064)
			(stroke
				(width 0.1524)
				(type default)
			)
			(layer "B.SilkS")
		)
		(fp_line
			(start -0.67945 0.3048)
			(end -0.120396 0.3048)
			(stroke
				(width 0.1)
				(type default)
			)
			(layer "B.Fab")
		)
		(fp_line
			(start -0.120396 0.3048)
			(end -0.120396 0.2794)
			(stroke
				(width 0.1)
				(type default)
			)
			(layer "B.Fab")
		)
		(fp_line
			(start 0.12065 0.3048)
			(end 0.67945 0.3048)
			(stroke
				(width 0.1)
				(type default)
			)
			(layer "B.Fab")
		)
		(fp_line
			(start 0.67945 0.3048)
			(end 0.67945 -0.305054)
			(stroke
				(width 0.1)
				(type default)
			)
			(layer "B.Fab")
		)
		(fp_line
			(start -0.120396 0.2794)
			(end 0.12065 0.2794)
			(stroke
				(width 0.1)
				(type default)
			)
			(layer "B.Fab")
		)
		(fp_line
			(start 0.12065 0.2794)
			(end 0.12065 0.3048)
			(stroke
				(width 0.1)
				(type default)
			)
			(layer "B.Fab")
		)
		(fp_line
			(start -0.12065 -0.2794)
			(end -0.12065 -0.3048)
			(stroke
				(width 0.1)
				(type default)
			)
			(layer "B.Fab")
		)
		(fp_line
			(start 0.12065 -0.2794)
			(end -0.12065 -0.2794)
			(stroke
				(width 0.1)
				(type default)
			)
			(layer "B.Fab")
		)
		(fp_line
			(start -0.67945 -0.3048)
			(end -0.67945 0.3048)
			(stroke
				(width 0.1)
				(type default)
			)
			(layer "B.Fab")
		)
		(fp_line
			(start -0.12065 -0.3048)
			(end -0.67945 -0.3048)
			(stroke
				(width 0.1)
				(type default)
			)
			(layer "B.Fab")
		)
		(fp_line
			(start 0.12065 -0.305054)
			(end 0.12065 -0.2794)
			(stroke
				(width 0.1)
				(type default)
			)
			(layer "B.Fab")
		)
		(fp_line
			(start 0.67945 -0.305054)
			(end 0.12065 -0.305054)
			(stroke
				(width 0.1)
				(type default)
			)
			(layer "B.Fab")
		)
		(pad "1" smd circle
			(at 0.40005 0 90)
			(size 0 0)
			(layers "B.Cu" "B.Mask" "B.Paste")
			(net "P3V3_AUX")
		)
		(pad "2" smd circle
			(at -0.40005 0 90)
			(size 0 0)
			(layers "B.Cu" "B.Mask" "B.Paste")
			(net "PWRGD_DSW_PWROK")
		)
	)
	(footprint ""
		(layer "B.Cu")
		(at 50.927 -76.3016)
		(property "Reference" "R55"
			(at 0 0 0)
			(layer "B.SilkS")
			(hide yes)
			(effects
				(font
					(size 1.27 1.27)
				)
				(justify mirror)
			)
		)
		(property "Value" ""
			(at 0 0 0)
			(layer "B.Fab")
			(effects
				(font
					(size 1.27 1.27)
				)
				(justify mirror)
			)
		)
		(duplicate_pad_numbers_are_jumpers no)
		(fp_line
			(start -0.7874 -0.4064)
			(end -0.7874 0.4064)
			(stroke
				(width 0.1524)
				(type default)
			)
			(layer "B.SilkS")
		)
		(fp_line
			(start -0.7874 0.4064)
			(end 0.7874 0.4064)
			(stroke
				(width 0.1524)
				(type default)
			)
			(layer "B.SilkS")
		)
		(fp_line
			(start 0.7874 -0.4064)
			(end -0.7874 -0.4064)
			(stroke
				(width 0.1524)
				(type default)
			)
			(layer "B.SilkS")
		)
		(fp_line
			(start 0.7874 0.4064)
			(end 0.7874 -0.4064)
			(stroke
				(width 0.1524)
				(type default)
			)
			(layer "B.SilkS")
		)
		(fp_line
			(start -0.67945 -0.3048)
			(end -0.67945 0.3048)
			(stroke
				(width 0.1)
				(type default)
			)
			(layer "B.Fab")
		)
		(fp_line
			(start -0.67945 0.3048)
			(end -0.120396 0.3048)
			(stroke
				(width 0.1)
				(type default)
			)
			(layer "B.Fab")
		)
		(fp_line
			(start -0.12065 -0.3048)
			(end -0.67945 -0.3048)
			(stroke
				(width 0.1)
				(type default)
			)
			(layer "B.Fab")
		)
		(fp_line
			(start -0.12065 -0.2794)
			(end -0.12065 -0.3048)
			(stroke
				(width 0.1)
				(type default)
			)
			(layer "B.Fab")
		)
		(fp_line
			(start -0.120396 0.2794)
			(end 0.12065 0.2794)
			(stroke
				(width 0.1)
				(type default)
			)
			(layer "B.Fab")
		)
		(fp_line
			(start -0.120396 0.3048)
			(end -0.120396 0.2794)
			(stroke
				(width 0.1)
				(type default)
			)
			(layer "B.Fab")
		)
		(fp_line
			(start 0.12065 -0.305054)
			(end 0.12065 -0.2794)
			(stroke
				(width 0.1)
				(type default)
			)
			(layer "B.Fab")
		)
		(fp_line
			(start 0.12065 -0.2794)
			(end -0.12065 -0.2794)
			(stroke
				(width 0.1)
				(type default)
			)
			(layer "B.Fab")
		)
		(fp_line
			(start 0.12065 0.2794)
			(end 0.12065 0.3048)
			(stroke
				(width 0.1)
				(type default)
			)
			(layer "B.Fab")
		)
		(fp_line
			(start 0.12065 0.3048)
			(end 0.67945 0.3048)
			(stroke
				(width 0.1)
				(type default)
			)
			(layer "B.Fab")
		)
		(fp_line
			(start 0.67945 -0.305054)
			(end 0.12065 -0.305054)
			(stroke
				(width 0.1)
				(type default)
			)
			(layer "B.Fab")
		)
		(fp_line
			(start 0.67945 0.3048)
			(end 0.67945 -0.305054)
			(stroke
				(width 0.1)
				(type default)
			)
			(layer "B.Fab")
		)
		(pad "1" smd circle
			(at 0.40005 0 180)
			(size 0 0)
			(layers "B.Cu" "B.Mask" "B.Paste")
			(net "P3V3_AUX")
		)
		(pad "2" smd circle
			(at -0.40005 0 180)
			(size 0 0)
			(layers "B.Cu" "B.Mask" "B.Paste")
			(net "FM_BMC_READY_R_PLD_N")
		)
	)
	(footprint ""
		(layer "B.Cu")
		(at 12.319 -88.392 180)
		(property "Reference" "R833"
			(at 0 0 0)
			(layer "B.SilkS")
			(hide yes)
			(effects
				(font
					(size 1.27 1.27)
				)
				(justify mirror)
			)
		)
		(property "Value" ""
			(at 0 0 0)
			(layer "B.Fab")
			(effects
				(font
					(size 1.27 1.27)
				)
				(justify mirror)
			)
		)
		(duplicate_pad_numbers_are_jumpers no)
		(fp_line
			(start 0.7874 0.4064)
			(end 0.7874 -0.4064)
			(stroke
				(width 0.1524)
				(type default)
			)
			(layer "B.SilkS")
		)
		(fp_line
			(start 0.7874 -0.4064)
			(end -0.7874 -0.4064)
			(stroke
				(width 0.1524)
				(type default)
			)
			(layer "B.SilkS")
		)
		(fp_line
			(start -0.7874 0.4064)
			(end 0.7874 0.4064)
			(stroke
				(width 0.1524)
				(type default)
			)
			(layer "B.SilkS")
		)
		(fp_line
			(start -0.7874 -0.4064)
			(end -0.7874 0.4064)
			(stroke
				(width 0.1524)
				(type default)
			)
			(layer "B.SilkS")
		)
		(fp_line
			(start 0.67945 0.3048)
			(end 0.67945 -0.305054)
			(stroke
				(width 0.1)
				(type default)
			)
			(layer "B.Fab")
		)
		(fp_line
			(start 0.67945 -0.305054)
			(end 0.12065 -0.305054)
			(stroke
				(width 0.1)
				(type default)
			)
			(layer "B.Fab")
		)
		(fp_line
			(start 0.12065 0.3048)
			(end 0.67945 0.3048)
			(stroke
				(width 0.1)
				(type default)
			)
			(layer "B.Fab")
		)
		(fp_line
			(start 0.12065 0.2794)
			(end 0.12065 0.3048)
			(stroke
				(width 0.1)
				(type default)
			)
			(layer "B.Fab")
		)
		(fp_line
			(start 0.12065 -0.2794)
			(end -0.12065 -0.2794)
			(stroke
				(width 0.1)
				(type default)
			)
			(layer "B.Fab")
		)
		(fp_line
			(start 0.12065 -0.305054)
			(end 0.12065 -0.2794)
			(stroke
				(width 0.1)
				(type default)
			)
			(layer "B.Fab")
		)
		(fp_line
			(start -0.120396 0.3048)
			(end -0.120396 0.2794)
			(stroke
				(width 0.1)
				(type default)
			)
			(layer "B.Fab")
		)
		(fp_line
			(start -0.120396 0.2794)
			(end 0.12065 0.2794)
			(stroke
				(width 0.1)
				(type default)
			)
			(layer "B.Fab")
		)
		(fp_line
			(start -0.12065 -0.2794)
			(end -0.12065 -0.3048)
			(stroke
				(width 0.1)
				(type default)
			)
			(layer "B.Fab")
		)
		(fp_line
			(start -0.12065 -0.3048)
			(end -0.67945 -0.3048)
			(stroke
				(width 0.1)
				(type default)
			)
			(layer "B.Fab")
		)
		(fp_line
			(start -0.67945 0.3048)
			(end -0.120396 0.3048)
			(stroke
				(width 0.1)
				(type default)
			)
			(layer "B.Fab")
		)
		(fp_line
			(start -0.67945 -0.3048)
			(end -0.67945 0.3048)
			(stroke
				(width 0.1)
				(type default)
			)
			(layer "B.Fab")
		)
		(pad "1" smd circle
			(at 0.40005 0)
			(size 0 0)
			(layers "B.Cu" "B.Mask" "B.Paste")
			(net "FM_ESPI_PLD_EN")
		)
		(pad "2" smd circle
			(at -0.40005 0)
			(size 0 0)
			(layers "B.Cu" "B.Mask" "B.Paste")
			(net "FM_ESPI_PLD_R_EN")
		)
	)
	(footprint ""
		(layer "B.Cu")
		(at 60.7314 -64.0588 -90)
		(property "Reference" "R725"
			(at 0 0 90)
			(layer "B.SilkS")
			(hide yes)
			(effects
				(font
					(size 1.27 1.27)
				)
				(justify mirror)
			)
		)
		(property "Value" ""
			(at 0 0 90)
			(layer "B.Fab")
			(effects
				(font
					(size 1.27 1.27)
				)
				(justify mirror)
			)
		)
		(duplicate_pad_numbers_are_jumpers no)
		(fp_line
			(start -0.7874 0.4064)
			(end 0.7874 0.4064)
			(stroke
				(width 0.1524)
				(type default)
			)
			(layer "B.SilkS")
		)
		(fp_line
			(start 0.7874 0.4064)
			(end 0.7874 -0.4064)
			(stroke
				(width 0.1524)
				(type default)
			)
			(layer "B.SilkS")
		)
		(fp_line
			(start -0.7874 -0.4064)
			(end -0.7874 0.4064)
			(stroke
				(width 0.1524)
				(type default)
			)
			(layer "B.SilkS")
		)
		(fp_line
			(start 0.7874 -0.4064)
			(end -0.7874 -0.4064)
			(stroke
				(width 0.1524)
				(type default)
			)
			(layer "B.SilkS")
		)
		(fp_line
			(start -0.67945 0.3048)
			(end -0.120396 0.3048)
			(stroke
				(width 0.1)
				(type default)
			)
			(layer "B.Fab")
		)
		(fp_line
			(start -0.120396 0.3048)
			(end -0.120396 0.2794)
			(stroke
				(width 0.1)
				(type default)
			)
			(layer "B.Fab")
		)
		(fp_line
			(start 0.12065 0.3048)
			(end 0.67945 0.3048)
			(stroke
				(width 0.1)
				(type default)
			)
			(layer "B.Fab")
		)
		(fp_line
			(start 0.67945 0.3048)
			(end 0.67945 -0.305054)
			(stroke
				(width 0.1)
				(type default)
			)
			(layer "B.Fab")
		)
		(fp_line
			(start -0.120396 0.2794)
			(end 0.12065 0.2794)
			(stroke
				(width 0.1)
				(type default)
			)
			(layer "B.Fab")
		)
		(fp_line
			(start 0.12065 0.2794)
			(end 0.12065 0.3048)
			(stroke
				(width 0.1)
				(type default)
			)
			(layer "B.Fab")
		)
		(fp_line
			(start -0.12065 -0.2794)
			(end -0.12065 -0.3048)
			(stroke
				(width 0.1)
				(type default)
			)
			(layer "B.Fab")
		)
		(fp_line
			(start 0.12065 -0.2794)
			(end -0.12065 -0.2794)
			(stroke
				(width 0.1)
				(type default)
			)
			(layer "B.Fab")
		)
		(fp_line
			(start -0.67945 -0.3048)
			(end -0.67945 0.3048)
			(stroke
				(width 0.1)
				(type default)
			)
			(layer "B.Fab")
		)
		(fp_line
			(start -0.12065 -0.3048)
			(end -0.67945 -0.3048)
			(stroke
				(width 0.1)
				(type default)
			)
			(layer "B.Fab")
		)
		(fp_line
			(start 0.12065 -0.305054)
			(end 0.12065 -0.2794)
			(stroke
				(width 0.1)
				(type default)
			)
			(layer "B.Fab")
		)
		(fp_line
			(start 0.67945 -0.305054)
			(end 0.12065 -0.305054)
			(stroke
				(width 0.1)
				(type default)
			)
			(layer "B.Fab")
		)
		(pad "1" smd circle
			(at 0.40005 0 90)
			(size 0 0)
			(layers "B.Cu" "B.Mask" "B.Paste")
			(net "SPI_BMC_BIOS_ROM_IO3")
		)
		(pad "2" smd circle
			(at -0.40005 0 90)
			(size 0 0)
			(layers "B.Cu" "B.Mask" "B.Paste")
			(net "SPI_BMC_BIOS_ROM_R_IO3")
		)
	)
	(footprint ""
		(layer "B.Cu")
		(at 25.019 -101.981 90)
		(property "Reference" "R575"
			(at 0 0 90)
			(layer "B.SilkS")
			(hide yes)
			(effects
				(font
					(size 1.27 1.27)
				)
				(justify mirror)
			)
		)
		(property "Value" ""
			(at 0 0 90)
			(layer "B.Fab")
			(effects
				(font
					(size 1.27 1.27)
				)
				(justify mirror)
			)
		)
		(duplicate_pad_numbers_are_jumpers no)
		(fp_line
			(start 0.7874 -0.4064)
			(end -0.7874 -0.4064)
			(stroke
				(width 0.1524)
				(type default)
			)
			(layer "B.SilkS")
		)
		(fp_line
			(start -0.7874 -0.4064)
			(end -0.7874 0.4064)
			(stroke
				(width 0.1524)
				(type default)
			)
			(layer "B.SilkS")
		)
		(fp_line
			(start 0.7874 0.4064)
			(end 0.7874 -0.4064)
			(stroke
				(width 0.1524)
				(type default)
			)
			(layer "B.SilkS")
		)
		(fp_line
			(start -0.7874 0.4064)
			(end 0.7874 0.4064)
			(stroke
				(width 0.1524)
				(type default)
			)
			(layer "B.SilkS")
		)
		(fp_line
			(start 0.67945 -0.305054)
			(end 0.12065 -0.305054)
			(stroke
				(width 0.1)
				(type default)
			)
			(layer "B.Fab")
		)
		(fp_line
			(start 0.12065 -0.305054)
			(end 0.12065 -0.2794)
			(stroke
				(width 0.1)
				(type default)
			)
			(layer "B.Fab")
		)
		(fp_line
			(start -0.12065 -0.3048)
			(end -0.67945 -0.3048)
			(stroke
				(width 0.1)
				(type default)
			)
			(layer "B.Fab")
		)
		(fp_line
			(start -0.67945 -0.3048)
			(end -0.67945 0.3048)
			(stroke
				(width 0.1)
				(type default)
			)
			(layer "B.Fab")
		)
		(fp_line
			(start 0.12065 -0.2794)
			(end -0.12065 -0.2794)
			(stroke
				(width 0.1)
				(type default)
			)
			(layer "B.Fab")
		)
		(fp_line
			(start -0.12065 -0.2794)
			(end -0.12065 -0.3048)
			(stroke
				(width 0.1)
				(type default)
			)
			(layer "B.Fab")
		)
		(fp_line
			(start 0.12065 0.2794)
			(end 0.12065 0.3048)
			(stroke
				(width 0.1)
				(type default)
			)
			(layer "B.Fab")
		)
		(fp_line
			(start -0.120396 0.2794)
			(end 0.12065 0.2794)
			(stroke
				(width 0.1)
				(type default)
			)
			(layer "B.Fab")
		)
		(fp_line
			(start 0.67945 0.3048)
			(end 0.67945 -0.305054)
			(stroke
				(width 0.1)
				(type default)
			)
			(layer "B.Fab")
		)
		(fp_line
			(start 0.12065 0.3048)
			(end 0.67945 0.3048)
			(stroke
				(width 0.1)
				(type default)
			)
			(layer "B.Fab")
		)
		(fp_line
			(start -0.120396 0.3048)
			(end -0.120396 0.2794)
			(stroke
				(width 0.1)
				(type default)
			)
			(layer "B.Fab")
		)
		(fp_line
			(start -0.67945 0.3048)
			(end -0.120396 0.3048)
			(stroke
				(width 0.1)
				(type default)
			)
			(layer "B.Fab")
		)
		(pad "1" smd circle
			(at 0.40005 0 270)
			(size 0 0)
			(layers "B.Cu" "B.Mask" "B.Paste")
			(net "FM_P12V_HSC_ENABLE")
		)
		(pad "2" smd circle
			(at -0.40005 0 270)
			(size 0 0)
			(layers "B.Cu" "B.Mask" "B.Paste")
			(net "FM_P12V_HSC_ENABLE_R2")
		)
	)
	(footprint ""
		(layer "B.Cu")
		(at 83.283552 -26.587704 180)
		(property "Reference" "R413"
			(at 0 0 0)
			(layer "B.SilkS")
			(hide yes)
			(effects
				(font
					(size 1.27 1.27)
				)
				(justify mirror)
			)
		)
		(property "Value" ""
			(at 0 0 0)
			(layer "B.Fab")
			(effects
				(font
					(size 1.27 1.27)
				)
				(justify mirror)
			)
		)
		(duplicate_pad_numbers_are_jumpers no)
		(fp_line
			(start 0.7874 0.4064)
			(end 0.7874 -0.4064)
			(stroke
				(width 0.1524)
				(type default)
			)
			(layer "B.SilkS")
		)
		(fp_line
			(start 0.7874 -0.4064)
			(end -0.7874 -0.4064)
			(stroke
				(width 0.1524)
				(type default)
			)
			(layer "B.SilkS")
		)
		(fp_line
			(start -0.7874 0.4064)
			(end 0.7874 0.4064)
			(stroke
				(width 0.1524)
				(type default)
			)
			(layer "B.SilkS")
		)
		(fp_line
			(start -0.7874 -0.4064)
			(end -0.7874 0.4064)
			(stroke
				(width 0.1524)
				(type default)
			)
			(layer "B.SilkS")
		)
		(fp_line
			(start 0.67945 0.3048)
			(end 0.67945 -0.305054)
			(stroke
				(width 0.1)
				(type default)
			)
			(layer "B.Fab")
		)
		(fp_line
			(start 0.67945 -0.305054)
			(end 0.12065 -0.305054)
			(stroke
				(width 0.1)
				(type default)
			)
			(layer "B.Fab")
		)
		(fp_line
			(start 0.12065 0.3048)
			(end 0.67945 0.3048)
			(stroke
				(width 0.1)
				(type default)
			)
			(layer "B.Fab")
		)
		(fp_line
			(start 0.12065 0.2794)
			(end 0.12065 0.3048)
			(stroke
				(width 0.1)
				(type default)
			)
			(layer "B.Fab")
		)
		(fp_line
			(start 0.12065 -0.2794)
			(end -0.12065 -0.2794)
			(stroke
				(width 0.1)
				(type default)
			)
			(layer "B.Fab")
		)
		(fp_line
			(start 0.12065 -0.305054)
			(end 0.12065 -0.2794)
			(stroke
				(width 0.1)
				(type default)
			)
			(layer "B.Fab")
		)
		(fp_line
			(start -0.120396 0.3048)
			(end -0.120396 0.2794)
			(stroke
				(width 0.1)
				(type default)
			)
			(layer "B.Fab")
		)
		(fp_line
			(start -0.120396 0.2794)
			(end 0.12065 0.2794)
			(stroke
				(width 0.1)
				(type default)
			)
			(layer "B.Fab")
		)
		(fp_line
			(start -0.12065 -0.2794)
			(end -0.12065 -0.3048)
			(stroke
				(width 0.1)
				(type default)
			)
			(layer "B.Fab")
		)
		(fp_line
			(start -0.12065 -0.3048)
			(end -0.67945 -0.3048)
			(stroke
				(width 0.1)
				(type default)
			)
			(layer "B.Fab")
		)
		(fp_line
			(start -0.67945 0.3048)
			(end -0.120396 0.3048)
			(stroke
				(width 0.1)
				(type default)
			)
			(layer "B.Fab")
		)
		(fp_line
			(start -0.67945 -0.3048)
			(end -0.67945 0.3048)
			(stroke
				(width 0.1)
				(type default)
			)
			(layer "B.Fab")
		)
		(pad "1" smd circle
			(at 0.40005 0)
			(size 0 0)
			(layers "B.Cu" "B.Mask" "B.Paste")
			(net "FRU_E2")
		)
		(pad "2" smd circle
			(at -0.40005 0)
			(size 0 0)
			(layers "B.Cu" "B.Mask" "B.Paste")
			(net "GND")
		)
	)
	(footprint ""
		(layer "B.Cu")
		(at 72.39 -19.685 90)
		(property "Reference" "R855"
			(at 0 0 90)
			(layer "B.SilkS")
			(hide yes)
			(effects
				(font
					(size 1.27 1.27)
				)
				(justify mirror)
			)
		)
		(property "Value" ""
			(at 0 0 90)
			(layer "B.Fab")
			(effects
				(font
					(size 1.27 1.27)
				)
				(justify mirror)
			)
		)
		(duplicate_pad_numbers_are_jumpers no)
		(fp_line
			(start 0.7874 -0.4064)
			(end -0.7874 -0.4064)
			(stroke
				(width 0.1524)
				(type default)
			)
			(layer "B.SilkS")
		)
		(fp_line
			(start -0.7874 -0.4064)
			(end -0.7874 0.4064)
			(stroke
				(width 0.1524)
				(type default)
			)
			(layer "B.SilkS")
		)
		(fp_line
			(start 0.7874 0.4064)
			(end 0.7874 -0.4064)
			(stroke
				(width 0.1524)
				(type default)
			)
			(layer "B.SilkS")
		)
		(fp_line
			(start -0.7874 0.4064)
			(end 0.7874 0.4064)
			(stroke
				(width 0.1524)
				(type default)
			)
			(layer "B.SilkS")
		)
		(fp_line
			(start 0.67945 -0.305054)
			(end 0.12065 -0.305054)
			(stroke
				(width 0.1)
				(type default)
			)
			(layer "B.Fab")
		)
		(fp_line
			(start 0.12065 -0.305054)
			(end 0.12065 -0.2794)
			(stroke
				(width 0.1)
				(type default)
			)
			(layer "B.Fab")
		)
		(fp_line
			(start -0.12065 -0.3048)
			(end -0.67945 -0.3048)
			(stroke
				(width 0.1)
				(type default)
			)
			(layer "B.Fab")
		)
		(fp_line
			(start -0.67945 -0.3048)
			(end -0.67945 0.3048)
			(stroke
				(width 0.1)
				(type default)
			)
			(layer "B.Fab")
		)
		(fp_line
			(start 0.12065 -0.2794)
			(end -0.12065 -0.2794)
			(stroke
				(width 0.1)
				(type default)
			)
			(layer "B.Fab")
		)
		(fp_line
			(start -0.12065 -0.2794)
			(end -0.12065 -0.3048)
			(stroke
				(width 0.1)
				(type default)
			)
			(layer "B.Fab")
		)
		(fp_line
			(start 0.12065 0.2794)
			(end 0.12065 0.3048)
			(stroke
				(width 0.1)
				(type default)
			)
			(layer "B.Fab")
		)
		(fp_line
			(start -0.120396 0.2794)
			(end 0.12065 0.2794)
			(stroke
				(width 0.1)
				(type default)
			)
			(layer "B.Fab")
		)
		(fp_line
			(start 0.67945 0.3048)
			(end 0.67945 -0.305054)
			(stroke
				(width 0.1)
				(type default)
			)
			(layer "B.Fab")
		)
		(fp_line
			(start 0.12065 0.3048)
			(end 0.67945 0.3048)
			(stroke
				(width 0.1)
				(type default)
			)
			(layer "B.Fab")
		)
		(fp_line
			(start -0.120396 0.3048)
			(end -0.120396 0.2794)
			(stroke
				(width 0.1)
				(type default)
			)
			(layer "B.Fab")
		)
		(fp_line
			(start -0.67945 0.3048)
			(end -0.120396 0.3048)
			(stroke
				(width 0.1)
				(type default)
			)
			(layer "B.Fab")
		)
		(pad "1" smd circle
			(at 0.40005 0 270)
			(size 0 0)
			(layers "B.Cu" "B.Mask" "B.Paste")
			(net "FM_BOARD_BMC_REV_ID2")
		)
		(pad "2" smd circle
			(at -0.40005 0 270)
			(size 0 0)
			(layers "B.Cu" "B.Mask" "B.Paste")
			(net "GND")
		)
	)
	(footprint ""
		(layer "B.Cu")
		(at 52.494688 -53.564536 -90)
		(property "Reference" "C66"
			(at 0 0 90)
			(layer "B.SilkS")
			(hide yes)
			(effects
				(font
					(size 1.27 1.27)
				)
				(justify mirror)
			)
		)
		(property "Value" ""
			(at 0 0 90)
			(layer "B.Fab")
			(effects
				(font
					(size 1.27 1.27)
				)
				(justify mirror)
			)
		)
		(duplicate_pad_numbers_are_jumpers no)
		(fp_line
			(start -0.7874 0.4064)
			(end 0.7874 0.4064)
			(stroke
				(width 0.1524)
				(type default)
			)
			(layer "B.SilkS")
		)
		(fp_line
			(start 0.7874 0.4064)
			(end 0.7874 -0.4064)
			(stroke
				(width 0.1524)
				(type default)
			)
			(layer "B.SilkS")
		)
		(fp_line
			(start -0.7874 -0.4064)
			(end -0.7874 0.4064)
			(stroke
				(width 0.1524)
				(type default)
			)
			(layer "B.SilkS")
		)
		(fp_line
			(start 0.7874 -0.4064)
			(end -0.7874 -0.4064)
			(stroke
				(width 0.1524)
				(type default)
			)
			(layer "B.SilkS")
		)
		(fp_line
			(start -0.67945 0.3048)
			(end -0.120396 0.3048)
			(stroke
				(width 0.1)
				(type default)
			)
			(layer "B.Fab")
		)
		(fp_line
			(start -0.120396 0.3048)
			(end -0.120396 0.2794)
			(stroke
				(width 0.1)
				(type default)
			)
			(layer "B.Fab")
		)
		(fp_line
			(start 0.12065 0.3048)
			(end 0.67945 0.3048)
			(stroke
				(width 0.1)
				(type default)
			)
			(layer "B.Fab")
		)
		(fp_line
			(start 0.67945 0.3048)
			(end 0.67945 -0.305054)
			(stroke
				(width 0.1)
				(type default)
			)
			(layer "B.Fab")
		)
		(fp_line
			(start -0.120396 0.2794)
			(end 0.12065 0.2794)
			(stroke
				(width 0.1)
				(type default)
			)
			(layer "B.Fab")
		)
		(fp_line
			(start 0.12065 0.2794)
			(end 0.12065 0.3048)
			(stroke
				(width 0.1)
				(type default)
			)
			(layer "B.Fab")
		)
		(fp_line
			(start -0.12065 -0.2794)
			(end -0.12065 -0.3048)
			(stroke
				(width 0.1)
				(type default)
			)
			(layer "B.Fab")
		)
		(fp_line
			(start 0.12065 -0.2794)
			(end -0.12065 -0.2794)
			(stroke
				(width 0.1)
				(type default)
			)
			(layer "B.Fab")
		)
		(fp_line
			(start -0.67945 -0.3048)
			(end -0.67945 0.3048)
			(stroke
				(width 0.1)
				(type default)
			)
			(layer "B.Fab")
		)
		(fp_line
			(start -0.12065 -0.3048)
			(end -0.67945 -0.3048)
			(stroke
				(width 0.1)
				(type default)
			)
			(layer "B.Fab")
		)
		(fp_line
			(start 0.12065 -0.305054)
			(end 0.12065 -0.2794)
			(stroke
				(width 0.1)
				(type default)
			)
			(layer "B.Fab")
		)
		(fp_line
			(start 0.67945 -0.305054)
			(end 0.12065 -0.305054)
			(stroke
				(width 0.1)
				(type default)
			)
			(layer "B.Fab")
		)
		(pad "1" smd circle
			(at 0.40005 0 90)
			(size 0 0)
			(layers "B.Cu" "B.Mask" "B.Paste")
			(net "P1V2_AUX")
		)
		(pad "2" smd circle
			(at -0.40005 0 90)
			(size 0 0)
			(layers "B.Cu" "B.Mask" "B.Paste")
			(net "GND")
		)
	)
	(footprint ""
		(layer "B.Cu")
		(at 48.624236 -30.857698 -90)
		(property "Reference" "R610"
			(at 0 0 90)
			(layer "B.SilkS")
			(hide yes)
			(effects
				(font
					(size 1.27 1.27)
				)
				(justify mirror)
			)
		)
		(property "Value" ""
			(at 0 0 90)
			(layer "B.Fab")
			(effects
				(font
					(size 1.27 1.27)
				)
				(justify mirror)
			)
		)
		(duplicate_pad_numbers_are_jumpers no)
		(fp_line
			(start -0.7874 0.4064)
			(end 0.7874 0.4064)
			(stroke
				(width 0.1524)
				(type default)
			)
			(layer "B.SilkS")
		)
		(fp_line
			(start 0.7874 0.4064)
			(end 0.7874 -0.4064)
			(stroke
				(width 0.1524)
				(type default)
			)
			(layer "B.SilkS")
		)
		(fp_line
			(start -0.7874 -0.4064)
			(end -0.7874 0.4064)
			(stroke
				(width 0.1524)
				(type default)
			)
			(layer "B.SilkS")
		)
		(fp_line
			(start 0.7874 -0.4064)
			(end -0.7874 -0.4064)
			(stroke
				(width 0.1524)
				(type default)
			)
			(layer "B.SilkS")
		)
		(fp_line
			(start -0.67945 0.3048)
			(end -0.120396 0.3048)
			(stroke
				(width 0.1)
				(type default)
			)
			(layer "B.Fab")
		)
		(fp_line
			(start -0.120396 0.3048)
			(end -0.120396 0.2794)
			(stroke
				(width 0.1)
				(type default)
			)
			(layer "B.Fab")
		)
		(fp_line
			(start 0.12065 0.3048)
			(end 0.67945 0.3048)
			(stroke
				(width 0.1)
				(type default)
			)
			(layer "B.Fab")
		)
		(fp_line
			(start 0.67945 0.3048)
			(end 0.67945 -0.305054)
			(stroke
				(width 0.1)
				(type default)
			)
			(layer "B.Fab")
		)
		(fp_line
			(start -0.120396 0.2794)
			(end 0.12065 0.2794)
			(stroke
				(width 0.1)
				(type default)
			)
			(layer "B.Fab")
		)
		(fp_line
			(start 0.12065 0.2794)
			(end 0.12065 0.3048)
			(stroke
				(width 0.1)
				(type default)
			)
			(layer "B.Fab")
		)
		(fp_line
			(start -0.12065 -0.2794)
			(end -0.12065 -0.3048)
			(stroke
				(width 0.1)
				(type default)
			)
			(layer "B.Fab")
		)
		(fp_line
			(start 0.12065 -0.2794)
			(end -0.12065 -0.2794)
			(stroke
				(width 0.1)
				(type default)
			)
			(layer "B.Fab")
		)
		(fp_line
			(start -0.67945 -0.3048)
			(end -0.67945 0.3048)
			(stroke
				(width 0.1)
				(type default)
			)
			(layer "B.Fab")
		)
		(fp_line
			(start -0.12065 -0.3048)
			(end -0.67945 -0.3048)
			(stroke
				(width 0.1)
				(type default)
			)
			(layer "B.Fab")
		)
		(fp_line
			(start 0.12065 -0.305054)
			(end 0.12065 -0.2794)
			(stroke
				(width 0.1)
				(type default)
			)
			(layer "B.Fab")
		)
		(fp_line
			(start 0.67945 -0.305054)
			(end 0.12065 -0.305054)
			(stroke
				(width 0.1)
				(type default)
			)
			(layer "B.Fab")
		)
		(pad "1" smd circle
			(at 0.40005 0 90)
			(size 0 0)
			(layers "B.Cu" "B.Mask" "B.Paste")
			(net "P3V3_AUX")
		)
		(pad "2" smd circle
			(at -0.40005 0 90)
			(size 0 0)
			(layers "B.Cu" "B.Mask" "B.Paste")
			(net "SMB_BMC_MM15_SCL")
		)
	)
	(footprint ""
		(layer "B.Cu")
		(at 59.042554 -45.939964 180)
		(property "Reference" "C45"
			(at 0 0 0)
			(layer "B.SilkS")
			(hide yes)
			(effects
				(font
					(size 1.27 1.27)
				)
				(justify mirror)
			)
		)
		(property "Value" ""
			(at 0 0 0)
			(layer "B.Fab")
			(effects
				(font
					(size 1.27 1.27)
				)
				(justify mirror)
			)
		)
		(duplicate_pad_numbers_are_jumpers no)
		(fp_line
			(start 0.7874 0.4064)
			(end 0.7874 -0.4064)
			(stroke
				(width 0.1524)
				(type default)
			)
			(layer "B.SilkS")
		)
		(fp_line
			(start 0.7874 -0.4064)
			(end -0.7874 -0.4064)
			(stroke
				(width 0.1524)
				(type default)
			)
			(layer "B.SilkS")
		)
		(fp_line
			(start -0.7874 0.4064)
			(end 0.7874 0.4064)
			(stroke
				(width 0.1524)
				(type default)
			)
			(layer "B.SilkS")
		)
		(fp_line
			(start -0.7874 -0.4064)
			(end -0.7874 0.4064)
			(stroke
				(width 0.1524)
				(type default)
			)
			(layer "B.SilkS")
		)
		(fp_line
			(start 0.67945 0.3048)
			(end 0.67945 -0.305054)
			(stroke
				(width 0.1)
				(type default)
			)
			(layer "B.Fab")
		)
		(fp_line
			(start 0.67945 -0.305054)
			(end 0.12065 -0.305054)
			(stroke
				(width 0.1)
				(type default)
			)
			(layer "B.Fab")
		)
		(fp_line
			(start 0.12065 0.3048)
			(end 0.67945 0.3048)
			(stroke
				(width 0.1)
				(type default)
			)
			(layer "B.Fab")
		)
		(fp_line
			(start 0.12065 0.2794)
			(end 0.12065 0.3048)
			(stroke
				(width 0.1)
				(type default)
			)
			(layer "B.Fab")
		)
		(fp_line
			(start 0.12065 -0.2794)
			(end -0.12065 -0.2794)
			(stroke
				(width 0.1)
				(type default)
			)
			(layer "B.Fab")
		)
		(fp_line
			(start 0.12065 -0.305054)
			(end 0.12065 -0.2794)
			(stroke
				(width 0.1)
				(type default)
			)
			(layer "B.Fab")
		)
		(fp_line
			(start -0.120396 0.3048)
			(end -0.120396 0.2794)
			(stroke
				(width 0.1)
				(type default)
			)
			(layer "B.Fab")
		)
		(fp_line
			(start -0.120396 0.2794)
			(end 0.12065 0.2794)
			(stroke
				(width 0.1)
				(type default)
			)
			(layer "B.Fab")
		)
		(fp_line
			(start -0.12065 -0.2794)
			(end -0.12065 -0.3048)
			(stroke
				(width 0.1)
				(type default)
			)
			(layer "B.Fab")
		)
		(fp_line
			(start -0.12065 -0.3048)
			(end -0.67945 -0.3048)
			(stroke
				(width 0.1)
				(type default)
			)
			(layer "B.Fab")
		)
		(fp_line
			(start -0.67945 0.3048)
			(end -0.120396 0.3048)
			(stroke
				(width 0.1)
				(type default)
			)
			(layer "B.Fab")
		)
		(fp_line
			(start -0.67945 -0.3048)
			(end -0.67945 0.3048)
			(stroke
				(width 0.1)
				(type default)
			)
			(layer "B.Fab")
		)
		(pad "1" smd circle
			(at 0.40005 0)
			(size 0 0)
			(layers "B.Cu" "B.Mask" "B.Paste")
			(net "P3V3_BMC_USB2AV33")
		)
		(pad "2" smd circle
			(at -0.40005 0)
			(size 0 0)
			(layers "B.Cu" "B.Mask" "B.Paste")
			(net "GND")
		)
	)
	(footprint ""
		(layer "B.Cu")
		(at 49.48682 -20.71624 -90)
		(property "Reference" "C157"
			(at 0 0 90)
			(layer "B.SilkS")
			(hide yes)
			(effects
				(font
					(size 1.27 1.27)
				)
				(justify mirror)
			)
		)
		(property "Value" ""
			(at 0 0 90)
			(layer "B.Fab")
			(effects
				(font
					(size 1.27 1.27)
				)
				(justify mirror)
			)
		)
		(duplicate_pad_numbers_are_jumpers no)
		(fp_line
			(start -0.7874 0.4064)
			(end 0.7874 0.4064)
			(stroke
				(width 0.1524)
				(type default)
			)
			(layer "B.SilkS")
		)
		(fp_line
			(start 0.7874 0.4064)
			(end 0.7874 -0.4064)
			(stroke
				(width 0.1524)
				(type default)
			)
			(layer "B.SilkS")
		)
		(fp_line
			(start -0.7874 -0.4064)
			(end -0.7874 0.4064)
			(stroke
				(width 0.1524)
				(type default)
			)
			(layer "B.SilkS")
		)
		(fp_line
			(start 0.7874 -0.4064)
			(end -0.7874 -0.4064)
			(stroke
				(width 0.1524)
				(type default)
			)
			(layer "B.SilkS")
		)
		(fp_line
			(start -0.67945 0.3048)
			(end -0.120396 0.3048)
			(stroke
				(width 0.1)
				(type default)
			)
			(layer "B.Fab")
		)
		(fp_line
			(start -0.120396 0.3048)
			(end -0.120396 0.2794)
			(stroke
				(width 0.1)
				(type default)
			)
			(layer "B.Fab")
		)
		(fp_line
			(start 0.12065 0.3048)
			(end 0.67945 0.3048)
			(stroke
				(width 0.1)
				(type default)
			)
			(layer "B.Fab")
		)
		(fp_line
			(start 0.67945 0.3048)
			(end 0.67945 -0.305054)
			(stroke
				(width 0.1)
				(type default)
			)
			(layer "B.Fab")
		)
		(fp_line
			(start -0.120396 0.2794)
			(end 0.12065 0.2794)
			(stroke
				(width 0.1)
				(type default)
			)
			(layer "B.Fab")
		)
		(fp_line
			(start 0.12065 0.2794)
			(end 0.12065 0.3048)
			(stroke
				(width 0.1)
				(type default)
			)
			(layer "B.Fab")
		)
		(fp_line
			(start -0.12065 -0.2794)
			(end -0.12065 -0.3048)
			(stroke
				(width 0.1)
				(type default)
			)
			(layer "B.Fab")
		)
		(fp_line
			(start 0.12065 -0.2794)
			(end -0.12065 -0.2794)
			(stroke
				(width 0.1)
				(type default)
			)
			(layer "B.Fab")
		)
		(fp_line
			(start -0.67945 -0.3048)
			(end -0.67945 0.3048)
			(stroke
				(width 0.1)
				(type default)
			)
			(layer "B.Fab")
		)
		(fp_line
			(start -0.12065 -0.3048)
			(end -0.67945 -0.3048)
			(stroke
				(width 0.1)
				(type default)
			)
			(layer "B.Fab")
		)
		(fp_line
			(start 0.12065 -0.305054)
			(end 0.12065 -0.2794)
			(stroke
				(width 0.1)
				(type default)
			)
			(layer "B.Fab")
		)
		(fp_line
			(start 0.67945 -0.305054)
			(end 0.12065 -0.305054)
			(stroke
				(width 0.1)
				(type default)
			)
			(layer "B.Fab")
		)
		(pad "1" smd circle
			(at 0.40005 0 90)
			(size 0 0)
			(layers "B.Cu" "B.Mask" "B.Paste")
			(net "P3V3_AUX")
		)
		(pad "2" smd circle
			(at -0.40005 0 90)
			(size 0 0)
			(layers "B.Cu" "B.Mask" "B.Paste")
			(net "GND")
		)
	)
	(footprint ""
		(layer "B.Cu")
		(at 14.097 -18.161 -90)
		(property "Reference" "R568"
			(at 0 0 90)
			(layer "B.SilkS")
			(hide yes)
			(effects
				(font
					(size 1.27 1.27)
				)
				(justify mirror)
			)
		)
		(property "Value" ""
			(at 0 0 90)
			(layer "B.Fab")
			(effects
				(font
					(size 1.27 1.27)
				)
				(justify mirror)
			)
		)
		(duplicate_pad_numbers_are_jumpers no)
		(fp_line
			(start -0.7874 0.4064)
			(end 0.7874 0.4064)
			(stroke
				(width 0.1524)
				(type default)
			)
			(layer "B.SilkS")
		)
		(fp_line
			(start 0.7874 0.4064)
			(end 0.7874 -0.4064)
			(stroke
				(width 0.1524)
				(type default)
			)
			(layer "B.SilkS")
		)
		(fp_line
			(start -0.7874 -0.4064)
			(end -0.7874 0.4064)
			(stroke
				(width 0.1524)
				(type default)
			)
			(layer "B.SilkS")
		)
		(fp_line
			(start 0.7874 -0.4064)
			(end -0.7874 -0.4064)
			(stroke
				(width 0.1524)
				(type default)
			)
			(layer "B.SilkS")
		)
		(fp_line
			(start -0.67945 0.3048)
			(end -0.120396 0.3048)
			(stroke
				(width 0.1)
				(type default)
			)
			(layer "B.Fab")
		)
		(fp_line
			(start -0.120396 0.3048)
			(end -0.120396 0.2794)
			(stroke
				(width 0.1)
				(type default)
			)
			(layer "B.Fab")
		)
		(fp_line
			(start 0.12065 0.3048)
			(end 0.67945 0.3048)
			(stroke
				(width 0.1)
				(type default)
			)
			(layer "B.Fab")
		)
		(fp_line
			(start 0.67945 0.3048)
			(end 0.67945 -0.305054)
			(stroke
				(width 0.1)
				(type default)
			)
			(layer "B.Fab")
		)
		(fp_line
			(start -0.120396 0.2794)
			(end 0.12065 0.2794)
			(stroke
				(width 0.1)
				(type default)
			)
			(layer "B.Fab")
		)
		(fp_line
			(start 0.12065 0.2794)
			(end 0.12065 0.3048)
			(stroke
				(width 0.1)
				(type default)
			)
			(layer "B.Fab")
		)
		(fp_line
			(start -0.12065 -0.2794)
			(end -0.12065 -0.3048)
			(stroke
				(width 0.1)
				(type default)
			)
			(layer "B.Fab")
		)
		(fp_line
			(start 0.12065 -0.2794)
			(end -0.12065 -0.2794)
			(stroke
				(width 0.1)
				(type default)
			)
			(layer "B.Fab")
		)
		(fp_line
			(start -0.67945 -0.3048)
			(end -0.67945 0.3048)
			(stroke
				(width 0.1)
				(type default)
			)
			(layer "B.Fab")
		)
		(fp_line
			(start -0.12065 -0.3048)
			(end -0.67945 -0.3048)
			(stroke
				(width 0.1)
				(type default)
			)
			(layer "B.Fab")
		)
		(fp_line
			(start 0.12065 -0.305054)
			(end 0.12065 -0.2794)
			(stroke
				(width 0.1)
				(type default)
			)
			(layer "B.Fab")
		)
		(fp_line
			(start 0.67945 -0.305054)
			(end 0.12065 -0.305054)
			(stroke
				(width 0.1)
				(type default)
			)
			(layer "B.Fab")
		)
		(pad "1" smd circle
			(at 0.40005 0 90)
			(size 0 0)
			(layers "B.Cu" "B.Mask" "B.Paste")
			(net "PWR_LED_P5V_AUX")
		)
		(pad "2" smd circle
			(at -0.40005 0 90)
			(size 0 0)
			(layers "B.Cu" "B.Mask" "B.Paste")
			(net "P5V_AUX")
		)
	)
	(footprint ""
		(layer "B.Cu")
		(at 48.461422 -55.170832 180)
		(property "Reference" "C77"
			(at 0 0 0)
			(layer "B.SilkS")
			(hide yes)
			(effects
				(font
					(size 1.27 1.27)
				)
				(justify mirror)
			)
		)
		(property "Value" ""
			(at 0 0 0)
			(layer "B.Fab")
			(effects
				(font
					(size 1.27 1.27)
				)
				(justify mirror)
			)
		)
		(duplicate_pad_numbers_are_jumpers no)
		(fp_line
			(start 0.7874 0.4064)
			(end 0.7874 -0.4064)
			(stroke
				(width 0.1524)
				(type default)
			)
			(layer "B.SilkS")
		)
		(fp_line
			(start 0.7874 -0.4064)
			(end -0.7874 -0.4064)
			(stroke
				(width 0.1524)
				(type default)
			)
			(layer "B.SilkS")
		)
		(fp_line
			(start -0.7874 0.4064)
			(end 0.7874 0.4064)
			(stroke
				(width 0.1524)
				(type default)
			)
			(layer "B.SilkS")
		)
		(fp_line
			(start -0.7874 -0.4064)
			(end -0.7874 0.4064)
			(stroke
				(width 0.1524)
				(type default)
			)
			(layer "B.SilkS")
		)
		(fp_line
			(start 0.67945 0.3048)
			(end 0.67945 -0.305054)
			(stroke
				(width 0.1)
				(type default)
			)
			(layer "B.Fab")
		)
		(fp_line
			(start 0.67945 -0.305054)
			(end 0.12065 -0.305054)
			(stroke
				(width 0.1)
				(type default)
			)
			(layer "B.Fab")
		)
		(fp_line
			(start 0.12065 0.3048)
			(end 0.67945 0.3048)
			(stroke
				(width 0.1)
				(type default)
			)
			(layer "B.Fab")
		)
		(fp_line
			(start 0.12065 0.2794)
			(end 0.12065 0.3048)
			(stroke
				(width 0.1)
				(type default)
			)
			(layer "B.Fab")
		)
		(fp_line
			(start 0.12065 -0.2794)
			(end -0.12065 -0.2794)
			(stroke
				(width 0.1)
				(type default)
			)
			(layer "B.Fab")
		)
		(fp_line
			(start 0.12065 -0.305054)
			(end 0.12065 -0.2794)
			(stroke
				(width 0.1)
				(type default)
			)
			(layer "B.Fab")
		)
		(fp_line
			(start -0.120396 0.3048)
			(end -0.120396 0.2794)
			(stroke
				(width 0.1)
				(type default)
			)
			(layer "B.Fab")
		)
		(fp_line
			(start -0.120396 0.2794)
			(end 0.12065 0.2794)
			(stroke
				(width 0.1)
				(type default)
			)
			(layer "B.Fab")
		)
		(fp_line
			(start -0.12065 -0.2794)
			(end -0.12065 -0.3048)
			(stroke
				(width 0.1)
				(type default)
			)
			(layer "B.Fab")
		)
		(fp_line
			(start -0.12065 -0.3048)
			(end -0.67945 -0.3048)
			(stroke
				(width 0.1)
				(type default)
			)
			(layer "B.Fab")
		)
		(fp_line
			(start -0.67945 0.3048)
			(end -0.120396 0.3048)
			(stroke
				(width 0.1)
				(type default)
			)
			(layer "B.Fab")
		)
		(fp_line
			(start -0.67945 -0.3048)
			(end -0.67945 0.3048)
			(stroke
				(width 0.1)
				(type default)
			)
			(layer "B.Fab")
		)
		(pad "1" smd circle
			(at 0.40005 0)
			(size 0 0)
			(layers "B.Cu" "B.Mask" "B.Paste")
			(net "A_BMC_ADCAV33")
		)
		(pad "2" smd circle
			(at -0.40005 0)
			(size 0 0)
			(layers "B.Cu" "B.Mask" "B.Paste")
			(net "GND")
		)
	)
	(footprint ""
		(layer "B.Cu")
		(at 57.75198 -30.867604 -90)
		(property "Reference" "R255"
			(at 0 0 90)
			(layer "B.SilkS")
			(hide yes)
			(effects
				(font
					(size 1.27 1.27)
				)
				(justify mirror)
			)
		)
		(property "Value" ""
			(at 0 0 90)
			(layer "B.Fab")
			(effects
				(font
					(size 1.27 1.27)
				)
				(justify mirror)
			)
		)
		(duplicate_pad_numbers_are_jumpers no)
		(fp_line
			(start -0.7874 0.4064)
			(end 0.7874 0.4064)
			(stroke
				(width 0.1524)
				(type default)
			)
			(layer "B.SilkS")
		)
		(fp_line
			(start 0.7874 0.4064)
			(end 0.7874 -0.4064)
			(stroke
				(width 0.1524)
				(type default)
			)
			(layer "B.SilkS")
		)
		(fp_line
			(start -0.7874 -0.4064)
			(end -0.7874 0.4064)
			(stroke
				(width 0.1524)
				(type default)
			)
			(layer "B.SilkS")
		)
		(fp_line
			(start 0.7874 -0.4064)
			(end -0.7874 -0.4064)
			(stroke
				(width 0.1524)
				(type default)
			)
			(layer "B.SilkS")
		)
		(fp_line
			(start -0.67945 0.3048)
			(end -0.120396 0.3048)
			(stroke
				(width 0.1)
				(type default)
			)
			(layer "B.Fab")
		)
		(fp_line
			(start -0.120396 0.3048)
			(end -0.120396 0.2794)
			(stroke
				(width 0.1)
				(type default)
			)
			(layer "B.Fab")
		)
		(fp_line
			(start 0.12065 0.3048)
			(end 0.67945 0.3048)
			(stroke
				(width 0.1)
				(type default)
			)
			(layer "B.Fab")
		)
		(fp_line
			(start 0.67945 0.3048)
			(end 0.67945 -0.305054)
			(stroke
				(width 0.1)
				(type default)
			)
			(layer "B.Fab")
		)
		(fp_line
			(start -0.120396 0.2794)
			(end 0.12065 0.2794)
			(stroke
				(width 0.1)
				(type default)
			)
			(layer "B.Fab")
		)
		(fp_line
			(start 0.12065 0.2794)
			(end 0.12065 0.3048)
			(stroke
				(width 0.1)
				(type default)
			)
			(layer "B.Fab")
		)
		(fp_line
			(start -0.12065 -0.2794)
			(end -0.12065 -0.3048)
			(stroke
				(width 0.1)
				(type default)
			)
			(layer "B.Fab")
		)
		(fp_line
			(start 0.12065 -0.2794)
			(end -0.12065 -0.2794)
			(stroke
				(width 0.1)
				(type default)
			)
			(layer "B.Fab")
		)
		(fp_line
			(start -0.67945 -0.3048)
			(end -0.67945 0.3048)
			(stroke
				(width 0.1)
				(type default)
			)
			(layer "B.Fab")
		)
		(fp_line
			(start -0.12065 -0.3048)
			(end -0.67945 -0.3048)
			(stroke
				(width 0.1)
				(type default)
			)
			(layer "B.Fab")
		)
		(fp_line
			(start 0.12065 -0.305054)
			(end 0.12065 -0.2794)
			(stroke
				(width 0.1)
				(type default)
			)
			(layer "B.Fab")
		)
		(fp_line
			(start 0.67945 -0.305054)
			(end 0.12065 -0.305054)
			(stroke
				(width 0.1)
				(type default)
			)
			(layer "B.Fab")
		)
		(pad "1" smd circle
			(at 0.40005 0 90)
			(size 0 0)
			(layers "B.Cu" "B.Mask" "B.Paste")
			(net "P3V3_AUX")
		)
		(pad "2" smd circle
			(at -0.40005 0 90)
			(size 0 0)
			(layers "B.Cu" "B.Mask" "B.Paste")
			(net "SMB_BMC_MM6_SDA")
		)
	)
	(footprint ""
		(layer "B.Cu")
		(at 69.85 -57.023)
		(property "Reference" "C113"
			(at 0 0 0)
			(layer "B.SilkS")
			(hide yes)
			(effects
				(font
					(size 1.27 1.27)
				)
				(justify mirror)
			)
		)
		(property "Value" ""
			(at 0 0 0)
			(layer "B.Fab")
			(effects
				(font
					(size 1.27 1.27)
				)
				(justify mirror)
			)
		)
		(duplicate_pad_numbers_are_jumpers no)
		(fp_line
			(start -1.2954 -0.5842)
			(end -1.2954 0.5842)
			(stroke
				(width 0.1524)
				(type default)
			)
			(layer "B.SilkS")
		)
		(fp_line
			(start -1.2954 0.5842)
			(end 1.2954 0.5842)
			(stroke
				(width 0.1524)
				(type default)
			)
			(layer "B.SilkS")
		)
		(fp_line
			(start 0 -0.5842)
			(end 0 0.5842)
			(stroke
				(width 0.1524)
				(type default)
			)
			(layer "B.SilkS")
		)
		(fp_line
			(start 1.2954 -0.5842)
			(end -1.2954 -0.5842)
			(stroke
				(width 0.1524)
				(type default)
			)
			(layer "B.SilkS")
		)
		(fp_line
			(start 1.2954 0.5842)
			(end 1.2954 -0.5842)
			(stroke
				(width 0.1524)
				(type default)
			)
			(layer "B.SilkS")
		)
		(fp_line
			(start -1.1938 -0.4064)
			(end -1.1938 0.4064)
			(stroke
				(width 0.1)
				(type default)
			)
			(layer "B.Fab")
		)
		(fp_line
			(start -1.1938 0.4064)
			(end -0.8636 0.4064)
			(stroke
				(width 0.1)
				(type default)
			)
			(layer "B.Fab")
		)
		(fp_line
			(start -0.8636 -0.4572)
			(end -0.8636 -0.4064)
			(stroke
				(width 0.1)
				(type default)
			)
			(layer "B.Fab")
		)
		(fp_line
			(start -0.8636 -0.4064)
			(end -1.1938 -0.4064)
			(stroke
				(width 0.1)
				(type default)
			)
			(layer "B.Fab")
		)
		(fp_line
			(start -0.8636 0.4064)
			(end -0.8636 0.4572)
			(stroke
				(width 0.1)
				(type default)
			)
			(layer "B.Fab")
		)
		(fp_line
			(start -0.8636 0.4572)
			(end 0.8636 0.4572)
			(stroke
				(width 0.1)
				(type default)
			)
			(layer "B.Fab")
		)
		(fp_line
			(start 0.8636 -0.4572)
			(end -0.8636 -0.4572)
			(stroke
				(width 0.1)
				(type default)
			)
			(layer "B.Fab")
		)
		(fp_line
			(start 0.8636 -0.4064)
			(end 0.8636 -0.4572)
			(stroke
				(width 0.1)
				(type default)
			)
			(layer "B.Fab")
		)
		(fp_line
			(start 0.8636 0.4064)
			(end 1.1938 0.4064)
			(stroke
				(width 0.1)
				(type default)
			)
			(layer "B.Fab")
		)
		(fp_line
			(start 0.8636 0.4572)
			(end 0.8636 0.4064)
			(stroke
				(width 0.1)
				(type default)
			)
			(layer "B.Fab")
		)
		(fp_line
			(start 1.1938 -0.4064)
			(end 0.8636 -0.4064)
			(stroke
				(width 0.1)
				(type default)
			)
			(layer "B.Fab")
		)
		(fp_line
			(start 1.1938 0.4064)
			(end 1.1938 -0.4064)
			(stroke
				(width 0.1)
				(type default)
			)
			(layer "B.Fab")
		)
		(pad "1" smd rect
			(at 0.7366 0 270)
			(size 0.7112 0.8128)
			(layers "B.Cu" "B.Mask" "B.Paste")
			(net "P1V0_AUX")
		)
		(pad "2" smd rect
			(at -0.7366 0 270)
			(size 0.7112 0.8128)
			(layers "B.Cu" "B.Mask" "B.Paste")
			(net "GND")
		)
	)
	(footprint ""
		(layer "B.Cu")
		(at 47.498 -34.671 90)
		(property "Reference" "R589"
			(at 0 0 90)
			(layer "B.SilkS")
			(hide yes)
			(effects
				(font
					(size 1.27 1.27)
				)
				(justify mirror)
			)
		)
		(property "Value" ""
			(at 0 0 90)
			(layer "B.Fab")
			(effects
				(font
					(size 1.27 1.27)
				)
				(justify mirror)
			)
		)
		(duplicate_pad_numbers_are_jumpers no)
		(fp_line
			(start 0.7874 -0.4064)
			(end -0.7874 -0.4064)
			(stroke
				(width 0.1524)
				(type default)
			)
			(layer "B.SilkS")
		)
		(fp_line
			(start -0.7874 -0.4064)
			(end -0.7874 0.4064)
			(stroke
				(width 0.1524)
				(type default)
			)
			(layer "B.SilkS")
		)
		(fp_line
			(start 0.7874 0.4064)
			(end 0.7874 -0.4064)
			(stroke
				(width 0.1524)
				(type default)
			)
			(layer "B.SilkS")
		)
		(fp_line
			(start -0.7874 0.4064)
			(end 0.7874 0.4064)
			(stroke
				(width 0.1524)
				(type default)
			)
			(layer "B.SilkS")
		)
		(fp_line
			(start 0.67945 -0.305054)
			(end 0.12065 -0.305054)
			(stroke
				(width 0.1)
				(type default)
			)
			(layer "B.Fab")
		)
		(fp_line
			(start 0.12065 -0.305054)
			(end 0.12065 -0.2794)
			(stroke
				(width 0.1)
				(type default)
			)
			(layer "B.Fab")
		)
		(fp_line
			(start -0.12065 -0.3048)
			(end -0.67945 -0.3048)
			(stroke
				(width 0.1)
				(type default)
			)
			(layer "B.Fab")
		)
		(fp_line
			(start -0.67945 -0.3048)
			(end -0.67945 0.3048)
			(stroke
				(width 0.1)
				(type default)
			)
			(layer "B.Fab")
		)
		(fp_line
			(start 0.12065 -0.2794)
			(end -0.12065 -0.2794)
			(stroke
				(width 0.1)
				(type default)
			)
			(layer "B.Fab")
		)
		(fp_line
			(start -0.12065 -0.2794)
			(end -0.12065 -0.3048)
			(stroke
				(width 0.1)
				(type default)
			)
			(layer "B.Fab")
		)
		(fp_line
			(start 0.12065 0.2794)
			(end 0.12065 0.3048)
			(stroke
				(width 0.1)
				(type default)
			)
			(layer "B.Fab")
		)
		(fp_line
			(start -0.120396 0.2794)
			(end 0.12065 0.2794)
			(stroke
				(width 0.1)
				(type default)
			)
			(layer "B.Fab")
		)
		(fp_line
			(start 0.67945 0.3048)
			(end 0.67945 -0.305054)
			(stroke
				(width 0.1)
				(type default)
			)
			(layer "B.Fab")
		)
		(fp_line
			(start 0.12065 0.3048)
			(end 0.67945 0.3048)
			(stroke
				(width 0.1)
				(type default)
			)
			(layer "B.Fab")
		)
		(fp_line
			(start -0.120396 0.3048)
			(end -0.120396 0.2794)
			(stroke
				(width 0.1)
				(type default)
			)
			(layer "B.Fab")
		)
		(fp_line
			(start -0.67945 0.3048)
			(end -0.120396 0.3048)
			(stroke
				(width 0.1)
				(type default)
			)
			(layer "B.Fab")
		)
		(pad "1" smd circle
			(at 0.40005 0 270)
			(size 0 0)
			(layers "B.Cu" "B.Mask" "B.Paste")
			(net "SMB_BMC_MM3_R_SCL")
		)
		(pad "2" smd circle
			(at -0.40005 0 270)
			(size 0 0)
			(layers "B.Cu" "B.Mask" "B.Paste")
			(net "SMB_BMC_MM3_SCL")
		)
	)
	(footprint ""
		(layer "B.Cu")
		(at 81.129886 -45.054012 180)
		(property "Reference" "R2"
			(at 0 0 0)
			(layer "B.SilkS")
			(hide yes)
			(effects
				(font
					(size 1.27 1.27)
				)
				(justify mirror)
			)
		)
		(property "Value" ""
			(at 0 0 0)
			(layer "B.Fab")
			(effects
				(font
					(size 1.27 1.27)
				)
				(justify mirror)
			)
		)
		(duplicate_pad_numbers_are_jumpers no)
		(fp_line
			(start 0.7874 0.4064)
			(end 0.7874 -0.4064)
			(stroke
				(width 0.1524)
				(type default)
			)
			(layer "B.SilkS")
		)
		(fp_line
			(start 0.7874 -0.4064)
			(end -0.7874 -0.4064)
			(stroke
				(width 0.1524)
				(type default)
			)
			(layer "B.SilkS")
		)
		(fp_line
			(start -0.7874 0.4064)
			(end 0.7874 0.4064)
			(stroke
				(width 0.1524)
				(type default)
			)
			(layer "B.SilkS")
		)
		(fp_line
			(start -0.7874 -0.4064)
			(end -0.7874 0.4064)
			(stroke
				(width 0.1524)
				(type default)
			)
			(layer "B.SilkS")
		)
		(fp_line
			(start 0.67945 0.3048)
			(end 0.67945 -0.305054)
			(stroke
				(width 0.1)
				(type default)
			)
			(layer "B.Fab")
		)
		(fp_line
			(start 0.67945 -0.305054)
			(end 0.12065 -0.305054)
			(stroke
				(width 0.1)
				(type default)
			)
			(layer "B.Fab")
		)
		(fp_line
			(start 0.12065 0.3048)
			(end 0.67945 0.3048)
			(stroke
				(width 0.1)
				(type default)
			)
			(layer "B.Fab")
		)
		(fp_line
			(start 0.12065 0.2794)
			(end 0.12065 0.3048)
			(stroke
				(width 0.1)
				(type default)
			)
			(layer "B.Fab")
		)
		(fp_line
			(start 0.12065 -0.2794)
			(end -0.12065 -0.2794)
			(stroke
				(width 0.1)
				(type default)
			)
			(layer "B.Fab")
		)
		(fp_line
			(start 0.12065 -0.305054)
			(end 0.12065 -0.2794)
			(stroke
				(width 0.1)
				(type default)
			)
			(layer "B.Fab")
		)
		(fp_line
			(start -0.120396 0.3048)
			(end -0.120396 0.2794)
			(stroke
				(width 0.1)
				(type default)
			)
			(layer "B.Fab")
		)
		(fp_line
			(start -0.120396 0.2794)
			(end 0.12065 0.2794)
			(stroke
				(width 0.1)
				(type default)
			)
			(layer "B.Fab")
		)
		(fp_line
			(start -0.12065 -0.2794)
			(end -0.12065 -0.3048)
			(stroke
				(width 0.1)
				(type default)
			)
			(layer "B.Fab")
		)
		(fp_line
			(start -0.12065 -0.3048)
			(end -0.67945 -0.3048)
			(stroke
				(width 0.1)
				(type default)
			)
			(layer "B.Fab")
		)
		(fp_line
			(start -0.67945 0.3048)
			(end -0.120396 0.3048)
			(stroke
				(width 0.1)
				(type default)
			)
			(layer "B.Fab")
		)
		(fp_line
			(start -0.67945 -0.3048)
			(end -0.67945 0.3048)
			(stroke
				(width 0.1)
				(type default)
			)
			(layer "B.Fab")
		)
		(pad "1" smd circle
			(at 0.40005 0)
			(size 0 0)
			(layers "B.Cu" "B.Mask" "B.Paste")
			(net "M_BMC_DDR4_BG1")
		)
		(pad "2" smd circle
			(at -0.40005 0)
			(size 0 0)
			(layers "B.Cu" "B.Mask" "B.Paste")
			(net "GND")
		)
	)
	(footprint ""
		(layer "B.Cu")
		(at 32.766 -91.821)
		(property "Reference" "R183"
			(at 0 0 0)
			(layer "B.SilkS")
			(hide yes)
			(effects
				(font
					(size 1.27 1.27)
				)
				(justify mirror)
			)
		)
		(property "Value" ""
			(at 0 0 0)
			(layer "B.Fab")
			(effects
				(font
					(size 1.27 1.27)
				)
				(justify mirror)
			)
		)
		(duplicate_pad_numbers_are_jumpers no)
		(fp_line
			(start -0.7874 -0.4064)
			(end -0.7874 0.4064)
			(stroke
				(width 0.1524)
				(type default)
			)
			(layer "B.SilkS")
		)
		(fp_line
			(start -0.7874 0.4064)
			(end 0.7874 0.4064)
			(stroke
				(width 0.1524)
				(type default)
			)
			(layer "B.SilkS")
		)
		(fp_line
			(start 0.7874 -0.4064)
			(end -0.7874 -0.4064)
			(stroke
				(width 0.1524)
				(type default)
			)
			(layer "B.SilkS")
		)
		(fp_line
			(start 0.7874 0.4064)
			(end 0.7874 -0.4064)
			(stroke
				(width 0.1524)
				(type default)
			)
			(layer "B.SilkS")
		)
		(fp_line
			(start -0.67945 -0.3048)
			(end -0.67945 0.3048)
			(stroke
				(width 0.1)
				(type default)
			)
			(layer "B.Fab")
		)
		(fp_line
			(start -0.67945 0.3048)
			(end -0.120396 0.3048)
			(stroke
				(width 0.1)
				(type default)
			)
			(layer "B.Fab")
		)
		(fp_line
			(start -0.12065 -0.3048)
			(end -0.67945 -0.3048)
			(stroke
				(width 0.1)
				(type default)
			)
			(layer "B.Fab")
		)
		(fp_line
			(start -0.12065 -0.2794)
			(end -0.12065 -0.3048)
			(stroke
				(width 0.1)
				(type default)
			)
			(layer "B.Fab")
		)
		(fp_line
			(start -0.120396 0.2794)
			(end 0.12065 0.2794)
			(stroke
				(width 0.1)
				(type default)
			)
			(layer "B.Fab")
		)
		(fp_line
			(start -0.120396 0.3048)
			(end -0.120396 0.2794)
			(stroke
				(width 0.1)
				(type default)
			)
			(layer "B.Fab")
		)
		(fp_line
			(start 0.12065 -0.305054)
			(end 0.12065 -0.2794)
			(stroke
				(width 0.1)
				(type default)
			)
			(layer "B.Fab")
		)
		(fp_line
			(start 0.12065 -0.2794)
			(end -0.12065 -0.2794)
			(stroke
				(width 0.1)
				(type default)
			)
			(layer "B.Fab")
		)
		(fp_line
			(start 0.12065 0.2794)
			(end 0.12065 0.3048)
			(stroke
				(width 0.1)
				(type default)
			)
			(layer "B.Fab")
		)
		(fp_line
			(start 0.12065 0.3048)
			(end 0.67945 0.3048)
			(stroke
				(width 0.1)
				(type default)
			)
			(layer "B.Fab")
		)
		(fp_line
			(start 0.67945 -0.305054)
			(end 0.12065 -0.305054)
			(stroke
				(width 0.1)
				(type default)
			)
			(layer "B.Fab")
		)
		(fp_line
			(start 0.67945 0.3048)
			(end 0.67945 -0.305054)
			(stroke
				(width 0.1)
				(type default)
			)
			(layer "B.Fab")
		)
		(pad "1" smd circle
			(at 0.40005 0 180)
			(size 0 0)
			(layers "B.Cu" "B.Mask" "B.Paste")
			(net "P3V3_AUX")
		)
		(pad "2" smd circle
			(at -0.40005 0 180)
			(size 0 0)
			(layers "B.Cu" "B.Mask" "B.Paste")
			(net "PVCCIO_AUX_PLD")
		)
	)
	(footprint ""
		(layer "B.Cu")
		(at 56.94934 -51.95697)
		(property "Reference" "C50"
			(at 0 0 0)
			(layer "B.SilkS")
			(hide yes)
			(effects
				(font
					(size 1.27 1.27)
				)
				(justify mirror)
			)
		)
		(property "Value" ""
			(at 0 0 0)
			(layer "B.Fab")
			(effects
				(font
					(size 1.27 1.27)
				)
				(justify mirror)
			)
		)
		(duplicate_pad_numbers_are_jumpers no)
		(fp_line
			(start -0.7874 -0.4064)
			(end -0.7874 0.4064)
			(stroke
				(width 0.1524)
				(type default)
			)
			(layer "B.SilkS")
		)
		(fp_line
			(start -0.7874 0.4064)
			(end 0.7874 0.4064)
			(stroke
				(width 0.1524)
				(type default)
			)
			(layer "B.SilkS")
		)
		(fp_line
			(start 0.7874 -0.4064)
			(end -0.7874 -0.4064)
			(stroke
				(width 0.1524)
				(type default)
			)
			(layer "B.SilkS")
		)
		(fp_line
			(start 0.7874 0.4064)
			(end 0.7874 -0.4064)
			(stroke
				(width 0.1524)
				(type default)
			)
			(layer "B.SilkS")
		)
		(fp_line
			(start -0.67945 -0.3048)
			(end -0.67945 0.3048)
			(stroke
				(width 0.1)
				(type default)
			)
			(layer "B.Fab")
		)
		(fp_line
			(start -0.67945 0.3048)
			(end -0.120396 0.3048)
			(stroke
				(width 0.1)
				(type default)
			)
			(layer "B.Fab")
		)
		(fp_line
			(start -0.12065 -0.3048)
			(end -0.67945 -0.3048)
			(stroke
				(width 0.1)
				(type default)
			)
			(layer "B.Fab")
		)
		(fp_line
			(start -0.12065 -0.2794)
			(end -0.12065 -0.3048)
			(stroke
				(width 0.1)
				(type default)
			)
			(layer "B.Fab")
		)
		(fp_line
			(start -0.120396 0.2794)
			(end 0.12065 0.2794)
			(stroke
				(width 0.1)
				(type default)
			)
			(layer "B.Fab")
		)
		(fp_line
			(start -0.120396 0.3048)
			(end -0.120396 0.2794)
			(stroke
				(width 0.1)
				(type default)
			)
			(layer "B.Fab")
		)
		(fp_line
			(start 0.12065 -0.305054)
			(end 0.12065 -0.2794)
			(stroke
				(width 0.1)
				(type default)
			)
			(layer "B.Fab")
		)
		(fp_line
			(start 0.12065 -0.2794)
			(end -0.12065 -0.2794)
			(stroke
				(width 0.1)
				(type default)
			)
			(layer "B.Fab")
		)
		(fp_line
			(start 0.12065 0.2794)
			(end 0.12065 0.3048)
			(stroke
				(width 0.1)
				(type default)
			)
			(layer "B.Fab")
		)
		(fp_line
			(start 0.12065 0.3048)
			(end 0.67945 0.3048)
			(stroke
				(width 0.1)
				(type default)
			)
			(layer "B.Fab")
		)
		(fp_line
			(start 0.67945 -0.305054)
			(end 0.12065 -0.305054)
			(stroke
				(width 0.1)
				(type default)
			)
			(layer "B.Fab")
		)
		(fp_line
			(start 0.67945 0.3048)
			(end 0.67945 -0.305054)
			(stroke
				(width 0.1)
				(type default)
			)
			(layer "B.Fab")
		)
		(pad "1" smd circle
			(at 0.40005 0 180)
			(size 0 0)
			(layers "B.Cu" "B.Mask" "B.Paste")
			(net "P1V0_STBY_RC_VCC10A")
		)
		(pad "2" smd circle
			(at -0.40005 0 180)
			(size 0 0)
			(layers "B.Cu" "B.Mask" "B.Paste")
			(net "GND")
		)
	)
	(footprint ""
		(layer "B.Cu")
		(at 49.53 -54.1528 180)
		(property "Reference" "C51"
			(at 0 0 0)
			(layer "B.SilkS")
			(hide yes)
			(effects
				(font
					(size 1.27 1.27)
				)
				(justify mirror)
			)
		)
		(property "Value" ""
			(at 0 0 0)
			(layer "B.Fab")
			(effects
				(font
					(size 1.27 1.27)
				)
				(justify mirror)
			)
		)
		(duplicate_pad_numbers_are_jumpers no)
		(fp_line
			(start 0.7874 0.4064)
			(end 0.7874 -0.4064)
			(stroke
				(width 0.1524)
				(type default)
			)
			(layer "B.SilkS")
		)
		(fp_line
			(start 0.7874 -0.4064)
			(end -0.7874 -0.4064)
			(stroke
				(width 0.1524)
				(type default)
			)
			(layer "B.SilkS")
		)
		(fp_line
			(start -0.7874 0.4064)
			(end 0.7874 0.4064)
			(stroke
				(width 0.1524)
				(type default)
			)
			(layer "B.SilkS")
		)
		(fp_line
			(start -0.7874 -0.4064)
			(end -0.7874 0.4064)
			(stroke
				(width 0.1524)
				(type default)
			)
			(layer "B.SilkS")
		)
		(fp_line
			(start 0.67945 0.3048)
			(end 0.67945 -0.305054)
			(stroke
				(width 0.1)
				(type default)
			)
			(layer "B.Fab")
		)
		(fp_line
			(start 0.67945 -0.305054)
			(end 0.12065 -0.305054)
			(stroke
				(width 0.1)
				(type default)
			)
			(layer "B.Fab")
		)
		(fp_line
			(start 0.12065 0.3048)
			(end 0.67945 0.3048)
			(stroke
				(width 0.1)
				(type default)
			)
			(layer "B.Fab")
		)
		(fp_line
			(start 0.12065 0.2794)
			(end 0.12065 0.3048)
			(stroke
				(width 0.1)
				(type default)
			)
			(layer "B.Fab")
		)
		(fp_line
			(start 0.12065 -0.2794)
			(end -0.12065 -0.2794)
			(stroke
				(width 0.1)
				(type default)
			)
			(layer "B.Fab")
		)
		(fp_line
			(start 0.12065 -0.305054)
			(end 0.12065 -0.2794)
			(stroke
				(width 0.1)
				(type default)
			)
			(layer "B.Fab")
		)
		(fp_line
			(start -0.120396 0.3048)
			(end -0.120396 0.2794)
			(stroke
				(width 0.1)
				(type default)
			)
			(layer "B.Fab")
		)
		(fp_line
			(start -0.120396 0.2794)
			(end 0.12065 0.2794)
			(stroke
				(width 0.1)
				(type default)
			)
			(layer "B.Fab")
		)
		(fp_line
			(start -0.12065 -0.2794)
			(end -0.12065 -0.3048)
			(stroke
				(width 0.1)
				(type default)
			)
			(layer "B.Fab")
		)
		(fp_line
			(start -0.12065 -0.3048)
			(end -0.67945 -0.3048)
			(stroke
				(width 0.1)
				(type default)
			)
			(layer "B.Fab")
		)
		(fp_line
			(start -0.67945 0.3048)
			(end -0.120396 0.3048)
			(stroke
				(width 0.1)
				(type default)
			)
			(layer "B.Fab")
		)
		(fp_line
			(start -0.67945 -0.3048)
			(end -0.67945 0.3048)
			(stroke
				(width 0.1)
				(type default)
			)
			(layer "B.Fab")
		)
		(pad "1" smd circle
			(at 0.40005 0)
			(size 0 0)
			(layers "B.Cu" "B.Mask" "B.Paste")
			(net "P3V3_STBY_DACAV33")
		)
		(pad "2" smd circle
			(at -0.40005 0)
			(size 0 0)
			(layers "B.Cu" "B.Mask" "B.Paste")
			(net "GND")
		)
	)
	(footprint ""
		(layer "B.Cu")
		(at 26.659332 -88.787224 -90)
		(property "Reference" "C269"
			(at 0 0 90)
			(layer "B.SilkS")
			(hide yes)
			(effects
				(font
					(size 1.27 1.27)
				)
				(justify mirror)
			)
		)
		(property "Value" ""
			(at 0 0 90)
			(layer "B.Fab")
			(effects
				(font
					(size 1.27 1.27)
				)
				(justify mirror)
			)
		)
		(duplicate_pad_numbers_are_jumpers no)
		(fp_line
			(start -0.69215 0.2921)
			(end 0.69215 0.2921)
			(stroke
				(width 0.1524)
				(type default)
			)
			(layer "B.SilkS")
		)
		(fp_line
			(start 0.69215 0.2921)
			(end 0.69215 -0.2921)
			(stroke
				(width 0.1524)
				(type default)
			)
			(layer "B.SilkS")
		)
		(fp_line
			(start -0.69215 -0.2921)
			(end -0.69215 0.2921)
			(stroke
				(width 0.1524)
				(type default)
			)
			(layer "B.SilkS")
		)
		(fp_line
			(start 0.69215 -0.2921)
			(end -0.69215 -0.2921)
			(stroke
				(width 0.1524)
				(type default)
			)
			(layer "B.SilkS")
		)
		(fp_line
			(start -0.51435 0.2794)
			(end 0.51435 0.2794)
			(stroke
				(width 0.1)
				(type default)
			)
			(layer "B.Fab")
		)
		(fp_line
			(start 0.51435 0.2794)
			(end 0.51435 -0.2794)
			(stroke
				(width 0.1)
				(type default)
			)
			(layer "B.Fab")
		)
		(fp_line
			(start -0.51435 -0.2794)
			(end -0.51435 0.2794)
			(stroke
				(width 0.1)
				(type default)
			)
			(layer "B.Fab")
		)
		(fp_line
			(start 0.51435 -0.2794)
			(end -0.51435 -0.2794)
			(stroke
				(width 0.1)
				(type default)
			)
			(layer "B.Fab")
		)
		(pad "1" smd circle
			(at 0.40005 0 90)
			(size 0 0)
			(layers "B.Cu" "B.Mask" "B.Paste")
			(net "PVCCA_AUX_PLD")
		)
		(pad "2" smd circle
			(at -0.40005 0 90)
			(size 0 0)
			(layers "B.Cu" "B.Mask" "B.Paste")
			(net "GND")
		)
		(zone
			(layer "B.Cu")
			(hatch none 0.5)
			(connect_pads
				(clearance 0)
			)
			(min_thickness 0.25)
			(keepout
				(tracks not_allowed)
				(vias allowed)
				(pads allowed)
				(copperpour not_allowed)
				(footprints allowed)
			)
			(placement
				(enabled no)
				(sheetname "")
			)
			(fill
				(thermal_gap 0.5)
				(thermal_bridge_width 0.5)
				(island_removal_mode 0)
			)
			(polygon
				(pts
					(xy 26.571702 -88.596724) (xy 26.513536 -88.688164) (xy 26.513536 -88.887554) (xy 26.571702 -88.977724)
					(xy 26.746962 -88.977724) (xy 26.805382 -88.887554) (xy 26.805382 -88.688164) (xy 26.747216 -88.596724)
				)
			)
		)
	)
	(footprint ""
		(layer "B.Cu")
		(at 79.8576 -30.988)
		(property "Reference" "R700"
			(at 0 0 0)
			(layer "B.SilkS")
			(hide yes)
			(effects
				(font
					(size 1.27 1.27)
				)
				(justify mirror)
			)
		)
		(property "Value" ""
			(at 0 0 0)
			(layer "B.Fab")
			(effects
				(font
					(size 1.27 1.27)
				)
				(justify mirror)
			)
		)
		(duplicate_pad_numbers_are_jumpers no)
		(fp_line
			(start -0.7874 -0.4064)
			(end -0.7874 0.4064)
			(stroke
				(width 0.1524)
				(type default)
			)
			(layer "B.SilkS")
		)
		(fp_line
			(start -0.7874 0.4064)
			(end 0.7874 0.4064)
			(stroke
				(width 0.1524)
				(type default)
			)
			(layer "B.SilkS")
		)
		(fp_line
			(start 0.7874 -0.4064)
			(end -0.7874 -0.4064)
			(stroke
				(width 0.1524)
				(type default)
			)
			(layer "B.SilkS")
		)
		(fp_line
			(start 0.7874 0.4064)
			(end 0.7874 -0.4064)
			(stroke
				(width 0.1524)
				(type default)
			)
			(layer "B.SilkS")
		)
		(fp_line
			(start -0.67945 -0.3048)
			(end -0.67945 0.3048)
			(stroke
				(width 0.1)
				(type default)
			)
			(layer "B.Fab")
		)
		(fp_line
			(start -0.67945 0.3048)
			(end -0.120396 0.3048)
			(stroke
				(width 0.1)
				(type default)
			)
			(layer "B.Fab")
		)
		(fp_line
			(start -0.12065 -0.3048)
			(end -0.67945 -0.3048)
			(stroke
				(width 0.1)
				(type default)
			)
			(layer "B.Fab")
		)
		(fp_line
			(start -0.12065 -0.2794)
			(end -0.12065 -0.3048)
			(stroke
				(width 0.1)
				(type default)
			)
			(layer "B.Fab")
		)
		(fp_line
			(start -0.120396 0.2794)
			(end 0.12065 0.2794)
			(stroke
				(width 0.1)
				(type default)
			)
			(layer "B.Fab")
		)
		(fp_line
			(start -0.120396 0.3048)
			(end -0.120396 0.2794)
			(stroke
				(width 0.1)
				(type default)
			)
			(layer "B.Fab")
		)
		(fp_line
			(start 0.12065 -0.305054)
			(end 0.12065 -0.2794)
			(stroke
				(width 0.1)
				(type default)
			)
			(layer "B.Fab")
		)
		(fp_line
			(start 0.12065 -0.2794)
			(end -0.12065 -0.2794)
			(stroke
				(width 0.1)
				(type default)
			)
			(layer "B.Fab")
		)
		(fp_line
			(start 0.12065 0.2794)
			(end 0.12065 0.3048)
			(stroke
				(width 0.1)
				(type default)
			)
			(layer "B.Fab")
		)
		(fp_line
			(start 0.12065 0.3048)
			(end 0.67945 0.3048)
			(stroke
				(width 0.1)
				(type default)
			)
			(layer "B.Fab")
		)
		(fp_line
			(start 0.67945 -0.305054)
			(end 0.12065 -0.305054)
			(stroke
				(width 0.1)
				(type default)
			)
			(layer "B.Fab")
		)
		(fp_line
			(start 0.67945 0.3048)
			(end 0.67945 -0.305054)
			(stroke
				(width 0.1)
				(type default)
			)
			(layer "B.Fab")
		)
		(pad "1" smd circle
			(at 0.40005 0 180)
			(size 0 0)
			(layers "B.Cu" "B.Mask" "B.Paste")
			(net "LED_POSTCODE_0")
		)
		(pad "2" smd circle
			(at -0.40005 0 180)
			(size 0 0)
			(layers "B.Cu" "B.Mask" "B.Paste")
			(net "LED_POSTCODE_0_R1")
		)
	)
	(footprint ""
		(layer "B.Cu")
		(at 41.966134 -47.231808)
		(property "Reference" "R818"
			(at 0 0 0)
			(layer "B.SilkS")
			(hide yes)
			(effects
				(font
					(size 1.27 1.27)
				)
				(justify mirror)
			)
		)
		(property "Value" ""
			(at 0 0 0)
			(layer "B.Fab")
			(effects
				(font
					(size 1.27 1.27)
				)
				(justify mirror)
			)
		)
		(duplicate_pad_numbers_are_jumpers no)
		(fp_line
			(start -0.7874 -0.4064)
			(end -0.7874 0.4064)
			(stroke
				(width 0.1524)
				(type default)
			)
			(layer "B.SilkS")
		)
		(fp_line
			(start -0.7874 0.4064)
			(end 0.7874 0.4064)
			(stroke
				(width 0.1524)
				(type default)
			)
			(layer "B.SilkS")
		)
		(fp_line
			(start 0.7874 -0.4064)
			(end -0.7874 -0.4064)
			(stroke
				(width 0.1524)
				(type default)
			)
			(layer "B.SilkS")
		)
		(fp_line
			(start 0.7874 0.4064)
			(end 0.7874 -0.4064)
			(stroke
				(width 0.1524)
				(type default)
			)
			(layer "B.SilkS")
		)
		(fp_line
			(start -0.67945 -0.3048)
			(end -0.67945 0.3048)
			(stroke
				(width 0.1)
				(type default)
			)
			(layer "B.Fab")
		)
		(fp_line
			(start -0.67945 0.3048)
			(end -0.120396 0.3048)
			(stroke
				(width 0.1)
				(type default)
			)
			(layer "B.Fab")
		)
		(fp_line
			(start -0.12065 -0.3048)
			(end -0.67945 -0.3048)
			(stroke
				(width 0.1)
				(type default)
			)
			(layer "B.Fab")
		)
		(fp_line
			(start -0.12065 -0.2794)
			(end -0.12065 -0.3048)
			(stroke
				(width 0.1)
				(type default)
			)
			(layer "B.Fab")
		)
		(fp_line
			(start -0.120396 0.2794)
			(end 0.12065 0.2794)
			(stroke
				(width 0.1)
				(type default)
			)
			(layer "B.Fab")
		)
		(fp_line
			(start -0.120396 0.3048)
			(end -0.120396 0.2794)
			(stroke
				(width 0.1)
				(type default)
			)
			(layer "B.Fab")
		)
		(fp_line
			(start 0.12065 -0.305054)
			(end 0.12065 -0.2794)
			(stroke
				(width 0.1)
				(type default)
			)
			(layer "B.Fab")
		)
		(fp_line
			(start 0.12065 -0.2794)
			(end -0.12065 -0.2794)
			(stroke
				(width 0.1)
				(type default)
			)
			(layer "B.Fab")
		)
		(fp_line
			(start 0.12065 0.2794)
			(end 0.12065 0.3048)
			(stroke
				(width 0.1)
				(type default)
			)
			(layer "B.Fab")
		)
		(fp_line
			(start 0.12065 0.3048)
			(end 0.67945 0.3048)
			(stroke
				(width 0.1)
				(type default)
			)
			(layer "B.Fab")
		)
		(fp_line
			(start 0.67945 -0.305054)
			(end 0.12065 -0.305054)
			(stroke
				(width 0.1)
				(type default)
			)
			(layer "B.Fab")
		)
		(fp_line
			(start 0.67945 0.3048)
			(end 0.67945 -0.305054)
			(stroke
				(width 0.1)
				(type default)
			)
			(layer "B.Fab")
		)
		(pad "1" smd circle
			(at 0.40005 0 180)
			(size 0 0)
			(layers "B.Cu" "B.Mask" "B.Paste")
			(net "SMB_BMC_MM13_R_SDA")
		)
		(pad "2" smd circle
			(at -0.40005 0 180)
			(size 0 0)
			(layers "B.Cu" "B.Mask" "B.Paste")
			(net "GND")
		)
	)
	(footprint ""
		(layer "B.Cu")
		(at 59.436 -99.06 180)
		(property "Reference" "Q8"
			(at 2.3622 1.10363 0)
			(unlocked yes)
			(layer "B.SilkS")
			(effects
				(font
					(size 0.7874 0.5842)
					(thickness 0.1524)
				)
				(justify left mirror)
			)
		)
		(property "Value" ""
			(at 0 0 0)
			(layer "B.Fab")
			(effects
				(font
					(size 1.27 1.27)
				)
				(justify mirror)
			)
		)
		(duplicate_pad_numbers_are_jumpers no)
		(fp_line
			(start 1.603248 1.500124)
			(end 1.603248 -1.500124)
			(stroke
				(width 0.1524)
				(type default)
			)
			(layer "B.SilkS")
		)
		(fp_line
			(start 1.603248 -1.500124)
			(end -1.603248 -1.500124)
			(stroke
				(width 0.1524)
				(type default)
			)
			(layer "B.SilkS")
		)
		(fp_line
			(start -1.603248 1.500124)
			(end 1.603248 1.500124)
			(stroke
				(width 0.1524)
				(type default)
			)
			(layer "B.SilkS")
		)
		(fp_line
			(start -1.603248 -1.500124)
			(end -1.603248 1.500124)
			(stroke
				(width 0.1524)
				(type default)
			)
			(layer "B.SilkS")
		)
		(fp_line
			(start 1.249934 1.169924)
			(end 0.700024 1.169924)
			(stroke
				(width 0.1)
				(type default)
			)
			(layer "B.Fab")
		)
		(fp_line
			(start 1.249934 0.729996)
			(end 1.249934 1.169924)
			(stroke
				(width 0.1)
				(type default)
			)
			(layer "B.Fab")
		)
		(fp_line
			(start 1.249934 -0.729996)
			(end 0.6985 -0.729996)
			(stroke
				(width 0.1)
				(type default)
			)
			(layer "B.Fab")
		)
		(fp_line
			(start 1.249934 -1.169924)
			(end 1.249934 -0.729996)
			(stroke
				(width 0.1)
				(type default)
			)
			(layer "B.Fab")
		)
		(fp_line
			(start 0.700024 1.500124)
			(end -0.700024 1.500124)
			(stroke
				(width 0.1)
				(type default)
			)
			(layer "B.Fab")
		)
		(fp_line
			(start 0.700024 1.169924)
			(end 0.700024 1.500124)
			(stroke
				(width 0.1)
				(type default)
			)
			(layer "B.Fab")
		)
		(fp_line
			(start 0.700024 -1.169924)
			(end 1.249934 -1.169924)
			(stroke
				(width 0.1)
				(type default)
			)
			(layer "B.Fab")
		)
		(fp_line
			(start 0.700024 -1.500124)
			(end 0.700024 -1.169924)
			(stroke
				(width 0.1)
				(type default)
			)
			(layer "B.Fab")
		)
		(fp_line
			(start 0.6985 0.729996)
			(end 1.249934 0.729996)
			(stroke
				(width 0.1)
				(type default)
			)
			(layer "B.Fab")
		)
		(fp_line
			(start 0.6985 -0.729996)
			(end 0.6985 0.729996)
			(stroke
				(width 0.1)
				(type default)
			)
			(layer "B.Fab")
		)
		(fp_line
			(start -0.700024 1.500124)
			(end -0.700024 0.219964)
			(stroke
				(width 0.1)
				(type default)
			)
			(layer "B.Fab")
		)
		(fp_line
			(start -0.700024 0.219964)
			(end -1.249934 0.219964)
			(stroke
				(width 0.1)
				(type default)
			)
			(layer "B.Fab")
		)
		(fp_line
			(start -0.700024 -0.219964)
			(end -0.700024 -1.500124)
			(stroke
				(width 0.1)
				(type default)
			)
			(layer "B.Fab")
		)
		(fp_line
			(start -0.700024 -1.500124)
			(end 0.700024 -1.500124)
			(stroke
				(width 0.1)
				(type default)
			)
			(layer "B.Fab")
		)
		(fp_line
			(start -1.249934 0.219964)
			(end -1.249934 -0.219964)
			(stroke
				(width 0.1)
				(type default)
			)
			(layer "B.Fab")
		)
		(fp_line
			(start -1.249934 -0.219964)
			(end -0.700024 -0.219964)
			(stroke
				(width 0.1)
				(type default)
			)
			(layer "B.Fab")
		)
		(fp_rect
			(start 0.700024 1.500124)
			(end -0.700024 -1.500124)
			(stroke
				(width 0)
				(type default)
			)
			(fill no)
			(layer "B.Fab")
		)
		(pad "D" smd rect
			(at -0.999998 0 90)
			(size 0.8128 0.9144)
			(layers "B.Cu" "B.Mask" "B.Paste")
			(net "FM_SOL_UART_CH_SEL_R3")
		)
		(pad "G" smd rect
			(at 0.999998 -0.94996 90)
			(size 0.8128 0.9144)
			(layers "B.Cu" "B.Mask" "B.Paste")
			(net "FM_UART_SEL_N")
		)
		(pad "S" smd rect
			(at 0.999998 0.94996 90)
			(size 0.8128 0.9144)
			(layers "B.Cu" "B.Mask" "B.Paste")
			(net "GND")
		)
	)
	(footprint ""
		(layer "B.Cu")
		(at 58.679334 -54.416198 -90)
		(property "Reference" "C69"
			(at 0 0 90)
			(layer "B.SilkS")
			(hide yes)
			(effects
				(font
					(size 1.27 1.27)
				)
				(justify mirror)
			)
		)
		(property "Value" ""
			(at 0 0 90)
			(layer "B.Fab")
			(effects
				(font
					(size 1.27 1.27)
				)
				(justify mirror)
			)
		)
		(duplicate_pad_numbers_are_jumpers no)
		(fp_line
			(start -0.7874 0.4064)
			(end 0.7874 0.4064)
			(stroke
				(width 0.1524)
				(type default)
			)
			(layer "B.SilkS")
		)
		(fp_line
			(start 0.7874 0.4064)
			(end 0.7874 -0.4064)
			(stroke
				(width 0.1524)
				(type default)
			)
			(layer "B.SilkS")
		)
		(fp_line
			(start -0.7874 -0.4064)
			(end -0.7874 0.4064)
			(stroke
				(width 0.1524)
				(type default)
			)
			(layer "B.SilkS")
		)
		(fp_line
			(start 0.7874 -0.4064)
			(end -0.7874 -0.4064)
			(stroke
				(width 0.1524)
				(type default)
			)
			(layer "B.SilkS")
		)
		(fp_line
			(start -0.67945 0.3048)
			(end -0.120396 0.3048)
			(stroke
				(width 0.1)
				(type default)
			)
			(layer "B.Fab")
		)
		(fp_line
			(start -0.120396 0.3048)
			(end -0.120396 0.2794)
			(stroke
				(width 0.1)
				(type default)
			)
			(layer "B.Fab")
		)
		(fp_line
			(start 0.12065 0.3048)
			(end 0.67945 0.3048)
			(stroke
				(width 0.1)
				(type default)
			)
			(layer "B.Fab")
		)
		(fp_line
			(start 0.67945 0.3048)
			(end 0.67945 -0.305054)
			(stroke
				(width 0.1)
				(type default)
			)
			(layer "B.Fab")
		)
		(fp_line
			(start -0.120396 0.2794)
			(end 0.12065 0.2794)
			(stroke
				(width 0.1)
				(type default)
			)
			(layer "B.Fab")
		)
		(fp_line
			(start 0.12065 0.2794)
			(end 0.12065 0.3048)
			(stroke
				(width 0.1)
				(type default)
			)
			(layer "B.Fab")
		)
		(fp_line
			(start -0.12065 -0.2794)
			(end -0.12065 -0.3048)
			(stroke
				(width 0.1)
				(type default)
			)
			(layer "B.Fab")
		)
		(fp_line
			(start 0.12065 -0.2794)
			(end -0.12065 -0.2794)
			(stroke
				(width 0.1)
				(type default)
			)
			(layer "B.Fab")
		)
		(fp_line
			(start -0.67945 -0.3048)
			(end -0.67945 0.3048)
			(stroke
				(width 0.1)
				(type default)
			)
			(layer "B.Fab")
		)
		(fp_line
			(start -0.12065 -0.3048)
			(end -0.67945 -0.3048)
			(stroke
				(width 0.1)
				(type default)
			)
			(layer "B.Fab")
		)
		(fp_line
			(start 0.12065 -0.305054)
			(end 0.12065 -0.2794)
			(stroke
				(width 0.1)
				(type default)
			)
			(layer "B.Fab")
		)
		(fp_line
			(start 0.67945 -0.305054)
			(end 0.12065 -0.305054)
			(stroke
				(width 0.1)
				(type default)
			)
			(layer "B.Fab")
		)
		(pad "1" smd circle
			(at 0.40005 0 90)
			(size 0 0)
			(layers "B.Cu" "B.Mask" "B.Paste")
			(net "P1V8_STBY_PE_VCC18A")
		)
		(pad "2" smd circle
			(at -0.40005 0 90)
			(size 0 0)
			(layers "B.Cu" "B.Mask" "B.Paste")
			(net "GND")
		)
	)
	(footprint ""
		(layer "B.Cu")
		(at 20.066 -24.003 -90)
		(property "Reference" "PC269"
			(at 0 0 90)
			(layer "B.SilkS")
			(hide yes)
			(effects
				(font
					(size 1.27 1.27)
				)
				(justify mirror)
			)
		)
		(property "Value" ""
			(at 0 0 90)
			(layer "B.Fab")
			(effects
				(font
					(size 1.27 1.27)
				)
				(justify mirror)
			)
		)
		(duplicate_pad_numbers_are_jumpers no)
		(fp_line
			(start -1.651 0.8382)
			(end 1.651 0.8382)
			(stroke
				(width 0.1524)
				(type default)
			)
			(layer "B.SilkS")
		)
		(fp_line
			(start 0 0.8382)
			(end 0 -0.8382)
			(stroke
				(width 0.1524)
				(type default)
			)
			(layer "B.SilkS")
		)
		(fp_line
			(start 1.651 0.8382)
			(end 1.651 -0.8382)
			(stroke
				(width 0.1524)
				(type default)
			)
			(layer "B.SilkS")
		)
		(fp_line
			(start -1.651 -0.8382)
			(end -1.651 0.8382)
			(stroke
				(width 0.1524)
				(type default)
			)
			(layer "B.SilkS")
		)
		(fp_line
			(start 1.651 -0.8382)
			(end -1.651 -0.8382)
			(stroke
				(width 0.1524)
				(type default)
			)
			(layer "B.SilkS")
		)
		(fp_line
			(start -1.55956 0.7366)
			(end -1.55956 -0.7366)
			(stroke
				(width 0.1)
				(type default)
			)
			(layer "B.Fab")
		)
		(fp_line
			(start -1.524 0.7366)
			(end -1.55956 0.7366)
			(stroke
				(width 0.1)
				(type default)
			)
			(layer "B.Fab")
		)
		(fp_line
			(start 1.524 0.7366)
			(end -1.524 0.7366)
			(stroke
				(width 0.1)
				(type default)
			)
			(layer "B.Fab")
		)
		(fp_line
			(start 1.55956 0.7366)
			(end 1.524 0.7366)
			(stroke
				(width 0.1)
				(type default)
			)
			(layer "B.Fab")
		)
		(fp_line
			(start -1.55956 -0.7366)
			(end -1.524 -0.7366)
			(stroke
				(width 0.1)
				(type default)
			)
			(layer "B.Fab")
		)
		(fp_line
			(start -1.524 -0.7366)
			(end 1.524 -0.7366)
			(stroke
				(width 0.1)
				(type default)
			)
			(layer "B.Fab")
		)
		(fp_line
			(start 1.524 -0.7366)
			(end 1.55956 -0.7366)
			(stroke
				(width 0.1)
				(type default)
			)
			(layer "B.Fab")
		)
		(fp_line
			(start 1.55956 -0.7366)
			(end 1.55956 0.7366)
			(stroke
				(width 0.1)
				(type default)
			)
			(layer "B.Fab")
		)
		(pad "1" smd rect
			(at 0.94996 0 270)
			(size 1.1176 1.3716)
			(layers "B.Cu" "B.Mask" "B.Paste")
			(net "P1V0_AUX")
		)
		(pad "2" smd rect
			(at -0.94996 0 270)
			(size 1.1176 1.3716)
			(layers "B.Cu" "B.Mask" "B.Paste")
			(net "GND")
		)
	)
	(footprint ""
		(layer "B.Cu")
		(at 58.381646 -46.974252 180)
		(property "Reference" "C41"
			(at 0 0 0)
			(layer "B.SilkS")
			(hide yes)
			(effects
				(font
					(size 1.27 1.27)
				)
				(justify mirror)
			)
		)
		(property "Value" ""
			(at 0 0 0)
			(layer "B.Fab")
			(effects
				(font
					(size 1.27 1.27)
				)
				(justify mirror)
			)
		)
		(duplicate_pad_numbers_are_jumpers no)
		(fp_line
			(start 0.7874 0.4064)
			(end 0.7874 -0.4064)
			(stroke
				(width 0.1524)
				(type default)
			)
			(layer "B.SilkS")
		)
		(fp_line
			(start 0.7874 -0.4064)
			(end -0.7874 -0.4064)
			(stroke
				(width 0.1524)
				(type default)
			)
			(layer "B.SilkS")
		)
		(fp_line
			(start -0.7874 0.4064)
			(end 0.7874 0.4064)
			(stroke
				(width 0.1524)
				(type default)
			)
			(layer "B.SilkS")
		)
		(fp_line
			(start -0.7874 -0.4064)
			(end -0.7874 0.4064)
			(stroke
				(width 0.1524)
				(type default)
			)
			(layer "B.SilkS")
		)
		(fp_line
			(start 0.67945 0.3048)
			(end 0.67945 -0.305054)
			(stroke
				(width 0.1)
				(type default)
			)
			(layer "B.Fab")
		)
		(fp_line
			(start 0.67945 -0.305054)
			(end 0.12065 -0.305054)
			(stroke
				(width 0.1)
				(type default)
			)
			(layer "B.Fab")
		)
		(fp_line
			(start 0.12065 0.3048)
			(end 0.67945 0.3048)
			(stroke
				(width 0.1)
				(type default)
			)
			(layer "B.Fab")
		)
		(fp_line
			(start 0.12065 0.2794)
			(end 0.12065 0.3048)
			(stroke
				(width 0.1)
				(type default)
			)
			(layer "B.Fab")
		)
		(fp_line
			(start 0.12065 -0.2794)
			(end -0.12065 -0.2794)
			(stroke
				(width 0.1)
				(type default)
			)
			(layer "B.Fab")
		)
		(fp_line
			(start 0.12065 -0.305054)
			(end 0.12065 -0.2794)
			(stroke
				(width 0.1)
				(type default)
			)
			(layer "B.Fab")
		)
		(fp_line
			(start -0.120396 0.3048)
			(end -0.120396 0.2794)
			(stroke
				(width 0.1)
				(type default)
			)
			(layer "B.Fab")
		)
		(fp_line
			(start -0.120396 0.2794)
			(end 0.12065 0.2794)
			(stroke
				(width 0.1)
				(type default)
			)
			(layer "B.Fab")
		)
		(fp_line
			(start -0.12065 -0.2794)
			(end -0.12065 -0.3048)
			(stroke
				(width 0.1)
				(type default)
			)
			(layer "B.Fab")
		)
		(fp_line
			(start -0.12065 -0.3048)
			(end -0.67945 -0.3048)
			(stroke
				(width 0.1)
				(type default)
			)
			(layer "B.Fab")
		)
		(fp_line
			(start -0.67945 0.3048)
			(end -0.120396 0.3048)
			(stroke
				(width 0.1)
				(type default)
			)
			(layer "B.Fab")
		)
		(fp_line
			(start -0.67945 -0.3048)
			(end -0.67945 0.3048)
			(stroke
				(width 0.1)
				(type default)
			)
			(layer "B.Fab")
		)
		(pad "1" smd circle
			(at 0.40005 0)
			(size 0 0)
			(layers "B.Cu" "B.Mask" "B.Paste")
			(net "P1V8_BMC_USB2AV18")
		)
		(pad "2" smd circle
			(at -0.40005 0)
			(size 0 0)
			(layers "B.Cu" "B.Mask" "B.Paste")
			(net "GND")
		)
	)
	(footprint ""
		(layer "B.Cu")
		(at 50.858674 -71.824342 180)
		(property "Reference" "C307"
			(at 0 0 0)
			(layer "B.SilkS")
			(hide yes)
			(effects
				(font
					(size 1.27 1.27)
				)
				(justify mirror)
			)
		)
		(property "Value" ""
			(at 0 0 0)
			(layer "B.Fab")
			(effects
				(font
					(size 1.27 1.27)
				)
				(justify mirror)
			)
		)
		(duplicate_pad_numbers_are_jumpers no)
		(fp_line
			(start 0.7874 0.4064)
			(end 0.7874 -0.4064)
			(stroke
				(width 0.1524)
				(type default)
			)
			(layer "B.SilkS")
		)
		(fp_line
			(start 0.7874 -0.4064)
			(end -0.7874 -0.4064)
			(stroke
				(width 0.1524)
				(type default)
			)
			(layer "B.SilkS")
		)
		(fp_line
			(start -0.7874 0.4064)
			(end 0.7874 0.4064)
			(stroke
				(width 0.1524)
				(type default)
			)
			(layer "B.SilkS")
		)
		(fp_line
			(start -0.7874 -0.4064)
			(end -0.7874 0.4064)
			(stroke
				(width 0.1524)
				(type default)
			)
			(layer "B.SilkS")
		)
		(fp_line
			(start 0.67945 0.3048)
			(end 0.67945 -0.305054)
			(stroke
				(width 0.1)
				(type default)
			)
			(layer "B.Fab")
		)
		(fp_line
			(start 0.67945 -0.305054)
			(end 0.12065 -0.305054)
			(stroke
				(width 0.1)
				(type default)
			)
			(layer "B.Fab")
		)
		(fp_line
			(start 0.12065 0.3048)
			(end 0.67945 0.3048)
			(stroke
				(width 0.1)
				(type default)
			)
			(layer "B.Fab")
		)
		(fp_line
			(start 0.12065 0.2794)
			(end 0.12065 0.3048)
			(stroke
				(width 0.1)
				(type default)
			)
			(layer "B.Fab")
		)
		(fp_line
			(start 0.12065 -0.2794)
			(end -0.12065 -0.2794)
			(stroke
				(width 0.1)
				(type default)
			)
			(layer "B.Fab")
		)
		(fp_line
			(start 0.12065 -0.305054)
			(end 0.12065 -0.2794)
			(stroke
				(width 0.1)
				(type default)
			)
			(layer "B.Fab")
		)
		(fp_line
			(start -0.120396 0.3048)
			(end -0.120396 0.2794)
			(stroke
				(width 0.1)
				(type default)
			)
			(layer "B.Fab")
		)
		(fp_line
			(start -0.120396 0.2794)
			(end 0.12065 0.2794)
			(stroke
				(width 0.1)
				(type default)
			)
			(layer "B.Fab")
		)
		(fp_line
			(start -0.12065 -0.2794)
			(end -0.12065 -0.3048)
			(stroke
				(width 0.1)
				(type default)
			)
			(layer "B.Fab")
		)
		(fp_line
			(start -0.12065 -0.3048)
			(end -0.67945 -0.3048)
			(stroke
				(width 0.1)
				(type default)
			)
			(layer "B.Fab")
		)
		(fp_line
			(start -0.67945 0.3048)
			(end -0.120396 0.3048)
			(stroke
				(width 0.1)
				(type default)
			)
			(layer "B.Fab")
		)
		(fp_line
			(start -0.67945 -0.3048)
			(end -0.67945 0.3048)
			(stroke
				(width 0.1)
				(type default)
			)
			(layer "B.Fab")
		)
		(pad "1" smd circle
			(at 0.40005 0)
			(size 0 0)
			(layers "B.Cu" "B.Mask" "B.Paste")
			(net "P1V8_SENSOR")
		)
		(pad "2" smd circle
			(at -0.40005 0)
			(size 0 0)
			(layers "B.Cu" "B.Mask" "B.Paste")
			(net "GND")
		)
	)
	(footprint ""
		(layer "B.Cu")
		(at 37.867336 -48.9204 180)
		(property "Reference" "R429"
			(at 0 0 0)
			(layer "B.SilkS")
			(hide yes)
			(effects
				(font
					(size 1.27 1.27)
				)
				(justify mirror)
			)
		)
		(property "Value" ""
			(at 0 0 0)
			(layer "B.Fab")
			(effects
				(font
					(size 1.27 1.27)
				)
				(justify mirror)
			)
		)
		(duplicate_pad_numbers_are_jumpers no)
		(fp_line
			(start 0.7874 0.4064)
			(end 0.7874 -0.4064)
			(stroke
				(width 0.1524)
				(type default)
			)
			(layer "B.SilkS")
		)
		(fp_line
			(start 0.7874 -0.4064)
			(end -0.7874 -0.4064)
			(stroke
				(width 0.1524)
				(type default)
			)
			(layer "B.SilkS")
		)
		(fp_line
			(start -0.7874 0.4064)
			(end 0.7874 0.4064)
			(stroke
				(width 0.1524)
				(type default)
			)
			(layer "B.SilkS")
		)
		(fp_line
			(start -0.7874 -0.4064)
			(end -0.7874 0.4064)
			(stroke
				(width 0.1524)
				(type default)
			)
			(layer "B.SilkS")
		)
		(fp_line
			(start 0.67945 0.3048)
			(end 0.67945 -0.305054)
			(stroke
				(width 0.1)
				(type default)
			)
			(layer "B.Fab")
		)
		(fp_line
			(start 0.67945 -0.305054)
			(end 0.12065 -0.305054)
			(stroke
				(width 0.1)
				(type default)
			)
			(layer "B.Fab")
		)
		(fp_line
			(start 0.12065 0.3048)
			(end 0.67945 0.3048)
			(stroke
				(width 0.1)
				(type default)
			)
			(layer "B.Fab")
		)
		(fp_line
			(start 0.12065 0.2794)
			(end 0.12065 0.3048)
			(stroke
				(width 0.1)
				(type default)
			)
			(layer "B.Fab")
		)
		(fp_line
			(start 0.12065 -0.2794)
			(end -0.12065 -0.2794)
			(stroke
				(width 0.1)
				(type default)
			)
			(layer "B.Fab")
		)
		(fp_line
			(start 0.12065 -0.305054)
			(end 0.12065 -0.2794)
			(stroke
				(width 0.1)
				(type default)
			)
			(layer "B.Fab")
		)
		(fp_line
			(start -0.120396 0.3048)
			(end -0.120396 0.2794)
			(stroke
				(width 0.1)
				(type default)
			)
			(layer "B.Fab")
		)
		(fp_line
			(start -0.120396 0.2794)
			(end 0.12065 0.2794)
			(stroke
				(width 0.1)
				(type default)
			)
			(layer "B.Fab")
		)
		(fp_line
			(start -0.12065 -0.2794)
			(end -0.12065 -0.3048)
			(stroke
				(width 0.1)
				(type default)
			)
			(layer "B.Fab")
		)
		(fp_line
			(start -0.12065 -0.3048)
			(end -0.67945 -0.3048)
			(stroke
				(width 0.1)
				(type default)
			)
			(layer "B.Fab")
		)
		(fp_line
			(start -0.67945 0.3048)
			(end -0.120396 0.3048)
			(stroke
				(width 0.1)
				(type default)
			)
			(layer "B.Fab")
		)
		(fp_line
			(start -0.67945 -0.3048)
			(end -0.67945 0.3048)
			(stroke
				(width 0.1)
				(type default)
			)
			(layer "B.Fab")
		)
		(pad "1" smd circle
			(at 0.40005 0)
			(size 0 0)
			(layers "B.Cu" "B.Mask" "B.Paste")
			(net "P3V3_AUX")
		)
		(pad "2" smd circle
			(at -0.40005 0)
			(size 0 0)
			(layers "B.Cu" "B.Mask" "B.Paste")
			(net "SMB_BMC_MM14_SCL")
		)
	)
	(footprint ""
		(layer "B.Cu")
		(at 49.7967 -104.2035 180)
		(property "Reference" "R866"
			(at 0 0 0)
			(layer "B.SilkS")
			(hide yes)
			(effects
				(font
					(size 1.27 1.27)
				)
				(justify mirror)
			)
		)
		(property "Value" ""
			(at 0 0 0)
			(layer "B.Fab")
			(effects
				(font
					(size 1.27 1.27)
				)
				(justify mirror)
			)
		)
		(duplicate_pad_numbers_are_jumpers no)
		(fp_line
			(start 0.7874 0.4064)
			(end 0.7874 -0.4064)
			(stroke
				(width 0.1524)
				(type default)
			)
			(layer "B.SilkS")
		)
		(fp_line
			(start 0.7874 -0.4064)
			(end -0.7874 -0.4064)
			(stroke
				(width 0.1524)
				(type default)
			)
			(layer "B.SilkS")
		)
		(fp_line
			(start -0.7874 0.4064)
			(end 0.7874 0.4064)
			(stroke
				(width 0.1524)
				(type default)
			)
			(layer "B.SilkS")
		)
		(fp_line
			(start -0.7874 -0.4064)
			(end -0.7874 0.4064)
			(stroke
				(width 0.1524)
				(type default)
			)
			(layer "B.SilkS")
		)
		(fp_line
			(start 0.67945 0.3048)
			(end 0.67945 -0.305054)
			(stroke
				(width 0.1)
				(type default)
			)
			(layer "B.Fab")
		)
		(fp_line
			(start 0.67945 -0.305054)
			(end 0.12065 -0.305054)
			(stroke
				(width 0.1)
				(type default)
			)
			(layer "B.Fab")
		)
		(fp_line
			(start 0.12065 0.3048)
			(end 0.67945 0.3048)
			(stroke
				(width 0.1)
				(type default)
			)
			(layer "B.Fab")
		)
		(fp_line
			(start 0.12065 0.2794)
			(end 0.12065 0.3048)
			(stroke
				(width 0.1)
				(type default)
			)
			(layer "B.Fab")
		)
		(fp_line
			(start 0.12065 -0.2794)
			(end -0.12065 -0.2794)
			(stroke
				(width 0.1)
				(type default)
			)
			(layer "B.Fab")
		)
		(fp_line
			(start 0.12065 -0.305054)
			(end 0.12065 -0.2794)
			(stroke
				(width 0.1)
				(type default)
			)
			(layer "B.Fab")
		)
		(fp_line
			(start -0.120396 0.3048)
			(end -0.120396 0.2794)
			(stroke
				(width 0.1)
				(type default)
			)
			(layer "B.Fab")
		)
		(fp_line
			(start -0.120396 0.2794)
			(end 0.12065 0.2794)
			(stroke
				(width 0.1)
				(type default)
			)
			(layer "B.Fab")
		)
		(fp_line
			(start -0.12065 -0.2794)
			(end -0.12065 -0.3048)
			(stroke
				(width 0.1)
				(type default)
			)
			(layer "B.Fab")
		)
		(fp_line
			(start -0.12065 -0.3048)
			(end -0.67945 -0.3048)
			(stroke
				(width 0.1)
				(type default)
			)
			(layer "B.Fab")
		)
		(fp_line
			(start -0.67945 0.3048)
			(end -0.120396 0.3048)
			(stroke
				(width 0.1)
				(type default)
			)
			(layer "B.Fab")
		)
		(fp_line
			(start -0.67945 -0.3048)
			(end -0.67945 0.3048)
			(stroke
				(width 0.1)
				(type default)
			)
			(layer "B.Fab")
		)
		(pad "1" smd circle
			(at 0.40005 0)
			(size 0 0)
			(layers "B.Cu" "B.Mask" "B.Paste")
			(net "FM_BMC_BIOS_MUX_CS_SPI_R_SEL_0")
		)
		(pad "2" smd circle
			(at -0.40005 0)
			(size 0 0)
			(layers "B.Cu" "B.Mask" "B.Paste")
			(net "GND")
		)
	)
	(footprint ""
		(layer "B.Cu")
		(at 83.16722 -46.586394)
		(property "Reference" "R1"
			(at 0 0 0)
			(layer "B.SilkS")
			(hide yes)
			(effects
				(font
					(size 1.27 1.27)
				)
				(justify mirror)
			)
		)
		(property "Value" ""
			(at 0 0 0)
			(layer "B.Fab")
			(effects
				(font
					(size 1.27 1.27)
				)
				(justify mirror)
			)
		)
		(duplicate_pad_numbers_are_jumpers no)
		(fp_line
			(start -0.7874 -0.4064)
			(end -0.7874 0.4064)
			(stroke
				(width 0.1524)
				(type default)
			)
			(layer "B.SilkS")
		)
		(fp_line
			(start -0.7874 0.4064)
			(end 0.7874 0.4064)
			(stroke
				(width 0.1524)
				(type default)
			)
			(layer "B.SilkS")
		)
		(fp_line
			(start 0.7874 -0.4064)
			(end -0.7874 -0.4064)
			(stroke
				(width 0.1524)
				(type default)
			)
			(layer "B.SilkS")
		)
		(fp_line
			(start 0.7874 0.4064)
			(end 0.7874 -0.4064)
			(stroke
				(width 0.1524)
				(type default)
			)
			(layer "B.SilkS")
		)
		(fp_line
			(start -0.67945 -0.3048)
			(end -0.67945 0.3048)
			(stroke
				(width 0.1)
				(type default)
			)
			(layer "B.Fab")
		)
		(fp_line
			(start -0.67945 0.3048)
			(end -0.120396 0.3048)
			(stroke
				(width 0.1)
				(type default)
			)
			(layer "B.Fab")
		)
		(fp_line
			(start -0.12065 -0.3048)
			(end -0.67945 -0.3048)
			(stroke
				(width 0.1)
				(type default)
			)
			(layer "B.Fab")
		)
		(fp_line
			(start -0.12065 -0.2794)
			(end -0.12065 -0.3048)
			(stroke
				(width 0.1)
				(type default)
			)
			(layer "B.Fab")
		)
		(fp_line
			(start -0.120396 0.2794)
			(end 0.12065 0.2794)
			(stroke
				(width 0.1)
				(type default)
			)
			(layer "B.Fab")
		)
		(fp_line
			(start -0.120396 0.3048)
			(end -0.120396 0.2794)
			(stroke
				(width 0.1)
				(type default)
			)
			(layer "B.Fab")
		)
		(fp_line
			(start 0.12065 -0.305054)
			(end 0.12065 -0.2794)
			(stroke
				(width 0.1)
				(type default)
			)
			(layer "B.Fab")
		)
		(fp_line
			(start 0.12065 -0.2794)
			(end -0.12065 -0.2794)
			(stroke
				(width 0.1)
				(type default)
			)
			(layer "B.Fab")
		)
		(fp_line
			(start 0.12065 0.2794)
			(end 0.12065 0.3048)
			(stroke
				(width 0.1)
				(type default)
			)
			(layer "B.Fab")
		)
		(fp_line
			(start 0.12065 0.3048)
			(end 0.67945 0.3048)
			(stroke
				(width 0.1)
				(type default)
			)
			(layer "B.Fab")
		)
		(fp_line
			(start 0.67945 -0.305054)
			(end 0.12065 -0.305054)
			(stroke
				(width 0.1)
				(type default)
			)
			(layer "B.Fab")
		)
		(fp_line
			(start 0.67945 0.3048)
			(end 0.67945 -0.305054)
			(stroke
				(width 0.1)
				(type default)
			)
			(layer "B.Fab")
		)
		(pad "1" smd circle
			(at 0.40005 0 180)
			(size 0 0)
			(layers "B.Cu" "B.Mask" "B.Paste")
			(net "M_BMC_DDR4_BG1")
		)
		(pad "2" smd circle
			(at -0.40005 0 180)
			(size 0 0)
			(layers "B.Cu" "B.Mask" "B.Paste")
			(net "M_BMC_DDR4_MBG1")
		)
	)
	(footprint ""
		(layer "B.Cu")
		(at 68.299838 -40.87622 90)
		(property "Reference" "C63"
			(at 0 0 90)
			(layer "B.SilkS")
			(hide yes)
			(effects
				(font
					(size 1.27 1.27)
				)
				(justify mirror)
			)
		)
		(property "Value" ""
			(at 0 0 90)
			(layer "B.Fab")
			(effects
				(font
					(size 1.27 1.27)
				)
				(justify mirror)
			)
		)
		(duplicate_pad_numbers_are_jumpers no)
		(fp_line
			(start 0.7874 -0.4064)
			(end -0.7874 -0.4064)
			(stroke
				(width 0.1524)
				(type default)
			)
			(layer "B.SilkS")
		)
		(fp_line
			(start -0.7874 -0.4064)
			(end -0.7874 0.4064)
			(stroke
				(width 0.1524)
				(type default)
			)
			(layer "B.SilkS")
		)
		(fp_line
			(start 0.7874 0.4064)
			(end 0.7874 -0.4064)
			(stroke
				(width 0.1524)
				(type default)
			)
			(layer "B.SilkS")
		)
		(fp_line
			(start -0.7874 0.4064)
			(end 0.7874 0.4064)
			(stroke
				(width 0.1524)
				(type default)
			)
			(layer "B.SilkS")
		)
		(fp_line
			(start 0.67945 -0.305054)
			(end 0.12065 -0.305054)
			(stroke
				(width 0.1)
				(type default)
			)
			(layer "B.Fab")
		)
		(fp_line
			(start 0.12065 -0.305054)
			(end 0.12065 -0.2794)
			(stroke
				(width 0.1)
				(type default)
			)
			(layer "B.Fab")
		)
		(fp_line
			(start -0.12065 -0.3048)
			(end -0.67945 -0.3048)
			(stroke
				(width 0.1)
				(type default)
			)
			(layer "B.Fab")
		)
		(fp_line
			(start -0.67945 -0.3048)
			(end -0.67945 0.3048)
			(stroke
				(width 0.1)
				(type default)
			)
			(layer "B.Fab")
		)
		(fp_line
			(start 0.12065 -0.2794)
			(end -0.12065 -0.2794)
			(stroke
				(width 0.1)
				(type default)
			)
			(layer "B.Fab")
		)
		(fp_line
			(start -0.12065 -0.2794)
			(end -0.12065 -0.3048)
			(stroke
				(width 0.1)
				(type default)
			)
			(layer "B.Fab")
		)
		(fp_line
			(start 0.12065 0.2794)
			(end 0.12065 0.3048)
			(stroke
				(width 0.1)
				(type default)
			)
			(layer "B.Fab")
		)
		(fp_line
			(start -0.120396 0.2794)
			(end 0.12065 0.2794)
			(stroke
				(width 0.1)
				(type default)
			)
			(layer "B.Fab")
		)
		(fp_line
			(start 0.67945 0.3048)
			(end 0.67945 -0.305054)
			(stroke
				(width 0.1)
				(type default)
			)
			(layer "B.Fab")
		)
		(fp_line
			(start 0.12065 0.3048)
			(end 0.67945 0.3048)
			(stroke
				(width 0.1)
				(type default)
			)
			(layer "B.Fab")
		)
		(fp_line
			(start -0.120396 0.3048)
			(end -0.120396 0.2794)
			(stroke
				(width 0.1)
				(type default)
			)
			(layer "B.Fab")
		)
		(fp_line
			(start -0.67945 0.3048)
			(end -0.120396 0.3048)
			(stroke
				(width 0.1)
				(type default)
			)
			(layer "B.Fab")
		)
		(pad "1" smd circle
			(at 0.40005 0 270)
			(size 0 0)
			(layers "B.Cu" "B.Mask" "B.Paste")
			(net "P1V2_STBY_MVDD_CK")
		)
		(pad "2" smd circle
			(at -0.40005 0 270)
			(size 0 0)
			(layers "B.Cu" "B.Mask" "B.Paste")
			(net "GND")
		)
	)
	(footprint ""
		(layer "B.Cu")
		(at 19.431 -83.693 -90)
		(property "Reference" "R571"
			(at 0 0 90)
			(layer "B.SilkS")
			(hide yes)
			(effects
				(font
					(size 1.27 1.27)
				)
				(justify mirror)
			)
		)
		(property "Value" ""
			(at 0 0 90)
			(layer "B.Fab")
			(effects
				(font
					(size 1.27 1.27)
				)
				(justify mirror)
			)
		)
		(duplicate_pad_numbers_are_jumpers no)
		(fp_line
			(start -0.7874 0.4064)
			(end 0.7874 0.4064)
			(stroke
				(width 0.1524)
				(type default)
			)
			(layer "B.SilkS")
		)
		(fp_line
			(start 0.7874 0.4064)
			(end 0.7874 -0.4064)
			(stroke
				(width 0.1524)
				(type default)
			)
			(layer "B.SilkS")
		)
		(fp_line
			(start -0.7874 -0.4064)
			(end -0.7874 0.4064)
			(stroke
				(width 0.1524)
				(type default)
			)
			(layer "B.SilkS")
		)
		(fp_line
			(start 0.7874 -0.4064)
			(end -0.7874 -0.4064)
			(stroke
				(width 0.1524)
				(type default)
			)
			(layer "B.SilkS")
		)
		(fp_line
			(start -0.67945 0.3048)
			(end -0.120396 0.3048)
			(stroke
				(width 0.1)
				(type default)
			)
			(layer "B.Fab")
		)
		(fp_line
			(start -0.120396 0.3048)
			(end -0.120396 0.2794)
			(stroke
				(width 0.1)
				(type default)
			)
			(layer "B.Fab")
		)
		(fp_line
			(start 0.12065 0.3048)
			(end 0.67945 0.3048)
			(stroke
				(width 0.1)
				(type default)
			)
			(layer "B.Fab")
		)
		(fp_line
			(start 0.67945 0.3048)
			(end 0.67945 -0.305054)
			(stroke
				(width 0.1)
				(type default)
			)
			(layer "B.Fab")
		)
		(fp_line
			(start -0.120396 0.2794)
			(end 0.12065 0.2794)
			(stroke
				(width 0.1)
				(type default)
			)
			(layer "B.Fab")
		)
		(fp_line
			(start 0.12065 0.2794)
			(end 0.12065 0.3048)
			(stroke
				(width 0.1)
				(type default)
			)
			(layer "B.Fab")
		)
		(fp_line
			(start -0.12065 -0.2794)
			(end -0.12065 -0.3048)
			(stroke
				(width 0.1)
				(type default)
			)
			(layer "B.Fab")
		)
		(fp_line
			(start 0.12065 -0.2794)
			(end -0.12065 -0.2794)
			(stroke
				(width 0.1)
				(type default)
			)
			(layer "B.Fab")
		)
		(fp_line
			(start -0.67945 -0.3048)
			(end -0.67945 0.3048)
			(stroke
				(width 0.1)
				(type default)
			)
			(layer "B.Fab")
		)
		(fp_line
			(start -0.12065 -0.3048)
			(end -0.67945 -0.3048)
			(stroke
				(width 0.1)
				(type default)
			)
			(layer "B.Fab")
		)
		(fp_line
			(start 0.12065 -0.305054)
			(end 0.12065 -0.2794)
			(stroke
				(width 0.1)
				(type default)
			)
			(layer "B.Fab")
		)
		(fp_line
			(start 0.67945 -0.305054)
			(end 0.12065 -0.305054)
			(stroke
				(width 0.1)
				(type default)
			)
			(layer "B.Fab")
		)
		(pad "1" smd circle
			(at 0.40005 0 90)
			(size 0 0)
			(layers "B.Cu" "B.Mask" "B.Paste")
			(net "IRQ_BMC_PCH_NMI_N")
		)
		(pad "2" smd circle
			(at -0.40005 0 90)
			(size 0 0)
			(layers "B.Cu" "B.Mask" "B.Paste")
			(net "IRQ_BMC_PCH_NMI_R_N")
		)
	)
	(footprint ""
		(layer "B.Cu")
		(at 12.319 -106.426 90)
		(property "Reference" "R134"
			(at 0 0 90)
			(layer "B.SilkS")
			(hide yes)
			(effects
				(font
					(size 1.27 1.27)
				)
				(justify mirror)
			)
		)
		(property "Value" ""
			(at 0 0 90)
			(layer "B.Fab")
			(effects
				(font
					(size 1.27 1.27)
				)
				(justify mirror)
			)
		)
		(duplicate_pad_numbers_are_jumpers no)
		(fp_line
			(start 0.7874 -0.4064)
			(end -0.7874 -0.4064)
			(stroke
				(width 0.1524)
				(type default)
			)
			(layer "B.SilkS")
		)
		(fp_line
			(start -0.7874 -0.4064)
			(end -0.7874 0.4064)
			(stroke
				(width 0.1524)
				(type default)
			)
			(layer "B.SilkS")
		)
		(fp_line
			(start 0.7874 0.4064)
			(end 0.7874 -0.4064)
			(stroke
				(width 0.1524)
				(type default)
			)
			(layer "B.SilkS")
		)
		(fp_line
			(start -0.7874 0.4064)
			(end 0.7874 0.4064)
			(stroke
				(width 0.1524)
				(type default)
			)
			(layer "B.SilkS")
		)
		(fp_line
			(start 0.67945 -0.305054)
			(end 0.12065 -0.305054)
			(stroke
				(width 0.1)
				(type default)
			)
			(layer "B.Fab")
		)
		(fp_line
			(start 0.12065 -0.305054)
			(end 0.12065 -0.2794)
			(stroke
				(width 0.1)
				(type default)
			)
			(layer "B.Fab")
		)
		(fp_line
			(start -0.12065 -0.3048)
			(end -0.67945 -0.3048)
			(stroke
				(width 0.1)
				(type default)
			)
			(layer "B.Fab")
		)
		(fp_line
			(start -0.67945 -0.3048)
			(end -0.67945 0.3048)
			(stroke
				(width 0.1)
				(type default)
			)
			(layer "B.Fab")
		)
		(fp_line
			(start 0.12065 -0.2794)
			(end -0.12065 -0.2794)
			(stroke
				(width 0.1)
				(type default)
			)
			(layer "B.Fab")
		)
		(fp_line
			(start -0.12065 -0.2794)
			(end -0.12065 -0.3048)
			(stroke
				(width 0.1)
				(type default)
			)
			(layer "B.Fab")
		)
		(fp_line
			(start 0.12065 0.2794)
			(end 0.12065 0.3048)
			(stroke
				(width 0.1)
				(type default)
			)
			(layer "B.Fab")
		)
		(fp_line
			(start -0.120396 0.2794)
			(end 0.12065 0.2794)
			(stroke
				(width 0.1)
				(type default)
			)
			(layer "B.Fab")
		)
		(fp_line
			(start 0.67945 0.3048)
			(end 0.67945 -0.305054)
			(stroke
				(width 0.1)
				(type default)
			)
			(layer "B.Fab")
		)
		(fp_line
			(start 0.12065 0.3048)
			(end 0.67945 0.3048)
			(stroke
				(width 0.1)
				(type default)
			)
			(layer "B.Fab")
		)
		(fp_line
			(start -0.120396 0.3048)
			(end -0.120396 0.2794)
			(stroke
				(width 0.1)
				(type default)
			)
			(layer "B.Fab")
		)
		(fp_line
			(start -0.67945 0.3048)
			(end -0.120396 0.3048)
			(stroke
				(width 0.1)
				(type default)
			)
			(layer "B.Fab")
		)
		(pad "1" smd circle
			(at 0.40005 0 270)
			(size 0 0)
			(layers "B.Cu" "B.Mask" "B.Paste")
			(net "FM_BMC_UARTSW_LSB_N")
		)
		(pad "2" smd circle
			(at -0.40005 0 270)
			(size 0 0)
			(layers "B.Cu" "B.Mask" "B.Paste")
			(net "FM_UARTSW_LSB_N")
		)
	)
	(footprint ""
		(layer "B.Cu")
		(at 12.319 -93.472 180)
		(property "Reference" "R825"
			(at 0 0 0)
			(layer "B.SilkS")
			(hide yes)
			(effects
				(font
					(size 1.27 1.27)
				)
				(justify mirror)
			)
		)
		(property "Value" ""
			(at 0 0 0)
			(layer "B.Fab")
			(effects
				(font
					(size 1.27 1.27)
				)
				(justify mirror)
			)
		)
		(duplicate_pad_numbers_are_jumpers no)
		(fp_line
			(start 0.7874 0.4064)
			(end 0.7874 -0.4064)
			(stroke
				(width 0.1524)
				(type default)
			)
			(layer "B.SilkS")
		)
		(fp_line
			(start 0.7874 -0.4064)
			(end -0.7874 -0.4064)
			(stroke
				(width 0.1524)
				(type default)
			)
			(layer "B.SilkS")
		)
		(fp_line
			(start -0.7874 0.4064)
			(end 0.7874 0.4064)
			(stroke
				(width 0.1524)
				(type default)
			)
			(layer "B.SilkS")
		)
		(fp_line
			(start -0.7874 -0.4064)
			(end -0.7874 0.4064)
			(stroke
				(width 0.1524)
				(type default)
			)
			(layer "B.SilkS")
		)
		(fp_line
			(start 0.67945 0.3048)
			(end 0.67945 -0.305054)
			(stroke
				(width 0.1)
				(type default)
			)
			(layer "B.Fab")
		)
		(fp_line
			(start 0.67945 -0.305054)
			(end 0.12065 -0.305054)
			(stroke
				(width 0.1)
				(type default)
			)
			(layer "B.Fab")
		)
		(fp_line
			(start 0.12065 0.3048)
			(end 0.67945 0.3048)
			(stroke
				(width 0.1)
				(type default)
			)
			(layer "B.Fab")
		)
		(fp_line
			(start 0.12065 0.2794)
			(end 0.12065 0.3048)
			(stroke
				(width 0.1)
				(type default)
			)
			(layer "B.Fab")
		)
		(fp_line
			(start 0.12065 -0.2794)
			(end -0.12065 -0.2794)
			(stroke
				(width 0.1)
				(type default)
			)
			(layer "B.Fab")
		)
		(fp_line
			(start 0.12065 -0.305054)
			(end 0.12065 -0.2794)
			(stroke
				(width 0.1)
				(type default)
			)
			(layer "B.Fab")
		)
		(fp_line
			(start -0.120396 0.3048)
			(end -0.120396 0.2794)
			(stroke
				(width 0.1)
				(type default)
			)
			(layer "B.Fab")
		)
		(fp_line
			(start -0.120396 0.2794)
			(end 0.12065 0.2794)
			(stroke
				(width 0.1)
				(type default)
			)
			(layer "B.Fab")
		)
		(fp_line
			(start -0.12065 -0.2794)
			(end -0.12065 -0.3048)
			(stroke
				(width 0.1)
				(type default)
			)
			(layer "B.Fab")
		)
		(fp_line
			(start -0.12065 -0.3048)
			(end -0.67945 -0.3048)
			(stroke
				(width 0.1)
				(type default)
			)
			(layer "B.Fab")
		)
		(fp_line
			(start -0.67945 0.3048)
			(end -0.120396 0.3048)
			(stroke
				(width 0.1)
				(type default)
			)
			(layer "B.Fab")
		)
		(fp_line
			(start -0.67945 -0.3048)
			(end -0.67945 0.3048)
			(stroke
				(width 0.1)
				(type default)
			)
			(layer "B.Fab")
		)
		(pad "1" smd circle
			(at 0.40005 0)
			(size 0 0)
			(layers "B.Cu" "B.Mask" "B.Paste")
			(net "RST_ROT_CPU_N")
		)
		(pad "2" smd circle
			(at -0.40005 0)
			(size 0 0)
			(layers "B.Cu" "B.Mask" "B.Paste")
			(net "RST_ROT_CPU_R_N")
		)
	)
	(footprint ""
		(layer "B.Cu")
		(at 76.691744 -35.540188 -90)
		(property "Reference" "R337"
			(at 0 0 90)
			(layer "B.SilkS")
			(hide yes)
			(effects
				(font
					(size 1.27 1.27)
				)
				(justify mirror)
			)
		)
		(property "Value" ""
			(at 0 0 90)
			(layer "B.Fab")
			(effects
				(font
					(size 1.27 1.27)
				)
				(justify mirror)
			)
		)
		(duplicate_pad_numbers_are_jumpers no)
		(fp_line
			(start -0.7874 0.4064)
			(end 0.7874 0.4064)
			(stroke
				(width 0.1524)
				(type default)
			)
			(layer "B.SilkS")
		)
		(fp_line
			(start 0.7874 0.4064)
			(end 0.7874 -0.4064)
			(stroke
				(width 0.1524)
				(type default)
			)
			(layer "B.SilkS")
		)
		(fp_line
			(start -0.7874 -0.4064)
			(end -0.7874 0.4064)
			(stroke
				(width 0.1524)
				(type default)
			)
			(layer "B.SilkS")
		)
		(fp_line
			(start 0.7874 -0.4064)
			(end -0.7874 -0.4064)
			(stroke
				(width 0.1524)
				(type default)
			)
			(layer "B.SilkS")
		)
		(fp_line
			(start -0.67945 0.3048)
			(end -0.120396 0.3048)
			(stroke
				(width 0.1)
				(type default)
			)
			(layer "B.Fab")
		)
		(fp_line
			(start -0.120396 0.3048)
			(end -0.120396 0.2794)
			(stroke
				(width 0.1)
				(type default)
			)
			(layer "B.Fab")
		)
		(fp_line
			(start 0.12065 0.3048)
			(end 0.67945 0.3048)
			(stroke
				(width 0.1)
				(type default)
			)
			(layer "B.Fab")
		)
		(fp_line
			(start 0.67945 0.3048)
			(end 0.67945 -0.305054)
			(stroke
				(width 0.1)
				(type default)
			)
			(layer "B.Fab")
		)
		(fp_line
			(start -0.120396 0.2794)
			(end 0.12065 0.2794)
			(stroke
				(width 0.1)
				(type default)
			)
			(layer "B.Fab")
		)
		(fp_line
			(start 0.12065 0.2794)
			(end 0.12065 0.3048)
			(stroke
				(width 0.1)
				(type default)
			)
			(layer "B.Fab")
		)
		(fp_line
			(start -0.12065 -0.2794)
			(end -0.12065 -0.3048)
			(stroke
				(width 0.1)
				(type default)
			)
			(layer "B.Fab")
		)
		(fp_line
			(start 0.12065 -0.2794)
			(end -0.12065 -0.2794)
			(stroke
				(width 0.1)
				(type default)
			)
			(layer "B.Fab")
		)
		(fp_line
			(start -0.67945 -0.3048)
			(end -0.67945 0.3048)
			(stroke
				(width 0.1)
				(type default)
			)
			(layer "B.Fab")
		)
		(fp_line
			(start -0.12065 -0.3048)
			(end -0.67945 -0.3048)
			(stroke
				(width 0.1)
				(type default)
			)
			(layer "B.Fab")
		)
		(fp_line
			(start 0.12065 -0.305054)
			(end 0.12065 -0.2794)
			(stroke
				(width 0.1)
				(type default)
			)
			(layer "B.Fab")
		)
		(fp_line
			(start 0.67945 -0.305054)
			(end 0.12065 -0.305054)
			(stroke
				(width 0.1)
				(type default)
			)
			(layer "B.Fab")
		)
		(pad "1" smd circle
			(at 0.40005 0 90)
			(size 0 0)
			(layers "B.Cu" "B.Mask" "B.Paste")
			(net "GND")
		)
		(pad "2" smd circle
			(at -0.40005 0 90)
			(size 0 0)
			(layers "B.Cu" "B.Mask" "B.Paste")
			(net "M_BMC_DDR4_MA<11>")
		)
	)
	(footprint ""
		(layer "B.Cu")
		(at 77.707744 -37.559488 90)
		(property "Reference" "R357"
			(at 0 0 90)
			(layer "B.SilkS")
			(hide yes)
			(effects
				(font
					(size 1.27 1.27)
				)
				(justify mirror)
			)
		)
		(property "Value" ""
			(at 0 0 90)
			(layer "B.Fab")
			(effects
				(font
					(size 1.27 1.27)
				)
				(justify mirror)
			)
		)
		(duplicate_pad_numbers_are_jumpers no)
		(fp_line
			(start 0.7874 -0.4064)
			(end -0.7874 -0.4064)
			(stroke
				(width 0.1524)
				(type default)
			)
			(layer "B.SilkS")
		)
		(fp_line
			(start -0.7874 -0.4064)
			(end -0.7874 0.4064)
			(stroke
				(width 0.1524)
				(type default)
			)
			(layer "B.SilkS")
		)
		(fp_line
			(start 0.7874 0.4064)
			(end 0.7874 -0.4064)
			(stroke
				(width 0.1524)
				(type default)
			)
			(layer "B.SilkS")
		)
		(fp_line
			(start -0.7874 0.4064)
			(end 0.7874 0.4064)
			(stroke
				(width 0.1524)
				(type default)
			)
			(layer "B.SilkS")
		)
		(fp_line
			(start 0.67945 -0.305054)
			(end 0.12065 -0.305054)
			(stroke
				(width 0.1)
				(type default)
			)
			(layer "B.Fab")
		)
		(fp_line
			(start 0.12065 -0.305054)
			(end 0.12065 -0.2794)
			(stroke
				(width 0.1)
				(type default)
			)
			(layer "B.Fab")
		)
		(fp_line
			(start -0.12065 -0.3048)
			(end -0.67945 -0.3048)
			(stroke
				(width 0.1)
				(type default)
			)
			(layer "B.Fab")
		)
		(fp_line
			(start -0.67945 -0.3048)
			(end -0.67945 0.3048)
			(stroke
				(width 0.1)
				(type default)
			)
			(layer "B.Fab")
		)
		(fp_line
			(start 0.12065 -0.2794)
			(end -0.12065 -0.2794)
			(stroke
				(width 0.1)
				(type default)
			)
			(layer "B.Fab")
		)
		(fp_line
			(start -0.12065 -0.2794)
			(end -0.12065 -0.3048)
			(stroke
				(width 0.1)
				(type default)
			)
			(layer "B.Fab")
		)
		(fp_line
			(start 0.12065 0.2794)
			(end 0.12065 0.3048)
			(stroke
				(width 0.1)
				(type default)
			)
			(layer "B.Fab")
		)
		(fp_line
			(start -0.120396 0.2794)
			(end 0.12065 0.2794)
			(stroke
				(width 0.1)
				(type default)
			)
			(layer "B.Fab")
		)
		(fp_line
			(start 0.67945 0.3048)
			(end 0.67945 -0.305054)
			(stroke
				(width 0.1)
				(type default)
			)
			(layer "B.Fab")
		)
		(fp_line
			(start 0.12065 0.3048)
			(end 0.67945 0.3048)
			(stroke
				(width 0.1)
				(type default)
			)
			(layer "B.Fab")
		)
		(fp_line
			(start -0.120396 0.3048)
			(end -0.120396 0.2794)
			(stroke
				(width 0.1)
				(type default)
			)
			(layer "B.Fab")
		)
		(fp_line
			(start -0.67945 0.3048)
			(end -0.120396 0.3048)
			(stroke
				(width 0.1)
				(type default)
			)
			(layer "B.Fab")
		)
		(pad "1" smd circle
			(at 0.40005 0 270)
			(size 0 0)
			(layers "B.Cu" "B.Mask" "B.Paste")
			(net "M_BMC_DDR4_MA<6>")
		)
		(pad "2" smd circle
			(at -0.40005 0 270)
			(size 0 0)
			(layers "B.Cu" "B.Mask" "B.Paste")
			(net "P1V2_AUX")
		)
	)
	(footprint ""
		(layer "B.Cu")
		(at 103.8225 -104.76484 90)
		(property "Reference" "J17"
			(at -0.87884 2.95783 270)
			(unlocked yes)
			(layer "B.SilkS")
			(effects
				(font
					(size 0.7874 0.5842)
					(thickness 0.1524)
				)
				(justify left mirror)
			)
		)
		(property "Value" ""
			(at 0 0 90)
			(layer "B.Fab")
			(effects
				(font
					(size 1.27 1.27)
				)
				(justify mirror)
			)
		)
		(duplicate_pad_numbers_are_jumpers no)
		(fp_line
			(start 1.2192 -2.1082)
			(end -1.2192 -2.1082)
			(stroke
				(width 0.1524)
				(type default)
			)
			(layer "B.SilkS")
		)
		(fp_line
			(start -1.2192 -2.1082)
			(end -1.2192 -0.456184)
			(stroke
				(width 0.1524)
				(type default)
			)
			(layer "B.SilkS")
		)
		(fp_line
			(start -1.2192 0.451104)
			(end -1.2192 2.1082)
			(stroke
				(width 0.1524)
				(type default)
			)
			(layer "B.SilkS")
		)
		(fp_line
			(start 1.2192 2.1082)
			(end 1.2192 -2.1082)
			(stroke
				(width 0.1524)
				(type default)
			)
			(layer "B.SilkS")
		)
		(fp_line
			(start -1.2192 2.1082)
			(end 1.2192 2.1082)
			(stroke
				(width 0.1524)
				(type default)
			)
			(layer "B.SilkS")
		)
		(pad "" np_thru_hole circle
			(at -3.4671 -1.27)
			(size 1.0414 1.0414)
			(drill 1.0414)
			(layers "*.Cu" "*.Mask")
			(clearance 0.381)
			(thermal_gap 0.381)
		)
		(pad "" np_thru_hole circle
			(at -3.4671 1.27)
			(size 1.0414 1.0414)
			(drill 1.0414)
			(layers "*.Cu" "*.Mask")
			(clearance 0.381)
			(thermal_gap 0.381)
		)
		(pad "" np_thru_hole circle
			(at 2.8829 -1.27)
			(size 1.0414 1.0414)
			(drill 1.0414)
			(layers "*.Cu" "*.Mask")
			(clearance 0.381)
			(thermal_gap 0.381)
		)
		(pad "" np_thru_hole circle
			(at 2.8829 1.27)
			(size 1.0414 1.0414)
			(drill 1.0414)
			(layers "*.Cu" "*.Mask")
			(clearance 0.381)
			(thermal_gap 0.381)
		)
		(pad "1" smd rect
			(at -0.8255 -0.249936)
			(size 0.3048 0.508)
			(layers "B.Cu" "B.Mask" "B.Paste")
			(net "85_5INCH_BOT_DN")
		)
		(pad "2" smd rect
			(at -0.8255 0.249936)
			(size 0.3048 0.508)
			(layers "B.Cu" "B.Mask" "B.Paste")
			(net "85_5INCH_BOT_DP")
		)
		(pad "3" smd circle
			(at 0 0 270)
			(size 0 0)
			(layers "B.Cu" "B.Mask" "B.Paste")
			(net "GND_P1")
		)
		(zone
			(layers "F.Cu" "B.Cu" "In1.Cu" "In2.Cu" "In3.Cu" "In4.Cu" "In5.Cu" "In6.Cu"
				"In7.Cu" "In8.Cu" "In9.Cu" "In10.Cu"
			)
			(hatch none 0.5)
			(connect_pads
				(clearance 0)
			)
			(min_thickness 0.25)
			(keepout
				(tracks not_allowed)
				(vias allowed)
				(pads allowed)
				(copperpour not_allowed)
				(footprints allowed)
			)
			(placement
				(enabled no)
				(sheetname "")
			)
			(fill
				(thermal_gap 0.5)
				(thermal_bridge_width 0.5)
				(island_removal_mode 0)
			)
			(polygon
				(pts
					(arc
						(start 103.4796 -107.64774)
						(mid 101.6254 -107.64774)
						(end 103.4796 -107.64774)
					)
				)
			)
		)
		(zone
			(layers "F.Cu" "B.Cu" "In1.Cu" "In2.Cu" "In3.Cu" "In4.Cu" "In5.Cu" "In6.Cu"
				"In7.Cu" "In8.Cu" "In9.Cu" "In10.Cu"
			)
			(hatch none 0.5)
			(connect_pads
				(clearance 0)
			)
			(min_thickness 0.25)
			(keepout
				(tracks not_allowed)
				(vias allowed)
				(pads allowed)
				(copperpour not_allowed)
				(footprints allowed)
			)
			(placement
				(enabled no)
				(sheetname "")
			)
			(fill
				(thermal_gap 0.5)
				(thermal_bridge_width 0.5)
				(island_removal_mode 0)
			)
			(polygon
				(pts
					(arc
						(start 103.4796 -101.29774)
						(mid 101.6254 -101.29774)
						(end 103.4796 -101.29774)
					)
				)
			)
		)
		(zone
			(layers "F.Cu" "B.Cu" "In1.Cu" "In2.Cu" "In3.Cu" "In4.Cu" "In5.Cu" "In6.Cu"
				"In7.Cu" "In8.Cu" "In9.Cu" "In10.Cu"
			)
			(hatch none 0.5)
			(connect_pads
				(clearance 0)
			)
			(min_thickness 0.25)
			(keepout
				(tracks not_allowed)
				(vias allowed)
				(pads allowed)
				(copperpour not_allowed)
				(footprints allowed)
			)
			(placement
				(enabled no)
				(sheetname "")
			)
			(fill
				(thermal_gap 0.5)
				(thermal_bridge_width 0.5)
				(island_removal_mode 0)
			)
			(polygon
				(pts
					(arc
						(start 106.0196 -107.64774)
						(mid 104.1654 -107.64774)
						(end 106.0196 -107.64774)
					)
				)
			)
		)
		(zone
			(layers "F.Cu" "B.Cu" "In1.Cu" "In2.Cu" "In3.Cu" "In4.Cu" "In5.Cu" "In6.Cu"
				"In7.Cu" "In8.Cu" "In9.Cu" "In10.Cu"
			)
			(hatch none 0.5)
			(connect_pads
				(clearance 0)
			)
			(min_thickness 0.25)
			(keepout
				(tracks not_allowed)
				(vias allowed)
				(pads allowed)
				(copperpour not_allowed)
				(footprints allowed)
			)
			(placement
				(enabled no)
				(sheetname "")
			)
			(fill
				(thermal_gap 0.5)
				(thermal_bridge_width 0.5)
				(island_removal_mode 0)
			)
			(polygon
				(pts
					(arc
						(start 106.0196 -101.29774)
						(mid 104.1654 -101.29774)
						(end 106.0196 -101.29774)
					)
				)
			)
		)
		(zone
			(layer "B.Cu")
			(hatch none 0.5)
			(connect_pads
				(clearance 0)
			)
			(min_thickness 0.25)
			(keepout
				(tracks not_allowed)
				(vias allowed)
				(pads allowed)
				(copperpour not_allowed)
				(footprints allowed)
			)
			(placement
				(enabled no)
				(sheetname "")
			)
			(fill
				(thermal_gap 0.5)
				(thermal_bridge_width 0.5)
				(island_removal_mode 0)
			)
			(polygon
				(pts
					(xy 103.27386 -103.64724) (xy 103.369364 -103.64724) (xy 103.369364 -104.24414) (xy 103.775764 -104.24414)
					(xy 103.775764 -103.64724) (xy 103.869236 -103.64724) (xy 103.869236 -104.24414) (xy 104.275636 -104.24414)
					(xy 104.275636 -103.64724) (xy 104.37114 -103.64724) (xy 104.37114 -104.34574) (xy 103.27386 -104.34574)
				)
			)
		)
	)
	(footprint ""
		(layer "B.Cu")
		(at 51.255422 -45.204126 180)
		(property "Reference" "C39"
			(at 0 0 0)
			(layer "B.SilkS")
			(hide yes)
			(effects
				(font
					(size 1.27 1.27)
				)
				(justify mirror)
			)
		)
		(property "Value" ""
			(at 0 0 0)
			(layer "B.Fab")
			(effects
				(font
					(size 1.27 1.27)
				)
				(justify mirror)
			)
		)
		(duplicate_pad_numbers_are_jumpers no)
		(fp_line
			(start 0.7874 0.4064)
			(end 0.7874 -0.4064)
			(stroke
				(width 0.1524)
				(type default)
			)
			(layer "B.SilkS")
		)
		(fp_line
			(start 0.7874 -0.4064)
			(end -0.7874 -0.4064)
			(stroke
				(width 0.1524)
				(type default)
			)
			(layer "B.SilkS")
		)
		(fp_line
			(start -0.7874 0.4064)
			(end 0.7874 0.4064)
			(stroke
				(width 0.1524)
				(type default)
			)
			(layer "B.SilkS")
		)
		(fp_line
			(start -0.7874 -0.4064)
			(end -0.7874 0.4064)
			(stroke
				(width 0.1524)
				(type default)
			)
			(layer "B.SilkS")
		)
		(fp_line
			(start 0.67945 0.3048)
			(end 0.67945 -0.305054)
			(stroke
				(width 0.1)
				(type default)
			)
			(layer "B.Fab")
		)
		(fp_line
			(start 0.67945 -0.305054)
			(end 0.12065 -0.305054)
			(stroke
				(width 0.1)
				(type default)
			)
			(layer "B.Fab")
		)
		(fp_line
			(start 0.12065 0.3048)
			(end 0.67945 0.3048)
			(stroke
				(width 0.1)
				(type default)
			)
			(layer "B.Fab")
		)
		(fp_line
			(start 0.12065 0.2794)
			(end 0.12065 0.3048)
			(stroke
				(width 0.1)
				(type default)
			)
			(layer "B.Fab")
		)
		(fp_line
			(start 0.12065 -0.2794)
			(end -0.12065 -0.2794)
			(stroke
				(width 0.1)
				(type default)
			)
			(layer "B.Fab")
		)
		(fp_line
			(start 0.12065 -0.305054)
			(end 0.12065 -0.2794)
			(stroke
				(width 0.1)
				(type default)
			)
			(layer "B.Fab")
		)
		(fp_line
			(start -0.120396 0.3048)
			(end -0.120396 0.2794)
			(stroke
				(width 0.1)
				(type default)
			)
			(layer "B.Fab")
		)
		(fp_line
			(start -0.120396 0.2794)
			(end 0.12065 0.2794)
			(stroke
				(width 0.1)
				(type default)
			)
			(layer "B.Fab")
		)
		(fp_line
			(start -0.12065 -0.2794)
			(end -0.12065 -0.3048)
			(stroke
				(width 0.1)
				(type default)
			)
			(layer "B.Fab")
		)
		(fp_line
			(start -0.12065 -0.3048)
			(end -0.67945 -0.3048)
			(stroke
				(width 0.1)
				(type default)
			)
			(layer "B.Fab")
		)
		(fp_line
			(start -0.67945 0.3048)
			(end -0.120396 0.3048)
			(stroke
				(width 0.1)
				(type default)
			)
			(layer "B.Fab")
		)
		(fp_line
			(start -0.67945 -0.3048)
			(end -0.67945 0.3048)
			(stroke
				(width 0.1)
				(type default)
			)
			(layer "B.Fab")
		)
		(pad "1" smd circle
			(at 0.40005 0)
			(size 0 0)
			(layers "B.Cu" "B.Mask" "B.Paste")
			(net "P3V3_P1V8_SD2VDD")
		)
		(pad "2" smd circle
			(at -0.40005 0)
			(size 0 0)
			(layers "B.Cu" "B.Mask" "B.Paste")
			(net "GND")
		)
	)
	(footprint ""
		(layer "B.Cu")
		(at 77.47 -31.115 90)
		(property "Reference" "R676"
			(at 0 0 90)
			(layer "B.SilkS")
			(hide yes)
			(effects
				(font
					(size 1.27 1.27)
				)
				(justify mirror)
			)
		)
		(property "Value" ""
			(at 0 0 90)
			(layer "B.Fab")
			(effects
				(font
					(size 1.27 1.27)
				)
				(justify mirror)
			)
		)
		(duplicate_pad_numbers_are_jumpers no)
		(fp_line
			(start 0.7874 -0.4064)
			(end -0.7874 -0.4064)
			(stroke
				(width 0.1524)
				(type default)
			)
			(layer "B.SilkS")
		)
		(fp_line
			(start -0.7874 -0.4064)
			(end -0.7874 0.4064)
			(stroke
				(width 0.1524)
				(type default)
			)
			(layer "B.SilkS")
		)
		(fp_line
			(start 0.7874 0.4064)
			(end 0.7874 -0.4064)
			(stroke
				(width 0.1524)
				(type default)
			)
			(layer "B.SilkS")
		)
		(fp_line
			(start -0.7874 0.4064)
			(end 0.7874 0.4064)
			(stroke
				(width 0.1524)
				(type default)
			)
			(layer "B.SilkS")
		)
		(fp_line
			(start 0.67945 -0.305054)
			(end 0.12065 -0.305054)
			(stroke
				(width 0.1)
				(type default)
			)
			(layer "B.Fab")
		)
		(fp_line
			(start 0.12065 -0.305054)
			(end 0.12065 -0.2794)
			(stroke
				(width 0.1)
				(type default)
			)
			(layer "B.Fab")
		)
		(fp_line
			(start -0.12065 -0.3048)
			(end -0.67945 -0.3048)
			(stroke
				(width 0.1)
				(type default)
			)
			(layer "B.Fab")
		)
		(fp_line
			(start -0.67945 -0.3048)
			(end -0.67945 0.3048)
			(stroke
				(width 0.1)
				(type default)
			)
			(layer "B.Fab")
		)
		(fp_line
			(start 0.12065 -0.2794)
			(end -0.12065 -0.2794)
			(stroke
				(width 0.1)
				(type default)
			)
			(layer "B.Fab")
		)
		(fp_line
			(start -0.12065 -0.2794)
			(end -0.12065 -0.3048)
			(stroke
				(width 0.1)
				(type default)
			)
			(layer "B.Fab")
		)
		(fp_line
			(start 0.12065 0.2794)
			(end 0.12065 0.3048)
			(stroke
				(width 0.1)
				(type default)
			)
			(layer "B.Fab")
		)
		(fp_line
			(start -0.120396 0.2794)
			(end 0.12065 0.2794)
			(stroke
				(width 0.1)
				(type default)
			)
			(layer "B.Fab")
		)
		(fp_line
			(start 0.67945 0.3048)
			(end 0.67945 -0.305054)
			(stroke
				(width 0.1)
				(type default)
			)
			(layer "B.Fab")
		)
		(fp_line
			(start 0.12065 0.3048)
			(end 0.67945 0.3048)
			(stroke
				(width 0.1)
				(type default)
			)
			(layer "B.Fab")
		)
		(fp_line
			(start -0.120396 0.3048)
			(end -0.120396 0.2794)
			(stroke
				(width 0.1)
				(type default)
			)
			(layer "B.Fab")
		)
		(fp_line
			(start -0.67945 0.3048)
			(end -0.120396 0.3048)
			(stroke
				(width 0.1)
				(type default)
			)
			(layer "B.Fab")
		)
		(pad "1" smd circle
			(at 0.40005 0 270)
			(size 0 0)
			(layers "B.Cu" "B.Mask" "B.Paste")
			(net "LED_POSTCODE_5")
		)
		(pad "2" smd circle
			(at -0.40005 0 270)
			(size 0 0)
			(layers "B.Cu" "B.Mask" "B.Paste")
			(net "LED_POSTCODE_5_R1")
		)
	)
	(footprint ""
		(layer "B.Cu")
		(at 26.533094 -19.955764 180)
		(property "Reference" "R86"
			(at 0 0 0)
			(layer "B.SilkS")
			(hide yes)
			(effects
				(font
					(size 1.27 1.27)
				)
				(justify mirror)
			)
		)
		(property "Value" ""
			(at 0 0 0)
			(layer "B.Fab")
			(effects
				(font
					(size 1.27 1.27)
				)
				(justify mirror)
			)
		)
		(duplicate_pad_numbers_are_jumpers no)
		(fp_line
			(start 0.7874 0.4064)
			(end 0.7874 -0.4064)
			(stroke
				(width 0.1524)
				(type default)
			)
			(layer "B.SilkS")
		)
		(fp_line
			(start 0.7874 -0.4064)
			(end -0.7874 -0.4064)
			(stroke
				(width 0.1524)
				(type default)
			)
			(layer "B.SilkS")
		)
		(fp_line
			(start -0.7874 0.4064)
			(end 0.7874 0.4064)
			(stroke
				(width 0.1524)
				(type default)
			)
			(layer "B.SilkS")
		)
		(fp_line
			(start -0.7874 -0.4064)
			(end -0.7874 0.4064)
			(stroke
				(width 0.1524)
				(type default)
			)
			(layer "B.SilkS")
		)
		(fp_line
			(start 0.67945 0.3048)
			(end 0.67945 -0.305054)
			(stroke
				(width 0.1)
				(type default)
			)
			(layer "B.Fab")
		)
		(fp_line
			(start 0.67945 -0.305054)
			(end 0.12065 -0.305054)
			(stroke
				(width 0.1)
				(type default)
			)
			(layer "B.Fab")
		)
		(fp_line
			(start 0.12065 0.3048)
			(end 0.67945 0.3048)
			(stroke
				(width 0.1)
				(type default)
			)
			(layer "B.Fab")
		)
		(fp_line
			(start 0.12065 0.2794)
			(end 0.12065 0.3048)
			(stroke
				(width 0.1)
				(type default)
			)
			(layer "B.Fab")
		)
		(fp_line
			(start 0.12065 -0.2794)
			(end -0.12065 -0.2794)
			(stroke
				(width 0.1)
				(type default)
			)
			(layer "B.Fab")
		)
		(fp_line
			(start 0.12065 -0.305054)
			(end 0.12065 -0.2794)
			(stroke
				(width 0.1)
				(type default)
			)
			(layer "B.Fab")
		)
		(fp_line
			(start -0.120396 0.3048)
			(end -0.120396 0.2794)
			(stroke
				(width 0.1)
				(type default)
			)
			(layer "B.Fab")
		)
		(fp_line
			(start -0.120396 0.2794)
			(end 0.12065 0.2794)
			(stroke
				(width 0.1)
				(type default)
			)
			(layer "B.Fab")
		)
		(fp_line
			(start -0.12065 -0.2794)
			(end -0.12065 -0.3048)
			(stroke
				(width 0.1)
				(type default)
			)
			(layer "B.Fab")
		)
		(fp_line
			(start -0.12065 -0.3048)
			(end -0.67945 -0.3048)
			(stroke
				(width 0.1)
				(type default)
			)
			(layer "B.Fab")
		)
		(fp_line
			(start -0.67945 0.3048)
			(end -0.120396 0.3048)
			(stroke
				(width 0.1)
				(type default)
			)
			(layer "B.Fab")
		)
		(fp_line
			(start -0.67945 -0.3048)
			(end -0.67945 0.3048)
			(stroke
				(width 0.1)
				(type default)
			)
			(layer "B.Fab")
		)
		(pad "1" smd circle
			(at 0.40005 0)
			(size 0 0)
			(layers "B.Cu" "B.Mask" "B.Paste")
			(net "P3V3_RGM")
		)
		(pad "2" smd circle
			(at -0.40005 0)
			(size 0 0)
			(layers "B.Cu" "B.Mask" "B.Paste")
			(net "V_BMC_DDC_LS_GATE")
		)
	)
	(footprint ""
		(layer "B.Cu")
		(at 11.098022 -67.644264)
		(property "Reference" "ME4"
			(at 0 0 0)
			(layer "B.SilkS")
			(hide yes)
			(effects
				(font
					(size 1.27 1.27)
				)
				(justify mirror)
			)
		)
		(property "Value" ""
			(at 0 0 0)
			(layer "B.Fab")
			(effects
				(font
					(size 1.27 1.27)
				)
				(justify mirror)
			)
		)
		(duplicate_pad_numbers_are_jumpers no)
		(fp_line
			(start -6.999986 -6.999986)
			(end -6.999986 -5.475986)
			(stroke
				(width 0.1524)
				(type default)
			)
			(layer "B.SilkS")
		)
		(fp_line
			(start -6.999986 -1.524)
			(end -6.999986 0)
			(stroke
				(width 0.1524)
				(type default)
			)
			(layer "B.SilkS")
		)
		(fp_line
			(start -6.999986 0)
			(end -5.475986 0)
			(stroke
				(width 0.1524)
				(type default)
			)
			(layer "B.SilkS")
		)
		(fp_line
			(start -5.475986 -6.999986)
			(end -6.999986 -6.999986)
			(stroke
				(width 0.1524)
				(type default)
			)
			(layer "B.SilkS")
		)
		(fp_line
			(start -1.524 -6.999986)
			(end 0 -6.999986)
			(stroke
				(width 0.1524)
				(type default)
			)
			(layer "B.SilkS")
		)
		(fp_line
			(start 0 -6.999986)
			(end 0 -5.475986)
			(stroke
				(width 0.1524)
				(type default)
			)
			(layer "B.SilkS")
		)
		(fp_line
			(start 0 -1.524)
			(end 0 0)
			(stroke
				(width 0.1524)
				(type default)
			)
			(layer "B.SilkS")
		)
		(fp_line
			(start 0 0)
			(end -1.524 0)
			(stroke
				(width 0.1524)
				(type default)
			)
			(layer "B.SilkS")
		)
		(fp_text user "S/N"
			(at -0.361188 -5.450078 0)
			(unlocked yes)
			(layer "B.SilkS")
			(effects
				(font
					(size 1.905 1.4224)
					(thickness 0.1524)
				)
				(justify left mirror)
			)
		)
	)
	(footprint ""
		(layer "B.Cu")
		(at 14.982444 -99.194112 135)
		(property "Reference" "C193"
			(at 0 0 135)
			(layer "B.SilkS")
			(hide yes)
			(effects
				(font
					(size 1.27 1.27)
				)
				(justify mirror)
			)
		)
		(property "Value" ""
			(at 0 0 135)
			(layer "B.Fab")
			(effects
				(font
					(size 1.27 1.27)
				)
				(justify mirror)
			)
		)
		(duplicate_pad_numbers_are_jumpers no)
		(fp_line
			(start 0.787389 -0.406267)
			(end -0.787389 -0.406267)
			(stroke
				(width 0.1524)
				(type default)
			)
			(layer "B.SilkS")
		)
		(fp_line
			(start 0.787389 0.406267)
			(end 0.787389 -0.406267)
			(stroke
				(width 0.1524)
				(type default)
			)
			(layer "B.SilkS")
		)
		(fp_line
			(start -0.787389 -0.406267)
			(end -0.787389 0.406267)
			(stroke
				(width 0.1524)
				(type default)
			)
			(layer "B.SilkS")
		)
		(fp_line
			(start -0.787389 0.406267)
			(end 0.787389 0.406267)
			(stroke
				(width 0.1524)
				(type default)
			)
			(layer "B.SilkS")
		)
		(fp_line
			(start 0.679446 -0.305149)
			(end 0.120695 -0.304969)
			(stroke
				(width 0.1)
				(type default)
			)
			(layer "B.Fab")
		)
		(fp_line
			(start 0.120695 -0.304969)
			(end 0.120695 -0.279466)
			(stroke
				(width 0.1)
				(type default)
			)
			(layer "B.Fab")
		)
		(fp_line
			(start 0.120695 -0.279466)
			(end -0.120695 -0.279466)
			(stroke
				(width 0.1)
				(type default)
			)
			(layer "B.Fab")
		)
		(fp_line
			(start 0.679446 0.30479)
			(end 0.679446 -0.305149)
			(stroke
				(width 0.1)
				(type default)
			)
			(layer "B.Fab")
		)
		(fp_line
			(start -0.120515 -0.30479)
			(end -0.679446 -0.30479)
			(stroke
				(width 0.1)
				(type default)
			)
			(layer "B.Fab")
		)
		(fp_line
			(start -0.120695 -0.279466)
			(end -0.120515 -0.30479)
			(stroke
				(width 0.1)
				(type default)
			)
			(layer "B.Fab")
		)
		(fp_line
			(start 0.120695 0.279466)
			(end 0.120515 0.30479)
			(stroke
				(width 0.1)
				(type default)
			)
			(layer "B.Fab")
		)
		(fp_line
			(start 0.120515 0.30479)
			(end 0.679446 0.30479)
			(stroke
				(width 0.1)
				(type default)
			)
			(layer "B.Fab")
		)
		(fp_line
			(start -0.679446 -0.30479)
			(end -0.679446 0.30479)
			(stroke
				(width 0.1)
				(type default)
			)
			(layer "B.Fab")
		)
		(fp_line
			(start -0.120335 0.279466)
			(end 0.120695 0.279466)
			(stroke
				(width 0.1)
				(type default)
			)
			(layer "B.Fab")
		)
		(fp_line
			(start -0.120515 0.30479)
			(end -0.120335 0.279466)
			(stroke
				(width 0.1)
				(type default)
			)
			(layer "B.Fab")
		)
		(fp_line
			(start -0.679446 0.30479)
			(end -0.120515 0.30479)
			(stroke
				(width 0.1)
				(type default)
			)
			(layer "B.Fab")
		)
		(pad "1" smd circle
			(at 0.40005 0 315)
			(size 0 0)
			(layers "B.Cu" "B.Mask" "B.Paste")
			(net "PVCCA_AUX_PLD")
		)
		(pad "2" smd circle
			(at -0.40005 0 315)
			(size 0 0)
			(layers "B.Cu" "B.Mask" "B.Paste")
			(net "GND")
		)
	)
	(footprint ""
		(layer "B.Cu")
		(at 18.259298 -95.587058 180)
		(property "Reference" "C281"
			(at 0 0 0)
			(layer "B.SilkS")
			(hide yes)
			(effects
				(font
					(size 1.27 1.27)
				)
				(justify mirror)
			)
		)
		(property "Value" ""
			(at 0 0 0)
			(layer "B.Fab")
			(effects
				(font
					(size 1.27 1.27)
				)
				(justify mirror)
			)
		)
		(duplicate_pad_numbers_are_jumpers no)
		(fp_line
			(start 0.69215 0.2921)
			(end 0.69215 -0.2921)
			(stroke
				(width 0.1524)
				(type default)
			)
			(layer "B.SilkS")
		)
		(fp_line
			(start 0.69215 -0.2921)
			(end -0.69215 -0.2921)
			(stroke
				(width 0.1524)
				(type default)
			)
			(layer "B.SilkS")
		)
		(fp_line
			(start -0.69215 0.2921)
			(end 0.69215 0.2921)
			(stroke
				(width 0.1524)
				(type default)
			)
			(layer "B.SilkS")
		)
		(fp_line
			(start -0.69215 -0.2921)
			(end -0.69215 0.2921)
			(stroke
				(width 0.1524)
				(type default)
			)
			(layer "B.SilkS")
		)
		(fp_line
			(start 0.51435 0.2794)
			(end 0.51435 -0.2794)
			(stroke
				(width 0.1)
				(type default)
			)
			(layer "B.Fab")
		)
		(fp_line
			(start 0.51435 -0.2794)
			(end -0.51435 -0.2794)
			(stroke
				(width 0.1)
				(type default)
			)
			(layer "B.Fab")
		)
		(fp_line
			(start -0.51435 0.2794)
			(end 0.51435 0.2794)
			(stroke
				(width 0.1)
				(type default)
			)
			(layer "B.Fab")
		)
		(fp_line
			(start -0.51435 -0.2794)
			(end -0.51435 0.2794)
			(stroke
				(width 0.1)
				(type default)
			)
			(layer "B.Fab")
		)
		(pad "1" smd circle
			(at 0.40005 0)
			(size 0 0)
			(layers "B.Cu" "B.Mask" "B.Paste")
			(net "VCCIO1")
		)
		(pad "2" smd circle
			(at -0.40005 0)
			(size 0 0)
			(layers "B.Cu" "B.Mask" "B.Paste")
			(net "GND")
		)
		(zone
			(layer "B.Cu")
			(hatch none 0.5)
			(connect_pads
				(clearance 0)
			)
			(min_thickness 0.25)
			(keepout
				(tracks not_allowed)
				(vias allowed)
				(pads allowed)
				(copperpour not_allowed)
				(footprints allowed)
			)
			(placement
				(enabled no)
				(sheetname "")
			)
			(fill
				(thermal_gap 0.5)
				(thermal_bridge_width 0.5)
				(island_removal_mode 0)
			)
			(polygon
				(pts
					(xy 18.068798 -95.674688) (xy 18.160238 -95.732854) (xy 18.359628 -95.732854) (xy 18.449798 -95.674688)
					(xy 18.449798 -95.499428) (xy 18.359628 -95.441008) (xy 18.160238 -95.441008) (xy 18.068798 -95.499174)
				)
			)
		)
	)
	(footprint ""
		(layer "B.Cu")
		(at 51.2445 -92.2655 180)
		(property "Reference" "R83"
			(at 0 0 0)
			(layer "B.SilkS")
			(hide yes)
			(effects
				(font
					(size 1.27 1.27)
				)
				(justify mirror)
			)
		)
		(property "Value" ""
			(at 0 0 0)
			(layer "B.Fab")
			(effects
				(font
					(size 1.27 1.27)
				)
				(justify mirror)
			)
		)
		(duplicate_pad_numbers_are_jumpers no)
		(fp_line
			(start 0.7874 0.4064)
			(end 0.7874 -0.4064)
			(stroke
				(width 0.1524)
				(type default)
			)
			(layer "B.SilkS")
		)
		(fp_line
			(start 0.7874 -0.4064)
			(end -0.7874 -0.4064)
			(stroke
				(width 0.1524)
				(type default)
			)
			(layer "B.SilkS")
		)
		(fp_line
			(start -0.7874 0.4064)
			(end 0.7874 0.4064)
			(stroke
				(width 0.1524)
				(type default)
			)
			(layer "B.SilkS")
		)
		(fp_line
			(start -0.7874 -0.4064)
			(end -0.7874 0.4064)
			(stroke
				(width 0.1524)
				(type default)
			)
			(layer "B.SilkS")
		)
		(fp_line
			(start 0.67945 0.3048)
			(end 0.67945 -0.305054)
			(stroke
				(width 0.1)
				(type default)
			)
			(layer "B.Fab")
		)
		(fp_line
			(start 0.67945 -0.305054)
			(end 0.12065 -0.305054)
			(stroke
				(width 0.1)
				(type default)
			)
			(layer "B.Fab")
		)
		(fp_line
			(start 0.12065 0.3048)
			(end 0.67945 0.3048)
			(stroke
				(width 0.1)
				(type default)
			)
			(layer "B.Fab")
		)
		(fp_line
			(start 0.12065 0.2794)
			(end 0.12065 0.3048)
			(stroke
				(width 0.1)
				(type default)
			)
			(layer "B.Fab")
		)
		(fp_line
			(start 0.12065 -0.2794)
			(end -0.12065 -0.2794)
			(stroke
				(width 0.1)
				(type default)
			)
			(layer "B.Fab")
		)
		(fp_line
			(start 0.12065 -0.305054)
			(end 0.12065 -0.2794)
			(stroke
				(width 0.1)
				(type default)
			)
			(layer "B.Fab")
		)
		(fp_line
			(start -0.120396 0.3048)
			(end -0.120396 0.2794)
			(stroke
				(width 0.1)
				(type default)
			)
			(layer "B.Fab")
		)
		(fp_line
			(start -0.120396 0.2794)
			(end 0.12065 0.2794)
			(stroke
				(width 0.1)
				(type default)
			)
			(layer "B.Fab")
		)
		(fp_line
			(start -0.12065 -0.2794)
			(end -0.12065 -0.3048)
			(stroke
				(width 0.1)
				(type default)
			)
			(layer "B.Fab")
		)
		(fp_line
			(start -0.12065 -0.3048)
			(end -0.67945 -0.3048)
			(stroke
				(width 0.1)
				(type default)
			)
			(layer "B.Fab")
		)
		(fp_line
			(start -0.67945 0.3048)
			(end -0.120396 0.3048)
			(stroke
				(width 0.1)
				(type default)
			)
			(layer "B.Fab")
		)
		(fp_line
			(start -0.67945 -0.3048)
			(end -0.67945 0.3048)
			(stroke
				(width 0.1)
				(type default)
			)
			(layer "B.Fab")
		)
		(pad "1" smd circle
			(at 0.40005 0)
			(size 0 0)
			(layers "B.Cu" "B.Mask" "B.Paste")
			(net "FM_UART_SEL_N")
		)
		(pad "2" smd circle
			(at -0.40005 0)
			(size 0 0)
			(layers "B.Cu" "B.Mask" "B.Paste")
			(net "FM_UART_SWITCH_N")
		)
	)
	(footprint ""
		(layer "B.Cu")
		(at 46.0756 -92.5322 -90)
		(property "Reference" "C237"
			(at 0 0 90)
			(layer "B.SilkS")
			(hide yes)
			(effects
				(font
					(size 1.27 1.27)
				)
				(justify mirror)
			)
		)
		(property "Value" ""
			(at 0 0 90)
			(layer "B.Fab")
			(effects
				(font
					(size 1.27 1.27)
				)
				(justify mirror)
			)
		)
		(duplicate_pad_numbers_are_jumpers no)
		(fp_line
			(start -0.7874 0.4064)
			(end 0.7874 0.4064)
			(stroke
				(width 0.1524)
				(type default)
			)
			(layer "B.SilkS")
		)
		(fp_line
			(start 0.7874 0.4064)
			(end 0.7874 -0.4064)
			(stroke
				(width 0.1524)
				(type default)
			)
			(layer "B.SilkS")
		)
		(fp_line
			(start -0.7874 -0.4064)
			(end -0.7874 0.4064)
			(stroke
				(width 0.1524)
				(type default)
			)
			(layer "B.SilkS")
		)
		(fp_line
			(start 0.7874 -0.4064)
			(end -0.7874 -0.4064)
			(stroke
				(width 0.1524)
				(type default)
			)
			(layer "B.SilkS")
		)
		(fp_line
			(start -0.67945 0.3048)
			(end -0.120396 0.3048)
			(stroke
				(width 0.1)
				(type default)
			)
			(layer "B.Fab")
		)
		(fp_line
			(start -0.120396 0.3048)
			(end -0.120396 0.2794)
			(stroke
				(width 0.1)
				(type default)
			)
			(layer "B.Fab")
		)
		(fp_line
			(start 0.12065 0.3048)
			(end 0.67945 0.3048)
			(stroke
				(width 0.1)
				(type default)
			)
			(layer "B.Fab")
		)
		(fp_line
			(start 0.67945 0.3048)
			(end 0.67945 -0.305054)
			(stroke
				(width 0.1)
				(type default)
			)
			(layer "B.Fab")
		)
		(fp_line
			(start -0.120396 0.2794)
			(end 0.12065 0.2794)
			(stroke
				(width 0.1)
				(type default)
			)
			(layer "B.Fab")
		)
		(fp_line
			(start 0.12065 0.2794)
			(end 0.12065 0.3048)
			(stroke
				(width 0.1)
				(type default)
			)
			(layer "B.Fab")
		)
		(fp_line
			(start -0.12065 -0.2794)
			(end -0.12065 -0.3048)
			(stroke
				(width 0.1)
				(type default)
			)
			(layer "B.Fab")
		)
		(fp_line
			(start 0.12065 -0.2794)
			(end -0.12065 -0.2794)
			(stroke
				(width 0.1)
				(type default)
			)
			(layer "B.Fab")
		)
		(fp_line
			(start -0.67945 -0.3048)
			(end -0.67945 0.3048)
			(stroke
				(width 0.1)
				(type default)
			)
			(layer "B.Fab")
		)
		(fp_line
			(start -0.12065 -0.3048)
			(end -0.67945 -0.3048)
			(stroke
				(width 0.1)
				(type default)
			)
			(layer "B.Fab")
		)
		(fp_line
			(start 0.12065 -0.305054)
			(end 0.12065 -0.2794)
			(stroke
				(width 0.1)
				(type default)
			)
			(layer "B.Fab")
		)
		(fp_line
			(start 0.67945 -0.305054)
			(end 0.12065 -0.305054)
			(stroke
				(width 0.1)
				(type default)
			)
			(layer "B.Fab")
		)
		(pad "1" smd circle
			(at 0.40005 0 90)
			(size 0 0)
			(layers "B.Cu" "B.Mask" "B.Paste")
			(net "P3V3_AUX")
		)
		(pad "2" smd circle
			(at -0.40005 0 90)
			(size 0 0)
			(layers "B.Cu" "B.Mask" "B.Paste")
			(net "GND")
		)
	)
	(footprint ""
		(layer "B.Cu")
		(at 84.08924 -51.381152 180)
		(property "Reference" "C170"
			(at 0 0 0)
			(layer "B.SilkS")
			(hide yes)
			(effects
				(font
					(size 1.27 1.27)
				)
				(justify mirror)
			)
		)
		(property "Value" ""
			(at 0 0 0)
			(layer "B.Fab")
			(effects
				(font
					(size 1.27 1.27)
				)
				(justify mirror)
			)
		)
		(duplicate_pad_numbers_are_jumpers no)
		(fp_line
			(start 0.7874 0.4064)
			(end 0.7874 -0.4064)
			(stroke
				(width 0.1524)
				(type default)
			)
			(layer "B.SilkS")
		)
		(fp_line
			(start 0.7874 -0.4064)
			(end -0.7874 -0.4064)
			(stroke
				(width 0.1524)
				(type default)
			)
			(layer "B.SilkS")
		)
		(fp_line
			(start -0.7874 0.4064)
			(end 0.7874 0.4064)
			(stroke
				(width 0.1524)
				(type default)
			)
			(layer "B.SilkS")
		)
		(fp_line
			(start -0.7874 -0.4064)
			(end -0.7874 0.4064)
			(stroke
				(width 0.1524)
				(type default)
			)
			(layer "B.SilkS")
		)
		(fp_line
			(start 0.67945 0.3048)
			(end 0.67945 -0.305054)
			(stroke
				(width 0.1)
				(type default)
			)
			(layer "B.Fab")
		)
		(fp_line
			(start 0.67945 -0.305054)
			(end 0.12065 -0.305054)
			(stroke
				(width 0.1)
				(type default)
			)
			(layer "B.Fab")
		)
		(fp_line
			(start 0.12065 0.3048)
			(end 0.67945 0.3048)
			(stroke
				(width 0.1)
				(type default)
			)
			(layer "B.Fab")
		)
		(fp_line
			(start 0.12065 0.2794)
			(end 0.12065 0.3048)
			(stroke
				(width 0.1)
				(type default)
			)
			(layer "B.Fab")
		)
		(fp_line
			(start 0.12065 -0.2794)
			(end -0.12065 -0.2794)
			(stroke
				(width 0.1)
				(type default)
			)
			(layer "B.Fab")
		)
		(fp_line
			(start 0.12065 -0.305054)
			(end 0.12065 -0.2794)
			(stroke
				(width 0.1)
				(type default)
			)
			(layer "B.Fab")
		)
		(fp_line
			(start -0.120396 0.3048)
			(end -0.120396 0.2794)
			(stroke
				(width 0.1)
				(type default)
			)
			(layer "B.Fab")
		)
		(fp_line
			(start -0.120396 0.2794)
			(end 0.12065 0.2794)
			(stroke
				(width 0.1)
				(type default)
			)
			(layer "B.Fab")
		)
		(fp_line
			(start -0.12065 -0.2794)
			(end -0.12065 -0.3048)
			(stroke
				(width 0.1)
				(type default)
			)
			(layer "B.Fab")
		)
		(fp_line
			(start -0.12065 -0.3048)
			(end -0.67945 -0.3048)
			(stroke
				(width 0.1)
				(type default)
			)
			(layer "B.Fab")
		)
		(fp_line
			(start -0.67945 0.3048)
			(end -0.120396 0.3048)
			(stroke
				(width 0.1)
				(type default)
			)
			(layer "B.Fab")
		)
		(fp_line
			(start -0.67945 -0.3048)
			(end -0.67945 0.3048)
			(stroke
				(width 0.1)
				(type default)
			)
			(layer "B.Fab")
		)
		(pad "1" smd circle
			(at 0.40005 0)
			(size 0 0)
			(layers "B.Cu" "B.Mask" "B.Paste")
			(net "P0V6_DDR_VREF_AUX")
		)
		(pad "2" smd circle
			(at -0.40005 0)
			(size 0 0)
			(layers "B.Cu" "B.Mask" "B.Paste")
			(net "GND")
		)
	)
	(footprint ""
		(layer "B.Cu")
		(at 72.909176 -42.113708)
		(property "Reference" "R4"
			(at 0 0 0)
			(layer "B.SilkS")
			(hide yes)
			(effects
				(font
					(size 1.27 1.27)
				)
				(justify mirror)
			)
		)
		(property "Value" ""
			(at 0 0 0)
			(layer "B.Fab")
			(effects
				(font
					(size 1.27 1.27)
				)
				(justify mirror)
			)
		)
		(duplicate_pad_numbers_are_jumpers no)
		(fp_line
			(start -0.7874 -0.4064)
			(end -0.7874 0.4064)
			(stroke
				(width 0.1524)
				(type default)
			)
			(layer "B.SilkS")
		)
		(fp_line
			(start -0.7874 0.4064)
			(end 0.7874 0.4064)
			(stroke
				(width 0.1524)
				(type default)
			)
			(layer "B.SilkS")
		)
		(fp_line
			(start 0.7874 -0.4064)
			(end -0.7874 -0.4064)
			(stroke
				(width 0.1524)
				(type default)
			)
			(layer "B.SilkS")
		)
		(fp_line
			(start 0.7874 0.4064)
			(end 0.7874 -0.4064)
			(stroke
				(width 0.1524)
				(type default)
			)
			(layer "B.SilkS")
		)
		(fp_line
			(start -0.67945 -0.3048)
			(end -0.67945 0.3048)
			(stroke
				(width 0.1)
				(type default)
			)
			(layer "B.Fab")
		)
		(fp_line
			(start -0.67945 0.3048)
			(end -0.120396 0.3048)
			(stroke
				(width 0.1)
				(type default)
			)
			(layer "B.Fab")
		)
		(fp_line
			(start -0.12065 -0.3048)
			(end -0.67945 -0.3048)
			(stroke
				(width 0.1)
				(type default)
			)
			(layer "B.Fab")
		)
		(fp_line
			(start -0.12065 -0.2794)
			(end -0.12065 -0.3048)
			(stroke
				(width 0.1)
				(type default)
			)
			(layer "B.Fab")
		)
		(fp_line
			(start -0.120396 0.2794)
			(end 0.12065 0.2794)
			(stroke
				(width 0.1)
				(type default)
			)
			(layer "B.Fab")
		)
		(fp_line
			(start -0.120396 0.3048)
			(end -0.120396 0.2794)
			(stroke
				(width 0.1)
				(type default)
			)
			(layer "B.Fab")
		)
		(fp_line
			(start 0.12065 -0.305054)
			(end 0.12065 -0.2794)
			(stroke
				(width 0.1)
				(type default)
			)
			(layer "B.Fab")
		)
		(fp_line
			(start 0.12065 -0.2794)
			(end -0.12065 -0.2794)
			(stroke
				(width 0.1)
				(type default)
			)
			(layer "B.Fab")
		)
		(fp_line
			(start 0.12065 0.2794)
			(end 0.12065 0.3048)
			(stroke
				(width 0.1)
				(type default)
			)
			(layer "B.Fab")
		)
		(fp_line
			(start 0.12065 0.3048)
			(end 0.67945 0.3048)
			(stroke
				(width 0.1)
				(type default)
			)
			(layer "B.Fab")
		)
		(fp_line
			(start 0.67945 -0.305054)
			(end 0.12065 -0.305054)
			(stroke
				(width 0.1)
				(type default)
			)
			(layer "B.Fab")
		)
		(fp_line
			(start 0.67945 0.3048)
			(end 0.67945 -0.305054)
			(stroke
				(width 0.1)
				(type default)
			)
			(layer "B.Fab")
		)
		(pad "1" smd circle
			(at 0.40005 0 180)
			(size 0 0)
			(layers "B.Cu" "B.Mask" "B.Paste")
			(net "PD_M_BMC_DDR4_PAR")
		)
		(pad "2" smd circle
			(at -0.40005 0 180)
			(size 0 0)
			(layers "B.Cu" "B.Mask" "B.Paste")
			(net "GND")
		)
	)
	(footprint ""
		(layer "B.Cu")
		(at 72.003412 -58.051954 -90)
		(property "Reference" "L13"
			(at 0 0 90)
			(layer "B.SilkS")
			(hide yes)
			(effects
				(font
					(size 1.27 1.27)
				)
				(justify mirror)
			)
		)
		(property "Value" ""
			(at 0 0 90)
			(layer "B.Fab")
			(effects
				(font
					(size 1.27 1.27)
				)
				(justify mirror)
			)
		)
		(duplicate_pad_numbers_are_jumpers no)
		(fp_line
			(start -1.27 0.5842)
			(end 1.27 0.5842)
			(stroke
				(width 0.1524)
				(type default)
			)
			(layer "B.SilkS")
		)
		(fp_line
			(start -1.27 0.5842)
			(end -1.27 -0.5842)
			(stroke
				(width 0.1524)
				(type default)
			)
			(layer "B.SilkS")
		)
		(fp_line
			(start -0.127 0.5842)
			(end -0.127 -0.5842)
			(stroke
				(width 0.1524)
				(type default)
			)
			(layer "B.SilkS")
		)
		(fp_line
			(start 0.127 0.5842)
			(end 0.127 -0.5842)
			(stroke
				(width 0.1524)
				(type default)
			)
			(layer "B.SilkS")
		)
		(fp_line
			(start 1.27 0.5842)
			(end 1.27 -0.5842)
			(stroke
				(width 0.1524)
				(type default)
			)
			(layer "B.SilkS")
		)
		(fp_line
			(start 1.27 -0.5588)
			(end 1.27 -0.5842)
			(stroke
				(width 0.1524)
				(type default)
			)
			(layer "B.SilkS")
		)
		(fp_line
			(start 1.27 -0.5842)
			(end -1.27 -0.5842)
			(stroke
				(width 0.1524)
				(type default)
			)
			(layer "B.SilkS")
		)
		(fp_line
			(start -0.9144 0.508)
			(end 0.9144 0.508)
			(stroke
				(width 0.1)
				(type default)
			)
			(layer "B.Fab")
		)
		(fp_line
			(start 0.9144 0.508)
			(end 0.9144 0.406654)
			(stroke
				(width 0.1)
				(type default)
			)
			(layer "B.Fab")
		)
		(fp_line
			(start 0.9144 0.406654)
			(end 1.194308 0.406654)
			(stroke
				(width 0.1)
				(type default)
			)
			(layer "B.Fab")
		)
		(fp_line
			(start 1.194308 0.406654)
			(end 1.194308 -0.406654)
			(stroke
				(width 0.1)
				(type default)
			)
			(layer "B.Fab")
		)
		(fp_line
			(start -1.1938 0.4064)
			(end -0.9144 0.4064)
			(stroke
				(width 0.1)
				(type default)
			)
			(layer "B.Fab")
		)
		(fp_line
			(start -0.9144 0.4064)
			(end -0.9144 0.508)
			(stroke
				(width 0.1)
				(type default)
			)
			(layer "B.Fab")
		)
		(fp_line
			(start -1.1938 -0.406654)
			(end -1.1938 0.4064)
			(stroke
				(width 0.1)
				(type default)
			)
			(layer "B.Fab")
		)
		(fp_line
			(start -0.9144 -0.406654)
			(end -1.1938 -0.406654)
			(stroke
				(width 0.1)
				(type default)
			)
			(layer "B.Fab")
		)
		(fp_line
			(start 0.9144 -0.406654)
			(end 0.9144 -0.508)
			(stroke
				(width 0.1)
				(type default)
			)
			(layer "B.Fab")
		)
		(fp_line
			(start 1.194308 -0.406654)
			(end 0.9144 -0.406654)
			(stroke
				(width 0.1)
				(type default)
			)
			(layer "B.Fab")
		)
		(fp_line
			(start -0.9144 -0.508)
			(end -0.9144 -0.406654)
			(stroke
				(width 0.1)
				(type default)
			)
			(layer "B.Fab")
		)
		(fp_line
			(start 0.9144 -0.508)
			(end -0.9144 -0.508)
			(stroke
				(width 0.1)
				(type default)
			)
			(layer "B.Fab")
		)
		(pad "1" smd rect
			(at 0.7366 0 180)
			(size 0.7112 0.8128)
			(layers "B.Cu" "B.Mask" "B.Paste")
			(net "P1V0_AUX")
		)
		(pad "2" smd rect
			(at -0.7366 0 180)
			(size 0.7112 0.8128)
			(layers "B.Cu" "B.Mask" "B.Paste")
			(net "P1V0_STBY_PE_VCC10A")
		)
	)
	(footprint ""
		(layer "B.Cu")
		(at 12.319 -97.536)
		(property "Reference" "R317"
			(at 0 0 0)
			(layer "B.SilkS")
			(hide yes)
			(effects
				(font
					(size 1.27 1.27)
				)
				(justify mirror)
			)
		)
		(property "Value" ""
			(at 0 0 0)
			(layer "B.Fab")
			(effects
				(font
					(size 1.27 1.27)
				)
				(justify mirror)
			)
		)
		(duplicate_pad_numbers_are_jumpers no)
		(fp_line
			(start -0.7874 -0.4064)
			(end -0.7874 0.4064)
			(stroke
				(width 0.1524)
				(type default)
			)
			(layer "B.SilkS")
		)
		(fp_line
			(start -0.7874 0.4064)
			(end 0.7874 0.4064)
			(stroke
				(width 0.1524)
				(type default)
			)
			(layer "B.SilkS")
		)
		(fp_line
			(start 0.7874 -0.4064)
			(end -0.7874 -0.4064)
			(stroke
				(width 0.1524)
				(type default)
			)
			(layer "B.SilkS")
		)
		(fp_line
			(start 0.7874 0.4064)
			(end 0.7874 -0.4064)
			(stroke
				(width 0.1524)
				(type default)
			)
			(layer "B.SilkS")
		)
		(fp_line
			(start -0.67945 -0.3048)
			(end -0.67945 0.3048)
			(stroke
				(width 0.1)
				(type default)
			)
			(layer "B.Fab")
		)
		(fp_line
			(start -0.67945 0.3048)
			(end -0.120396 0.3048)
			(stroke
				(width 0.1)
				(type default)
			)
			(layer "B.Fab")
		)
		(fp_line
			(start -0.12065 -0.3048)
			(end -0.67945 -0.3048)
			(stroke
				(width 0.1)
				(type default)
			)
			(layer "B.Fab")
		)
		(fp_line
			(start -0.12065 -0.2794)
			(end -0.12065 -0.3048)
			(stroke
				(width 0.1)
				(type default)
			)
			(layer "B.Fab")
		)
		(fp_line
			(start -0.120396 0.2794)
			(end 0.12065 0.2794)
			(stroke
				(width 0.1)
				(type default)
			)
			(layer "B.Fab")
		)
		(fp_line
			(start -0.120396 0.3048)
			(end -0.120396 0.2794)
			(stroke
				(width 0.1)
				(type default)
			)
			(layer "B.Fab")
		)
		(fp_line
			(start 0.12065 -0.305054)
			(end 0.12065 -0.2794)
			(stroke
				(width 0.1)
				(type default)
			)
			(layer "B.Fab")
		)
		(fp_line
			(start 0.12065 -0.2794)
			(end -0.12065 -0.2794)
			(stroke
				(width 0.1)
				(type default)
			)
			(layer "B.Fab")
		)
		(fp_line
			(start 0.12065 0.2794)
			(end 0.12065 0.3048)
			(stroke
				(width 0.1)
				(type default)
			)
			(layer "B.Fab")
		)
		(fp_line
			(start 0.12065 0.3048)
			(end 0.67945 0.3048)
			(stroke
				(width 0.1)
				(type default)
			)
			(layer "B.Fab")
		)
		(fp_line
			(start 0.67945 -0.305054)
			(end 0.12065 -0.305054)
			(stroke
				(width 0.1)
				(type default)
			)
			(layer "B.Fab")
		)
		(fp_line
			(start 0.67945 0.3048)
			(end 0.67945 -0.305054)
			(stroke
				(width 0.1)
				(type default)
			)
			(layer "B.Fab")
		)
		(pad "1" smd circle
			(at 0.40005 0 180)
			(size 0 0)
			(layers "B.Cu" "B.Mask" "B.Paste")
			(net "PWR_LED_CPLD")
		)
		(pad "2" smd circle
			(at -0.40005 0 180)
			(size 0 0)
			(layers "B.Cu" "B.Mask" "B.Paste")
			(net "PWR_LED")
		)
	)
	(footprint ""
		(layer "B.Cu")
		(at 74.717148 -93.358208 -90)
		(property "Reference" "R42"
			(at 0 0 90)
			(layer "B.SilkS")
			(hide yes)
			(effects
				(font
					(size 1.27 1.27)
				)
				(justify mirror)
			)
		)
		(property "Value" ""
			(at 0 0 90)
			(layer "B.Fab")
			(effects
				(font
					(size 1.27 1.27)
				)
				(justify mirror)
			)
		)
		(duplicate_pad_numbers_are_jumpers no)
		(fp_line
			(start -0.7874 0.4064)
			(end 0.7874 0.4064)
			(stroke
				(width 0.1524)
				(type default)
			)
			(layer "B.SilkS")
		)
		(fp_line
			(start 0.7874 0.4064)
			(end 0.7874 -0.4064)
			(stroke
				(width 0.1524)
				(type default)
			)
			(layer "B.SilkS")
		)
		(fp_line
			(start -0.7874 -0.4064)
			(end -0.7874 0.4064)
			(stroke
				(width 0.1524)
				(type default)
			)
			(layer "B.SilkS")
		)
		(fp_line
			(start 0.7874 -0.4064)
			(end -0.7874 -0.4064)
			(stroke
				(width 0.1524)
				(type default)
			)
			(layer "B.SilkS")
		)
		(fp_line
			(start -0.67945 0.3048)
			(end -0.120396 0.3048)
			(stroke
				(width 0.1)
				(type default)
			)
			(layer "B.Fab")
		)
		(fp_line
			(start -0.120396 0.3048)
			(end -0.120396 0.2794)
			(stroke
				(width 0.1)
				(type default)
			)
			(layer "B.Fab")
		)
		(fp_line
			(start 0.12065 0.3048)
			(end 0.67945 0.3048)
			(stroke
				(width 0.1)
				(type default)
			)
			(layer "B.Fab")
		)
		(fp_line
			(start 0.67945 0.3048)
			(end 0.67945 -0.305054)
			(stroke
				(width 0.1)
				(type default)
			)
			(layer "B.Fab")
		)
		(fp_line
			(start -0.120396 0.2794)
			(end 0.12065 0.2794)
			(stroke
				(width 0.1)
				(type default)
			)
			(layer "B.Fab")
		)
		(fp_line
			(start 0.12065 0.2794)
			(end 0.12065 0.3048)
			(stroke
				(width 0.1)
				(type default)
			)
			(layer "B.Fab")
		)
		(fp_line
			(start -0.12065 -0.2794)
			(end -0.12065 -0.3048)
			(stroke
				(width 0.1)
				(type default)
			)
			(layer "B.Fab")
		)
		(fp_line
			(start 0.12065 -0.2794)
			(end -0.12065 -0.2794)
			(stroke
				(width 0.1)
				(type default)
			)
			(layer "B.Fab")
		)
		(fp_line
			(start -0.67945 -0.3048)
			(end -0.67945 0.3048)
			(stroke
				(width 0.1)
				(type default)
			)
			(layer "B.Fab")
		)
		(fp_line
			(start -0.12065 -0.3048)
			(end -0.67945 -0.3048)
			(stroke
				(width 0.1)
				(type default)
			)
			(layer "B.Fab")
		)
		(fp_line
			(start 0.12065 -0.305054)
			(end 0.12065 -0.2794)
			(stroke
				(width 0.1)
				(type default)
			)
			(layer "B.Fab")
		)
		(fp_line
			(start 0.67945 -0.305054)
			(end 0.12065 -0.305054)
			(stroke
				(width 0.1)
				(type default)
			)
			(layer "B.Fab")
		)
		(pad "1" smd circle
			(at 0.40005 0 90)
			(size 0 0)
			(layers "B.Cu" "B.Mask" "B.Paste")
			(net "P3V3_AUX")
		)
		(pad "2" smd circle
			(at -0.40005 0 90)
			(size 0 0)
			(layers "B.Cu" "B.Mask" "B.Paste")
			(net "Q7_D")
		)
	)
	(footprint ""
		(layer "B.Cu")
		(at 71.858378 -47.106332 -90)
		(property "Reference" "R374"
			(at 0 0 90)
			(layer "B.SilkS")
			(hide yes)
			(effects
				(font
					(size 1.27 1.27)
				)
				(justify mirror)
			)
		)
		(property "Value" ""
			(at 0 0 90)
			(layer "B.Fab")
			(effects
				(font
					(size 1.27 1.27)
				)
				(justify mirror)
			)
		)
		(duplicate_pad_numbers_are_jumpers no)
		(fp_line
			(start -0.7874 0.4064)
			(end 0.7874 0.4064)
			(stroke
				(width 0.1524)
				(type default)
			)
			(layer "B.SilkS")
		)
		(fp_line
			(start 0.7874 0.4064)
			(end 0.7874 -0.4064)
			(stroke
				(width 0.1524)
				(type default)
			)
			(layer "B.SilkS")
		)
		(fp_line
			(start -0.7874 -0.4064)
			(end -0.7874 0.4064)
			(stroke
				(width 0.1524)
				(type default)
			)
			(layer "B.SilkS")
		)
		(fp_line
			(start 0.7874 -0.4064)
			(end -0.7874 -0.4064)
			(stroke
				(width 0.1524)
				(type default)
			)
			(layer "B.SilkS")
		)
		(fp_line
			(start -0.67945 0.3048)
			(end -0.120396 0.3048)
			(stroke
				(width 0.1)
				(type default)
			)
			(layer "B.Fab")
		)
		(fp_line
			(start -0.120396 0.3048)
			(end -0.120396 0.2794)
			(stroke
				(width 0.1)
				(type default)
			)
			(layer "B.Fab")
		)
		(fp_line
			(start 0.12065 0.3048)
			(end 0.67945 0.3048)
			(stroke
				(width 0.1)
				(type default)
			)
			(layer "B.Fab")
		)
		(fp_line
			(start 0.67945 0.3048)
			(end 0.67945 -0.305054)
			(stroke
				(width 0.1)
				(type default)
			)
			(layer "B.Fab")
		)
		(fp_line
			(start -0.120396 0.2794)
			(end 0.12065 0.2794)
			(stroke
				(width 0.1)
				(type default)
			)
			(layer "B.Fab")
		)
		(fp_line
			(start 0.12065 0.2794)
			(end 0.12065 0.3048)
			(stroke
				(width 0.1)
				(type default)
			)
			(layer "B.Fab")
		)
		(fp_line
			(start -0.12065 -0.2794)
			(end -0.12065 -0.3048)
			(stroke
				(width 0.1)
				(type default)
			)
			(layer "B.Fab")
		)
		(fp_line
			(start 0.12065 -0.2794)
			(end -0.12065 -0.2794)
			(stroke
				(width 0.1)
				(type default)
			)
			(layer "B.Fab")
		)
		(fp_line
			(start -0.67945 -0.3048)
			(end -0.67945 0.3048)
			(stroke
				(width 0.1)
				(type default)
			)
			(layer "B.Fab")
		)
		(fp_line
			(start -0.12065 -0.3048)
			(end -0.67945 -0.3048)
			(stroke
				(width 0.1)
				(type default)
			)
			(layer "B.Fab")
		)
		(fp_line
			(start 0.12065 -0.305054)
			(end 0.12065 -0.2794)
			(stroke
				(width 0.1)
				(type default)
			)
			(layer "B.Fab")
		)
		(fp_line
			(start 0.67945 -0.305054)
			(end 0.12065 -0.305054)
			(stroke
				(width 0.1)
				(type default)
			)
			(layer "B.Fab")
		)
		(pad "1" smd circle
			(at 0.40005 0 90)
			(size 0 0)
			(layers "B.Cu" "B.Mask" "B.Paste")
			(net "M_BMC_DDR4_MCKE")
		)
		(pad "2" smd circle
			(at -0.40005 0 90)
			(size 0 0)
			(layers "B.Cu" "B.Mask" "B.Paste")
			(net "P1V2_AUX")
		)
	)
	(footprint ""
		(layer "B.Cu")
		(at 56.462422 -72.46239 90)
		(property "Reference" "R784"
			(at 0 0 90)
			(layer "B.SilkS")
			(hide yes)
			(effects
				(font
					(size 1.27 1.27)
				)
				(justify mirror)
			)
		)
		(property "Value" ""
			(at 0 0 90)
			(layer "B.Fab")
			(effects
				(font
					(size 1.27 1.27)
				)
				(justify mirror)
			)
		)
		(duplicate_pad_numbers_are_jumpers no)
		(fp_line
			(start 0.7874 -0.4064)
			(end -0.7874 -0.4064)
			(stroke
				(width 0.1524)
				(type default)
			)
			(layer "B.SilkS")
		)
		(fp_line
			(start -0.7874 -0.4064)
			(end -0.7874 0.4064)
			(stroke
				(width 0.1524)
				(type default)
			)
			(layer "B.SilkS")
		)
		(fp_line
			(start 0.7874 0.4064)
			(end 0.7874 -0.4064)
			(stroke
				(width 0.1524)
				(type default)
			)
			(layer "B.SilkS")
		)
		(fp_line
			(start -0.7874 0.4064)
			(end 0.7874 0.4064)
			(stroke
				(width 0.1524)
				(type default)
			)
			(layer "B.SilkS")
		)
		(fp_line
			(start 0.67945 -0.305054)
			(end 0.12065 -0.305054)
			(stroke
				(width 0.1)
				(type default)
			)
			(layer "B.Fab")
		)
		(fp_line
			(start 0.12065 -0.305054)
			(end 0.12065 -0.2794)
			(stroke
				(width 0.1)
				(type default)
			)
			(layer "B.Fab")
		)
		(fp_line
			(start -0.12065 -0.3048)
			(end -0.67945 -0.3048)
			(stroke
				(width 0.1)
				(type default)
			)
			(layer "B.Fab")
		)
		(fp_line
			(start -0.67945 -0.3048)
			(end -0.67945 0.3048)
			(stroke
				(width 0.1)
				(type default)
			)
			(layer "B.Fab")
		)
		(fp_line
			(start 0.12065 -0.2794)
			(end -0.12065 -0.2794)
			(stroke
				(width 0.1)
				(type default)
			)
			(layer "B.Fab")
		)
		(fp_line
			(start -0.12065 -0.2794)
			(end -0.12065 -0.3048)
			(stroke
				(width 0.1)
				(type default)
			)
			(layer "B.Fab")
		)
		(fp_line
			(start 0.12065 0.2794)
			(end 0.12065 0.3048)
			(stroke
				(width 0.1)
				(type default)
			)
			(layer "B.Fab")
		)
		(fp_line
			(start -0.120396 0.2794)
			(end 0.12065 0.2794)
			(stroke
				(width 0.1)
				(type default)
			)
			(layer "B.Fab")
		)
		(fp_line
			(start 0.67945 0.3048)
			(end 0.67945 -0.305054)
			(stroke
				(width 0.1)
				(type default)
			)
			(layer "B.Fab")
		)
		(fp_line
			(start 0.12065 0.3048)
			(end 0.67945 0.3048)
			(stroke
				(width 0.1)
				(type default)
			)
			(layer "B.Fab")
		)
		(fp_line
			(start -0.120396 0.3048)
			(end -0.120396 0.2794)
			(stroke
				(width 0.1)
				(type default)
			)
			(layer "B.Fab")
		)
		(fp_line
			(start -0.67945 0.3048)
			(end -0.120396 0.3048)
			(stroke
				(width 0.1)
				(type default)
			)
			(layer "B.Fab")
		)
		(pad "1" smd circle
			(at 0.40005 0 270)
			(size 0 0)
			(layers "B.Cu" "B.Mask" "B.Paste")
			(net "P1V2_AUX")
		)
		(pad "2" smd circle
			(at -0.40005 0 270)
			(size 0 0)
			(layers "B.Cu" "B.Mask" "B.Paste")
			(net "ADCVREFEXT0")
		)
	)
	(footprint ""
		(layer "B.Cu")
		(at 62.442344 -34.637726 90)
		(property "Reference" "R567"
			(at 0 0 90)
			(layer "B.SilkS")
			(hide yes)
			(effects
				(font
					(size 1.27 1.27)
				)
				(justify mirror)
			)
		)
		(property "Value" ""
			(at 0 0 90)
			(layer "B.Fab")
			(effects
				(font
					(size 1.27 1.27)
				)
				(justify mirror)
			)
		)
		(duplicate_pad_numbers_are_jumpers no)
		(fp_line
			(start 0.7874 -0.4064)
			(end -0.7874 -0.4064)
			(stroke
				(width 0.1524)
				(type default)
			)
			(layer "B.SilkS")
		)
		(fp_line
			(start -0.7874 -0.4064)
			(end -0.7874 0.4064)
			(stroke
				(width 0.1524)
				(type default)
			)
			(layer "B.SilkS")
		)
		(fp_line
			(start 0.7874 0.4064)
			(end 0.7874 -0.4064)
			(stroke
				(width 0.1524)
				(type default)
			)
			(layer "B.SilkS")
		)
		(fp_line
			(start -0.7874 0.4064)
			(end 0.7874 0.4064)
			(stroke
				(width 0.1524)
				(type default)
			)
			(layer "B.SilkS")
		)
		(fp_line
			(start 0.67945 -0.305054)
			(end 0.12065 -0.305054)
			(stroke
				(width 0.1)
				(type default)
			)
			(layer "B.Fab")
		)
		(fp_line
			(start 0.12065 -0.305054)
			(end 0.12065 -0.2794)
			(stroke
				(width 0.1)
				(type default)
			)
			(layer "B.Fab")
		)
		(fp_line
			(start -0.12065 -0.3048)
			(end -0.67945 -0.3048)
			(stroke
				(width 0.1)
				(type default)
			)
			(layer "B.Fab")
		)
		(fp_line
			(start -0.67945 -0.3048)
			(end -0.67945 0.3048)
			(stroke
				(width 0.1)
				(type default)
			)
			(layer "B.Fab")
		)
		(fp_line
			(start 0.12065 -0.2794)
			(end -0.12065 -0.2794)
			(stroke
				(width 0.1)
				(type default)
			)
			(layer "B.Fab")
		)
		(fp_line
			(start -0.12065 -0.2794)
			(end -0.12065 -0.3048)
			(stroke
				(width 0.1)
				(type default)
			)
			(layer "B.Fab")
		)
		(fp_line
			(start 0.12065 0.2794)
			(end 0.12065 0.3048)
			(stroke
				(width 0.1)
				(type default)
			)
			(layer "B.Fab")
		)
		(fp_line
			(start -0.120396 0.2794)
			(end 0.12065 0.2794)
			(stroke
				(width 0.1)
				(type default)
			)
			(layer "B.Fab")
		)
		(fp_line
			(start 0.67945 0.3048)
			(end 0.67945 -0.305054)
			(stroke
				(width 0.1)
				(type default)
			)
			(layer "B.Fab")
		)
		(fp_line
			(start 0.12065 0.3048)
			(end 0.67945 0.3048)
			(stroke
				(width 0.1)
				(type default)
			)
			(layer "B.Fab")
		)
		(fp_line
			(start -0.120396 0.3048)
			(end -0.120396 0.2794)
			(stroke
				(width 0.1)
				(type default)
			)
			(layer "B.Fab")
		)
		(fp_line
			(start -0.67945 0.3048)
			(end -0.120396 0.3048)
			(stroke
				(width 0.1)
				(type default)
			)
			(layer "B.Fab")
		)
		(pad "1" smd circle
			(at 0.40005 0 270)
			(size 0 0)
			(layers "B.Cu" "B.Mask" "B.Paste")
			(net "SMB_BMC_MM7_R_SCL")
		)
		(pad "2" smd circle
			(at -0.40005 0 270)
			(size 0 0)
			(layers "B.Cu" "B.Mask" "B.Paste")
			(net "SMB_BMC_MM7_SCL")
		)
	)
	(footprint ""
		(layer "B.Cu")
		(at 17.907 -19.431)
		(property "Reference" "R417"
			(at 0 0 0)
			(layer "B.SilkS")
			(hide yes)
			(effects
				(font
					(size 1.27 1.27)
				)
				(justify mirror)
			)
		)
		(property "Value" ""
			(at 0 0 0)
			(layer "B.Fab")
			(effects
				(font
					(size 1.27 1.27)
				)
				(justify mirror)
			)
		)
		(duplicate_pad_numbers_are_jumpers no)
		(fp_line
			(start -0.7874 -0.4064)
			(end -0.7874 0.4064)
			(stroke
				(width 0.1524)
				(type default)
			)
			(layer "B.SilkS")
		)
		(fp_line
			(start -0.7874 0.4064)
			(end 0.7874 0.4064)
			(stroke
				(width 0.1524)
				(type default)
			)
			(layer "B.SilkS")
		)
		(fp_line
			(start 0.7874 -0.4064)
			(end -0.7874 -0.4064)
			(stroke
				(width 0.1524)
				(type default)
			)
			(layer "B.SilkS")
		)
		(fp_line
			(start 0.7874 0.4064)
			(end 0.7874 -0.4064)
			(stroke
				(width 0.1524)
				(type default)
			)
			(layer "B.SilkS")
		)
		(fp_line
			(start -0.67945 -0.3048)
			(end -0.67945 0.3048)
			(stroke
				(width 0.1)
				(type default)
			)
			(layer "B.Fab")
		)
		(fp_line
			(start -0.67945 0.3048)
			(end -0.120396 0.3048)
			(stroke
				(width 0.1)
				(type default)
			)
			(layer "B.Fab")
		)
		(fp_line
			(start -0.12065 -0.3048)
			(end -0.67945 -0.3048)
			(stroke
				(width 0.1)
				(type default)
			)
			(layer "B.Fab")
		)
		(fp_line
			(start -0.12065 -0.2794)
			(end -0.12065 -0.3048)
			(stroke
				(width 0.1)
				(type default)
			)
			(layer "B.Fab")
		)
		(fp_line
			(start -0.120396 0.2794)
			(end 0.12065 0.2794)
			(stroke
				(width 0.1)
				(type default)
			)
			(layer "B.Fab")
		)
		(fp_line
			(start -0.120396 0.3048)
			(end -0.120396 0.2794)
			(stroke
				(width 0.1)
				(type default)
			)
			(layer "B.Fab")
		)
		(fp_line
			(start 0.12065 -0.305054)
			(end 0.12065 -0.2794)
			(stroke
				(width 0.1)
				(type default)
			)
			(layer "B.Fab")
		)
		(fp_line
			(start 0.12065 -0.2794)
			(end -0.12065 -0.2794)
			(stroke
				(width 0.1)
				(type default)
			)
			(layer "B.Fab")
		)
		(fp_line
			(start 0.12065 0.2794)
			(end 0.12065 0.3048)
			(stroke
				(width 0.1)
				(type default)
			)
			(layer "B.Fab")
		)
		(fp_line
			(start 0.12065 0.3048)
			(end 0.67945 0.3048)
			(stroke
				(width 0.1)
				(type default)
			)
			(layer "B.Fab")
		)
		(fp_line
			(start 0.67945 -0.305054)
			(end 0.12065 -0.305054)
			(stroke
				(width 0.1)
				(type default)
			)
			(layer "B.Fab")
		)
		(fp_line
			(start 0.67945 0.3048)
			(end 0.67945 -0.305054)
			(stroke
				(width 0.1)
				(type default)
			)
			(layer "B.Fab")
		)
		(pad "1" smd circle
			(at 0.40005 0 180)
			(size 0 0)
			(layers "B.Cu" "B.Mask" "B.Paste")
			(net "TMC75_A0")
		)
		(pad "2" smd circle
			(at -0.40005 0 180)
			(size 0 0)
			(layers "B.Cu" "B.Mask" "B.Paste")
			(net "GND")
		)
	)
	(footprint ""
		(layer "B.Cu")
		(at 29.591 -20.6502 -90)
		(property "Reference" "D16"
			(at 5.0292 0.02667 270)
			(unlocked yes)
			(layer "B.SilkS")
			(effects
				(font
					(size 0.7874 0.5842)
					(thickness 0.1524)
				)
				(justify left mirror)
			)
		)
		(property "Value" ""
			(at 0 0 90)
			(layer "B.Fab")
			(effects
				(font
					(size 1.27 1.27)
				)
				(justify mirror)
			)
		)
		(duplicate_pad_numbers_are_jumpers no)
		(fp_line
			(start -1.3208 0.635)
			(end 1.056894 0.635)
			(stroke
				(width 0.1524)
				(type default)
			)
			(layer "B.SilkS")
		)
		(fp_line
			(start 1.056894 0.635)
			(end 1.056894 -0.635)
			(stroke
				(width 0.1524)
				(type default)
			)
			(layer "B.SilkS")
		)
		(fp_line
			(start -1.3208 -0.635)
			(end -1.3208 0.635)
			(stroke
				(width 0.1524)
				(type default)
			)
			(layer "B.SilkS")
		)
		(fp_line
			(start -1.3208 -0.635)
			(end -1.3208 0.635)
			(stroke
				(width 0.1524)
				(type default)
			)
			(layer "B.SilkS")
		)
		(fp_line
			(start -1.27 -0.635)
			(end -1.27 0.635)
			(stroke
				(width 0.1524)
				(type default)
			)
			(layer "B.SilkS")
		)
		(fp_line
			(start -1.1684 -0.635)
			(end -1.1684 0.635)
			(stroke
				(width 0.1524)
				(type default)
			)
			(layer "B.SilkS")
		)
		(fp_line
			(start -1.0668 -0.635)
			(end -1.0668 0.635)
			(stroke
				(width 0.1524)
				(type default)
			)
			(layer "B.SilkS")
		)
		(fp_line
			(start 1.056894 -0.635)
			(end -1.3208 -0.635)
			(stroke
				(width 0.1524)
				(type default)
			)
			(layer "B.SilkS")
		)
		(fp_line
			(start -0.824992 0.525018)
			(end -0.824992 -0.525018)
			(stroke
				(width 0.1)
				(type default)
			)
			(layer "B.Fab")
		)
		(fp_line
			(start 0.824992 0.525018)
			(end -0.824992 0.525018)
			(stroke
				(width 0.1)
				(type default)
			)
			(layer "B.Fab")
		)
		(fp_line
			(start -0.824992 -0.525018)
			(end 0.824992 -0.525018)
			(stroke
				(width 0.1)
				(type default)
			)
			(layer "B.Fab")
		)
		(fp_line
			(start 0.824992 -0.525018)
			(end 0.824992 0.525018)
			(stroke
				(width 0.1)
				(type default)
			)
			(layer "B.Fab")
		)
		(fp_text user "+"
			(at 2.3622 -0.22225 270)
			(unlocked yes)
			(layer "B.SilkS")
			(effects
				(font
					(size 1.905 1.4224)
					(thickness 0.1524)
				)
				(justify left mirror)
			)
		)
		(fp_text user "-"
			(at -1.3716 -0.27305 270)
			(unlocked yes)
			(layer "B.SilkS")
			(effects
				(font
					(size 1.905 1.4224)
					(thickness 0.1524)
				)
				(justify left mirror)
			)
		)
		(fp_text user "+"
			(at 2.3622 -0.22225 270)
			(unlocked yes)
			(layer "B.Fab")
			(effects
				(font
					(size 1.905 1.4224)
					(thickness 0.1524)
				)
				(justify left mirror)
			)
		)
		(fp_text user "-"
			(at -1.3716 -0.27305 270)
			(unlocked yes)
			(layer "B.Fab")
			(effects
				(font
					(size 1.905 1.4224)
					(thickness 0.1524)
				)
				(justify left mirror)
			)
		)
		(pad "1" smd rect
			(at 0.612394 0 90)
			(size 0.635 1.016)
			(layers "B.Cu" "B.Mask" "B.Paste")
			(net "P5V_AUX")
		)
		(pad "2" smd rect
			(at -0.612394 0 90)
			(size 0.635 1.016)
			(layers "B.Cu" "B.Mask" "B.Paste")
			(net "CRT_VCC5_2_D")
		)
	)
	(footprint ""
		(layer "B.Cu")
		(at 49.868328 -36.935664 -90)
		(property "Reference" "R151"
			(at 0 0 90)
			(layer "B.SilkS")
			(hide yes)
			(effects
				(font
					(size 1.27 1.27)
				)
				(justify mirror)
			)
		)
		(property "Value" ""
			(at 0 0 90)
			(layer "B.Fab")
			(effects
				(font
					(size 1.27 1.27)
				)
				(justify mirror)
			)
		)
		(duplicate_pad_numbers_are_jumpers no)
		(fp_line
			(start -0.7874 0.4064)
			(end 0.7874 0.4064)
			(stroke
				(width 0.1524)
				(type default)
			)
			(layer "B.SilkS")
		)
		(fp_line
			(start 0.7874 0.4064)
			(end 0.7874 -0.4064)
			(stroke
				(width 0.1524)
				(type default)
			)
			(layer "B.SilkS")
		)
		(fp_line
			(start -0.7874 -0.4064)
			(end -0.7874 0.4064)
			(stroke
				(width 0.1524)
				(type default)
			)
			(layer "B.SilkS")
		)
		(fp_line
			(start 0.7874 -0.4064)
			(end -0.7874 -0.4064)
			(stroke
				(width 0.1524)
				(type default)
			)
			(layer "B.SilkS")
		)
		(fp_line
			(start -0.67945 0.3048)
			(end -0.120396 0.3048)
			(stroke
				(width 0.1)
				(type default)
			)
			(layer "B.Fab")
		)
		(fp_line
			(start -0.120396 0.3048)
			(end -0.120396 0.2794)
			(stroke
				(width 0.1)
				(type default)
			)
			(layer "B.Fab")
		)
		(fp_line
			(start 0.12065 0.3048)
			(end 0.67945 0.3048)
			(stroke
				(width 0.1)
				(type default)
			)
			(layer "B.Fab")
		)
		(fp_line
			(start 0.67945 0.3048)
			(end 0.67945 -0.305054)
			(stroke
				(width 0.1)
				(type default)
			)
			(layer "B.Fab")
		)
		(fp_line
			(start -0.120396 0.2794)
			(end 0.12065 0.2794)
			(stroke
				(width 0.1)
				(type default)
			)
			(layer "B.Fab")
		)
		(fp_line
			(start 0.12065 0.2794)
			(end 0.12065 0.3048)
			(stroke
				(width 0.1)
				(type default)
			)
			(layer "B.Fab")
		)
		(fp_line
			(start -0.12065 -0.2794)
			(end -0.12065 -0.3048)
			(stroke
				(width 0.1)
				(type default)
			)
			(layer "B.Fab")
		)
		(fp_line
			(start 0.12065 -0.2794)
			(end -0.12065 -0.2794)
			(stroke
				(width 0.1)
				(type default)
			)
			(layer "B.Fab")
		)
		(fp_line
			(start -0.67945 -0.3048)
			(end -0.67945 0.3048)
			(stroke
				(width 0.1)
				(type default)
			)
			(layer "B.Fab")
		)
		(fp_line
			(start -0.12065 -0.3048)
			(end -0.67945 -0.3048)
			(stroke
				(width 0.1)
				(type default)
			)
			(layer "B.Fab")
		)
		(fp_line
			(start 0.12065 -0.305054)
			(end 0.12065 -0.2794)
			(stroke
				(width 0.1)
				(type default)
			)
			(layer "B.Fab")
		)
		(fp_line
			(start 0.67945 -0.305054)
			(end 0.12065 -0.305054)
			(stroke
				(width 0.1)
				(type default)
			)
			(layer "B.Fab")
		)
		(pad "1" smd circle
			(at 0.40005 0 90)
			(size 0 0)
			(layers "B.Cu" "B.Mask" "B.Paste")
			(net "SGPIO_DO_1")
		)
		(pad "2" smd circle
			(at -0.40005 0 90)
			(size 0 0)
			(layers "B.Cu" "B.Mask" "B.Paste")
			(net "SGPIO_BMC_M1_DO")
		)
	)
	(footprint ""
		(layer "B.Cu")
		(at 77.598778 -48.63084 -90)
		(property "Reference" "C229"
			(at 0 0 90)
			(layer "B.SilkS")
			(hide yes)
			(effects
				(font
					(size 1.27 1.27)
				)
				(justify mirror)
			)
		)
		(property "Value" ""
			(at 0 0 90)
			(layer "B.Fab")
			(effects
				(font
					(size 1.27 1.27)
				)
				(justify mirror)
			)
		)
		(duplicate_pad_numbers_are_jumpers no)
		(fp_line
			(start -0.7874 0.4064)
			(end 0.7874 0.4064)
			(stroke
				(width 0.1524)
				(type default)
			)
			(layer "B.SilkS")
		)
		(fp_line
			(start 0.7874 0.4064)
			(end 0.7874 -0.4064)
			(stroke
				(width 0.1524)
				(type default)
			)
			(layer "B.SilkS")
		)
		(fp_line
			(start -0.7874 -0.4064)
			(end -0.7874 0.4064)
			(stroke
				(width 0.1524)
				(type default)
			)
			(layer "B.SilkS")
		)
		(fp_line
			(start 0.7874 -0.4064)
			(end -0.7874 -0.4064)
			(stroke
				(width 0.1524)
				(type default)
			)
			(layer "B.SilkS")
		)
		(fp_line
			(start -0.67945 0.3048)
			(end -0.120396 0.3048)
			(stroke
				(width 0.1)
				(type default)
			)
			(layer "B.Fab")
		)
		(fp_line
			(start -0.120396 0.3048)
			(end -0.120396 0.2794)
			(stroke
				(width 0.1)
				(type default)
			)
			(layer "B.Fab")
		)
		(fp_line
			(start 0.12065 0.3048)
			(end 0.67945 0.3048)
			(stroke
				(width 0.1)
				(type default)
			)
			(layer "B.Fab")
		)
		(fp_line
			(start 0.67945 0.3048)
			(end 0.67945 -0.305054)
			(stroke
				(width 0.1)
				(type default)
			)
			(layer "B.Fab")
		)
		(fp_line
			(start -0.120396 0.2794)
			(end 0.12065 0.2794)
			(stroke
				(width 0.1)
				(type default)
			)
			(layer "B.Fab")
		)
		(fp_line
			(start 0.12065 0.2794)
			(end 0.12065 0.3048)
			(stroke
				(width 0.1)
				(type default)
			)
			(layer "B.Fab")
		)
		(fp_line
			(start -0.12065 -0.2794)
			(end -0.12065 -0.3048)
			(stroke
				(width 0.1)
				(type default)
			)
			(layer "B.Fab")
		)
		(fp_line
			(start 0.12065 -0.2794)
			(end -0.12065 -0.2794)
			(stroke
				(width 0.1)
				(type default)
			)
			(layer "B.Fab")
		)
		(fp_line
			(start -0.67945 -0.3048)
			(end -0.67945 0.3048)
			(stroke
				(width 0.1)
				(type default)
			)
			(layer "B.Fab")
		)
		(fp_line
			(start -0.12065 -0.3048)
			(end -0.67945 -0.3048)
			(stroke
				(width 0.1)
				(type default)
			)
			(layer "B.Fab")
		)
		(fp_line
			(start 0.12065 -0.305054)
			(end 0.12065 -0.2794)
			(stroke
				(width 0.1)
				(type default)
			)
			(layer "B.Fab")
		)
		(fp_line
			(start 0.67945 -0.305054)
			(end 0.12065 -0.305054)
			(stroke
				(width 0.1)
				(type default)
			)
			(layer "B.Fab")
		)
		(pad "1" smd circle
			(at 0.40005 0 90)
			(size 0 0)
			(layers "B.Cu" "B.Mask" "B.Paste")
			(net "M_BMC_DDR4_MCLK_C")
		)
		(pad "2" smd circle
			(at -0.40005 0 90)
			(size 0 0)
			(layers "B.Cu" "B.Mask" "B.Paste")
			(net "P1V2_AUX")
		)
	)
	(footprint ""
		(layer "B.Cu")
		(at 71.979282 -62.776608 90)
		(property "Reference" "C128"
			(at 0 0 90)
			(layer "B.SilkS")
			(hide yes)
			(effects
				(font
					(size 1.27 1.27)
				)
				(justify mirror)
			)
		)
		(property "Value" ""
			(at 0 0 90)
			(layer "B.Fab")
			(effects
				(font
					(size 1.27 1.27)
				)
				(justify mirror)
			)
		)
		(duplicate_pad_numbers_are_jumpers no)
		(fp_line
			(start 0.7874 -0.4064)
			(end -0.7874 -0.4064)
			(stroke
				(width 0.1524)
				(type default)
			)
			(layer "B.SilkS")
		)
		(fp_line
			(start -0.7874 -0.4064)
			(end -0.7874 0.4064)
			(stroke
				(width 0.1524)
				(type default)
			)
			(layer "B.SilkS")
		)
		(fp_line
			(start 0.7874 0.4064)
			(end 0.7874 -0.4064)
			(stroke
				(width 0.1524)
				(type default)
			)
			(layer "B.SilkS")
		)
		(fp_line
			(start -0.7874 0.4064)
			(end 0.7874 0.4064)
			(stroke
				(width 0.1524)
				(type default)
			)
			(layer "B.SilkS")
		)
		(fp_line
			(start 0.67945 -0.305054)
			(end 0.12065 -0.305054)
			(stroke
				(width 0.1)
				(type default)
			)
			(layer "B.Fab")
		)
		(fp_line
			(start 0.12065 -0.305054)
			(end 0.12065 -0.2794)
			(stroke
				(width 0.1)
				(type default)
			)
			(layer "B.Fab")
		)
		(fp_line
			(start -0.12065 -0.3048)
			(end -0.67945 -0.3048)
			(stroke
				(width 0.1)
				(type default)
			)
			(layer "B.Fab")
		)
		(fp_line
			(start -0.67945 -0.3048)
			(end -0.67945 0.3048)
			(stroke
				(width 0.1)
				(type default)
			)
			(layer "B.Fab")
		)
		(fp_line
			(start 0.12065 -0.2794)
			(end -0.12065 -0.2794)
			(stroke
				(width 0.1)
				(type default)
			)
			(layer "B.Fab")
		)
		(fp_line
			(start -0.12065 -0.2794)
			(end -0.12065 -0.3048)
			(stroke
				(width 0.1)
				(type default)
			)
			(layer "B.Fab")
		)
		(fp_line
			(start 0.12065 0.2794)
			(end 0.12065 0.3048)
			(stroke
				(width 0.1)
				(type default)
			)
			(layer "B.Fab")
		)
		(fp_line
			(start -0.120396 0.2794)
			(end 0.12065 0.2794)
			(stroke
				(width 0.1)
				(type default)
			)
			(layer "B.Fab")
		)
		(fp_line
			(start 0.67945 0.3048)
			(end 0.67945 -0.305054)
			(stroke
				(width 0.1)
				(type default)
			)
			(layer "B.Fab")
		)
		(fp_line
			(start 0.12065 0.3048)
			(end 0.67945 0.3048)
			(stroke
				(width 0.1)
				(type default)
			)
			(layer "B.Fab")
		)
		(fp_line
			(start -0.120396 0.3048)
			(end -0.120396 0.2794)
			(stroke
				(width 0.1)
				(type default)
			)
			(layer "B.Fab")
		)
		(fp_line
			(start -0.67945 0.3048)
			(end -0.120396 0.3048)
			(stroke
				(width 0.1)
				(type default)
			)
			(layer "B.Fab")
		)
		(pad "1" smd circle
			(at 0.40005 0 270)
			(size 0 0)
			(layers "B.Cu" "B.Mask" "B.Paste")
			(net "P1V8_STBY_DP_VCC18A")
		)
		(pad "2" smd circle
			(at -0.40005 0 270)
			(size 0 0)
			(layers "B.Cu" "B.Mask" "B.Paste")
			(net "GND")
		)
	)
	(footprint ""
		(layer "B.Cu")
		(at 40.0304 -106.3752 -90)
		(property "Reference" "R228"
			(at 0 0 90)
			(layer "B.SilkS")
			(hide yes)
			(effects
				(font
					(size 1.27 1.27)
				)
				(justify mirror)
			)
		)
		(property "Value" ""
			(at 0 0 90)
			(layer "B.Fab")
			(effects
				(font
					(size 1.27 1.27)
				)
				(justify mirror)
			)
		)
		(duplicate_pad_numbers_are_jumpers no)
		(fp_line
			(start -0.7874 0.4064)
			(end 0.7874 0.4064)
			(stroke
				(width 0.1524)
				(type default)
			)
			(layer "B.SilkS")
		)
		(fp_line
			(start 0.7874 0.4064)
			(end 0.7874 -0.4064)
			(stroke
				(width 0.1524)
				(type default)
			)
			(layer "B.SilkS")
		)
		(fp_line
			(start -0.7874 -0.4064)
			(end -0.7874 0.4064)
			(stroke
				(width 0.1524)
				(type default)
			)
			(layer "B.SilkS")
		)
		(fp_line
			(start 0.7874 -0.4064)
			(end -0.7874 -0.4064)
			(stroke
				(width 0.1524)
				(type default)
			)
			(layer "B.SilkS")
		)
		(fp_line
			(start -0.67945 0.3048)
			(end -0.120396 0.3048)
			(stroke
				(width 0.1)
				(type default)
			)
			(layer "B.Fab")
		)
		(fp_line
			(start -0.120396 0.3048)
			(end -0.120396 0.2794)
			(stroke
				(width 0.1)
				(type default)
			)
			(layer "B.Fab")
		)
		(fp_line
			(start 0.12065 0.3048)
			(end 0.67945 0.3048)
			(stroke
				(width 0.1)
				(type default)
			)
			(layer "B.Fab")
		)
		(fp_line
			(start 0.67945 0.3048)
			(end 0.67945 -0.305054)
			(stroke
				(width 0.1)
				(type default)
			)
			(layer "B.Fab")
		)
		(fp_line
			(start -0.120396 0.2794)
			(end 0.12065 0.2794)
			(stroke
				(width 0.1)
				(type default)
			)
			(layer "B.Fab")
		)
		(fp_line
			(start 0.12065 0.2794)
			(end 0.12065 0.3048)
			(stroke
				(width 0.1)
				(type default)
			)
			(layer "B.Fab")
		)
		(fp_line
			(start -0.12065 -0.2794)
			(end -0.12065 -0.3048)
			(stroke
				(width 0.1)
				(type default)
			)
			(layer "B.Fab")
		)
		(fp_line
			(start 0.12065 -0.2794)
			(end -0.12065 -0.2794)
			(stroke
				(width 0.1)
				(type default)
			)
			(layer "B.Fab")
		)
		(fp_line
			(start -0.67945 -0.3048)
			(end -0.67945 0.3048)
			(stroke
				(width 0.1)
				(type default)
			)
			(layer "B.Fab")
		)
		(fp_line
			(start -0.12065 -0.3048)
			(end -0.67945 -0.3048)
			(stroke
				(width 0.1)
				(type default)
			)
			(layer "B.Fab")
		)
		(fp_line
			(start 0.12065 -0.305054)
			(end 0.12065 -0.2794)
			(stroke
				(width 0.1)
				(type default)
			)
			(layer "B.Fab")
		)
		(fp_line
			(start 0.67945 -0.305054)
			(end 0.12065 -0.305054)
			(stroke
				(width 0.1)
				(type default)
			)
			(layer "B.Fab")
		)
		(pad "1" smd circle
			(at 0.40005 0 90)
			(size 0 0)
			(layers "B.Cu" "B.Mask" "B.Paste")
			(net "GND")
		)
		(pad "2" smd circle
			(at -0.40005 0 90)
			(size 0 0)
			(layers "B.Cu" "B.Mask" "B.Paste")
			(net "JTAG_MB_TCK")
		)
	)
	(footprint ""
		(layer "B.Cu")
		(at 82.108294 -52.746656 180)
		(property "Reference" "C169"
			(at 0 0 0)
			(layer "B.SilkS")
			(hide yes)
			(effects
				(font
					(size 1.27 1.27)
				)
				(justify mirror)
			)
		)
		(property "Value" ""
			(at 0 0 0)
			(layer "B.Fab")
			(effects
				(font
					(size 1.27 1.27)
				)
				(justify mirror)
			)
		)
		(duplicate_pad_numbers_are_jumpers no)
		(fp_line
			(start 0.7874 0.4064)
			(end 0.7874 -0.4064)
			(stroke
				(width 0.1524)
				(type default)
			)
			(layer "B.SilkS")
		)
		(fp_line
			(start 0.7874 -0.4064)
			(end -0.7874 -0.4064)
			(stroke
				(width 0.1524)
				(type default)
			)
			(layer "B.SilkS")
		)
		(fp_line
			(start -0.7874 0.4064)
			(end 0.7874 0.4064)
			(stroke
				(width 0.1524)
				(type default)
			)
			(layer "B.SilkS")
		)
		(fp_line
			(start -0.7874 -0.4064)
			(end -0.7874 0.4064)
			(stroke
				(width 0.1524)
				(type default)
			)
			(layer "B.SilkS")
		)
		(fp_line
			(start 0.67945 0.3048)
			(end 0.67945 -0.305054)
			(stroke
				(width 0.1)
				(type default)
			)
			(layer "B.Fab")
		)
		(fp_line
			(start 0.67945 -0.305054)
			(end 0.12065 -0.305054)
			(stroke
				(width 0.1)
				(type default)
			)
			(layer "B.Fab")
		)
		(fp_line
			(start 0.12065 0.3048)
			(end 0.67945 0.3048)
			(stroke
				(width 0.1)
				(type default)
			)
			(layer "B.Fab")
		)
		(fp_line
			(start 0.12065 0.2794)
			(end 0.12065 0.3048)
			(stroke
				(width 0.1)
				(type default)
			)
			(layer "B.Fab")
		)
		(fp_line
			(start 0.12065 -0.2794)
			(end -0.12065 -0.2794)
			(stroke
				(width 0.1)
				(type default)
			)
			(layer "B.Fab")
		)
		(fp_line
			(start 0.12065 -0.305054)
			(end 0.12065 -0.2794)
			(stroke
				(width 0.1)
				(type default)
			)
			(layer "B.Fab")
		)
		(fp_line
			(start -0.120396 0.3048)
			(end -0.120396 0.2794)
			(stroke
				(width 0.1)
				(type default)
			)
			(layer "B.Fab")
		)
		(fp_line
			(start -0.120396 0.2794)
			(end 0.12065 0.2794)
			(stroke
				(width 0.1)
				(type default)
			)
			(layer "B.Fab")
		)
		(fp_line
			(start -0.12065 -0.2794)
			(end -0.12065 -0.3048)
			(stroke
				(width 0.1)
				(type default)
			)
			(layer "B.Fab")
		)
		(fp_line
			(start -0.12065 -0.3048)
			(end -0.67945 -0.3048)
			(stroke
				(width 0.1)
				(type default)
			)
			(layer "B.Fab")
		)
		(fp_line
			(start -0.67945 0.3048)
			(end -0.120396 0.3048)
			(stroke
				(width 0.1)
				(type default)
			)
			(layer "B.Fab")
		)
		(fp_line
			(start -0.67945 -0.3048)
			(end -0.67945 0.3048)
			(stroke
				(width 0.1)
				(type default)
			)
			(layer "B.Fab")
		)
		(pad "1" smd circle
			(at 0.40005 0)
			(size 0 0)
			(layers "B.Cu" "B.Mask" "B.Paste")
			(net "P1V2_AUX")
		)
		(pad "2" smd circle
			(at -0.40005 0)
			(size 0 0)
			(layers "B.Cu" "B.Mask" "B.Paste")
			(net "P0V6_DDR_VREF_AUX")
		)
	)
	(footprint ""
		(layer "B.Cu")
		(at 52.27574 -69.397372 -90)
		(property "Reference" "C299"
			(at 0 0 90)
			(layer "B.SilkS")
			(hide yes)
			(effects
				(font
					(size 1.27 1.27)
				)
				(justify mirror)
			)
		)
		(property "Value" ""
			(at 0 0 90)
			(layer "B.Fab")
			(effects
				(font
					(size 1.27 1.27)
				)
				(justify mirror)
			)
		)
		(duplicate_pad_numbers_are_jumpers no)
		(fp_line
			(start -0.7874 0.4064)
			(end 0.7874 0.4064)
			(stroke
				(width 0.1524)
				(type default)
			)
			(layer "B.SilkS")
		)
		(fp_line
			(start 0.7874 0.4064)
			(end 0.7874 -0.4064)
			(stroke
				(width 0.1524)
				(type default)
			)
			(layer "B.SilkS")
		)
		(fp_line
			(start -0.7874 -0.4064)
			(end -0.7874 0.4064)
			(stroke
				(width 0.1524)
				(type default)
			)
			(layer "B.SilkS")
		)
		(fp_line
			(start 0.7874 -0.4064)
			(end -0.7874 -0.4064)
			(stroke
				(width 0.1524)
				(type default)
			)
			(layer "B.SilkS")
		)
		(fp_line
			(start -0.67945 0.3048)
			(end -0.120396 0.3048)
			(stroke
				(width 0.1)
				(type default)
			)
			(layer "B.Fab")
		)
		(fp_line
			(start -0.120396 0.3048)
			(end -0.120396 0.2794)
			(stroke
				(width 0.1)
				(type default)
			)
			(layer "B.Fab")
		)
		(fp_line
			(start 0.12065 0.3048)
			(end 0.67945 0.3048)
			(stroke
				(width 0.1)
				(type default)
			)
			(layer "B.Fab")
		)
		(fp_line
			(start 0.67945 0.3048)
			(end 0.67945 -0.305054)
			(stroke
				(width 0.1)
				(type default)
			)
			(layer "B.Fab")
		)
		(fp_line
			(start -0.120396 0.2794)
			(end 0.12065 0.2794)
			(stroke
				(width 0.1)
				(type default)
			)
			(layer "B.Fab")
		)
		(fp_line
			(start 0.12065 0.2794)
			(end 0.12065 0.3048)
			(stroke
				(width 0.1)
				(type default)
			)
			(layer "B.Fab")
		)
		(fp_line
			(start -0.12065 -0.2794)
			(end -0.12065 -0.3048)
			(stroke
				(width 0.1)
				(type default)
			)
			(layer "B.Fab")
		)
		(fp_line
			(start 0.12065 -0.2794)
			(end -0.12065 -0.2794)
			(stroke
				(width 0.1)
				(type default)
			)
			(layer "B.Fab")
		)
		(fp_line
			(start -0.67945 -0.3048)
			(end -0.67945 0.3048)
			(stroke
				(width 0.1)
				(type default)
			)
			(layer "B.Fab")
		)
		(fp_line
			(start -0.12065 -0.3048)
			(end -0.67945 -0.3048)
			(stroke
				(width 0.1)
				(type default)
			)
			(layer "B.Fab")
		)
		(fp_line
			(start 0.12065 -0.305054)
			(end 0.12065 -0.2794)
			(stroke
				(width 0.1)
				(type default)
			)
			(layer "B.Fab")
		)
		(fp_line
			(start 0.67945 -0.305054)
			(end 0.12065 -0.305054)
			(stroke
				(width 0.1)
				(type default)
			)
			(layer "B.Fab")
		)
		(pad "1" smd circle
			(at 0.40005 0 90)
			(size 0 0)
			(layers "B.Cu" "B.Mask" "B.Paste")
			(net "P3V3_SENSOR")
		)
		(pad "2" smd circle
			(at -0.40005 0 90)
			(size 0 0)
			(layers "B.Cu" "B.Mask" "B.Paste")
			(net "GND")
		)
	)
	(footprint ""
		(layer "B.Cu")
		(at 52.701444 -47.617126 -90)
		(property "Reference" "C91"
			(at 0 0 90)
			(layer "B.SilkS")
			(hide yes)
			(effects
				(font
					(size 1.27 1.27)
				)
				(justify mirror)
			)
		)
		(property "Value" ""
			(at 0 0 90)
			(layer "B.Fab")
			(effects
				(font
					(size 1.27 1.27)
				)
				(justify mirror)
			)
		)
		(duplicate_pad_numbers_are_jumpers no)
		(fp_line
			(start -0.7874 0.4064)
			(end 0.7874 0.4064)
			(stroke
				(width 0.1524)
				(type default)
			)
			(layer "B.SilkS")
		)
		(fp_line
			(start 0.7874 0.4064)
			(end 0.7874 -0.4064)
			(stroke
				(width 0.1524)
				(type default)
			)
			(layer "B.SilkS")
		)
		(fp_line
			(start -0.7874 -0.4064)
			(end -0.7874 0.4064)
			(stroke
				(width 0.1524)
				(type default)
			)
			(layer "B.SilkS")
		)
		(fp_line
			(start 0.7874 -0.4064)
			(end -0.7874 -0.4064)
			(stroke
				(width 0.1524)
				(type default)
			)
			(layer "B.SilkS")
		)
		(fp_line
			(start -0.67945 0.3048)
			(end -0.120396 0.3048)
			(stroke
				(width 0.1)
				(type default)
			)
			(layer "B.Fab")
		)
		(fp_line
			(start -0.120396 0.3048)
			(end -0.120396 0.2794)
			(stroke
				(width 0.1)
				(type default)
			)
			(layer "B.Fab")
		)
		(fp_line
			(start 0.12065 0.3048)
			(end 0.67945 0.3048)
			(stroke
				(width 0.1)
				(type default)
			)
			(layer "B.Fab")
		)
		(fp_line
			(start 0.67945 0.3048)
			(end 0.67945 -0.305054)
			(stroke
				(width 0.1)
				(type default)
			)
			(layer "B.Fab")
		)
		(fp_line
			(start -0.120396 0.2794)
			(end 0.12065 0.2794)
			(stroke
				(width 0.1)
				(type default)
			)
			(layer "B.Fab")
		)
		(fp_line
			(start 0.12065 0.2794)
			(end 0.12065 0.3048)
			(stroke
				(width 0.1)
				(type default)
			)
			(layer "B.Fab")
		)
		(fp_line
			(start -0.12065 -0.2794)
			(end -0.12065 -0.3048)
			(stroke
				(width 0.1)
				(type default)
			)
			(layer "B.Fab")
		)
		(fp_line
			(start 0.12065 -0.2794)
			(end -0.12065 -0.2794)
			(stroke
				(width 0.1)
				(type default)
			)
			(layer "B.Fab")
		)
		(fp_line
			(start -0.67945 -0.3048)
			(end -0.67945 0.3048)
			(stroke
				(width 0.1)
				(type default)
			)
			(layer "B.Fab")
		)
		(fp_line
			(start -0.12065 -0.3048)
			(end -0.67945 -0.3048)
			(stroke
				(width 0.1)
				(type default)
			)
			(layer "B.Fab")
		)
		(fp_line
			(start 0.12065 -0.305054)
			(end 0.12065 -0.2794)
			(stroke
				(width 0.1)
				(type default)
			)
			(layer "B.Fab")
		)
		(fp_line
			(start 0.67945 -0.305054)
			(end 0.12065 -0.305054)
			(stroke
				(width 0.1)
				(type default)
			)
			(layer "B.Fab")
		)
		(pad "1" smd circle
			(at 0.40005 0 90)
			(size 0 0)
			(layers "B.Cu" "B.Mask" "B.Paste")
			(net "P1V2_AUX")
		)
		(pad "2" smd circle
			(at -0.40005 0 90)
			(size 0 0)
			(layers "B.Cu" "B.Mask" "B.Paste")
			(net "GND")
		)
	)
	(footprint ""
		(layer "B.Cu")
		(at 37.311076 -38.822376 180)
		(property "Reference" "R207"
			(at 0 0 0)
			(layer "B.SilkS")
			(hide yes)
			(effects
				(font
					(size 1.27 1.27)
				)
				(justify mirror)
			)
		)
		(property "Value" ""
			(at 0 0 0)
			(layer "B.Fab")
			(effects
				(font
					(size 1.27 1.27)
				)
				(justify mirror)
			)
		)
		(duplicate_pad_numbers_are_jumpers no)
		(fp_line
			(start 0.7874 0.4064)
			(end 0.7874 -0.4064)
			(stroke
				(width 0.1524)
				(type default)
			)
			(layer "B.SilkS")
		)
		(fp_line
			(start 0.7874 -0.4064)
			(end -0.7874 -0.4064)
			(stroke
				(width 0.1524)
				(type default)
			)
			(layer "B.SilkS")
		)
		(fp_line
			(start -0.7874 0.4064)
			(end 0.7874 0.4064)
			(stroke
				(width 0.1524)
				(type default)
			)
			(layer "B.SilkS")
		)
		(fp_line
			(start -0.7874 -0.4064)
			(end -0.7874 0.4064)
			(stroke
				(width 0.1524)
				(type default)
			)
			(layer "B.SilkS")
		)
		(fp_line
			(start 0.67945 0.3048)
			(end 0.67945 -0.305054)
			(stroke
				(width 0.1)
				(type default)
			)
			(layer "B.Fab")
		)
		(fp_line
			(start 0.67945 -0.305054)
			(end 0.12065 -0.305054)
			(stroke
				(width 0.1)
				(type default)
			)
			(layer "B.Fab")
		)
		(fp_line
			(start 0.12065 0.3048)
			(end 0.67945 0.3048)
			(stroke
				(width 0.1)
				(type default)
			)
			(layer "B.Fab")
		)
		(fp_line
			(start 0.12065 0.2794)
			(end 0.12065 0.3048)
			(stroke
				(width 0.1)
				(type default)
			)
			(layer "B.Fab")
		)
		(fp_line
			(start 0.12065 -0.2794)
			(end -0.12065 -0.2794)
			(stroke
				(width 0.1)
				(type default)
			)
			(layer "B.Fab")
		)
		(fp_line
			(start 0.12065 -0.305054)
			(end 0.12065 -0.2794)
			(stroke
				(width 0.1)
				(type default)
			)
			(layer "B.Fab")
		)
		(fp_line
			(start -0.120396 0.3048)
			(end -0.120396 0.2794)
			(stroke
				(width 0.1)
				(type default)
			)
			(layer "B.Fab")
		)
		(fp_line
			(start -0.120396 0.2794)
			(end 0.12065 0.2794)
			(stroke
				(width 0.1)
				(type default)
			)
			(layer "B.Fab")
		)
		(fp_line
			(start -0.12065 -0.2794)
			(end -0.12065 -0.3048)
			(stroke
				(width 0.1)
				(type default)
			)
			(layer "B.Fab")
		)
		(fp_line
			(start -0.12065 -0.3048)
			(end -0.67945 -0.3048)
			(stroke
				(width 0.1)
				(type default)
			)
			(layer "B.Fab")
		)
		(fp_line
			(start -0.67945 0.3048)
			(end -0.120396 0.3048)
			(stroke
				(width 0.1)
				(type default)
			)
			(layer "B.Fab")
		)
		(fp_line
			(start -0.67945 -0.3048)
			(end -0.67945 0.3048)
			(stroke
				(width 0.1)
				(type default)
			)
			(layer "B.Fab")
		)
		(pad "1" smd circle
			(at 0.40005 0)
			(size 0 0)
			(layers "B.Cu" "B.Mask" "B.Paste")
			(net "P3V3_AUX")
		)
		(pad "2" smd circle
			(at -0.40005 0)
			(size 0 0)
			(layers "B.Cu" "B.Mask" "B.Paste")
			(net "P3V3_P1V8_SD1VDD")
		)
	)
	(footprint ""
		(layer "B.Cu")
		(at 46.96206 -61.97981 90)
		(property "Reference" "C136"
			(at 0 0 90)
			(layer "B.SilkS")
			(hide yes)
			(effects
				(font
					(size 1.27 1.27)
				)
				(justify mirror)
			)
		)
		(property "Value" ""
			(at 0 0 90)
			(layer "B.Fab")
			(effects
				(font
					(size 1.27 1.27)
				)
				(justify mirror)
			)
		)
		(duplicate_pad_numbers_are_jumpers no)
		(fp_line
			(start 0.7874 -0.4064)
			(end -0.7874 -0.4064)
			(stroke
				(width 0.1524)
				(type default)
			)
			(layer "B.SilkS")
		)
		(fp_line
			(start -0.7874 -0.4064)
			(end -0.7874 0.4064)
			(stroke
				(width 0.1524)
				(type default)
			)
			(layer "B.SilkS")
		)
		(fp_line
			(start 0.7874 0.4064)
			(end 0.7874 -0.4064)
			(stroke
				(width 0.1524)
				(type default)
			)
			(layer "B.SilkS")
		)
		(fp_line
			(start -0.7874 0.4064)
			(end 0.7874 0.4064)
			(stroke
				(width 0.1524)
				(type default)
			)
			(layer "B.SilkS")
		)
		(fp_line
			(start 0.67945 -0.305054)
			(end 0.12065 -0.305054)
			(stroke
				(width 0.1)
				(type default)
			)
			(layer "B.Fab")
		)
		(fp_line
			(start 0.12065 -0.305054)
			(end 0.12065 -0.2794)
			(stroke
				(width 0.1)
				(type default)
			)
			(layer "B.Fab")
		)
		(fp_line
			(start -0.12065 -0.3048)
			(end -0.67945 -0.3048)
			(stroke
				(width 0.1)
				(type default)
			)
			(layer "B.Fab")
		)
		(fp_line
			(start -0.67945 -0.3048)
			(end -0.67945 0.3048)
			(stroke
				(width 0.1)
				(type default)
			)
			(layer "B.Fab")
		)
		(fp_line
			(start 0.12065 -0.2794)
			(end -0.12065 -0.2794)
			(stroke
				(width 0.1)
				(type default)
			)
			(layer "B.Fab")
		)
		(fp_line
			(start -0.12065 -0.2794)
			(end -0.12065 -0.3048)
			(stroke
				(width 0.1)
				(type default)
			)
			(layer "B.Fab")
		)
		(fp_line
			(start 0.12065 0.2794)
			(end 0.12065 0.3048)
			(stroke
				(width 0.1)
				(type default)
			)
			(layer "B.Fab")
		)
		(fp_line
			(start -0.120396 0.2794)
			(end 0.12065 0.2794)
			(stroke
				(width 0.1)
				(type default)
			)
			(layer "B.Fab")
		)
		(fp_line
			(start 0.67945 0.3048)
			(end 0.67945 -0.305054)
			(stroke
				(width 0.1)
				(type default)
			)
			(layer "B.Fab")
		)
		(fp_line
			(start 0.12065 0.3048)
			(end 0.67945 0.3048)
			(stroke
				(width 0.1)
				(type default)
			)
			(layer "B.Fab")
		)
		(fp_line
			(start -0.120396 0.3048)
			(end -0.120396 0.2794)
			(stroke
				(width 0.1)
				(type default)
			)
			(layer "B.Fab")
		)
		(fp_line
			(start -0.67945 0.3048)
			(end -0.120396 0.3048)
			(stroke
				(width 0.1)
				(type default)
			)
			(layer "B.Fab")
		)
		(pad "1" smd circle
			(at 0.40005 0 270)
			(size 0 0)
			(layers "B.Cu" "B.Mask" "B.Paste")
			(net "GND")
		)
		(pad "2" smd circle
			(at -0.40005 0 270)
			(size 0 0)
			(layers "B.Cu" "B.Mask" "B.Paste")
			(net "A_BMC_ADCVREFP0")
		)
	)
	(footprint ""
		(layer "B.Cu")
		(at 84.452968 -99.238054 180)
		(property "Reference" "C248"
			(at 0 0 0)
			(layer "B.SilkS")
			(hide yes)
			(effects
				(font
					(size 1.27 1.27)
				)
				(justify mirror)
			)
		)
		(property "Value" ""
			(at 0 0 0)
			(layer "B.Fab")
			(effects
				(font
					(size 1.27 1.27)
				)
				(justify mirror)
			)
		)
		(duplicate_pad_numbers_are_jumpers no)
		(fp_line
			(start 0.7874 0.4064)
			(end 0.7874 -0.4064)
			(stroke
				(width 0.1524)
				(type default)
			)
			(layer "B.SilkS")
		)
		(fp_line
			(start 0.7874 -0.4064)
			(end -0.7874 -0.4064)
			(stroke
				(width 0.1524)
				(type default)
			)
			(layer "B.SilkS")
		)
		(fp_line
			(start -0.7874 0.4064)
			(end 0.7874 0.4064)
			(stroke
				(width 0.1524)
				(type default)
			)
			(layer "B.SilkS")
		)
		(fp_line
			(start -0.7874 -0.4064)
			(end -0.7874 0.4064)
			(stroke
				(width 0.1524)
				(type default)
			)
			(layer "B.SilkS")
		)
		(fp_line
			(start 0.67945 0.3048)
			(end 0.67945 -0.305054)
			(stroke
				(width 0.1)
				(type default)
			)
			(layer "B.Fab")
		)
		(fp_line
			(start 0.67945 -0.305054)
			(end 0.12065 -0.305054)
			(stroke
				(width 0.1)
				(type default)
			)
			(layer "B.Fab")
		)
		(fp_line
			(start 0.12065 0.3048)
			(end 0.67945 0.3048)
			(stroke
				(width 0.1)
				(type default)
			)
			(layer "B.Fab")
		)
		(fp_line
			(start 0.12065 0.2794)
			(end 0.12065 0.3048)
			(stroke
				(width 0.1)
				(type default)
			)
			(layer "B.Fab")
		)
		(fp_line
			(start 0.12065 -0.2794)
			(end -0.12065 -0.2794)
			(stroke
				(width 0.1)
				(type default)
			)
			(layer "B.Fab")
		)
		(fp_line
			(start 0.12065 -0.305054)
			(end 0.12065 -0.2794)
			(stroke
				(width 0.1)
				(type default)
			)
			(layer "B.Fab")
		)
		(fp_line
			(start -0.120396 0.3048)
			(end -0.120396 0.2794)
			(stroke
				(width 0.1)
				(type default)
			)
			(layer "B.Fab")
		)
		(fp_line
			(start -0.120396 0.2794)
			(end 0.12065 0.2794)
			(stroke
				(width 0.1)
				(type default)
			)
			(layer "B.Fab")
		)
		(fp_line
			(start -0.12065 -0.2794)
			(end -0.12065 -0.3048)
			(stroke
				(width 0.1)
				(type default)
			)
			(layer "B.Fab")
		)
		(fp_line
			(start -0.12065 -0.3048)
			(end -0.67945 -0.3048)
			(stroke
				(width 0.1)
				(type default)
			)
			(layer "B.Fab")
		)
		(fp_line
			(start -0.67945 0.3048)
			(end -0.120396 0.3048)
			(stroke
				(width 0.1)
				(type default)
			)
			(layer "B.Fab")
		)
		(fp_line
			(start -0.67945 -0.3048)
			(end -0.67945 0.3048)
			(stroke
				(width 0.1)
				(type default)
			)
			(layer "B.Fab")
		)
		(pad "1" smd circle
			(at 0.40005 0)
			(size 0 0)
			(layers "B.Cu" "B.Mask" "B.Paste")
			(net "P3V3_AUX")
		)
		(pad "2" smd circle
			(at -0.40005 0)
			(size 0 0)
			(layers "B.Cu" "B.Mask" "B.Paste")
			(net "GND")
		)
	)
	(footprint ""
		(layer "B.Cu")
		(at 54.880764 -52.938934 90)
		(property "Reference" "C121"
			(at 0 0 90)
			(layer "B.SilkS")
			(hide yes)
			(effects
				(font
					(size 1.27 1.27)
				)
				(justify mirror)
			)
		)
		(property "Value" ""
			(at 0 0 90)
			(layer "B.Fab")
			(effects
				(font
					(size 1.27 1.27)
				)
				(justify mirror)
			)
		)
		(duplicate_pad_numbers_are_jumpers no)
		(fp_line
			(start 1.2954 -0.5842)
			(end -1.2954 -0.5842)
			(stroke
				(width 0.1524)
				(type default)
			)
			(layer "B.SilkS")
		)
		(fp_line
			(start 0 -0.5842)
			(end 0 0.5842)
			(stroke
				(width 0.1524)
				(type default)
			)
			(layer "B.SilkS")
		)
		(fp_line
			(start -1.2954 -0.5842)
			(end -1.2954 0.5842)
			(stroke
				(width 0.1524)
				(type default)
			)
			(layer "B.SilkS")
		)
		(fp_line
			(start 1.2954 0.5842)
			(end 1.2954 -0.5842)
			(stroke
				(width 0.1524)
				(type default)
			)
			(layer "B.SilkS")
		)
		(fp_line
			(start -1.2954 0.5842)
			(end 1.2954 0.5842)
			(stroke
				(width 0.1524)
				(type default)
			)
			(layer "B.SilkS")
		)
		(fp_line
			(start 0.8636 -0.4572)
			(end -0.8636 -0.4572)
			(stroke
				(width 0.1)
				(type default)
			)
			(layer "B.Fab")
		)
		(fp_line
			(start -0.8636 -0.4572)
			(end -0.8636 -0.4064)
			(stroke
				(width 0.1)
				(type default)
			)
			(layer "B.Fab")
		)
		(fp_line
			(start 1.1938 -0.4064)
			(end 0.8636 -0.4064)
			(stroke
				(width 0.1)
				(type default)
			)
			(layer "B.Fab")
		)
		(fp_line
			(start 0.8636 -0.4064)
			(end 0.8636 -0.4572)
			(stroke
				(width 0.1)
				(type default)
			)
			(layer "B.Fab")
		)
		(fp_line
			(start -0.8636 -0.4064)
			(end -1.1938 -0.4064)
			(stroke
				(width 0.1)
				(type default)
			)
			(layer "B.Fab")
		)
		(fp_line
			(start -1.1938 -0.4064)
			(end -1.1938 0.4064)
			(stroke
				(width 0.1)
				(type default)
			)
			(layer "B.Fab")
		)
		(fp_line
			(start 1.1938 0.4064)
			(end 1.1938 -0.4064)
			(stroke
				(width 0.1)
				(type default)
			)
			(layer "B.Fab")
		)
		(fp_line
			(start 0.8636 0.4064)
			(end 1.1938 0.4064)
			(stroke
				(width 0.1)
				(type default)
			)
			(layer "B.Fab")
		)
		(fp_line
			(start -0.8636 0.4064)
			(end -0.8636 0.4572)
			(stroke
				(width 0.1)
				(type default)
			)
			(layer "B.Fab")
		)
		(fp_line
			(start -1.1938 0.4064)
			(end -0.8636 0.4064)
			(stroke
				(width 0.1)
				(type default)
			)
			(layer "B.Fab")
		)
		(fp_line
			(start 0.8636 0.4572)
			(end 0.8636 0.4064)
			(stroke
				(width 0.1)
				(type default)
			)
			(layer "B.Fab")
		)
		(fp_line
			(start -0.8636 0.4572)
			(end 0.8636 0.4572)
			(stroke
				(width 0.1)
				(type default)
			)
			(layer "B.Fab")
		)
		(pad "1" smd rect
			(at 0.7366 0)
			(size 0.7112 0.8128)
			(layers "B.Cu" "B.Mask" "B.Paste")
			(net "P1V8_AUX")
		)
		(pad "2" smd rect
			(at -0.7366 0)
			(size 0.7112 0.8128)
			(layers "B.Cu" "B.Mask" "B.Paste")
			(net "GND")
		)
	)
	(footprint ""
		(layer "B.Cu")
		(at 71.73976 -37.271706 -90)
		(property "Reference" "C127"
			(at 0 0 90)
			(layer "B.SilkS")
			(hide yes)
			(effects
				(font
					(size 1.27 1.27)
				)
				(justify mirror)
			)
		)
		(property "Value" ""
			(at 0 0 90)
			(layer "B.Fab")
			(effects
				(font
					(size 1.27 1.27)
				)
				(justify mirror)
			)
		)
		(duplicate_pad_numbers_are_jumpers no)
		(fp_line
			(start -0.7874 0.4064)
			(end 0.7874 0.4064)
			(stroke
				(width 0.1524)
				(type default)
			)
			(layer "B.SilkS")
		)
		(fp_line
			(start 0.7874 0.4064)
			(end 0.7874 -0.4064)
			(stroke
				(width 0.1524)
				(type default)
			)
			(layer "B.SilkS")
		)
		(fp_line
			(start -0.7874 -0.4064)
			(end -0.7874 0.4064)
			(stroke
				(width 0.1524)
				(type default)
			)
			(layer "B.SilkS")
		)
		(fp_line
			(start 0.7874 -0.4064)
			(end -0.7874 -0.4064)
			(stroke
				(width 0.1524)
				(type default)
			)
			(layer "B.SilkS")
		)
		(fp_line
			(start -0.67945 0.3048)
			(end -0.120396 0.3048)
			(stroke
				(width 0.1)
				(type default)
			)
			(layer "B.Fab")
		)
		(fp_line
			(start -0.120396 0.3048)
			(end -0.120396 0.2794)
			(stroke
				(width 0.1)
				(type default)
			)
			(layer "B.Fab")
		)
		(fp_line
			(start 0.12065 0.3048)
			(end 0.67945 0.3048)
			(stroke
				(width 0.1)
				(type default)
			)
			(layer "B.Fab")
		)
		(fp_line
			(start 0.67945 0.3048)
			(end 0.67945 -0.305054)
			(stroke
				(width 0.1)
				(type default)
			)
			(layer "B.Fab")
		)
		(fp_line
			(start -0.120396 0.2794)
			(end 0.12065 0.2794)
			(stroke
				(width 0.1)
				(type default)
			)
			(layer "B.Fab")
		)
		(fp_line
			(start 0.12065 0.2794)
			(end 0.12065 0.3048)
			(stroke
				(width 0.1)
				(type default)
			)
			(layer "B.Fab")
		)
		(fp_line
			(start -0.12065 -0.2794)
			(end -0.12065 -0.3048)
			(stroke
				(width 0.1)
				(type default)
			)
			(layer "B.Fab")
		)
		(fp_line
			(start 0.12065 -0.2794)
			(end -0.12065 -0.2794)
			(stroke
				(width 0.1)
				(type default)
			)
			(layer "B.Fab")
		)
		(fp_line
			(start -0.67945 -0.3048)
			(end -0.67945 0.3048)
			(stroke
				(width 0.1)
				(type default)
			)
			(layer "B.Fab")
		)
		(fp_line
			(start -0.12065 -0.3048)
			(end -0.67945 -0.3048)
			(stroke
				(width 0.1)
				(type default)
			)
			(layer "B.Fab")
		)
		(fp_line
			(start 0.12065 -0.305054)
			(end 0.12065 -0.2794)
			(stroke
				(width 0.1)
				(type default)
			)
			(layer "B.Fab")
		)
		(fp_line
			(start 0.67945 -0.305054)
			(end 0.12065 -0.305054)
			(stroke
				(width 0.1)
				(type default)
			)
			(layer "B.Fab")
		)
		(pad "1" smd circle
			(at 0.40005 0 90)
			(size 0 0)
			(layers "B.Cu" "B.Mask" "B.Paste")
			(net "P1V2_AUX")
		)
		(pad "2" smd circle
			(at -0.40005 0 90)
			(size 0 0)
			(layers "B.Cu" "B.Mask" "B.Paste")
			(net "GND")
		)
	)
	(footprint ""
		(layer "B.Cu")
		(at 45.212 -86.44255 90)
		(property "Reference" "R754"
			(at 0 0 90)
			(layer "B.SilkS")
			(hide yes)
			(effects
				(font
					(size 1.27 1.27)
				)
				(justify mirror)
			)
		)
		(property "Value" ""
			(at 0 0 90)
			(layer "B.Fab")
			(effects
				(font
					(size 1.27 1.27)
				)
				(justify mirror)
			)
		)
		(duplicate_pad_numbers_are_jumpers no)
		(fp_line
			(start 0.7874 -0.4064)
			(end -0.7874 -0.4064)
			(stroke
				(width 0.1524)
				(type default)
			)
			(layer "B.SilkS")
		)
		(fp_line
			(start -0.7874 -0.4064)
			(end -0.7874 0.4064)
			(stroke
				(width 0.1524)
				(type default)
			)
			(layer "B.SilkS")
		)
		(fp_line
			(start 0.7874 0.4064)
			(end 0.7874 -0.4064)
			(stroke
				(width 0.1524)
				(type default)
			)
			(layer "B.SilkS")
		)
		(fp_line
			(start -0.7874 0.4064)
			(end 0.7874 0.4064)
			(stroke
				(width 0.1524)
				(type default)
			)
			(layer "B.SilkS")
		)
		(fp_line
			(start 0.67945 -0.305054)
			(end 0.12065 -0.305054)
			(stroke
				(width 0.1)
				(type default)
			)
			(layer "B.Fab")
		)
		(fp_line
			(start 0.12065 -0.305054)
			(end 0.12065 -0.2794)
			(stroke
				(width 0.1)
				(type default)
			)
			(layer "B.Fab")
		)
		(fp_line
			(start -0.12065 -0.3048)
			(end -0.67945 -0.3048)
			(stroke
				(width 0.1)
				(type default)
			)
			(layer "B.Fab")
		)
		(fp_line
			(start -0.67945 -0.3048)
			(end -0.67945 0.3048)
			(stroke
				(width 0.1)
				(type default)
			)
			(layer "B.Fab")
		)
		(fp_line
			(start 0.12065 -0.2794)
			(end -0.12065 -0.2794)
			(stroke
				(width 0.1)
				(type default)
			)
			(layer "B.Fab")
		)
		(fp_line
			(start -0.12065 -0.2794)
			(end -0.12065 -0.3048)
			(stroke
				(width 0.1)
				(type default)
			)
			(layer "B.Fab")
		)
		(fp_line
			(start 0.12065 0.2794)
			(end 0.12065 0.3048)
			(stroke
				(width 0.1)
				(type default)
			)
			(layer "B.Fab")
		)
		(fp_line
			(start -0.120396 0.2794)
			(end 0.12065 0.2794)
			(stroke
				(width 0.1)
				(type default)
			)
			(layer "B.Fab")
		)
		(fp_line
			(start 0.67945 0.3048)
			(end 0.67945 -0.305054)
			(stroke
				(width 0.1)
				(type default)
			)
			(layer "B.Fab")
		)
		(fp_line
			(start 0.12065 0.3048)
			(end 0.67945 0.3048)
			(stroke
				(width 0.1)
				(type default)
			)
			(layer "B.Fab")
		)
		(fp_line
			(start -0.120396 0.3048)
			(end -0.120396 0.2794)
			(stroke
				(width 0.1)
				(type default)
			)
			(layer "B.Fab")
		)
		(fp_line
			(start -0.67945 0.3048)
			(end -0.120396 0.3048)
			(stroke
				(width 0.1)
				(type default)
			)
			(layer "B.Fab")
		)
		(pad "1" smd circle
			(at 0.40005 0 270)
			(size 0 0)
			(layers "B.Cu" "B.Mask" "B.Paste")
			(net "P3V3_RGM")
		)
		(pad "2" smd circle
			(at -0.40005 0 270)
			(size 0 0)
			(layers "B.Cu" "B.Mask" "B.Paste")
			(net "UART_BMC_5_TXD_R")
		)
	)
	(footprint ""
		(layer "B.Cu")
		(at 52.959 -66.1416 -90)
		(property "Reference" "R38"
			(at 0 0 90)
			(layer "B.SilkS")
			(hide yes)
			(effects
				(font
					(size 1.27 1.27)
				)
				(justify mirror)
			)
		)
		(property "Value" ""
			(at 0 0 90)
			(layer "B.Fab")
			(effects
				(font
					(size 1.27 1.27)
				)
				(justify mirror)
			)
		)
		(duplicate_pad_numbers_are_jumpers no)
		(fp_line
			(start -0.7874 0.4064)
			(end 0.7874 0.4064)
			(stroke
				(width 0.1524)
				(type default)
			)
			(layer "B.SilkS")
		)
		(fp_line
			(start 0.7874 0.4064)
			(end 0.7874 -0.4064)
			(stroke
				(width 0.1524)
				(type default)
			)
			(layer "B.SilkS")
		)
		(fp_line
			(start -0.7874 -0.4064)
			(end -0.7874 0.4064)
			(stroke
				(width 0.1524)
				(type default)
			)
			(layer "B.SilkS")
		)
		(fp_line
			(start 0.7874 -0.4064)
			(end -0.7874 -0.4064)
			(stroke
				(width 0.1524)
				(type default)
			)
			(layer "B.SilkS")
		)
		(fp_line
			(start -0.67945 0.3048)
			(end -0.120396 0.3048)
			(stroke
				(width 0.1)
				(type default)
			)
			(layer "B.Fab")
		)
		(fp_line
			(start -0.120396 0.3048)
			(end -0.120396 0.2794)
			(stroke
				(width 0.1)
				(type default)
			)
			(layer "B.Fab")
		)
		(fp_line
			(start 0.12065 0.3048)
			(end 0.67945 0.3048)
			(stroke
				(width 0.1)
				(type default)
			)
			(layer "B.Fab")
		)
		(fp_line
			(start 0.67945 0.3048)
			(end 0.67945 -0.305054)
			(stroke
				(width 0.1)
				(type default)
			)
			(layer "B.Fab")
		)
		(fp_line
			(start -0.120396 0.2794)
			(end 0.12065 0.2794)
			(stroke
				(width 0.1)
				(type default)
			)
			(layer "B.Fab")
		)
		(fp_line
			(start 0.12065 0.2794)
			(end 0.12065 0.3048)
			(stroke
				(width 0.1)
				(type default)
			)
			(layer "B.Fab")
		)
		(fp_line
			(start -0.12065 -0.2794)
			(end -0.12065 -0.3048)
			(stroke
				(width 0.1)
				(type default)
			)
			(layer "B.Fab")
		)
		(fp_line
			(start 0.12065 -0.2794)
			(end -0.12065 -0.2794)
			(stroke
				(width 0.1)
				(type default)
			)
			(layer "B.Fab")
		)
		(fp_line
			(start -0.67945 -0.3048)
			(end -0.67945 0.3048)
			(stroke
				(width 0.1)
				(type default)
			)
			(layer "B.Fab")
		)
		(fp_line
			(start -0.12065 -0.3048)
			(end -0.67945 -0.3048)
			(stroke
				(width 0.1)
				(type default)
			)
			(layer "B.Fab")
		)
		(fp_line
			(start 0.12065 -0.305054)
			(end 0.12065 -0.2794)
			(stroke
				(width 0.1)
				(type default)
			)
			(layer "B.Fab")
		)
		(fp_line
			(start 0.67945 -0.305054)
			(end 0.12065 -0.305054)
			(stroke
				(width 0.1)
				(type default)
			)
			(layer "B.Fab")
		)
		(pad "1" smd circle
			(at 0.40005 0 90)
			(size 0 0)
			(layers "B.Cu" "B.Mask" "B.Paste")
			(net "P3V3_AUX")
		)
		(pad "2" smd circle
			(at -0.40005 0 90)
			(size 0 0)
			(layers "B.Cu" "B.Mask" "B.Paste")
			(net "FM_BMC_SUSACK_N")
		)
	)
	(footprint ""
		(layer "B.Cu")
		(at 112.014 -85.344 90)
		(property "Reference" "X1"
			(at 1.73863 2.4638 0)
			(unlocked yes)
			(layer "B.SilkS")
			(effects
				(font
					(size 0.7874 0.5842)
					(thickness 0.1524)
				)
				(justify left mirror)
			)
		)
		(property "Value" ""
			(at 0 0 90)
			(layer "B.Fab")
			(effects
				(font
					(size 1.27 1.27)
				)
				(justify mirror)
			)
		)
		(property "Device Type" "TP_TDR_4P_FTS_TH-TP_TDR_4P_DIPA"
			(at -1.30175 1.27 0)
			(unlocked yes)
			(layer "B.Fab")
			(hide yes)
			(effects
				(font
					(size 0.635 0.4064)
					(thickness 0.1524)
				)
				(justify mirror)
			)
		)
		(property "User Part Number" "N_A"
			(at -1.30175 1.27 0)
			(unlocked yes)
			(layer "Cmts.User")
			(hide yes)
			(effects
				(font
					(size 0.635 0.4064)
					(thickness 0.1524)
				)
				(justify mirror)
			)
		)
		(duplicate_pad_numbers_are_jumpers no)
		(fp_line
			(start 0 -1.27)
			(end 0 -0.635)
			(stroke
				(width 0.1524)
				(type default)
			)
			(layer "B.SilkS")
		)
		(fp_line
			(start -2.54 -1.27)
			(end 0 -1.27)
			(stroke
				(width 0.1524)
				(type default)
			)
			(layer "B.SilkS")
		)
		(fp_line
			(start -2.54 -1.1303)
			(end -2.54 -1.27)
			(stroke
				(width 0.1524)
				(type default)
			)
			(layer "B.SilkS")
		)
		(fp_line
			(start 0 0.635)
			(end 0 1.905)
			(stroke
				(width 0.1524)
				(type default)
			)
			(layer "B.SilkS")
		)
		(fp_line
			(start -2.54 1.4097)
			(end -2.54 1.1303)
			(stroke
				(width 0.1524)
				(type default)
			)
			(layer "B.SilkS")
		)
		(fp_line
			(start 0 3.175)
			(end 0 3.81)
			(stroke
				(width 0.1524)
				(type default)
			)
			(layer "B.SilkS")
		)
		(fp_line
			(start 0 3.81)
			(end -2.54 3.81)
			(stroke
				(width 0.1524)
				(type default)
			)
			(layer "B.SilkS")
		)
		(fp_line
			(start -2.54 3.81)
			(end -2.54 3.6703)
			(stroke
				(width 0.1524)
				(type default)
			)
			(layer "B.SilkS")
		)
		(fp_poly
			(pts
				(xy 0.761746 0) (xy 2.285746 -0.762) (xy 2.285746 0.762)
			)
			(stroke
				(width 0)
				(type default)
			)
			(fill yes)
			(layer "B.SilkS")
		)
		(fp_line
			(start 0 -1.27)
			(end 0 3.81)
			(stroke
				(width 0.1)
				(type default)
			)
			(layer "B.Fab")
		)
		(fp_line
			(start -2.54 -1.27)
			(end 0 -1.27)
			(stroke
				(width 0.1)
				(type default)
			)
			(layer "B.Fab")
		)
		(fp_line
			(start 0 3.81)
			(end -2.54 3.81)
			(stroke
				(width 0.1)
				(type default)
			)
			(layer "B.Fab")
		)
		(fp_line
			(start -2.54 3.81)
			(end -2.54 -1.27)
			(stroke
				(width 0.1)
				(type default)
			)
			(layer "B.Fab")
		)
		(fp_poly
			(pts
				(xy 0.761746 0) (xy 2.285746 -0.762) (xy 2.285746 0.762)
			)
			(stroke
				(width 0)
				(type default)
			)
			(fill yes)
			(layer "B.Fab")
		)
		(pad "1" thru_hole circle
			(at 0 0 270)
			(size 1.0033 1.0033)
			(drill 0.249936)
			(layers "*.Cu" "*.Mask")
			(remove_unused_layers no)
			(net "TDR_DIFF_85_TOP_DP")
			(clearance 0.10795)
			(padstack
				(mode front_inner_back)
				(layer "Inner"
					(shape circle)
					(size 0.8001 0.8001)
					(clearance 0.1524)
				)
				(layer "B.Cu"
					(shape circle)
					(size 1.0033 1.0033)
					(thermal_gap 0.10795)
					(clearance 0.10795)
				)
			)
		)
		(pad "2" thru_hole circle
			(at -2.54 0 270)
			(size 1.9939 1.9939)
			(drill 0.249936)
			(layers "*.Cu" "*.Mask")
			(remove_unused_layers no)
			(net "GND_P1")
			(clearance 0.10795)
			(padstack
				(mode front_inner_back)
				(layer "Inner"
					(shape circle)
					(size 0.8001 0.8001)
					(clearance 0.1524)
				)
				(layer "B.Cu"
					(shape circle)
					(size 1.9939 1.9939)
					(thermal_gap 0.10795)
					(clearance 0.10795)
				)
			)
		)
		(pad "3" thru_hole circle
			(at -2.54 2.54 270)
			(size 1.9939 1.9939)
			(drill 0.249936)
			(layers "*.Cu" "*.Mask")
			(remove_unused_layers no)
			(net "GND_P1")
			(clearance 0.10795)
			(padstack
				(mode front_inner_back)
				(layer "Inner"
					(shape circle)
					(size 0.8001 0.8001)
					(clearance 0.1524)
				)
				(layer "B.Cu"
					(shape circle)
					(size 1.9939 1.9939)
					(thermal_gap 0.10795)
					(clearance 0.10795)
				)
			)
		)
		(pad "4" thru_hole circle
			(at 0 2.54 270)
			(size 1.0033 1.0033)
			(drill 0.249936)
			(layers "*.Cu" "*.Mask")
			(remove_unused_layers no)
			(net "TDR_DIFF_85_TOP_DN")
			(clearance 0.10795)
			(padstack
				(mode front_inner_back)
				(layer "Inner"
					(shape circle)
					(size 0.8001 0.8001)
					(clearance 0.1524)
				)
				(layer "B.Cu"
					(shape circle)
					(size 1.0033 1.0033)
					(thermal_gap 0.10795)
					(clearance 0.10795)
				)
			)
		)
	)
	(footprint ""
		(layer "B.Cu")
		(at 26.8224 -84.3788 -90)
		(property "Reference" "R625"
			(at 0 0 90)
			(layer "B.SilkS")
			(hide yes)
			(effects
				(font
					(size 1.27 1.27)
				)
				(justify mirror)
			)
		)
		(property "Value" ""
			(at 0 0 90)
			(layer "B.Fab")
			(effects
				(font
					(size 1.27 1.27)
				)
				(justify mirror)
			)
		)
		(duplicate_pad_numbers_are_jumpers no)
		(fp_line
			(start -0.7874 0.4064)
			(end 0.7874 0.4064)
			(stroke
				(width 0.1524)
				(type default)
			)
			(layer "B.SilkS")
		)
		(fp_line
			(start 0.7874 0.4064)
			(end 0.7874 -0.4064)
			(stroke
				(width 0.1524)
				(type default)
			)
			(layer "B.SilkS")
		)
		(fp_line
			(start -0.7874 -0.4064)
			(end -0.7874 0.4064)
			(stroke
				(width 0.1524)
				(type default)
			)
			(layer "B.SilkS")
		)
		(fp_line
			(start 0.7874 -0.4064)
			(end -0.7874 -0.4064)
			(stroke
				(width 0.1524)
				(type default)
			)
			(layer "B.SilkS")
		)
		(fp_line
			(start -0.67945 0.3048)
			(end -0.120396 0.3048)
			(stroke
				(width 0.1)
				(type default)
			)
			(layer "B.Fab")
		)
		(fp_line
			(start -0.120396 0.3048)
			(end -0.120396 0.2794)
			(stroke
				(width 0.1)
				(type default)
			)
			(layer "B.Fab")
		)
		(fp_line
			(start 0.12065 0.3048)
			(end 0.67945 0.3048)
			(stroke
				(width 0.1)
				(type default)
			)
			(layer "B.Fab")
		)
		(fp_line
			(start 0.67945 0.3048)
			(end 0.67945 -0.305054)
			(stroke
				(width 0.1)
				(type default)
			)
			(layer "B.Fab")
		)
		(fp_line
			(start -0.120396 0.2794)
			(end 0.12065 0.2794)
			(stroke
				(width 0.1)
				(type default)
			)
			(layer "B.Fab")
		)
		(fp_line
			(start 0.12065 0.2794)
			(end 0.12065 0.3048)
			(stroke
				(width 0.1)
				(type default)
			)
			(layer "B.Fab")
		)
		(fp_line
			(start -0.12065 -0.2794)
			(end -0.12065 -0.3048)
			(stroke
				(width 0.1)
				(type default)
			)
			(layer "B.Fab")
		)
		(fp_line
			(start 0.12065 -0.2794)
			(end -0.12065 -0.2794)
			(stroke
				(width 0.1)
				(type default)
			)
			(layer "B.Fab")
		)
		(fp_line
			(start -0.67945 -0.3048)
			(end -0.67945 0.3048)
			(stroke
				(width 0.1)
				(type default)
			)
			(layer "B.Fab")
		)
		(fp_line
			(start -0.12065 -0.3048)
			(end -0.67945 -0.3048)
			(stroke
				(width 0.1)
				(type default)
			)
			(layer "B.Fab")
		)
		(fp_line
			(start 0.12065 -0.305054)
			(end 0.12065 -0.2794)
			(stroke
				(width 0.1)
				(type default)
			)
			(layer "B.Fab")
		)
		(fp_line
			(start 0.67945 -0.305054)
			(end 0.12065 -0.305054)
			(stroke
				(width 0.1)
				(type default)
			)
			(layer "B.Fab")
		)
		(pad "1" smd circle
			(at 0.40005 0 90)
			(size 0 0)
			(layers "B.Cu" "B.Mask" "B.Paste")
			(net "P3V3_AUX")
		)
		(pad "2" smd circle
			(at -0.40005 0 90)
			(size 0 0)
			(layers "B.Cu" "B.Mask" "B.Paste")
			(net "RST_RSMRST_N")
		)
	)
	(footprint ""
		(layer "B.Cu")
		(at 66.127884 -30.740604 -90)
		(property "Reference" "R211"
			(at 0 0 90)
			(layer "B.SilkS")
			(hide yes)
			(effects
				(font
					(size 1.27 1.27)
				)
				(justify mirror)
			)
		)
		(property "Value" ""
			(at 0 0 90)
			(layer "B.Fab")
			(effects
				(font
					(size 1.27 1.27)
				)
				(justify mirror)
			)
		)
		(duplicate_pad_numbers_are_jumpers no)
		(fp_line
			(start -0.7874 0.4064)
			(end 0.7874 0.4064)
			(stroke
				(width 0.1524)
				(type default)
			)
			(layer "B.SilkS")
		)
		(fp_line
			(start 0.7874 0.4064)
			(end 0.7874 -0.4064)
			(stroke
				(width 0.1524)
				(type default)
			)
			(layer "B.SilkS")
		)
		(fp_line
			(start -0.7874 -0.4064)
			(end -0.7874 0.4064)
			(stroke
				(width 0.1524)
				(type default)
			)
			(layer "B.SilkS")
		)
		(fp_line
			(start 0.7874 -0.4064)
			(end -0.7874 -0.4064)
			(stroke
				(width 0.1524)
				(type default)
			)
			(layer "B.SilkS")
		)
		(fp_line
			(start -0.67945 0.3048)
			(end -0.120396 0.3048)
			(stroke
				(width 0.1)
				(type default)
			)
			(layer "B.Fab")
		)
		(fp_line
			(start -0.120396 0.3048)
			(end -0.120396 0.2794)
			(stroke
				(width 0.1)
				(type default)
			)
			(layer "B.Fab")
		)
		(fp_line
			(start 0.12065 0.3048)
			(end 0.67945 0.3048)
			(stroke
				(width 0.1)
				(type default)
			)
			(layer "B.Fab")
		)
		(fp_line
			(start 0.67945 0.3048)
			(end 0.67945 -0.305054)
			(stroke
				(width 0.1)
				(type default)
			)
			(layer "B.Fab")
		)
		(fp_line
			(start -0.120396 0.2794)
			(end 0.12065 0.2794)
			(stroke
				(width 0.1)
				(type default)
			)
			(layer "B.Fab")
		)
		(fp_line
			(start 0.12065 0.2794)
			(end 0.12065 0.3048)
			(stroke
				(width 0.1)
				(type default)
			)
			(layer "B.Fab")
		)
		(fp_line
			(start -0.12065 -0.2794)
			(end -0.12065 -0.3048)
			(stroke
				(width 0.1)
				(type default)
			)
			(layer "B.Fab")
		)
		(fp_line
			(start 0.12065 -0.2794)
			(end -0.12065 -0.2794)
			(stroke
				(width 0.1)
				(type default)
			)
			(layer "B.Fab")
		)
		(fp_line
			(start -0.67945 -0.3048)
			(end -0.67945 0.3048)
			(stroke
				(width 0.1)
				(type default)
			)
			(layer "B.Fab")
		)
		(fp_line
			(start -0.12065 -0.3048)
			(end -0.67945 -0.3048)
			(stroke
				(width 0.1)
				(type default)
			)
			(layer "B.Fab")
		)
		(fp_line
			(start 0.12065 -0.305054)
			(end 0.12065 -0.2794)
			(stroke
				(width 0.1)
				(type default)
			)
			(layer "B.Fab")
		)
		(fp_line
			(start 0.67945 -0.305054)
			(end 0.12065 -0.305054)
			(stroke
				(width 0.1)
				(type default)
			)
			(layer "B.Fab")
		)
		(pad "1" smd circle
			(at 0.40005 0 90)
			(size 0 0)
			(layers "B.Cu" "B.Mask" "B.Paste")
			(net "P3V3_RGM")
		)
		(pad "2" smd circle
			(at -0.40005 0 90)
			(size 0 0)
			(layers "B.Cu" "B.Mask" "B.Paste")
			(net "FM_BMC_SSPRST_N")
		)
	)
	(footprint ""
		(layer "B.Cu")
		(at 56.904636 -54.898544 180)
		(property "Reference" "C102"
			(at 0 0 0)
			(layer "B.SilkS")
			(hide yes)
			(effects
				(font
					(size 1.27 1.27)
				)
				(justify mirror)
			)
		)
		(property "Value" ""
			(at 0 0 0)
			(layer "B.Fab")
			(effects
				(font
					(size 1.27 1.27)
				)
				(justify mirror)
			)
		)
		(duplicate_pad_numbers_are_jumpers no)
		(fp_line
			(start 0.7874 0.4064)
			(end 0.7874 -0.4064)
			(stroke
				(width 0.1524)
				(type default)
			)
			(layer "B.SilkS")
		)
		(fp_line
			(start 0.7874 -0.4064)
			(end -0.7874 -0.4064)
			(stroke
				(width 0.1524)
				(type default)
			)
			(layer "B.SilkS")
		)
		(fp_line
			(start -0.7874 0.4064)
			(end 0.7874 0.4064)
			(stroke
				(width 0.1524)
				(type default)
			)
			(layer "B.SilkS")
		)
		(fp_line
			(start -0.7874 -0.4064)
			(end -0.7874 0.4064)
			(stroke
				(width 0.1524)
				(type default)
			)
			(layer "B.SilkS")
		)
		(fp_line
			(start 0.67945 0.3048)
			(end 0.67945 -0.305054)
			(stroke
				(width 0.1)
				(type default)
			)
			(layer "B.Fab")
		)
		(fp_line
			(start 0.67945 -0.305054)
			(end 0.12065 -0.305054)
			(stroke
				(width 0.1)
				(type default)
			)
			(layer "B.Fab")
		)
		(fp_line
			(start 0.12065 0.3048)
			(end 0.67945 0.3048)
			(stroke
				(width 0.1)
				(type default)
			)
			(layer "B.Fab")
		)
		(fp_line
			(start 0.12065 0.2794)
			(end 0.12065 0.3048)
			(stroke
				(width 0.1)
				(type default)
			)
			(layer "B.Fab")
		)
		(fp_line
			(start 0.12065 -0.2794)
			(end -0.12065 -0.2794)
			(stroke
				(width 0.1)
				(type default)
			)
			(layer "B.Fab")
		)
		(fp_line
			(start 0.12065 -0.305054)
			(end 0.12065 -0.2794)
			(stroke
				(width 0.1)
				(type default)
			)
			(layer "B.Fab")
		)
		(fp_line
			(start -0.120396 0.3048)
			(end -0.120396 0.2794)
			(stroke
				(width 0.1)
				(type default)
			)
			(layer "B.Fab")
		)
		(fp_line
			(start -0.120396 0.2794)
			(end 0.12065 0.2794)
			(stroke
				(width 0.1)
				(type default)
			)
			(layer "B.Fab")
		)
		(fp_line
			(start -0.12065 -0.2794)
			(end -0.12065 -0.3048)
			(stroke
				(width 0.1)
				(type default)
			)
			(layer "B.Fab")
		)
		(fp_line
			(start -0.12065 -0.3048)
			(end -0.67945 -0.3048)
			(stroke
				(width 0.1)
				(type default)
			)
			(layer "B.Fab")
		)
		(fp_line
			(start -0.67945 0.3048)
			(end -0.120396 0.3048)
			(stroke
				(width 0.1)
				(type default)
			)
			(layer "B.Fab")
		)
		(fp_line
			(start -0.67945 -0.3048)
			(end -0.67945 0.3048)
			(stroke
				(width 0.1)
				(type default)
			)
			(layer "B.Fab")
		)
		(pad "1" smd circle
			(at 0.40005 0)
			(size 0 0)
			(layers "B.Cu" "B.Mask" "B.Paste")
			(net "P1V8_AUX")
		)
		(pad "2" smd circle
			(at -0.40005 0)
			(size 0 0)
			(layers "B.Cu" "B.Mask" "B.Paste")
			(net "GND")
		)
	)
	(footprint ""
		(layer "B.Cu")
		(at 42.346118 -34.637726 90)
		(property "Reference" "R165"
			(at 0 0 90)
			(layer "B.SilkS")
			(hide yes)
			(effects
				(font
					(size 1.27 1.27)
				)
				(justify mirror)
			)
		)
		(property "Value" ""
			(at 0 0 90)
			(layer "B.Fab")
			(effects
				(font
					(size 1.27 1.27)
				)
				(justify mirror)
			)
		)
		(duplicate_pad_numbers_are_jumpers no)
		(fp_line
			(start 0.7874 -0.4064)
			(end -0.7874 -0.4064)
			(stroke
				(width 0.1524)
				(type default)
			)
			(layer "B.SilkS")
		)
		(fp_line
			(start -0.7874 -0.4064)
			(end -0.7874 0.4064)
			(stroke
				(width 0.1524)
				(type default)
			)
			(layer "B.SilkS")
		)
		(fp_line
			(start 0.7874 0.4064)
			(end 0.7874 -0.4064)
			(stroke
				(width 0.1524)
				(type default)
			)
			(layer "B.SilkS")
		)
		(fp_line
			(start -0.7874 0.4064)
			(end 0.7874 0.4064)
			(stroke
				(width 0.1524)
				(type default)
			)
			(layer "B.SilkS")
		)
		(fp_line
			(start 0.67945 -0.305054)
			(end 0.12065 -0.305054)
			(stroke
				(width 0.1)
				(type default)
			)
			(layer "B.Fab")
		)
		(fp_line
			(start 0.12065 -0.305054)
			(end 0.12065 -0.2794)
			(stroke
				(width 0.1)
				(type default)
			)
			(layer "B.Fab")
		)
		(fp_line
			(start -0.12065 -0.3048)
			(end -0.67945 -0.3048)
			(stroke
				(width 0.1)
				(type default)
			)
			(layer "B.Fab")
		)
		(fp_line
			(start -0.67945 -0.3048)
			(end -0.67945 0.3048)
			(stroke
				(width 0.1)
				(type default)
			)
			(layer "B.Fab")
		)
		(fp_line
			(start 0.12065 -0.2794)
			(end -0.12065 -0.2794)
			(stroke
				(width 0.1)
				(type default)
			)
			(layer "B.Fab")
		)
		(fp_line
			(start -0.12065 -0.2794)
			(end -0.12065 -0.3048)
			(stroke
				(width 0.1)
				(type default)
			)
			(layer "B.Fab")
		)
		(fp_line
			(start 0.12065 0.2794)
			(end 0.12065 0.3048)
			(stroke
				(width 0.1)
				(type default)
			)
			(layer "B.Fab")
		)
		(fp_line
			(start -0.120396 0.2794)
			(end 0.12065 0.2794)
			(stroke
				(width 0.1)
				(type default)
			)
			(layer "B.Fab")
		)
		(fp_line
			(start 0.67945 0.3048)
			(end 0.67945 -0.305054)
			(stroke
				(width 0.1)
				(type default)
			)
			(layer "B.Fab")
		)
		(fp_line
			(start 0.12065 0.3048)
			(end 0.67945 0.3048)
			(stroke
				(width 0.1)
				(type default)
			)
			(layer "B.Fab")
		)
		(fp_line
			(start -0.120396 0.3048)
			(end -0.120396 0.2794)
			(stroke
				(width 0.1)
				(type default)
			)
			(layer "B.Fab")
		)
		(fp_line
			(start -0.67945 0.3048)
			(end -0.120396 0.3048)
			(stroke
				(width 0.1)
				(type default)
			)
			(layer "B.Fab")
		)
		(pad "1" smd circle
			(at 0.40005 0 270)
			(size 0 0)
			(layers "B.Cu" "B.Mask" "B.Paste")
			(net "SMB_BMC_MM2_R_SCL")
		)
		(pad "2" smd circle
			(at -0.40005 0 270)
			(size 0 0)
			(layers "B.Cu" "B.Mask" "B.Paste")
			(net "SMB_BMC_MM2_SCL")
		)
	)
	(footprint ""
		(layer "B.Cu")
		(at 49.420018 -49.808638 -90)
		(property "Reference" "C70"
			(at 0 0 90)
			(layer "B.SilkS")
			(hide yes)
			(effects
				(font
					(size 1.27 1.27)
				)
				(justify mirror)
			)
		)
		(property "Value" ""
			(at 0 0 90)
			(layer "B.Fab")
			(effects
				(font
					(size 1.27 1.27)
				)
				(justify mirror)
			)
		)
		(duplicate_pad_numbers_are_jumpers no)
		(fp_line
			(start -0.7874 0.4064)
			(end 0.7874 0.4064)
			(stroke
				(width 0.1524)
				(type default)
			)
			(layer "B.SilkS")
		)
		(fp_line
			(start 0.7874 0.4064)
			(end 0.7874 -0.4064)
			(stroke
				(width 0.1524)
				(type default)
			)
			(layer "B.SilkS")
		)
		(fp_line
			(start -0.7874 -0.4064)
			(end -0.7874 0.4064)
			(stroke
				(width 0.1524)
				(type default)
			)
			(layer "B.SilkS")
		)
		(fp_line
			(start 0.7874 -0.4064)
			(end -0.7874 -0.4064)
			(stroke
				(width 0.1524)
				(type default)
			)
			(layer "B.SilkS")
		)
		(fp_line
			(start -0.67945 0.3048)
			(end -0.120396 0.3048)
			(stroke
				(width 0.1)
				(type default)
			)
			(layer "B.Fab")
		)
		(fp_line
			(start -0.120396 0.3048)
			(end -0.120396 0.2794)
			(stroke
				(width 0.1)
				(type default)
			)
			(layer "B.Fab")
		)
		(fp_line
			(start 0.12065 0.3048)
			(end 0.67945 0.3048)
			(stroke
				(width 0.1)
				(type default)
			)
			(layer "B.Fab")
		)
		(fp_line
			(start 0.67945 0.3048)
			(end 0.67945 -0.305054)
			(stroke
				(width 0.1)
				(type default)
			)
			(layer "B.Fab")
		)
		(fp_line
			(start -0.120396 0.2794)
			(end 0.12065 0.2794)
			(stroke
				(width 0.1)
				(type default)
			)
			(layer "B.Fab")
		)
		(fp_line
			(start 0.12065 0.2794)
			(end 0.12065 0.3048)
			(stroke
				(width 0.1)
				(type default)
			)
			(layer "B.Fab")
		)
		(fp_line
			(start -0.12065 -0.2794)
			(end -0.12065 -0.3048)
			(stroke
				(width 0.1)
				(type default)
			)
			(layer "B.Fab")
		)
		(fp_line
			(start 0.12065 -0.2794)
			(end -0.12065 -0.2794)
			(stroke
				(width 0.1)
				(type default)
			)
			(layer "B.Fab")
		)
		(fp_line
			(start -0.67945 -0.3048)
			(end -0.67945 0.3048)
			(stroke
				(width 0.1)
				(type default)
			)
			(layer "B.Fab")
		)
		(fp_line
			(start -0.12065 -0.3048)
			(end -0.67945 -0.3048)
			(stroke
				(width 0.1)
				(type default)
			)
			(layer "B.Fab")
		)
		(fp_line
			(start 0.12065 -0.305054)
			(end 0.12065 -0.2794)
			(stroke
				(width 0.1)
				(type default)
			)
			(layer "B.Fab")
		)
		(fp_line
			(start 0.67945 -0.305054)
			(end 0.12065 -0.305054)
			(stroke
				(width 0.1)
				(type default)
			)
			(layer "B.Fab")
		)
		(pad "1" smd circle
			(at 0.40005 0 90)
			(size 0 0)
			(layers "B.Cu" "B.Mask" "B.Paste")
			(net "P1V2_AUX")
		)
		(pad "2" smd circle
			(at -0.40005 0 90)
			(size 0 0)
			(layers "B.Cu" "B.Mask" "B.Paste")
			(net "GND")
		)
	)
	(footprint ""
		(layer "B.Cu")
		(at 81.28 -101.473 90)
		(property "Reference" "C329"
			(at 0 0 90)
			(layer "B.SilkS")
			(hide yes)
			(effects
				(font
					(size 1.27 1.27)
				)
				(justify mirror)
			)
		)
		(property "Value" ""
			(at 0 0 90)
			(layer "B.Fab")
			(effects
				(font
					(size 1.27 1.27)
				)
				(justify mirror)
			)
		)
		(duplicate_pad_numbers_are_jumpers no)
		(fp_line
			(start 1.524 -0.762)
			(end -1.524 -0.762)
			(stroke
				(width 0.1524)
				(type default)
			)
			(layer "B.SilkS")
		)
		(fp_line
			(start -1.524 -0.762)
			(end -1.524 0.762)
			(stroke
				(width 0.1524)
				(type default)
			)
			(layer "B.SilkS")
		)
		(fp_line
			(start 1.524 0.762)
			(end 1.524 -0.762)
			(stroke
				(width 0.1524)
				(type default)
			)
			(layer "B.SilkS")
		)
		(fp_line
			(start -1.524 0.762)
			(end 1.524 0.762)
			(stroke
				(width 0.1524)
				(type default)
			)
			(layer "B.SilkS")
		)
		(fp_line
			(start 1.1049 -0.724916)
			(end 1.1049 0.724916)
			(stroke
				(width 0.1)
				(type default)
			)
			(layer "B.Fab")
		)
		(fp_line
			(start -1.1049 -0.724916)
			(end 1.1049 -0.724916)
			(stroke
				(width 0.1)
				(type default)
			)
			(layer "B.Fab")
		)
		(fp_line
			(start 1.1049 0.724916)
			(end -1.1049 0.724916)
			(stroke
				(width 0.1)
				(type default)
			)
			(layer "B.Fab")
		)
		(fp_line
			(start -1.1049 0.724916)
			(end -1.1049 -0.724916)
			(stroke
				(width 0.1)
				(type default)
			)
			(layer "B.Fab")
		)
		(pad "1" smd rect
			(at 0.889 0 90)
			(size 1.016 1.27)
			(layers "B.Cu" "B.Mask" "B.Paste")
			(net "P12V_AUX")
		)
		(pad "2" smd rect
			(at -0.889 0 90)
			(size 1.016 1.27)
			(layers "B.Cu" "B.Mask" "B.Paste")
			(net "GND")
		)
	)
	(footprint ""
		(layer "B.Cu")
		(at 51.3715 -86.9315 180)
		(property "Reference" "R702"
			(at 0 0 0)
			(layer "B.SilkS")
			(hide yes)
			(effects
				(font
					(size 1.27 1.27)
				)
				(justify mirror)
			)
		)
		(property "Value" ""
			(at 0 0 0)
			(layer "B.Fab")
			(effects
				(font
					(size 1.27 1.27)
				)
				(justify mirror)
			)
		)
		(duplicate_pad_numbers_are_jumpers no)
		(fp_line
			(start 0.7874 0.4064)
			(end 0.7874 -0.4064)
			(stroke
				(width 0.1524)
				(type default)
			)
			(layer "B.SilkS")
		)
		(fp_line
			(start 0.7874 -0.4064)
			(end -0.7874 -0.4064)
			(stroke
				(width 0.1524)
				(type default)
			)
			(layer "B.SilkS")
		)
		(fp_line
			(start -0.7874 0.4064)
			(end 0.7874 0.4064)
			(stroke
				(width 0.1524)
				(type default)
			)
			(layer "B.SilkS")
		)
		(fp_line
			(start -0.7874 -0.4064)
			(end -0.7874 0.4064)
			(stroke
				(width 0.1524)
				(type default)
			)
			(layer "B.SilkS")
		)
		(fp_line
			(start 0.67945 0.3048)
			(end 0.67945 -0.305054)
			(stroke
				(width 0.1)
				(type default)
			)
			(layer "B.Fab")
		)
		(fp_line
			(start 0.67945 -0.305054)
			(end 0.12065 -0.305054)
			(stroke
				(width 0.1)
				(type default)
			)
			(layer "B.Fab")
		)
		(fp_line
			(start 0.12065 0.3048)
			(end 0.67945 0.3048)
			(stroke
				(width 0.1)
				(type default)
			)
			(layer "B.Fab")
		)
		(fp_line
			(start 0.12065 0.2794)
			(end 0.12065 0.3048)
			(stroke
				(width 0.1)
				(type default)
			)
			(layer "B.Fab")
		)
		(fp_line
			(start 0.12065 -0.2794)
			(end -0.12065 -0.2794)
			(stroke
				(width 0.1)
				(type default)
			)
			(layer "B.Fab")
		)
		(fp_line
			(start 0.12065 -0.305054)
			(end 0.12065 -0.2794)
			(stroke
				(width 0.1)
				(type default)
			)
			(layer "B.Fab")
		)
		(fp_line
			(start -0.120396 0.3048)
			(end -0.120396 0.2794)
			(stroke
				(width 0.1)
				(type default)
			)
			(layer "B.Fab")
		)
		(fp_line
			(start -0.120396 0.2794)
			(end 0.12065 0.2794)
			(stroke
				(width 0.1)
				(type default)
			)
			(layer "B.Fab")
		)
		(fp_line
			(start -0.12065 -0.2794)
			(end -0.12065 -0.3048)
			(stroke
				(width 0.1)
				(type default)
			)
			(layer "B.Fab")
		)
		(fp_line
			(start -0.12065 -0.3048)
			(end -0.67945 -0.3048)
			(stroke
				(width 0.1)
				(type default)
			)
			(layer "B.Fab")
		)
		(fp_line
			(start -0.67945 0.3048)
			(end -0.120396 0.3048)
			(stroke
				(width 0.1)
				(type default)
			)
			(layer "B.Fab")
		)
		(fp_line
			(start -0.67945 -0.3048)
			(end -0.67945 0.3048)
			(stroke
				(width 0.1)
				(type default)
			)
			(layer "B.Fab")
		)
		(pad "1" smd circle
			(at 0.40005 0)
			(size 0 0)
			(layers "B.Cu" "B.Mask" "B.Paste")
			(net "RST_PLTRST_N")
		)
		(pad "2" smd circle
			(at -0.40005 0)
			(size 0 0)
			(layers "B.Cu" "B.Mask" "B.Paste")
			(net "RST_PLTRST_R2_N")
		)
	)
	(footprint ""
		(layer "B.Cu")
		(at 77.707744 -35.540188 -90)
		(property "Reference" "R332"
			(at 0 0 90)
			(layer "B.SilkS")
			(hide yes)
			(effects
				(font
					(size 1.27 1.27)
				)
				(justify mirror)
			)
		)
		(property "Value" ""
			(at 0 0 90)
			(layer "B.Fab")
			(effects
				(font
					(size 1.27 1.27)
				)
				(justify mirror)
			)
		)
		(duplicate_pad_numbers_are_jumpers no)
		(fp_line
			(start -0.7874 0.4064)
			(end 0.7874 0.4064)
			(stroke
				(width 0.1524)
				(type default)
			)
			(layer "B.SilkS")
		)
		(fp_line
			(start 0.7874 0.4064)
			(end 0.7874 -0.4064)
			(stroke
				(width 0.1524)
				(type default)
			)
			(layer "B.SilkS")
		)
		(fp_line
			(start -0.7874 -0.4064)
			(end -0.7874 0.4064)
			(stroke
				(width 0.1524)
				(type default)
			)
			(layer "B.SilkS")
		)
		(fp_line
			(start 0.7874 -0.4064)
			(end -0.7874 -0.4064)
			(stroke
				(width 0.1524)
				(type default)
			)
			(layer "B.SilkS")
		)
		(fp_line
			(start -0.67945 0.3048)
			(end -0.120396 0.3048)
			(stroke
				(width 0.1)
				(type default)
			)
			(layer "B.Fab")
		)
		(fp_line
			(start -0.120396 0.3048)
			(end -0.120396 0.2794)
			(stroke
				(width 0.1)
				(type default)
			)
			(layer "B.Fab")
		)
		(fp_line
			(start 0.12065 0.3048)
			(end 0.67945 0.3048)
			(stroke
				(width 0.1)
				(type default)
			)
			(layer "B.Fab")
		)
		(fp_line
			(start 0.67945 0.3048)
			(end 0.67945 -0.305054)
			(stroke
				(width 0.1)
				(type default)
			)
			(layer "B.Fab")
		)
		(fp_line
			(start -0.120396 0.2794)
			(end 0.12065 0.2794)
			(stroke
				(width 0.1)
				(type default)
			)
			(layer "B.Fab")
		)
		(fp_line
			(start 0.12065 0.2794)
			(end 0.12065 0.3048)
			(stroke
				(width 0.1)
				(type default)
			)
			(layer "B.Fab")
		)
		(fp_line
			(start -0.12065 -0.2794)
			(end -0.12065 -0.3048)
			(stroke
				(width 0.1)
				(type default)
			)
			(layer "B.Fab")
		)
		(fp_line
			(start 0.12065 -0.2794)
			(end -0.12065 -0.2794)
			(stroke
				(width 0.1)
				(type default)
			)
			(layer "B.Fab")
		)
		(fp_line
			(start -0.67945 -0.3048)
			(end -0.67945 0.3048)
			(stroke
				(width 0.1)
				(type default)
			)
			(layer "B.Fab")
		)
		(fp_line
			(start -0.12065 -0.3048)
			(end -0.67945 -0.3048)
			(stroke
				(width 0.1)
				(type default)
			)
			(layer "B.Fab")
		)
		(fp_line
			(start 0.12065 -0.305054)
			(end 0.12065 -0.2794)
			(stroke
				(width 0.1)
				(type default)
			)
			(layer "B.Fab")
		)
		(fp_line
			(start 0.67945 -0.305054)
			(end 0.12065 -0.305054)
			(stroke
				(width 0.1)
				(type default)
			)
			(layer "B.Fab")
		)
		(pad "1" smd circle
			(at 0.40005 0 90)
			(size 0 0)
			(layers "B.Cu" "B.Mask" "B.Paste")
			(net "GND")
		)
		(pad "2" smd circle
			(at -0.40005 0 90)
			(size 0 0)
			(layers "B.Cu" "B.Mask" "B.Paste")
			(net "M_BMC_DDR4_MA<6>")
		)
	)
	(footprint ""
		(layer "B.Cu")
		(at 36.77412 -96.20504 180)
		(property "Reference" "R732"
			(at 0 0 0)
			(layer "B.SilkS")
			(hide yes)
			(effects
				(font
					(size 1.27 1.27)
				)
				(justify mirror)
			)
		)
		(property "Value" ""
			(at 0 0 0)
			(layer "B.Fab")
			(effects
				(font
					(size 1.27 1.27)
				)
				(justify mirror)
			)
		)
		(duplicate_pad_numbers_are_jumpers no)
		(fp_line
			(start 0.7874 0.4064)
			(end 0.7874 -0.4064)
			(stroke
				(width 0.1524)
				(type default)
			)
			(layer "B.SilkS")
		)
		(fp_line
			(start 0.7874 -0.4064)
			(end -0.7874 -0.4064)
			(stroke
				(width 0.1524)
				(type default)
			)
			(layer "B.SilkS")
		)
		(fp_line
			(start -0.7874 0.4064)
			(end 0.7874 0.4064)
			(stroke
				(width 0.1524)
				(type default)
			)
			(layer "B.SilkS")
		)
		(fp_line
			(start -0.7874 -0.4064)
			(end -0.7874 0.4064)
			(stroke
				(width 0.1524)
				(type default)
			)
			(layer "B.SilkS")
		)
		(fp_line
			(start 0.67945 0.3048)
			(end 0.67945 -0.305054)
			(stroke
				(width 0.1)
				(type default)
			)
			(layer "B.Fab")
		)
		(fp_line
			(start 0.67945 -0.305054)
			(end 0.12065 -0.305054)
			(stroke
				(width 0.1)
				(type default)
			)
			(layer "B.Fab")
		)
		(fp_line
			(start 0.12065 0.3048)
			(end 0.67945 0.3048)
			(stroke
				(width 0.1)
				(type default)
			)
			(layer "B.Fab")
		)
		(fp_line
			(start 0.12065 0.2794)
			(end 0.12065 0.3048)
			(stroke
				(width 0.1)
				(type default)
			)
			(layer "B.Fab")
		)
		(fp_line
			(start 0.12065 -0.2794)
			(end -0.12065 -0.2794)
			(stroke
				(width 0.1)
				(type default)
			)
			(layer "B.Fab")
		)
		(fp_line
			(start 0.12065 -0.305054)
			(end 0.12065 -0.2794)
			(stroke
				(width 0.1)
				(type default)
			)
			(layer "B.Fab")
		)
		(fp_line
			(start -0.120396 0.3048)
			(end -0.120396 0.2794)
			(stroke
				(width 0.1)
				(type default)
			)
			(layer "B.Fab")
		)
		(fp_line
			(start -0.120396 0.2794)
			(end 0.12065 0.2794)
			(stroke
				(width 0.1)
				(type default)
			)
			(layer "B.Fab")
		)
		(fp_line
			(start -0.12065 -0.2794)
			(end -0.12065 -0.3048)
			(stroke
				(width 0.1)
				(type default)
			)
			(layer "B.Fab")
		)
		(fp_line
			(start -0.12065 -0.3048)
			(end -0.67945 -0.3048)
			(stroke
				(width 0.1)
				(type default)
			)
			(layer "B.Fab")
		)
		(fp_line
			(start -0.67945 0.3048)
			(end -0.120396 0.3048)
			(stroke
				(width 0.1)
				(type default)
			)
			(layer "B.Fab")
		)
		(fp_line
			(start -0.67945 -0.3048)
			(end -0.67945 0.3048)
			(stroke
				(width 0.1)
				(type default)
			)
			(layer "B.Fab")
		)
		(pad "1" smd circle
			(at 0.40005 0)
			(size 0 0)
			(layers "B.Cu" "B.Mask" "B.Paste")
			(net "SMB_DEBUG_AUX_LVC3_USB_SCL")
		)
		(pad "2" smd circle
			(at -0.40005 0)
			(size 0 0)
			(layers "B.Cu" "B.Mask" "B.Paste")
			(net "SMB_DEBUG_AUX_LVC3_USB_R2_SCL")
		)
	)
	(footprint ""
		(layer "B.Cu")
		(at 76.582778 -48.63084 -90)
		(property "Reference" "C12"
			(at 0 0 90)
			(layer "B.SilkS")
			(hide yes)
			(effects
				(font
					(size 1.27 1.27)
				)
				(justify mirror)
			)
		)
		(property "Value" ""
			(at 0 0 90)
			(layer "B.Fab")
			(effects
				(font
					(size 1.27 1.27)
				)
				(justify mirror)
			)
		)
		(duplicate_pad_numbers_are_jumpers no)
		(fp_line
			(start -0.7874 0.4064)
			(end 0.7874 0.4064)
			(stroke
				(width 0.1524)
				(type default)
			)
			(layer "B.SilkS")
		)
		(fp_line
			(start 0.7874 0.4064)
			(end 0.7874 -0.4064)
			(stroke
				(width 0.1524)
				(type default)
			)
			(layer "B.SilkS")
		)
		(fp_line
			(start -0.7874 -0.4064)
			(end -0.7874 0.4064)
			(stroke
				(width 0.1524)
				(type default)
			)
			(layer "B.SilkS")
		)
		(fp_line
			(start 0.7874 -0.4064)
			(end -0.7874 -0.4064)
			(stroke
				(width 0.1524)
				(type default)
			)
			(layer "B.SilkS")
		)
		(fp_line
			(start -0.67945 0.3048)
			(end -0.120396 0.3048)
			(stroke
				(width 0.1)
				(type default)
			)
			(layer "B.Fab")
		)
		(fp_line
			(start -0.120396 0.3048)
			(end -0.120396 0.2794)
			(stroke
				(width 0.1)
				(type default)
			)
			(layer "B.Fab")
		)
		(fp_line
			(start 0.12065 0.3048)
			(end 0.67945 0.3048)
			(stroke
				(width 0.1)
				(type default)
			)
			(layer "B.Fab")
		)
		(fp_line
			(start 0.67945 0.3048)
			(end 0.67945 -0.305054)
			(stroke
				(width 0.1)
				(type default)
			)
			(layer "B.Fab")
		)
		(fp_line
			(start -0.120396 0.2794)
			(end 0.12065 0.2794)
			(stroke
				(width 0.1)
				(type default)
			)
			(layer "B.Fab")
		)
		(fp_line
			(start 0.12065 0.2794)
			(end 0.12065 0.3048)
			(stroke
				(width 0.1)
				(type default)
			)
			(layer "B.Fab")
		)
		(fp_line
			(start -0.12065 -0.2794)
			(end -0.12065 -0.3048)
			(stroke
				(width 0.1)
				(type default)
			)
			(layer "B.Fab")
		)
		(fp_line
			(start 0.12065 -0.2794)
			(end -0.12065 -0.2794)
			(stroke
				(width 0.1)
				(type default)
			)
			(layer "B.Fab")
		)
		(fp_line
			(start -0.67945 -0.3048)
			(end -0.67945 0.3048)
			(stroke
				(width 0.1)
				(type default)
			)
			(layer "B.Fab")
		)
		(fp_line
			(start -0.12065 -0.3048)
			(end -0.67945 -0.3048)
			(stroke
				(width 0.1)
				(type default)
			)
			(layer "B.Fab")
		)
		(fp_line
			(start 0.12065 -0.305054)
			(end 0.12065 -0.2794)
			(stroke
				(width 0.1)
				(type default)
			)
			(layer "B.Fab")
		)
		(fp_line
			(start 0.67945 -0.305054)
			(end 0.12065 -0.305054)
			(stroke
				(width 0.1)
				(type default)
			)
			(layer "B.Fab")
		)
		(pad "1" smd circle
			(at 0.40005 0 90)
			(size 0 0)
			(layers "B.Cu" "B.Mask" "B.Paste")
			(net "M_BMC_DDR4_MCLK_C")
		)
		(pad "2" smd circle
			(at -0.40005 0 90)
			(size 0 0)
			(layers "B.Cu" "B.Mask" "B.Paste")
			(net "GND")
		)
	)
	(footprint ""
		(layer "B.Cu")
		(at 77.47 -33.34766)
		(property "Reference" "R695"
			(at 0 0 0)
			(layer "B.SilkS")
			(hide yes)
			(effects
				(font
					(size 1.27 1.27)
				)
				(justify mirror)
			)
		)
		(property "Value" ""
			(at 0 0 0)
			(layer "B.Fab")
			(effects
				(font
					(size 1.27 1.27)
				)
				(justify mirror)
			)
		)
		(duplicate_pad_numbers_are_jumpers no)
		(fp_line
			(start -0.7874 -0.4064)
			(end -0.7874 0.4064)
			(stroke
				(width 0.1524)
				(type default)
			)
			(layer "B.SilkS")
		)
		(fp_line
			(start -0.7874 0.4064)
			(end 0.7874 0.4064)
			(stroke
				(width 0.1524)
				(type default)
			)
			(layer "B.SilkS")
		)
		(fp_line
			(start 0.7874 -0.4064)
			(end -0.7874 -0.4064)
			(stroke
				(width 0.1524)
				(type default)
			)
			(layer "B.SilkS")
		)
		(fp_line
			(start 0.7874 0.4064)
			(end 0.7874 -0.4064)
			(stroke
				(width 0.1524)
				(type default)
			)
			(layer "B.SilkS")
		)
		(fp_line
			(start -0.67945 -0.3048)
			(end -0.67945 0.3048)
			(stroke
				(width 0.1)
				(type default)
			)
			(layer "B.Fab")
		)
		(fp_line
			(start -0.67945 0.3048)
			(end -0.120396 0.3048)
			(stroke
				(width 0.1)
				(type default)
			)
			(layer "B.Fab")
		)
		(fp_line
			(start -0.12065 -0.3048)
			(end -0.67945 -0.3048)
			(stroke
				(width 0.1)
				(type default)
			)
			(layer "B.Fab")
		)
		(fp_line
			(start -0.12065 -0.2794)
			(end -0.12065 -0.3048)
			(stroke
				(width 0.1)
				(type default)
			)
			(layer "B.Fab")
		)
		(fp_line
			(start -0.120396 0.2794)
			(end 0.12065 0.2794)
			(stroke
				(width 0.1)
				(type default)
			)
			(layer "B.Fab")
		)
		(fp_line
			(start -0.120396 0.3048)
			(end -0.120396 0.2794)
			(stroke
				(width 0.1)
				(type default)
			)
			(layer "B.Fab")
		)
		(fp_line
			(start 0.12065 -0.305054)
			(end 0.12065 -0.2794)
			(stroke
				(width 0.1)
				(type default)
			)
			(layer "B.Fab")
		)
		(fp_line
			(start 0.12065 -0.2794)
			(end -0.12065 -0.2794)
			(stroke
				(width 0.1)
				(type default)
			)
			(layer "B.Fab")
		)
		(fp_line
			(start 0.12065 0.2794)
			(end 0.12065 0.3048)
			(stroke
				(width 0.1)
				(type default)
			)
			(layer "B.Fab")
		)
		(fp_line
			(start 0.12065 0.3048)
			(end 0.67945 0.3048)
			(stroke
				(width 0.1)
				(type default)
			)
			(layer "B.Fab")
		)
		(fp_line
			(start 0.67945 -0.305054)
			(end 0.12065 -0.305054)
			(stroke
				(width 0.1)
				(type default)
			)
			(layer "B.Fab")
		)
		(fp_line
			(start 0.67945 0.3048)
			(end 0.67945 -0.305054)
			(stroke
				(width 0.1)
				(type default)
			)
			(layer "B.Fab")
		)
		(pad "1" smd circle
			(at 0.40005 0 180)
			(size 0 0)
			(layers "B.Cu" "B.Mask" "B.Paste")
			(net "LED_POSTCODE_4")
		)
		(pad "2" smd circle
			(at -0.40005 0 180)
			(size 0 0)
			(layers "B.Cu" "B.Mask" "B.Paste")
			(net "LED_POSTCODE_4_R1")
		)
	)
	(footprint ""
		(layer "B.Cu")
		(at 56.87568 -95.26524 -90)
		(property "Reference" "R738"
			(at 0 0 90)
			(layer "B.SilkS")
			(hide yes)
			(effects
				(font
					(size 1.27 1.27)
				)
				(justify mirror)
			)
		)
		(property "Value" ""
			(at 0 0 90)
			(layer "B.Fab")
			(effects
				(font
					(size 1.27 1.27)
				)
				(justify mirror)
			)
		)
		(duplicate_pad_numbers_are_jumpers no)
		(fp_line
			(start -0.7874 0.4064)
			(end 0.7874 0.4064)
			(stroke
				(width 0.1524)
				(type default)
			)
			(layer "B.SilkS")
		)
		(fp_line
			(start 0.7874 0.4064)
			(end 0.7874 -0.4064)
			(stroke
				(width 0.1524)
				(type default)
			)
			(layer "B.SilkS")
		)
		(fp_line
			(start -0.7874 -0.4064)
			(end -0.7874 0.4064)
			(stroke
				(width 0.1524)
				(type default)
			)
			(layer "B.SilkS")
		)
		(fp_line
			(start 0.7874 -0.4064)
			(end -0.7874 -0.4064)
			(stroke
				(width 0.1524)
				(type default)
			)
			(layer "B.SilkS")
		)
		(fp_line
			(start -0.67945 0.3048)
			(end -0.120396 0.3048)
			(stroke
				(width 0.1)
				(type default)
			)
			(layer "B.Fab")
		)
		(fp_line
			(start -0.120396 0.3048)
			(end -0.120396 0.2794)
			(stroke
				(width 0.1)
				(type default)
			)
			(layer "B.Fab")
		)
		(fp_line
			(start 0.12065 0.3048)
			(end 0.67945 0.3048)
			(stroke
				(width 0.1)
				(type default)
			)
			(layer "B.Fab")
		)
		(fp_line
			(start 0.67945 0.3048)
			(end 0.67945 -0.305054)
			(stroke
				(width 0.1)
				(type default)
			)
			(layer "B.Fab")
		)
		(fp_line
			(start -0.120396 0.2794)
			(end 0.12065 0.2794)
			(stroke
				(width 0.1)
				(type default)
			)
			(layer "B.Fab")
		)
		(fp_line
			(start 0.12065 0.2794)
			(end 0.12065 0.3048)
			(stroke
				(width 0.1)
				(type default)
			)
			(layer "B.Fab")
		)
		(fp_line
			(start -0.12065 -0.2794)
			(end -0.12065 -0.3048)
			(stroke
				(width 0.1)
				(type default)
			)
			(layer "B.Fab")
		)
		(fp_line
			(start 0.12065 -0.2794)
			(end -0.12065 -0.2794)
			(stroke
				(width 0.1)
				(type default)
			)
			(layer "B.Fab")
		)
		(fp_line
			(start -0.67945 -0.3048)
			(end -0.67945 0.3048)
			(stroke
				(width 0.1)
				(type default)
			)
			(layer "B.Fab")
		)
		(fp_line
			(start -0.12065 -0.3048)
			(end -0.67945 -0.3048)
			(stroke
				(width 0.1)
				(type default)
			)
			(layer "B.Fab")
		)
		(fp_line
			(start 0.12065 -0.305054)
			(end 0.12065 -0.2794)
			(stroke
				(width 0.1)
				(type default)
			)
			(layer "B.Fab")
		)
		(fp_line
			(start 0.67945 -0.305054)
			(end 0.12065 -0.305054)
			(stroke
				(width 0.1)
				(type default)
			)
			(layer "B.Fab")
		)
		(pad "1" smd circle
			(at 0.40005 0 90)
			(size 0 0)
			(layers "B.Cu" "B.Mask" "B.Paste")
			(net "P3V3_AUX")
		)
		(pad "2" smd circle
			(at -0.40005 0 90)
			(size 0 0)
			(layers "B.Cu" "B.Mask" "B.Paste")
			(net "LED_POSTCODE_A0")
		)
	)
	(footprint ""
		(layer "B.Cu")
		(at 18.288 -83.693 90)
		(property "Reference" "R303"
			(at 0 0 90)
			(layer "B.SilkS")
			(hide yes)
			(effects
				(font
					(size 1.27 1.27)
				)
				(justify mirror)
			)
		)
		(property "Value" ""
			(at 0 0 90)
			(layer "B.Fab")
			(effects
				(font
					(size 1.27 1.27)
				)
				(justify mirror)
			)
		)
		(duplicate_pad_numbers_are_jumpers no)
		(fp_line
			(start 0.7874 -0.4064)
			(end -0.7874 -0.4064)
			(stroke
				(width 0.1524)
				(type default)
			)
			(layer "B.SilkS")
		)
		(fp_line
			(start -0.7874 -0.4064)
			(end -0.7874 0.4064)
			(stroke
				(width 0.1524)
				(type default)
			)
			(layer "B.SilkS")
		)
		(fp_line
			(start 0.7874 0.4064)
			(end 0.7874 -0.4064)
			(stroke
				(width 0.1524)
				(type default)
			)
			(layer "B.SilkS")
		)
		(fp_line
			(start -0.7874 0.4064)
			(end 0.7874 0.4064)
			(stroke
				(width 0.1524)
				(type default)
			)
			(layer "B.SilkS")
		)
		(fp_line
			(start 0.67945 -0.305054)
			(end 0.12065 -0.305054)
			(stroke
				(width 0.1)
				(type default)
			)
			(layer "B.Fab")
		)
		(fp_line
			(start 0.12065 -0.305054)
			(end 0.12065 -0.2794)
			(stroke
				(width 0.1)
				(type default)
			)
			(layer "B.Fab")
		)
		(fp_line
			(start -0.12065 -0.3048)
			(end -0.67945 -0.3048)
			(stroke
				(width 0.1)
				(type default)
			)
			(layer "B.Fab")
		)
		(fp_line
			(start -0.67945 -0.3048)
			(end -0.67945 0.3048)
			(stroke
				(width 0.1)
				(type default)
			)
			(layer "B.Fab")
		)
		(fp_line
			(start 0.12065 -0.2794)
			(end -0.12065 -0.2794)
			(stroke
				(width 0.1)
				(type default)
			)
			(layer "B.Fab")
		)
		(fp_line
			(start -0.12065 -0.2794)
			(end -0.12065 -0.3048)
			(stroke
				(width 0.1)
				(type default)
			)
			(layer "B.Fab")
		)
		(fp_line
			(start 0.12065 0.2794)
			(end 0.12065 0.3048)
			(stroke
				(width 0.1)
				(type default)
			)
			(layer "B.Fab")
		)
		(fp_line
			(start -0.120396 0.2794)
			(end 0.12065 0.2794)
			(stroke
				(width 0.1)
				(type default)
			)
			(layer "B.Fab")
		)
		(fp_line
			(start 0.67945 0.3048)
			(end 0.67945 -0.305054)
			(stroke
				(width 0.1)
				(type default)
			)
			(layer "B.Fab")
		)
		(fp_line
			(start 0.12065 0.3048)
			(end 0.67945 0.3048)
			(stroke
				(width 0.1)
				(type default)
			)
			(layer "B.Fab")
		)
		(fp_line
			(start -0.120396 0.3048)
			(end -0.120396 0.2794)
			(stroke
				(width 0.1)
				(type default)
			)
			(layer "B.Fab")
		)
		(fp_line
			(start -0.67945 0.3048)
			(end -0.120396 0.3048)
			(stroke
				(width 0.1)
				(type default)
			)
			(layer "B.Fab")
		)
		(pad "1" smd circle
			(at 0.40005 0 270)
			(size 0 0)
			(layers "B.Cu" "B.Mask" "B.Paste")
			(net "SMB_BMC_MM16_R3_SDA")
		)
		(pad "2" smd circle
			(at -0.40005 0 270)
			(size 0 0)
			(layers "B.Cu" "B.Mask" "B.Paste")
			(net "SMB_BMC_MM16_R5_SDA")
		)
	)
	(footprint ""
		(layer "B.Cu")
		(at 84.08924 -52.397152 180)
		(property "Reference" "C168"
			(at 0 0 0)
			(layer "B.SilkS")
			(hide yes)
			(effects
				(font
					(size 1.27 1.27)
				)
				(justify mirror)
			)
		)
		(property "Value" ""
			(at 0 0 0)
			(layer "B.Fab")
			(effects
				(font
					(size 1.27 1.27)
				)
				(justify mirror)
			)
		)
		(duplicate_pad_numbers_are_jumpers no)
		(fp_line
			(start 0.7874 0.4064)
			(end 0.7874 -0.4064)
			(stroke
				(width 0.1524)
				(type default)
			)
			(layer "B.SilkS")
		)
		(fp_line
			(start 0.7874 -0.4064)
			(end -0.7874 -0.4064)
			(stroke
				(width 0.1524)
				(type default)
			)
			(layer "B.SilkS")
		)
		(fp_line
			(start -0.7874 0.4064)
			(end 0.7874 0.4064)
			(stroke
				(width 0.1524)
				(type default)
			)
			(layer "B.SilkS")
		)
		(fp_line
			(start -0.7874 -0.4064)
			(end -0.7874 0.4064)
			(stroke
				(width 0.1524)
				(type default)
			)
			(layer "B.SilkS")
		)
		(fp_line
			(start 0.67945 0.3048)
			(end 0.67945 -0.305054)
			(stroke
				(width 0.1)
				(type default)
			)
			(layer "B.Fab")
		)
		(fp_line
			(start 0.67945 -0.305054)
			(end 0.12065 -0.305054)
			(stroke
				(width 0.1)
				(type default)
			)
			(layer "B.Fab")
		)
		(fp_line
			(start 0.12065 0.3048)
			(end 0.67945 0.3048)
			(stroke
				(width 0.1)
				(type default)
			)
			(layer "B.Fab")
		)
		(fp_line
			(start 0.12065 0.2794)
			(end 0.12065 0.3048)
			(stroke
				(width 0.1)
				(type default)
			)
			(layer "B.Fab")
		)
		(fp_line
			(start 0.12065 -0.2794)
			(end -0.12065 -0.2794)
			(stroke
				(width 0.1)
				(type default)
			)
			(layer "B.Fab")
		)
		(fp_line
			(start 0.12065 -0.305054)
			(end 0.12065 -0.2794)
			(stroke
				(width 0.1)
				(type default)
			)
			(layer "B.Fab")
		)
		(fp_line
			(start -0.120396 0.3048)
			(end -0.120396 0.2794)
			(stroke
				(width 0.1)
				(type default)
			)
			(layer "B.Fab")
		)
		(fp_line
			(start -0.120396 0.2794)
			(end 0.12065 0.2794)
			(stroke
				(width 0.1)
				(type default)
			)
			(layer "B.Fab")
		)
		(fp_line
			(start -0.12065 -0.2794)
			(end -0.12065 -0.3048)
			(stroke
				(width 0.1)
				(type default)
			)
			(layer "B.Fab")
		)
		(fp_line
			(start -0.12065 -0.3048)
			(end -0.67945 -0.3048)
			(stroke
				(width 0.1)
				(type default)
			)
			(layer "B.Fab")
		)
		(fp_line
			(start -0.67945 0.3048)
			(end -0.120396 0.3048)
			(stroke
				(width 0.1)
				(type default)
			)
			(layer "B.Fab")
		)
		(fp_line
			(start -0.67945 -0.3048)
			(end -0.67945 0.3048)
			(stroke
				(width 0.1)
				(type default)
			)
			(layer "B.Fab")
		)
		(pad "1" smd circle
			(at 0.40005 0)
			(size 0 0)
			(layers "B.Cu" "B.Mask" "B.Paste")
			(net "P0V6_DDR_VREF_AUX")
		)
		(pad "2" smd circle
			(at -0.40005 0)
			(size 0 0)
			(layers "B.Cu" "B.Mask" "B.Paste")
			(net "GND")
		)
	)
	(footprint ""
		(layer "B.Cu")
		(at 63.9572 -89.2048 180)
		(property "Reference" "R745"
			(at 0 0 0)
			(layer "B.SilkS")
			(hide yes)
			(effects
				(font
					(size 1.27 1.27)
				)
				(justify mirror)
			)
		)
		(property "Value" ""
			(at 0 0 0)
			(layer "B.Fab")
			(effects
				(font
					(size 1.27 1.27)
				)
				(justify mirror)
			)
		)
		(duplicate_pad_numbers_are_jumpers no)
		(fp_line
			(start 0.7874 0.4064)
			(end 0.7874 -0.4064)
			(stroke
				(width 0.1524)
				(type default)
			)
			(layer "B.SilkS")
		)
		(fp_line
			(start 0.7874 -0.4064)
			(end -0.7874 -0.4064)
			(stroke
				(width 0.1524)
				(type default)
			)
			(layer "B.SilkS")
		)
		(fp_line
			(start -0.7874 0.4064)
			(end 0.7874 0.4064)
			(stroke
				(width 0.1524)
				(type default)
			)
			(layer "B.SilkS")
		)
		(fp_line
			(start -0.7874 -0.4064)
			(end -0.7874 0.4064)
			(stroke
				(width 0.1524)
				(type default)
			)
			(layer "B.SilkS")
		)
		(fp_line
			(start 0.67945 0.3048)
			(end 0.67945 -0.305054)
			(stroke
				(width 0.1)
				(type default)
			)
			(layer "B.Fab")
		)
		(fp_line
			(start 0.67945 -0.305054)
			(end 0.12065 -0.305054)
			(stroke
				(width 0.1)
				(type default)
			)
			(layer "B.Fab")
		)
		(fp_line
			(start 0.12065 0.3048)
			(end 0.67945 0.3048)
			(stroke
				(width 0.1)
				(type default)
			)
			(layer "B.Fab")
		)
		(fp_line
			(start 0.12065 0.2794)
			(end 0.12065 0.3048)
			(stroke
				(width 0.1)
				(type default)
			)
			(layer "B.Fab")
		)
		(fp_line
			(start 0.12065 -0.2794)
			(end -0.12065 -0.2794)
			(stroke
				(width 0.1)
				(type default)
			)
			(layer "B.Fab")
		)
		(fp_line
			(start 0.12065 -0.305054)
			(end 0.12065 -0.2794)
			(stroke
				(width 0.1)
				(type default)
			)
			(layer "B.Fab")
		)
		(fp_line
			(start -0.120396 0.3048)
			(end -0.120396 0.2794)
			(stroke
				(width 0.1)
				(type default)
			)
			(layer "B.Fab")
		)
		(fp_line
			(start -0.120396 0.2794)
			(end 0.12065 0.2794)
			(stroke
				(width 0.1)
				(type default)
			)
			(layer "B.Fab")
		)
		(fp_line
			(start -0.12065 -0.2794)
			(end -0.12065 -0.3048)
			(stroke
				(width 0.1)
				(type default)
			)
			(layer "B.Fab")
		)
		(fp_line
			(start -0.12065 -0.3048)
			(end -0.67945 -0.3048)
			(stroke
				(width 0.1)
				(type default)
			)
			(layer "B.Fab")
		)
		(fp_line
			(start -0.67945 0.3048)
			(end -0.120396 0.3048)
			(stroke
				(width 0.1)
				(type default)
			)
			(layer "B.Fab")
		)
		(fp_line
			(start -0.67945 -0.3048)
			(end -0.67945 0.3048)
			(stroke
				(width 0.1)
				(type default)
			)
			(layer "B.Fab")
		)
		(pad "1" smd circle
			(at 0.40005 0)
			(size 0 0)
			(layers "B.Cu" "B.Mask" "B.Paste")
			(net "LED_POSTCODE_A2")
		)
		(pad "2" smd circle
			(at -0.40005 0)
			(size 0 0)
			(layers "B.Cu" "B.Mask" "B.Paste")
			(net "GND")
		)
	)
	(footprint ""
		(layer "B.Cu")
		(at 17.907 -101.981 -90)
		(property "Reference" "R379"
			(at 0 0 90)
			(layer "B.SilkS")
			(hide yes)
			(effects
				(font
					(size 1.27 1.27)
				)
				(justify mirror)
			)
		)
		(property "Value" ""
			(at 0 0 90)
			(layer "B.Fab")
			(effects
				(font
					(size 1.27 1.27)
				)
				(justify mirror)
			)
		)
		(duplicate_pad_numbers_are_jumpers no)
		(fp_line
			(start -0.7874 0.4064)
			(end 0.7874 0.4064)
			(stroke
				(width 0.1524)
				(type default)
			)
			(layer "B.SilkS")
		)
		(fp_line
			(start 0.7874 0.4064)
			(end 0.7874 -0.4064)
			(stroke
				(width 0.1524)
				(type default)
			)
			(layer "B.SilkS")
		)
		(fp_line
			(start -0.7874 -0.4064)
			(end -0.7874 0.4064)
			(stroke
				(width 0.1524)
				(type default)
			)
			(layer "B.SilkS")
		)
		(fp_line
			(start 0.7874 -0.4064)
			(end -0.7874 -0.4064)
			(stroke
				(width 0.1524)
				(type default)
			)
			(layer "B.SilkS")
		)
		(fp_line
			(start -0.67945 0.3048)
			(end -0.120396 0.3048)
			(stroke
				(width 0.1)
				(type default)
			)
			(layer "B.Fab")
		)
		(fp_line
			(start -0.120396 0.3048)
			(end -0.120396 0.2794)
			(stroke
				(width 0.1)
				(type default)
			)
			(layer "B.Fab")
		)
		(fp_line
			(start 0.12065 0.3048)
			(end 0.67945 0.3048)
			(stroke
				(width 0.1)
				(type default)
			)
			(layer "B.Fab")
		)
		(fp_line
			(start 0.67945 0.3048)
			(end 0.67945 -0.305054)
			(stroke
				(width 0.1)
				(type default)
			)
			(layer "B.Fab")
		)
		(fp_line
			(start -0.120396 0.2794)
			(end 0.12065 0.2794)
			(stroke
				(width 0.1)
				(type default)
			)
			(layer "B.Fab")
		)
		(fp_line
			(start 0.12065 0.2794)
			(end 0.12065 0.3048)
			(stroke
				(width 0.1)
				(type default)
			)
			(layer "B.Fab")
		)
		(fp_line
			(start -0.12065 -0.2794)
			(end -0.12065 -0.3048)
			(stroke
				(width 0.1)
				(type default)
			)
			(layer "B.Fab")
		)
		(fp_line
			(start 0.12065 -0.2794)
			(end -0.12065 -0.2794)
			(stroke
				(width 0.1)
				(type default)
			)
			(layer "B.Fab")
		)
		(fp_line
			(start -0.67945 -0.3048)
			(end -0.67945 0.3048)
			(stroke
				(width 0.1)
				(type default)
			)
			(layer "B.Fab")
		)
		(fp_line
			(start -0.12065 -0.3048)
			(end -0.67945 -0.3048)
			(stroke
				(width 0.1)
				(type default)
			)
			(layer "B.Fab")
		)
		(fp_line
			(start 0.12065 -0.305054)
			(end 0.12065 -0.2794)
			(stroke
				(width 0.1)
				(type default)
			)
			(layer "B.Fab")
		)
		(fp_line
			(start 0.67945 -0.305054)
			(end 0.12065 -0.305054)
			(stroke
				(width 0.1)
				(type default)
			)
			(layer "B.Fab")
		)
		(pad "1" smd circle
			(at 0.40005 0 90)
			(size 0 0)
			(layers "B.Cu" "B.Mask" "B.Paste")
			(net "PWRGD_P1V0_AUX_R1")
		)
		(pad "2" smd circle
			(at -0.40005 0 90)
			(size 0 0)
			(layers "B.Cu" "B.Mask" "B.Paste")
			(net "PWRGD_P1V0_AUX")
		)
	)
	(footprint ""
		(layer "B.Cu")
		(at 42.220134 -39.95166)
		(property "Reference" "R171"
			(at 0 0 0)
			(layer "B.SilkS")
			(hide yes)
			(effects
				(font
					(size 1.27 1.27)
				)
				(justify mirror)
			)
		)
		(property "Value" ""
			(at 0 0 0)
			(layer "B.Fab")
			(effects
				(font
					(size 1.27 1.27)
				)
				(justify mirror)
			)
		)
		(duplicate_pad_numbers_are_jumpers no)
		(fp_line
			(start -0.7874 -0.4064)
			(end -0.7874 0.4064)
			(stroke
				(width 0.1524)
				(type default)
			)
			(layer "B.SilkS")
		)
		(fp_line
			(start -0.7874 0.4064)
			(end 0.7874 0.4064)
			(stroke
				(width 0.1524)
				(type default)
			)
			(layer "B.SilkS")
		)
		(fp_line
			(start 0.7874 -0.4064)
			(end -0.7874 -0.4064)
			(stroke
				(width 0.1524)
				(type default)
			)
			(layer "B.SilkS")
		)
		(fp_line
			(start 0.7874 0.4064)
			(end 0.7874 -0.4064)
			(stroke
				(width 0.1524)
				(type default)
			)
			(layer "B.SilkS")
		)
		(fp_line
			(start -0.67945 -0.3048)
			(end -0.67945 0.3048)
			(stroke
				(width 0.1)
				(type default)
			)
			(layer "B.Fab")
		)
		(fp_line
			(start -0.67945 0.3048)
			(end -0.120396 0.3048)
			(stroke
				(width 0.1)
				(type default)
			)
			(layer "B.Fab")
		)
		(fp_line
			(start -0.12065 -0.3048)
			(end -0.67945 -0.3048)
			(stroke
				(width 0.1)
				(type default)
			)
			(layer "B.Fab")
		)
		(fp_line
			(start -0.12065 -0.2794)
			(end -0.12065 -0.3048)
			(stroke
				(width 0.1)
				(type default)
			)
			(layer "B.Fab")
		)
		(fp_line
			(start -0.120396 0.2794)
			(end 0.12065 0.2794)
			(stroke
				(width 0.1)
				(type default)
			)
			(layer "B.Fab")
		)
		(fp_line
			(start -0.120396 0.3048)
			(end -0.120396 0.2794)
			(stroke
				(width 0.1)
				(type default)
			)
			(layer "B.Fab")
		)
		(fp_line
			(start 0.12065 -0.305054)
			(end 0.12065 -0.2794)
			(stroke
				(width 0.1)
				(type default)
			)
			(layer "B.Fab")
		)
		(fp_line
			(start 0.12065 -0.2794)
			(end -0.12065 -0.2794)
			(stroke
				(width 0.1)
				(type default)
			)
			(layer "B.Fab")
		)
		(fp_line
			(start 0.12065 0.2794)
			(end 0.12065 0.3048)
			(stroke
				(width 0.1)
				(type default)
			)
			(layer "B.Fab")
		)
		(fp_line
			(start 0.12065 0.3048)
			(end 0.67945 0.3048)
			(stroke
				(width 0.1)
				(type default)
			)
			(layer "B.Fab")
		)
		(fp_line
			(start 0.67945 -0.305054)
			(end 0.12065 -0.305054)
			(stroke
				(width 0.1)
				(type default)
			)
			(layer "B.Fab")
		)
		(fp_line
			(start 0.67945 0.3048)
			(end 0.67945 -0.305054)
			(stroke
				(width 0.1)
				(type default)
			)
			(layer "B.Fab")
		)
		(pad "1" smd circle
			(at 0.40005 0 180)
			(size 0 0)
			(layers "B.Cu" "B.Mask" "B.Paste")
			(net "RMII_TXEN_R")
		)
		(pad "2" smd circle
			(at -0.40005 0 180)
			(size 0 0)
			(layers "B.Cu" "B.Mask" "B.Paste")
			(net "RMII_TXEN")
		)
	)
	(footprint ""
		(layer "B.Cu")
		(at 51.30546 -51.69154 180)
		(property "Reference" "C112"
			(at 0 0 0)
			(layer "B.SilkS")
			(hide yes)
			(effects
				(font
					(size 1.27 1.27)
				)
				(justify mirror)
			)
		)
		(property "Value" ""
			(at 0 0 0)
			(layer "B.Fab")
			(effects
				(font
					(size 1.27 1.27)
				)
				(justify mirror)
			)
		)
		(duplicate_pad_numbers_are_jumpers no)
		(fp_line
			(start 0.7874 0.4064)
			(end 0.7874 -0.4064)
			(stroke
				(width 0.1524)
				(type default)
			)
			(layer "B.SilkS")
		)
		(fp_line
			(start 0.7874 -0.4064)
			(end -0.7874 -0.4064)
			(stroke
				(width 0.1524)
				(type default)
			)
			(layer "B.SilkS")
		)
		(fp_line
			(start -0.7874 0.4064)
			(end 0.7874 0.4064)
			(stroke
				(width 0.1524)
				(type default)
			)
			(layer "B.SilkS")
		)
		(fp_line
			(start -0.7874 -0.4064)
			(end -0.7874 0.4064)
			(stroke
				(width 0.1524)
				(type default)
			)
			(layer "B.SilkS")
		)
		(fp_line
			(start 0.67945 0.3048)
			(end 0.67945 -0.305054)
			(stroke
				(width 0.1)
				(type default)
			)
			(layer "B.Fab")
		)
		(fp_line
			(start 0.67945 -0.305054)
			(end 0.12065 -0.305054)
			(stroke
				(width 0.1)
				(type default)
			)
			(layer "B.Fab")
		)
		(fp_line
			(start 0.12065 0.3048)
			(end 0.67945 0.3048)
			(stroke
				(width 0.1)
				(type default)
			)
			(layer "B.Fab")
		)
		(fp_line
			(start 0.12065 0.2794)
			(end 0.12065 0.3048)
			(stroke
				(width 0.1)
				(type default)
			)
			(layer "B.Fab")
		)
		(fp_line
			(start 0.12065 -0.2794)
			(end -0.12065 -0.2794)
			(stroke
				(width 0.1)
				(type default)
			)
			(layer "B.Fab")
		)
		(fp_line
			(start 0.12065 -0.305054)
			(end 0.12065 -0.2794)
			(stroke
				(width 0.1)
				(type default)
			)
			(layer "B.Fab")
		)
		(fp_line
			(start -0.120396 0.3048)
			(end -0.120396 0.2794)
			(stroke
				(width 0.1)
				(type default)
			)
			(layer "B.Fab")
		)
		(fp_line
			(start -0.120396 0.2794)
			(end 0.12065 0.2794)
			(stroke
				(width 0.1)
				(type default)
			)
			(layer "B.Fab")
		)
		(fp_line
			(start -0.12065 -0.2794)
			(end -0.12065 -0.3048)
			(stroke
				(width 0.1)
				(type default)
			)
			(layer "B.Fab")
		)
		(fp_line
			(start -0.12065 -0.3048)
			(end -0.67945 -0.3048)
			(stroke
				(width 0.1)
				(type default)
			)
			(layer "B.Fab")
		)
		(fp_line
			(start -0.67945 0.3048)
			(end -0.120396 0.3048)
			(stroke
				(width 0.1)
				(type default)
			)
			(layer "B.Fab")
		)
		(fp_line
			(start -0.67945 -0.3048)
			(end -0.67945 0.3048)
			(stroke
				(width 0.1)
				(type default)
			)
			(layer "B.Fab")
		)
		(pad "1" smd circle
			(at 0.40005 0)
			(size 0 0)
			(layers "B.Cu" "B.Mask" "B.Paste")
			(net "P1V2_AUX")
		)
		(pad "2" smd circle
			(at -0.40005 0)
			(size 0 0)
			(layers "B.Cu" "B.Mask" "B.Paste")
			(net "GND")
		)
	)
	(footprint ""
		(layer "B.Cu")
		(at 51.558952 -43.765216)
		(property "Reference" "C101"
			(at 0 0 0)
			(layer "B.SilkS")
			(hide yes)
			(effects
				(font
					(size 1.27 1.27)
				)
				(justify mirror)
			)
		)
		(property "Value" ""
			(at 0 0 0)
			(layer "B.Fab")
			(effects
				(font
					(size 1.27 1.27)
				)
				(justify mirror)
			)
		)
		(duplicate_pad_numbers_are_jumpers no)
		(fp_line
			(start -0.7874 -0.4064)
			(end -0.7874 0.4064)
			(stroke
				(width 0.1524)
				(type default)
			)
			(layer "B.SilkS")
		)
		(fp_line
			(start -0.7874 0.4064)
			(end 0.7874 0.4064)
			(stroke
				(width 0.1524)
				(type default)
			)
			(layer "B.SilkS")
		)
		(fp_line
			(start 0.7874 -0.4064)
			(end -0.7874 -0.4064)
			(stroke
				(width 0.1524)
				(type default)
			)
			(layer "B.SilkS")
		)
		(fp_line
			(start 0.7874 0.4064)
			(end 0.7874 -0.4064)
			(stroke
				(width 0.1524)
				(type default)
			)
			(layer "B.SilkS")
		)
		(fp_line
			(start -0.67945 -0.3048)
			(end -0.67945 0.3048)
			(stroke
				(width 0.1)
				(type default)
			)
			(layer "B.Fab")
		)
		(fp_line
			(start -0.67945 0.3048)
			(end -0.120396 0.3048)
			(stroke
				(width 0.1)
				(type default)
			)
			(layer "B.Fab")
		)
		(fp_line
			(start -0.12065 -0.3048)
			(end -0.67945 -0.3048)
			(stroke
				(width 0.1)
				(type default)
			)
			(layer "B.Fab")
		)
		(fp_line
			(start -0.12065 -0.2794)
			(end -0.12065 -0.3048)
			(stroke
				(width 0.1)
				(type default)
			)
			(layer "B.Fab")
		)
		(fp_line
			(start -0.120396 0.2794)
			(end 0.12065 0.2794)
			(stroke
				(width 0.1)
				(type default)
			)
			(layer "B.Fab")
		)
		(fp_line
			(start -0.120396 0.3048)
			(end -0.120396 0.2794)
			(stroke
				(width 0.1)
				(type default)
			)
			(layer "B.Fab")
		)
		(fp_line
			(start 0.12065 -0.305054)
			(end 0.12065 -0.2794)
			(stroke
				(width 0.1)
				(type default)
			)
			(layer "B.Fab")
		)
		(fp_line
			(start 0.12065 -0.2794)
			(end -0.12065 -0.2794)
			(stroke
				(width 0.1)
				(type default)
			)
			(layer "B.Fab")
		)
		(fp_line
			(start 0.12065 0.2794)
			(end 0.12065 0.3048)
			(stroke
				(width 0.1)
				(type default)
			)
			(layer "B.Fab")
		)
		(fp_line
			(start 0.12065 0.3048)
			(end 0.67945 0.3048)
			(stroke
				(width 0.1)
				(type default)
			)
			(layer "B.Fab")
		)
		(fp_line
			(start 0.67945 -0.305054)
			(end 0.12065 -0.305054)
			(stroke
				(width 0.1)
				(type default)
			)
			(layer "B.Fab")
		)
		(fp_line
			(start 0.67945 0.3048)
			(end 0.67945 -0.305054)
			(stroke
				(width 0.1)
				(type default)
			)
			(layer "B.Fab")
		)
		(pad "1" smd circle
			(at 0.40005 0 180)
			(size 0 0)
			(layers "B.Cu" "B.Mask" "B.Paste")
			(net "P3V3_AUX")
		)
		(pad "2" smd circle
			(at -0.40005 0 180)
			(size 0 0)
			(layers "B.Cu" "B.Mask" "B.Paste")
			(net "GND")
		)
	)
	(footprint ""
		(layer "B.Cu")
		(at 11.303 -54.356 90)
		(property "Reference" "C150"
			(at 0 0 90)
			(layer "B.SilkS")
			(hide yes)
			(effects
				(font
					(size 1.27 1.27)
				)
				(justify mirror)
			)
		)
		(property "Value" ""
			(at 0 0 90)
			(layer "B.Fab")
			(effects
				(font
					(size 1.27 1.27)
				)
				(justify mirror)
			)
		)
		(duplicate_pad_numbers_are_jumpers no)
		(fp_line
			(start 0.7874 -0.4064)
			(end -0.7874 -0.4064)
			(stroke
				(width 0.1524)
				(type default)
			)
			(layer "B.SilkS")
		)
		(fp_line
			(start -0.7874 -0.4064)
			(end -0.7874 0.4064)
			(stroke
				(width 0.1524)
				(type default)
			)
			(layer "B.SilkS")
		)
		(fp_line
			(start 0.7874 0.4064)
			(end 0.7874 -0.4064)
			(stroke
				(width 0.1524)
				(type default)
			)
			(layer "B.SilkS")
		)
		(fp_line
			(start -0.7874 0.4064)
			(end 0.7874 0.4064)
			(stroke
				(width 0.1524)
				(type default)
			)
			(layer "B.SilkS")
		)
		(fp_line
			(start 0.67945 -0.305054)
			(end 0.12065 -0.305054)
			(stroke
				(width 0.1)
				(type default)
			)
			(layer "B.Fab")
		)
		(fp_line
			(start 0.12065 -0.305054)
			(end 0.12065 -0.2794)
			(stroke
				(width 0.1)
				(type default)
			)
			(layer "B.Fab")
		)
		(fp_line
			(start -0.12065 -0.3048)
			(end -0.67945 -0.3048)
			(stroke
				(width 0.1)
				(type default)
			)
			(layer "B.Fab")
		)
		(fp_line
			(start -0.67945 -0.3048)
			(end -0.67945 0.3048)
			(stroke
				(width 0.1)
				(type default)
			)
			(layer "B.Fab")
		)
		(fp_line
			(start 0.12065 -0.2794)
			(end -0.12065 -0.2794)
			(stroke
				(width 0.1)
				(type default)
			)
			(layer "B.Fab")
		)
		(fp_line
			(start -0.12065 -0.2794)
			(end -0.12065 -0.3048)
			(stroke
				(width 0.1)
				(type default)
			)
			(layer "B.Fab")
		)
		(fp_line
			(start 0.12065 0.2794)
			(end 0.12065 0.3048)
			(stroke
				(width 0.1)
				(type default)
			)
			(layer "B.Fab")
		)
		(fp_line
			(start -0.120396 0.2794)
			(end 0.12065 0.2794)
			(stroke
				(width 0.1)
				(type default)
			)
			(layer "B.Fab")
		)
		(fp_line
			(start 0.67945 0.3048)
			(end 0.67945 -0.305054)
			(stroke
				(width 0.1)
				(type default)
			)
			(layer "B.Fab")
		)
		(fp_line
			(start 0.12065 0.3048)
			(end 0.67945 0.3048)
			(stroke
				(width 0.1)
				(type default)
			)
			(layer "B.Fab")
		)
		(fp_line
			(start -0.120396 0.3048)
			(end -0.120396 0.2794)
			(stroke
				(width 0.1)
				(type default)
			)
			(layer "B.Fab")
		)
		(fp_line
			(start -0.67945 0.3048)
			(end -0.120396 0.3048)
			(stroke
				(width 0.1)
				(type default)
			)
			(layer "B.Fab")
		)
		(pad "1" smd circle
			(at 0.40005 0 270)
			(size 0 0)
			(layers "B.Cu" "B.Mask" "B.Paste")
			(net "PWRGD_P5V_AUX_R")
		)
		(pad "2" smd circle
			(at -0.40005 0 270)
			(size 0 0)
			(layers "B.Cu" "B.Mask" "B.Paste")
			(net "GND")
		)
	)
	(footprint ""
		(layer "B.Cu")
		(at 34.4424 -49.6824)
		(property "Reference" "R398"
			(at 0 0 0)
			(layer "B.SilkS")
			(hide yes)
			(effects
				(font
					(size 1.27 1.27)
				)
				(justify mirror)
			)
		)
		(property "Value" ""
			(at 0 0 0)
			(layer "B.Fab")
			(effects
				(font
					(size 1.27 1.27)
				)
				(justify mirror)
			)
		)
		(duplicate_pad_numbers_are_jumpers no)
		(fp_line
			(start -0.7874 -0.4064)
			(end -0.7874 0.4064)
			(stroke
				(width 0.1524)
				(type default)
			)
			(layer "B.SilkS")
		)
		(fp_line
			(start -0.7874 0.4064)
			(end 0.7874 0.4064)
			(stroke
				(width 0.1524)
				(type default)
			)
			(layer "B.SilkS")
		)
		(fp_line
			(start 0.7874 -0.4064)
			(end -0.7874 -0.4064)
			(stroke
				(width 0.1524)
				(type default)
			)
			(layer "B.SilkS")
		)
		(fp_line
			(start 0.7874 0.4064)
			(end 0.7874 -0.4064)
			(stroke
				(width 0.1524)
				(type default)
			)
			(layer "B.SilkS")
		)
		(fp_line
			(start -0.67945 -0.3048)
			(end -0.67945 0.3048)
			(stroke
				(width 0.1)
				(type default)
			)
			(layer "B.Fab")
		)
		(fp_line
			(start -0.67945 0.3048)
			(end -0.120396 0.3048)
			(stroke
				(width 0.1)
				(type default)
			)
			(layer "B.Fab")
		)
		(fp_line
			(start -0.12065 -0.3048)
			(end -0.67945 -0.3048)
			(stroke
				(width 0.1)
				(type default)
			)
			(layer "B.Fab")
		)
		(fp_line
			(start -0.12065 -0.2794)
			(end -0.12065 -0.3048)
			(stroke
				(width 0.1)
				(type default)
			)
			(layer "B.Fab")
		)
		(fp_line
			(start -0.120396 0.2794)
			(end 0.12065 0.2794)
			(stroke
				(width 0.1)
				(type default)
			)
			(layer "B.Fab")
		)
		(fp_line
			(start -0.120396 0.3048)
			(end -0.120396 0.2794)
			(stroke
				(width 0.1)
				(type default)
			)
			(layer "B.Fab")
		)
		(fp_line
			(start 0.12065 -0.305054)
			(end 0.12065 -0.2794)
			(stroke
				(width 0.1)
				(type default)
			)
			(layer "B.Fab")
		)
		(fp_line
			(start 0.12065 -0.2794)
			(end -0.12065 -0.2794)
			(stroke
				(width 0.1)
				(type default)
			)
			(layer "B.Fab")
		)
		(fp_line
			(start 0.12065 0.2794)
			(end 0.12065 0.3048)
			(stroke
				(width 0.1)
				(type default)
			)
			(layer "B.Fab")
		)
		(fp_line
			(start 0.12065 0.3048)
			(end 0.67945 0.3048)
			(stroke
				(width 0.1)
				(type default)
			)
			(layer "B.Fab")
		)
		(fp_line
			(start 0.67945 -0.305054)
			(end 0.12065 -0.305054)
			(stroke
				(width 0.1)
				(type default)
			)
			(layer "B.Fab")
		)
		(fp_line
			(start 0.67945 0.3048)
			(end 0.67945 -0.305054)
			(stroke
				(width 0.1)
				(type default)
			)
			(layer "B.Fab")
		)
		(pad "1" smd circle
			(at 0.40005 0 180)
			(size 0 0)
			(layers "B.Cu" "B.Mask" "B.Paste")
			(net "JTAG_1_BMC_TDO")
		)
		(pad "2" smd circle
			(at -0.40005 0 180)
			(size 0 0)
			(layers "B.Cu" "B.Mask" "B.Paste")
			(net "JTAG_1_BMC_TDO_R")
		)
	)
	(footprint ""
		(layer "B.Cu")
		(at 51.2445 -87.8205 180)
		(property "Reference" "R719"
			(at 0 0 0)
			(layer "B.SilkS")
			(hide yes)
			(effects
				(font
					(size 1.27 1.27)
				)
				(justify mirror)
			)
		)
		(property "Value" ""
			(at 0 0 0)
			(layer "B.Fab")
			(effects
				(font
					(size 1.27 1.27)
				)
				(justify mirror)
			)
		)
		(duplicate_pad_numbers_are_jumpers no)
		(fp_line
			(start 0.7874 0.4064)
			(end 0.7874 -0.4064)
			(stroke
				(width 0.1524)
				(type default)
			)
			(layer "B.SilkS")
		)
		(fp_line
			(start 0.7874 -0.4064)
			(end -0.7874 -0.4064)
			(stroke
				(width 0.1524)
				(type default)
			)
			(layer "B.SilkS")
		)
		(fp_line
			(start -0.7874 0.4064)
			(end 0.7874 0.4064)
			(stroke
				(width 0.1524)
				(type default)
			)
			(layer "B.SilkS")
		)
		(fp_line
			(start -0.7874 -0.4064)
			(end -0.7874 0.4064)
			(stroke
				(width 0.1524)
				(type default)
			)
			(layer "B.SilkS")
		)
		(fp_line
			(start 0.67945 0.3048)
			(end 0.67945 -0.305054)
			(stroke
				(width 0.1)
				(type default)
			)
			(layer "B.Fab")
		)
		(fp_line
			(start 0.67945 -0.305054)
			(end 0.12065 -0.305054)
			(stroke
				(width 0.1)
				(type default)
			)
			(layer "B.Fab")
		)
		(fp_line
			(start 0.12065 0.3048)
			(end 0.67945 0.3048)
			(stroke
				(width 0.1)
				(type default)
			)
			(layer "B.Fab")
		)
		(fp_line
			(start 0.12065 0.2794)
			(end 0.12065 0.3048)
			(stroke
				(width 0.1)
				(type default)
			)
			(layer "B.Fab")
		)
		(fp_line
			(start 0.12065 -0.2794)
			(end -0.12065 -0.2794)
			(stroke
				(width 0.1)
				(type default)
			)
			(layer "B.Fab")
		)
		(fp_line
			(start 0.12065 -0.305054)
			(end 0.12065 -0.2794)
			(stroke
				(width 0.1)
				(type default)
			)
			(layer "B.Fab")
		)
		(fp_line
			(start -0.120396 0.3048)
			(end -0.120396 0.2794)
			(stroke
				(width 0.1)
				(type default)
			)
			(layer "B.Fab")
		)
		(fp_line
			(start -0.120396 0.2794)
			(end 0.12065 0.2794)
			(stroke
				(width 0.1)
				(type default)
			)
			(layer "B.Fab")
		)
		(fp_line
			(start -0.12065 -0.2794)
			(end -0.12065 -0.3048)
			(stroke
				(width 0.1)
				(type default)
			)
			(layer "B.Fab")
		)
		(fp_line
			(start -0.12065 -0.3048)
			(end -0.67945 -0.3048)
			(stroke
				(width 0.1)
				(type default)
			)
			(layer "B.Fab")
		)
		(fp_line
			(start -0.67945 0.3048)
			(end -0.120396 0.3048)
			(stroke
				(width 0.1)
				(type default)
			)
			(layer "B.Fab")
		)
		(fp_line
			(start -0.67945 -0.3048)
			(end -0.67945 0.3048)
			(stroke
				(width 0.1)
				(type default)
			)
			(layer "B.Fab")
		)
		(pad "1" smd circle
			(at 0.40005 0)
			(size 0 0)
			(layers "B.Cu" "B.Mask" "B.Paste")
			(net "PWRGD_PSU_AC_PWROK")
		)
		(pad "2" smd circle
			(at -0.40005 0)
			(size 0 0)
			(layers "B.Cu" "B.Mask" "B.Paste")
			(net "PWRGD_DSW_PWROK_R3")
		)
	)
	(footprint ""
		(layer "B.Cu")
		(at 24.003 -18.034 90)
		(property "Reference" "R419"
			(at 0 0 90)
			(layer "B.SilkS")
			(hide yes)
			(effects
				(font
					(size 1.27 1.27)
				)
				(justify mirror)
			)
		)
		(property "Value" ""
			(at 0 0 90)
			(layer "B.Fab")
			(effects
				(font
					(size 1.27 1.27)
				)
				(justify mirror)
			)
		)
		(duplicate_pad_numbers_are_jumpers no)
		(fp_line
			(start 0.7874 -0.4064)
			(end -0.7874 -0.4064)
			(stroke
				(width 0.1524)
				(type default)
			)
			(layer "B.SilkS")
		)
		(fp_line
			(start -0.7874 -0.4064)
			(end -0.7874 0.4064)
			(stroke
				(width 0.1524)
				(type default)
			)
			(layer "B.SilkS")
		)
		(fp_line
			(start 0.7874 0.4064)
			(end 0.7874 -0.4064)
			(stroke
				(width 0.1524)
				(type default)
			)
			(layer "B.SilkS")
		)
		(fp_line
			(start -0.7874 0.4064)
			(end 0.7874 0.4064)
			(stroke
				(width 0.1524)
				(type default)
			)
			(layer "B.SilkS")
		)
		(fp_line
			(start 0.67945 -0.305054)
			(end 0.12065 -0.305054)
			(stroke
				(width 0.1)
				(type default)
			)
			(layer "B.Fab")
		)
		(fp_line
			(start 0.12065 -0.305054)
			(end 0.12065 -0.2794)
			(stroke
				(width 0.1)
				(type default)
			)
			(layer "B.Fab")
		)
		(fp_line
			(start -0.12065 -0.3048)
			(end -0.67945 -0.3048)
			(stroke
				(width 0.1)
				(type default)
			)
			(layer "B.Fab")
		)
		(fp_line
			(start -0.67945 -0.3048)
			(end -0.67945 0.3048)
			(stroke
				(width 0.1)
				(type default)
			)
			(layer "B.Fab")
		)
		(fp_line
			(start 0.12065 -0.2794)
			(end -0.12065 -0.2794)
			(stroke
				(width 0.1)
				(type default)
			)
			(layer "B.Fab")
		)
		(fp_line
			(start -0.12065 -0.2794)
			(end -0.12065 -0.3048)
			(stroke
				(width 0.1)
				(type default)
			)
			(layer "B.Fab")
		)
		(fp_line
			(start 0.12065 0.2794)
			(end 0.12065 0.3048)
			(stroke
				(width 0.1)
				(type default)
			)
			(layer "B.Fab")
		)
		(fp_line
			(start -0.120396 0.2794)
			(end 0.12065 0.2794)
			(stroke
				(width 0.1)
				(type default)
			)
			(layer "B.Fab")
		)
		(fp_line
			(start 0.67945 0.3048)
			(end 0.67945 -0.305054)
			(stroke
				(width 0.1)
				(type default)
			)
			(layer "B.Fab")
		)
		(fp_line
			(start 0.12065 0.3048)
			(end 0.67945 0.3048)
			(stroke
				(width 0.1)
				(type default)
			)
			(layer "B.Fab")
		)
		(fp_line
			(start -0.120396 0.3048)
			(end -0.120396 0.2794)
			(stroke
				(width 0.1)
				(type default)
			)
			(layer "B.Fab")
		)
		(fp_line
			(start -0.67945 0.3048)
			(end -0.120396 0.3048)
			(stroke
				(width 0.1)
				(type default)
			)
			(layer "B.Fab")
		)
		(pad "1" smd circle
			(at 0.40005 0 270)
			(size 0 0)
			(layers "B.Cu" "B.Mask" "B.Paste")
			(net "TMC75_A2")
		)
		(pad "2" smd circle
			(at -0.40005 0 270)
			(size 0 0)
			(layers "B.Cu" "B.Mask" "B.Paste")
			(net "GND")
		)
	)
	(footprint ""
		(layer "B.Cu")
		(at 80.018636 -47.846488)
		(property "Reference" "C222"
			(at 0 0 0)
			(layer "B.SilkS")
			(hide yes)
			(effects
				(font
					(size 1.27 1.27)
				)
				(justify mirror)
			)
		)
		(property "Value" ""
			(at 0 0 0)
			(layer "B.Fab")
			(effects
				(font
					(size 1.27 1.27)
				)
				(justify mirror)
			)
		)
		(duplicate_pad_numbers_are_jumpers no)
		(fp_line
			(start -0.7874 -0.4064)
			(end -0.7874 0.4064)
			(stroke
				(width 0.1524)
				(type default)
			)
			(layer "B.SilkS")
		)
		(fp_line
			(start -0.7874 0.4064)
			(end 0.7874 0.4064)
			(stroke
				(width 0.1524)
				(type default)
			)
			(layer "B.SilkS")
		)
		(fp_line
			(start 0.7874 -0.4064)
			(end -0.7874 -0.4064)
			(stroke
				(width 0.1524)
				(type default)
			)
			(layer "B.SilkS")
		)
		(fp_line
			(start 0.7874 0.4064)
			(end 0.7874 -0.4064)
			(stroke
				(width 0.1524)
				(type default)
			)
			(layer "B.SilkS")
		)
		(fp_line
			(start -0.67945 -0.3048)
			(end -0.67945 0.3048)
			(stroke
				(width 0.1)
				(type default)
			)
			(layer "B.Fab")
		)
		(fp_line
			(start -0.67945 0.3048)
			(end -0.120396 0.3048)
			(stroke
				(width 0.1)
				(type default)
			)
			(layer "B.Fab")
		)
		(fp_line
			(start -0.12065 -0.3048)
			(end -0.67945 -0.3048)
			(stroke
				(width 0.1)
				(type default)
			)
			(layer "B.Fab")
		)
		(fp_line
			(start -0.12065 -0.2794)
			(end -0.12065 -0.3048)
			(stroke
				(width 0.1)
				(type default)
			)
			(layer "B.Fab")
		)
		(fp_line
			(start -0.120396 0.2794)
			(end 0.12065 0.2794)
			(stroke
				(width 0.1)
				(type default)
			)
			(layer "B.Fab")
		)
		(fp_line
			(start -0.120396 0.3048)
			(end -0.120396 0.2794)
			(stroke
				(width 0.1)
				(type default)
			)
			(layer "B.Fab")
		)
		(fp_line
			(start 0.12065 -0.305054)
			(end 0.12065 -0.2794)
			(stroke
				(width 0.1)
				(type default)
			)
			(layer "B.Fab")
		)
		(fp_line
			(start 0.12065 -0.2794)
			(end -0.12065 -0.2794)
			(stroke
				(width 0.1)
				(type default)
			)
			(layer "B.Fab")
		)
		(fp_line
			(start 0.12065 0.2794)
			(end 0.12065 0.3048)
			(stroke
				(width 0.1)
				(type default)
			)
			(layer "B.Fab")
		)
		(fp_line
			(start 0.12065 0.3048)
			(end 0.67945 0.3048)
			(stroke
				(width 0.1)
				(type default)
			)
			(layer "B.Fab")
		)
		(fp_line
			(start 0.67945 -0.305054)
			(end 0.12065 -0.305054)
			(stroke
				(width 0.1)
				(type default)
			)
			(layer "B.Fab")
		)
		(fp_line
			(start 0.67945 0.3048)
			(end 0.67945 -0.305054)
			(stroke
				(width 0.1)
				(type default)
			)
			(layer "B.Fab")
		)
		(pad "1" smd circle
			(at 0.40005 0 180)
			(size 0 0)
			(layers "B.Cu" "B.Mask" "B.Paste")
			(net "P1V2_AUX")
		)
		(pad "2" smd circle
			(at -0.40005 0 180)
			(size 0 0)
			(layers "B.Cu" "B.Mask" "B.Paste")
			(net "GND")
		)
	)
	(footprint ""
		(layer "B.Cu")
		(at 27.305 -101.981 90)
		(property "Reference" "L19"
			(at 0 0 90)
			(layer "B.SilkS")
			(hide yes)
			(effects
				(font
					(size 1.27 1.27)
				)
				(justify mirror)
			)
		)
		(property "Value" ""
			(at 0 0 90)
			(layer "B.Fab")
			(effects
				(font
					(size 1.27 1.27)
				)
				(justify mirror)
			)
		)
		(duplicate_pad_numbers_are_jumpers no)
		(fp_line
			(start 1.27 -0.5842)
			(end -1.27 -0.5842)
			(stroke
				(width 0.1524)
				(type default)
			)
			(layer "B.SilkS")
		)
		(fp_line
			(start 1.27 -0.5588)
			(end 1.27 -0.5842)
			(stroke
				(width 0.1524)
				(type default)
			)
			(layer "B.SilkS")
		)
		(fp_line
			(start 1.27 0.5842)
			(end 1.27 -0.5842)
			(stroke
				(width 0.1524)
				(type default)
			)
			(layer "B.SilkS")
		)
		(fp_line
			(start 0.127 0.5842)
			(end 0.127 -0.5842)
			(stroke
				(width 0.1524)
				(type default)
			)
			(layer "B.SilkS")
		)
		(fp_line
			(start -0.127 0.5842)
			(end -0.127 -0.5842)
			(stroke
				(width 0.1524)
				(type default)
			)
			(layer "B.SilkS")
		)
		(fp_line
			(start -1.27 0.5842)
			(end -1.27 -0.5842)
			(stroke
				(width 0.1524)
				(type default)
			)
			(layer "B.SilkS")
		)
		(fp_line
			(start -1.27 0.5842)
			(end 1.27 0.5842)
			(stroke
				(width 0.1524)
				(type default)
			)
			(layer "B.SilkS")
		)
		(fp_line
			(start 0.9144 -0.508)
			(end -0.9144 -0.508)
			(stroke
				(width 0.1)
				(type default)
			)
			(layer "B.Fab")
		)
		(fp_line
			(start -0.9144 -0.508)
			(end -0.914654 -0.406654)
			(stroke
				(width 0.1)
				(type default)
			)
			(layer "B.Fab")
		)
		(fp_line
			(start 1.194308 -0.406654)
			(end 0.914654 -0.406654)
			(stroke
				(width 0.1)
				(type default)
			)
			(layer "B.Fab")
		)
		(fp_line
			(start 0.914654 -0.406654)
			(end 0.9144 -0.508)
			(stroke
				(width 0.1)
				(type default)
			)
			(layer "B.Fab")
		)
		(fp_line
			(start -0.914654 -0.406654)
			(end -1.193546 -0.406654)
			(stroke
				(width 0.1)
				(type default)
			)
			(layer "B.Fab")
		)
		(fp_line
			(start -1.193546 -0.406654)
			(end -1.1938 0.4064)
			(stroke
				(width 0.1)
				(type default)
			)
			(layer "B.Fab")
		)
		(fp_line
			(start -0.9144 0.4064)
			(end -0.9144 0.508)
			(stroke
				(width 0.1)
				(type default)
			)
			(layer "B.Fab")
		)
		(fp_line
			(start -1.1938 0.4064)
			(end -0.9144 0.4064)
			(stroke
				(width 0.1)
				(type default)
			)
			(layer "B.Fab")
		)
		(fp_line
			(start 1.194308 0.406654)
			(end 1.194308 -0.406654)
			(stroke
				(width 0.1)
				(type default)
			)
			(layer "B.Fab")
		)
		(fp_line
			(start 0.914654 0.406654)
			(end 1.194308 0.406654)
			(stroke
				(width 0.1)
				(type default)
			)
			(layer "B.Fab")
		)
		(fp_line
			(start 0.9144 0.508)
			(end 0.914654 0.406654)
			(stroke
				(width 0.1)
				(type default)
			)
			(layer "B.Fab")
		)
		(fp_line
			(start -0.9144 0.508)
			(end 0.9144 0.508)
			(stroke
				(width 0.1)
				(type default)
			)
			(layer "B.Fab")
		)
		(pad "1" smd rect
			(at 0.7366 0)
			(size 0.7112 0.8128)
			(layers "B.Cu" "B.Mask" "B.Paste")
			(net "P3V3_AUX")
		)
		(pad "2" smd rect
			(at -0.7366 0)
			(size 0.7112 0.8128)
			(layers "B.Cu" "B.Mask" "B.Paste")
			(net "PVCCA_AUX_PLD")
		)
	)
	(footprint ""
		(layer "B.Cu")
		(at 29.468826 -92.106242)
		(property "Reference" "R519"
			(at 0 0 0)
			(layer "B.SilkS")
			(hide yes)
			(effects
				(font
					(size 1.27 1.27)
				)
				(justify mirror)
			)
		)
		(property "Value" ""
			(at 0 0 0)
			(layer "B.Fab")
			(effects
				(font
					(size 1.27 1.27)
				)
				(justify mirror)
			)
		)
		(duplicate_pad_numbers_are_jumpers no)
		(fp_line
			(start -0.7874 -0.4064)
			(end -0.7874 0.4064)
			(stroke
				(width 0.1524)
				(type default)
			)
			(layer "B.SilkS")
		)
		(fp_line
			(start -0.7874 0.4064)
			(end 0.7874 0.4064)
			(stroke
				(width 0.1524)
				(type default)
			)
			(layer "B.SilkS")
		)
		(fp_line
			(start 0.7874 -0.4064)
			(end -0.7874 -0.4064)
			(stroke
				(width 0.1524)
				(type default)
			)
			(layer "B.SilkS")
		)
		(fp_line
			(start 0.7874 0.4064)
			(end 0.7874 -0.4064)
			(stroke
				(width 0.1524)
				(type default)
			)
			(layer "B.SilkS")
		)
		(fp_line
			(start -0.67945 -0.3048)
			(end -0.67945 0.3048)
			(stroke
				(width 0.1)
				(type default)
			)
			(layer "B.Fab")
		)
		(fp_line
			(start -0.67945 0.3048)
			(end -0.120396 0.3048)
			(stroke
				(width 0.1)
				(type default)
			)
			(layer "B.Fab")
		)
		(fp_line
			(start -0.12065 -0.3048)
			(end -0.67945 -0.3048)
			(stroke
				(width 0.1)
				(type default)
			)
			(layer "B.Fab")
		)
		(fp_line
			(start -0.12065 -0.2794)
			(end -0.12065 -0.3048)
			(stroke
				(width 0.1)
				(type default)
			)
			(layer "B.Fab")
		)
		(fp_line
			(start -0.120396 0.2794)
			(end 0.12065 0.2794)
			(stroke
				(width 0.1)
				(type default)
			)
			(layer "B.Fab")
		)
		(fp_line
			(start -0.120396 0.3048)
			(end -0.120396 0.2794)
			(stroke
				(width 0.1)
				(type default)
			)
			(layer "B.Fab")
		)
		(fp_line
			(start 0.12065 -0.305054)
			(end 0.12065 -0.2794)
			(stroke
				(width 0.1)
				(type default)
			)
			(layer "B.Fab")
		)
		(fp_line
			(start 0.12065 -0.2794)
			(end -0.12065 -0.2794)
			(stroke
				(width 0.1)
				(type default)
			)
			(layer "B.Fab")
		)
		(fp_line
			(start 0.12065 0.2794)
			(end 0.12065 0.3048)
			(stroke
				(width 0.1)
				(type default)
			)
			(layer "B.Fab")
		)
		(fp_line
			(start 0.12065 0.3048)
			(end 0.67945 0.3048)
			(stroke
				(width 0.1)
				(type default)
			)
			(layer "B.Fab")
		)
		(fp_line
			(start 0.67945 -0.305054)
			(end 0.12065 -0.305054)
			(stroke
				(width 0.1)
				(type default)
			)
			(layer "B.Fab")
		)
		(fp_line
			(start 0.67945 0.3048)
			(end 0.67945 -0.305054)
			(stroke
				(width 0.1)
				(type default)
			)
			(layer "B.Fab")
		)
		(pad "1" smd circle
			(at 0.40005 0 180)
			(size 0 0)
			(layers "B.Cu" "B.Mask" "B.Paste")
			(net "BMC_CPLD_GPIO_2")
		)
		(pad "2" smd circle
			(at -0.40005 0 180)
			(size 0 0)
			(layers "B.Cu" "B.Mask" "B.Paste")
			(net "BMC_CPLD_GPIO_2_R2")
		)
	)
	(footprint ""
		(layer "B.Cu")
		(at 41.913302 -63.756794 -90)
		(property "Reference" "R197"
			(at 0 0 90)
			(layer "B.SilkS")
			(hide yes)
			(effects
				(font
					(size 1.27 1.27)
				)
				(justify mirror)
			)
		)
		(property "Value" ""
			(at 0 0 90)
			(layer "B.Fab")
			(effects
				(font
					(size 1.27 1.27)
				)
				(justify mirror)
			)
		)
		(duplicate_pad_numbers_are_jumpers no)
		(fp_line
			(start -0.7874 0.4064)
			(end 0.7874 0.4064)
			(stroke
				(width 0.1524)
				(type default)
			)
			(layer "B.SilkS")
		)
		(fp_line
			(start 0.7874 0.4064)
			(end 0.7874 -0.4064)
			(stroke
				(width 0.1524)
				(type default)
			)
			(layer "B.SilkS")
		)
		(fp_line
			(start -0.7874 -0.4064)
			(end -0.7874 0.4064)
			(stroke
				(width 0.1524)
				(type default)
			)
			(layer "B.SilkS")
		)
		(fp_line
			(start 0.7874 -0.4064)
			(end -0.7874 -0.4064)
			(stroke
				(width 0.1524)
				(type default)
			)
			(layer "B.SilkS")
		)
		(fp_line
			(start -0.67945 0.3048)
			(end -0.120396 0.3048)
			(stroke
				(width 0.1)
				(type default)
			)
			(layer "B.Fab")
		)
		(fp_line
			(start -0.120396 0.3048)
			(end -0.120396 0.2794)
			(stroke
				(width 0.1)
				(type default)
			)
			(layer "B.Fab")
		)
		(fp_line
			(start 0.12065 0.3048)
			(end 0.67945 0.3048)
			(stroke
				(width 0.1)
				(type default)
			)
			(layer "B.Fab")
		)
		(fp_line
			(start 0.67945 0.3048)
			(end 0.67945 -0.305054)
			(stroke
				(width 0.1)
				(type default)
			)
			(layer "B.Fab")
		)
		(fp_line
			(start -0.120396 0.2794)
			(end 0.12065 0.2794)
			(stroke
				(width 0.1)
				(type default)
			)
			(layer "B.Fab")
		)
		(fp_line
			(start 0.12065 0.2794)
			(end 0.12065 0.3048)
			(stroke
				(width 0.1)
				(type default)
			)
			(layer "B.Fab")
		)
		(fp_line
			(start -0.12065 -0.2794)
			(end -0.12065 -0.3048)
			(stroke
				(width 0.1)
				(type default)
			)
			(layer "B.Fab")
		)
		(fp_line
			(start 0.12065 -0.2794)
			(end -0.12065 -0.2794)
			(stroke
				(width 0.1)
				(type default)
			)
			(layer "B.Fab")
		)
		(fp_line
			(start -0.67945 -0.3048)
			(end -0.67945 0.3048)
			(stroke
				(width 0.1)
				(type default)
			)
			(layer "B.Fab")
		)
		(fp_line
			(start -0.12065 -0.3048)
			(end -0.67945 -0.3048)
			(stroke
				(width 0.1)
				(type default)
			)
			(layer "B.Fab")
		)
		(fp_line
			(start 0.12065 -0.305054)
			(end 0.12065 -0.2794)
			(stroke
				(width 0.1)
				(type default)
			)
			(layer "B.Fab")
		)
		(fp_line
			(start 0.67945 -0.305054)
			(end 0.12065 -0.305054)
			(stroke
				(width 0.1)
				(type default)
			)
			(layer "B.Fab")
		)
		(pad "1" smd circle
			(at 0.40005 0 90)
			(size 0 0)
			(layers "B.Cu" "B.Mask" "B.Paste")
			(net "P1V2_P1V0_I3C_VDDL1")
		)
		(pad "2" smd circle
			(at -0.40005 0 90)
			(size 0 0)
			(layers "B.Cu" "B.Mask" "B.Paste")
			(net "I3C4_SPD_SDA")
		)
	)
	(footprint ""
		(layer "B.Cu")
		(at 63.014098 -28.356306 -90)
		(property "Reference" "R256"
			(at 0 0 90)
			(layer "B.SilkS")
			(hide yes)
			(effects
				(font
					(size 1.27 1.27)
				)
				(justify mirror)
			)
		)
		(property "Value" ""
			(at 0 0 90)
			(layer "B.Fab")
			(effects
				(font
					(size 1.27 1.27)
				)
				(justify mirror)
			)
		)
		(duplicate_pad_numbers_are_jumpers no)
		(fp_line
			(start -0.7874 0.4064)
			(end 0.7874 0.4064)
			(stroke
				(width 0.1524)
				(type default)
			)
			(layer "B.SilkS")
		)
		(fp_line
			(start 0.7874 0.4064)
			(end 0.7874 -0.4064)
			(stroke
				(width 0.1524)
				(type default)
			)
			(layer "B.SilkS")
		)
		(fp_line
			(start -0.7874 -0.4064)
			(end -0.7874 0.4064)
			(stroke
				(width 0.1524)
				(type default)
			)
			(layer "B.SilkS")
		)
		(fp_line
			(start 0.7874 -0.4064)
			(end -0.7874 -0.4064)
			(stroke
				(width 0.1524)
				(type default)
			)
			(layer "B.SilkS")
		)
		(fp_line
			(start -0.67945 0.3048)
			(end -0.120396 0.3048)
			(stroke
				(width 0.1)
				(type default)
			)
			(layer "B.Fab")
		)
		(fp_line
			(start -0.120396 0.3048)
			(end -0.120396 0.2794)
			(stroke
				(width 0.1)
				(type default)
			)
			(layer "B.Fab")
		)
		(fp_line
			(start 0.12065 0.3048)
			(end 0.67945 0.3048)
			(stroke
				(width 0.1)
				(type default)
			)
			(layer "B.Fab")
		)
		(fp_line
			(start 0.67945 0.3048)
			(end 0.67945 -0.305054)
			(stroke
				(width 0.1)
				(type default)
			)
			(layer "B.Fab")
		)
		(fp_line
			(start -0.120396 0.2794)
			(end 0.12065 0.2794)
			(stroke
				(width 0.1)
				(type default)
			)
			(layer "B.Fab")
		)
		(fp_line
			(start 0.12065 0.2794)
			(end 0.12065 0.3048)
			(stroke
				(width 0.1)
				(type default)
			)
			(layer "B.Fab")
		)
		(fp_line
			(start -0.12065 -0.2794)
			(end -0.12065 -0.3048)
			(stroke
				(width 0.1)
				(type default)
			)
			(layer "B.Fab")
		)
		(fp_line
			(start 0.12065 -0.2794)
			(end -0.12065 -0.2794)
			(stroke
				(width 0.1)
				(type default)
			)
			(layer "B.Fab")
		)
		(fp_line
			(start -0.67945 -0.3048)
			(end -0.67945 0.3048)
			(stroke
				(width 0.1)
				(type default)
			)
			(layer "B.Fab")
		)
		(fp_line
			(start -0.12065 -0.3048)
			(end -0.67945 -0.3048)
			(stroke
				(width 0.1)
				(type default)
			)
			(layer "B.Fab")
		)
		(fp_line
			(start 0.12065 -0.305054)
			(end 0.12065 -0.2794)
			(stroke
				(width 0.1)
				(type default)
			)
			(layer "B.Fab")
		)
		(fp_line
			(start 0.67945 -0.305054)
			(end 0.12065 -0.305054)
			(stroke
				(width 0.1)
				(type default)
			)
			(layer "B.Fab")
		)
		(pad "1" smd circle
			(at 0.40005 0 90)
			(size 0 0)
			(layers "B.Cu" "B.Mask" "B.Paste")
			(net "P3V3_AUX")
		)
		(pad "2" smd circle
			(at -0.40005 0 90)
			(size 0 0)
			(layers "B.Cu" "B.Mask" "B.Paste")
			(net "SMB_BMC_MM7_R_SCL")
		)
	)
	(footprint ""
		(layer "B.Cu")
		(at 60.452 -27.87904)
		(property "Reference" "R253"
			(at 0 0 0)
			(layer "B.SilkS")
			(hide yes)
			(effects
				(font
					(size 1.27 1.27)
				)
				(justify mirror)
			)
		)
		(property "Value" ""
			(at 0 0 0)
			(layer "B.Fab")
			(effects
				(font
					(size 1.27 1.27)
				)
				(justify mirror)
			)
		)
		(duplicate_pad_numbers_are_jumpers no)
		(fp_line
			(start -0.7874 -0.4064)
			(end -0.7874 0.4064)
			(stroke
				(width 0.1524)
				(type default)
			)
			(layer "B.SilkS")
		)
		(fp_line
			(start -0.7874 0.4064)
			(end 0.7874 0.4064)
			(stroke
				(width 0.1524)
				(type default)
			)
			(layer "B.SilkS")
		)
		(fp_line
			(start 0.7874 -0.4064)
			(end -0.7874 -0.4064)
			(stroke
				(width 0.1524)
				(type default)
			)
			(layer "B.SilkS")
		)
		(fp_line
			(start 0.7874 0.4064)
			(end 0.7874 -0.4064)
			(stroke
				(width 0.1524)
				(type default)
			)
			(layer "B.SilkS")
		)
		(fp_line
			(start -0.67945 -0.3048)
			(end -0.67945 0.3048)
			(stroke
				(width 0.1)
				(type default)
			)
			(layer "B.Fab")
		)
		(fp_line
			(start -0.67945 0.3048)
			(end -0.120396 0.3048)
			(stroke
				(width 0.1)
				(type default)
			)
			(layer "B.Fab")
		)
		(fp_line
			(start -0.12065 -0.3048)
			(end -0.67945 -0.3048)
			(stroke
				(width 0.1)
				(type default)
			)
			(layer "B.Fab")
		)
		(fp_line
			(start -0.12065 -0.2794)
			(end -0.12065 -0.3048)
			(stroke
				(width 0.1)
				(type default)
			)
			(layer "B.Fab")
		)
		(fp_line
			(start -0.120396 0.2794)
			(end 0.12065 0.2794)
			(stroke
				(width 0.1)
				(type default)
			)
			(layer "B.Fab")
		)
		(fp_line
			(start -0.120396 0.3048)
			(end -0.120396 0.2794)
			(stroke
				(width 0.1)
				(type default)
			)
			(layer "B.Fab")
		)
		(fp_line
			(start 0.12065 -0.305054)
			(end 0.12065 -0.2794)
			(stroke
				(width 0.1)
				(type default)
			)
			(layer "B.Fab")
		)
		(fp_line
			(start 0.12065 -0.2794)
			(end -0.12065 -0.2794)
			(stroke
				(width 0.1)
				(type default)
			)
			(layer "B.Fab")
		)
		(fp_line
			(start 0.12065 0.2794)
			(end 0.12065 0.3048)
			(stroke
				(width 0.1)
				(type default)
			)
			(layer "B.Fab")
		)
		(fp_line
			(start 0.12065 0.3048)
			(end 0.67945 0.3048)
			(stroke
				(width 0.1)
				(type default)
			)
			(layer "B.Fab")
		)
		(fp_line
			(start 0.67945 -0.305054)
			(end 0.12065 -0.305054)
			(stroke
				(width 0.1)
				(type default)
			)
			(layer "B.Fab")
		)
		(fp_line
			(start 0.67945 0.3048)
			(end 0.67945 -0.305054)
			(stroke
				(width 0.1)
				(type default)
			)
			(layer "B.Fab")
		)
		(pad "1" smd circle
			(at 0.40005 0 180)
			(size 0 0)
			(layers "B.Cu" "B.Mask" "B.Paste")
			(net "P3V3_AUX")
		)
		(pad "2" smd circle
			(at -0.40005 0 180)
			(size 0 0)
			(layers "B.Cu" "B.Mask" "B.Paste")
			(net "SMB_BMC_MM5_R_SDA")
		)
	)
	(footprint ""
		(layer "B.Cu")
		(at 49.784 -28.829 -90)
		(property "Reference" "R880"
			(at 0 0 90)
			(layer "B.SilkS")
			(hide yes)
			(effects
				(font
					(size 1.27 1.27)
				)
				(justify mirror)
			)
		)
		(property "Value" ""
			(at 0 0 90)
			(layer "B.Fab")
			(effects
				(font
					(size 1.27 1.27)
				)
				(justify mirror)
			)
		)
		(duplicate_pad_numbers_are_jumpers no)
		(fp_line
			(start -0.7874 0.4064)
			(end 0.7874 0.4064)
			(stroke
				(width 0.1524)
				(type default)
			)
			(layer "B.SilkS")
		)
		(fp_line
			(start 0.7874 0.4064)
			(end 0.7874 -0.4064)
			(stroke
				(width 0.1524)
				(type default)
			)
			(layer "B.SilkS")
		)
		(fp_line
			(start -0.7874 -0.4064)
			(end -0.7874 0.4064)
			(stroke
				(width 0.1524)
				(type default)
			)
			(layer "B.SilkS")
		)
		(fp_line
			(start 0.7874 -0.4064)
			(end -0.7874 -0.4064)
			(stroke
				(width 0.1524)
				(type default)
			)
			(layer "B.SilkS")
		)
		(fp_line
			(start -0.67945 0.3048)
			(end -0.120396 0.3048)
			(stroke
				(width 0.1)
				(type default)
			)
			(layer "B.Fab")
		)
		(fp_line
			(start -0.120396 0.3048)
			(end -0.120396 0.2794)
			(stroke
				(width 0.1)
				(type default)
			)
			(layer "B.Fab")
		)
		(fp_line
			(start 0.12065 0.3048)
			(end 0.67945 0.3048)
			(stroke
				(width 0.1)
				(type default)
			)
			(layer "B.Fab")
		)
		(fp_line
			(start 0.67945 0.3048)
			(end 0.67945 -0.305054)
			(stroke
				(width 0.1)
				(type default)
			)
			(layer "B.Fab")
		)
		(fp_line
			(start -0.120396 0.2794)
			(end 0.12065 0.2794)
			(stroke
				(width 0.1)
				(type default)
			)
			(layer "B.Fab")
		)
		(fp_line
			(start 0.12065 0.2794)
			(end 0.12065 0.3048)
			(stroke
				(width 0.1)
				(type default)
			)
			(layer "B.Fab")
		)
		(fp_line
			(start -0.12065 -0.2794)
			(end -0.12065 -0.3048)
			(stroke
				(width 0.1)
				(type default)
			)
			(layer "B.Fab")
		)
		(fp_line
			(start 0.12065 -0.2794)
			(end -0.12065 -0.2794)
			(stroke
				(width 0.1)
				(type default)
			)
			(layer "B.Fab")
		)
		(fp_line
			(start -0.67945 -0.3048)
			(end -0.67945 0.3048)
			(stroke
				(width 0.1)
				(type default)
			)
			(layer "B.Fab")
		)
		(fp_line
			(start -0.12065 -0.3048)
			(end -0.67945 -0.3048)
			(stroke
				(width 0.1)
				(type default)
			)
			(layer "B.Fab")
		)
		(fp_line
			(start 0.12065 -0.305054)
			(end 0.12065 -0.2794)
			(stroke
				(width 0.1)
				(type default)
			)
			(layer "B.Fab")
		)
		(fp_line
			(start 0.67945 -0.305054)
			(end 0.12065 -0.305054)
			(stroke
				(width 0.1)
				(type default)
			)
			(layer "B.Fab")
		)
		(pad "1" smd circle
			(at 0.40005 0 90)
			(size 0 0)
			(layers "B.Cu" "B.Mask" "B.Paste")
			(net "SMB_BMC_MM16_R5_SDA")
		)
		(pad "2" smd circle
			(at -0.40005 0 90)
			(size 0 0)
			(layers "B.Cu" "B.Mask" "B.Paste")
			(net "SMB_BMC_MM16_SDA")
		)
	)
	(footprint ""
		(layer "B.Cu")
		(at 40.62222 -60.35294 -90)
		(property "Reference" "R462"
			(at 0 0 90)
			(layer "B.SilkS")
			(hide yes)
			(effects
				(font
					(size 1.27 1.27)
				)
				(justify mirror)
			)
		)
		(property "Value" ""
			(at 0 0 90)
			(layer "B.Fab")
			(effects
				(font
					(size 1.27 1.27)
				)
				(justify mirror)
			)
		)
		(duplicate_pad_numbers_are_jumpers no)
		(fp_line
			(start -0.7874 0.4064)
			(end 0.7874 0.4064)
			(stroke
				(width 0.1524)
				(type default)
			)
			(layer "B.SilkS")
		)
		(fp_line
			(start 0.7874 0.4064)
			(end 0.7874 -0.4064)
			(stroke
				(width 0.1524)
				(type default)
			)
			(layer "B.SilkS")
		)
		(fp_line
			(start -0.7874 -0.4064)
			(end -0.7874 0.4064)
			(stroke
				(width 0.1524)
				(type default)
			)
			(layer "B.SilkS")
		)
		(fp_line
			(start 0.7874 -0.4064)
			(end -0.7874 -0.4064)
			(stroke
				(width 0.1524)
				(type default)
			)
			(layer "B.SilkS")
		)
		(fp_line
			(start -0.67945 0.3048)
			(end -0.120396 0.3048)
			(stroke
				(width 0.1)
				(type default)
			)
			(layer "B.Fab")
		)
		(fp_line
			(start -0.120396 0.3048)
			(end -0.120396 0.2794)
			(stroke
				(width 0.1)
				(type default)
			)
			(layer "B.Fab")
		)
		(fp_line
			(start 0.12065 0.3048)
			(end 0.67945 0.3048)
			(stroke
				(width 0.1)
				(type default)
			)
			(layer "B.Fab")
		)
		(fp_line
			(start 0.67945 0.3048)
			(end 0.67945 -0.305054)
			(stroke
				(width 0.1)
				(type default)
			)
			(layer "B.Fab")
		)
		(fp_line
			(start -0.120396 0.2794)
			(end 0.12065 0.2794)
			(stroke
				(width 0.1)
				(type default)
			)
			(layer "B.Fab")
		)
		(fp_line
			(start 0.12065 0.2794)
			(end 0.12065 0.3048)
			(stroke
				(width 0.1)
				(type default)
			)
			(layer "B.Fab")
		)
		(fp_line
			(start -0.12065 -0.2794)
			(end -0.12065 -0.3048)
			(stroke
				(width 0.1)
				(type default)
			)
			(layer "B.Fab")
		)
		(fp_line
			(start 0.12065 -0.2794)
			(end -0.12065 -0.2794)
			(stroke
				(width 0.1)
				(type default)
			)
			(layer "B.Fab")
		)
		(fp_line
			(start -0.67945 -0.3048)
			(end -0.67945 0.3048)
			(stroke
				(width 0.1)
				(type default)
			)
			(layer "B.Fab")
		)
		(fp_line
			(start -0.12065 -0.3048)
			(end -0.67945 -0.3048)
			(stroke
				(width 0.1)
				(type default)
			)
			(layer "B.Fab")
		)
		(fp_line
			(start 0.12065 -0.305054)
			(end 0.12065 -0.2794)
			(stroke
				(width 0.1)
				(type default)
			)
			(layer "B.Fab")
		)
		(fp_line
			(start 0.67945 -0.305054)
			(end 0.12065 -0.305054)
			(stroke
				(width 0.1)
				(type default)
			)
			(layer "B.Fab")
		)
		(pad "1" smd circle
			(at 0.40005 0 90)
			(size 0 0)
			(layers "B.Cu" "B.Mask" "B.Paste")
			(net "P3V3_AUX")
		)
		(pad "2" smd circle
			(at -0.40005 0 90)
			(size 0 0)
			(layers "B.Cu" "B.Mask" "B.Paste")
			(net "SYS_BMC_PWRBTN_R1_N")
		)
	)
	(footprint ""
		(layer "B.Cu")
		(at 45.339 -96.8248 -90)
		(property "Reference" "R672"
			(at 0 0 90)
			(layer "B.SilkS")
			(hide yes)
			(effects
				(font
					(size 1.27 1.27)
				)
				(justify mirror)
			)
		)
		(property "Value" ""
			(at 0 0 90)
			(layer "B.Fab")
			(effects
				(font
					(size 1.27 1.27)
				)
				(justify mirror)
			)
		)
		(duplicate_pad_numbers_are_jumpers no)
		(fp_line
			(start -0.7874 0.4064)
			(end 0.7874 0.4064)
			(stroke
				(width 0.1524)
				(type default)
			)
			(layer "B.SilkS")
		)
		(fp_line
			(start 0.7874 0.4064)
			(end 0.7874 -0.4064)
			(stroke
				(width 0.1524)
				(type default)
			)
			(layer "B.SilkS")
		)
		(fp_line
			(start -0.7874 -0.4064)
			(end -0.7874 0.4064)
			(stroke
				(width 0.1524)
				(type default)
			)
			(layer "B.SilkS")
		)
		(fp_line
			(start 0.7874 -0.4064)
			(end -0.7874 -0.4064)
			(stroke
				(width 0.1524)
				(type default)
			)
			(layer "B.SilkS")
		)
		(fp_line
			(start -0.67945 0.3048)
			(end -0.120396 0.3048)
			(stroke
				(width 0.1)
				(type default)
			)
			(layer "B.Fab")
		)
		(fp_line
			(start -0.120396 0.3048)
			(end -0.120396 0.2794)
			(stroke
				(width 0.1)
				(type default)
			)
			(layer "B.Fab")
		)
		(fp_line
			(start 0.12065 0.3048)
			(end 0.67945 0.3048)
			(stroke
				(width 0.1)
				(type default)
			)
			(layer "B.Fab")
		)
		(fp_line
			(start 0.67945 0.3048)
			(end 0.67945 -0.305054)
			(stroke
				(width 0.1)
				(type default)
			)
			(layer "B.Fab")
		)
		(fp_line
			(start -0.120396 0.2794)
			(end 0.12065 0.2794)
			(stroke
				(width 0.1)
				(type default)
			)
			(layer "B.Fab")
		)
		(fp_line
			(start 0.12065 0.2794)
			(end 0.12065 0.3048)
			(stroke
				(width 0.1)
				(type default)
			)
			(layer "B.Fab")
		)
		(fp_line
			(start -0.12065 -0.2794)
			(end -0.12065 -0.3048)
			(stroke
				(width 0.1)
				(type default)
			)
			(layer "B.Fab")
		)
		(fp_line
			(start 0.12065 -0.2794)
			(end -0.12065 -0.2794)
			(stroke
				(width 0.1)
				(type default)
			)
			(layer "B.Fab")
		)
		(fp_line
			(start -0.67945 -0.3048)
			(end -0.67945 0.3048)
			(stroke
				(width 0.1)
				(type default)
			)
			(layer "B.Fab")
		)
		(fp_line
			(start -0.12065 -0.3048)
			(end -0.67945 -0.3048)
			(stroke
				(width 0.1)
				(type default)
			)
			(layer "B.Fab")
		)
		(fp_line
			(start 0.12065 -0.305054)
			(end 0.12065 -0.2794)
			(stroke
				(width 0.1)
				(type default)
			)
			(layer "B.Fab")
		)
		(fp_line
			(start 0.67945 -0.305054)
			(end 0.12065 -0.305054)
			(stroke
				(width 0.1)
				(type default)
			)
			(layer "B.Fab")
		)
		(pad "1" smd circle
			(at 0.40005 0 90)
			(size 0 0)
			(layers "B.Cu" "B.Mask" "B.Paste")
			(net "USB3_01_TXN_C")
		)
		(pad "2" smd circle
			(at -0.40005 0 90)
			(size 0 0)
			(layers "B.Cu" "B.Mask" "B.Paste")
			(net "USB3_FPNL_TXN")
		)
	)
	(footprint ""
		(layer "B.Cu")
		(at 74.774552 -35.01898 180)
		(property "Reference" "C55"
			(at 0 0 0)
			(layer "B.SilkS")
			(hide yes)
			(effects
				(font
					(size 1.27 1.27)
				)
				(justify mirror)
			)
		)
		(property "Value" ""
			(at 0 0 0)
			(layer "B.Fab")
			(effects
				(font
					(size 1.27 1.27)
				)
				(justify mirror)
			)
		)
		(duplicate_pad_numbers_are_jumpers no)
		(fp_line
			(start 1.2954 0.5842)
			(end 1.2954 -0.5842)
			(stroke
				(width 0.1524)
				(type default)
			)
			(layer "B.SilkS")
		)
		(fp_line
			(start 1.2954 -0.5842)
			(end -1.2954 -0.5842)
			(stroke
				(width 0.1524)
				(type default)
			)
			(layer "B.SilkS")
		)
		(fp_line
			(start 0 -0.5842)
			(end 0 0.5842)
			(stroke
				(width 0.1524)
				(type default)
			)
			(layer "B.SilkS")
		)
		(fp_line
			(start -1.2954 0.5842)
			(end 1.2954 0.5842)
			(stroke
				(width 0.1524)
				(type default)
			)
			(layer "B.SilkS")
		)
		(fp_line
			(start -1.2954 -0.5842)
			(end -1.2954 0.5842)
			(stroke
				(width 0.1524)
				(type default)
			)
			(layer "B.SilkS")
		)
		(fp_line
			(start 1.1938 0.4064)
			(end 1.1938 -0.4064)
			(stroke
				(width 0.1)
				(type default)
			)
			(layer "B.Fab")
		)
		(fp_line
			(start 1.1938 -0.4064)
			(end 0.8636 -0.4064)
			(stroke
				(width 0.1)
				(type default)
			)
			(layer "B.Fab")
		)
		(fp_line
			(start 0.8636 0.4572)
			(end 0.8636 0.4064)
			(stroke
				(width 0.1)
				(type default)
			)
			(layer "B.Fab")
		)
		(fp_line
			(start 0.8636 0.4064)
			(end 1.1938 0.4064)
			(stroke
				(width 0.1)
				(type default)
			)
			(layer "B.Fab")
		)
		(fp_line
			(start 0.8636 -0.4064)
			(end 0.8636 -0.4572)
			(stroke
				(width 0.1)
				(type default)
			)
			(layer "B.Fab")
		)
		(fp_line
			(start 0.8636 -0.4572)
			(end -0.8636 -0.4572)
			(stroke
				(width 0.1)
				(type default)
			)
			(layer "B.Fab")
		)
		(fp_line
			(start -0.8636 0.4572)
			(end 0.8636 0.4572)
			(stroke
				(width 0.1)
				(type default)
			)
			(layer "B.Fab")
		)
		(fp_line
			(start -0.8636 0.4064)
			(end -0.8636 0.4572)
			(stroke
				(width 0.1)
				(type default)
			)
			(layer "B.Fab")
		)
		(fp_line
			(start -0.8636 -0.4064)
			(end -1.1938 -0.4064)
			(stroke
				(width 0.1)
				(type default)
			)
			(layer "B.Fab")
		)
		(fp_line
			(start -0.8636 -0.4572)
			(end -0.8636 -0.4064)
			(stroke
				(width 0.1)
				(type default)
			)
			(layer "B.Fab")
		)
		(fp_line
			(start -1.1938 0.4064)
			(end -0.8636 0.4064)
			(stroke
				(width 0.1)
				(type default)
			)
			(layer "B.Fab")
		)
		(fp_line
			(start -1.1938 -0.4064)
			(end -1.1938 0.4064)
			(stroke
				(width 0.1)
				(type default)
			)
			(layer "B.Fab")
		)
		(pad "1" smd rect
			(at 0.7366 0 90)
			(size 0.7112 0.8128)
			(layers "B.Cu" "B.Mask" "B.Paste")
			(net "P1V2_AUX")
		)
		(pad "2" smd rect
			(at -0.7366 0 90)
			(size 0.7112 0.8128)
			(layers "B.Cu" "B.Mask" "B.Paste")
			(net "GND")
		)
	)
	(footprint ""
		(layer "B.Cu")
		(at 15.24 -83.693 90)
		(property "Reference" "R435"
			(at 0 0 90)
			(layer "B.SilkS")
			(hide yes)
			(effects
				(font
					(size 1.27 1.27)
				)
				(justify mirror)
			)
		)
		(property "Value" ""
			(at 0 0 90)
			(layer "B.Fab")
			(effects
				(font
					(size 1.27 1.27)
				)
				(justify mirror)
			)
		)
		(duplicate_pad_numbers_are_jumpers no)
		(fp_line
			(start 0.7874 -0.4064)
			(end -0.7874 -0.4064)
			(stroke
				(width 0.1524)
				(type default)
			)
			(layer "B.SilkS")
		)
		(fp_line
			(start -0.7874 -0.4064)
			(end -0.7874 0.4064)
			(stroke
				(width 0.1524)
				(type default)
			)
			(layer "B.SilkS")
		)
		(fp_line
			(start 0.7874 0.4064)
			(end 0.7874 -0.4064)
			(stroke
				(width 0.1524)
				(type default)
			)
			(layer "B.SilkS")
		)
		(fp_line
			(start -0.7874 0.4064)
			(end 0.7874 0.4064)
			(stroke
				(width 0.1524)
				(type default)
			)
			(layer "B.SilkS")
		)
		(fp_line
			(start 0.67945 -0.305054)
			(end 0.12065 -0.305054)
			(stroke
				(width 0.1)
				(type default)
			)
			(layer "B.Fab")
		)
		(fp_line
			(start 0.12065 -0.305054)
			(end 0.12065 -0.2794)
			(stroke
				(width 0.1)
				(type default)
			)
			(layer "B.Fab")
		)
		(fp_line
			(start -0.12065 -0.3048)
			(end -0.67945 -0.3048)
			(stroke
				(width 0.1)
				(type default)
			)
			(layer "B.Fab")
		)
		(fp_line
			(start -0.67945 -0.3048)
			(end -0.67945 0.3048)
			(stroke
				(width 0.1)
				(type default)
			)
			(layer "B.Fab")
		)
		(fp_line
			(start 0.12065 -0.2794)
			(end -0.12065 -0.2794)
			(stroke
				(width 0.1)
				(type default)
			)
			(layer "B.Fab")
		)
		(fp_line
			(start -0.12065 -0.2794)
			(end -0.12065 -0.3048)
			(stroke
				(width 0.1)
				(type default)
			)
			(layer "B.Fab")
		)
		(fp_line
			(start 0.12065 0.2794)
			(end 0.12065 0.3048)
			(stroke
				(width 0.1)
				(type default)
			)
			(layer "B.Fab")
		)
		(fp_line
			(start -0.120396 0.2794)
			(end 0.12065 0.2794)
			(stroke
				(width 0.1)
				(type default)
			)
			(layer "B.Fab")
		)
		(fp_line
			(start 0.67945 0.3048)
			(end 0.67945 -0.305054)
			(stroke
				(width 0.1)
				(type default)
			)
			(layer "B.Fab")
		)
		(fp_line
			(start 0.12065 0.3048)
			(end 0.67945 0.3048)
			(stroke
				(width 0.1)
				(type default)
			)
			(layer "B.Fab")
		)
		(fp_line
			(start -0.120396 0.3048)
			(end -0.120396 0.2794)
			(stroke
				(width 0.1)
				(type default)
			)
			(layer "B.Fab")
		)
		(fp_line
			(start -0.67945 0.3048)
			(end -0.120396 0.3048)
			(stroke
				(width 0.1)
				(type default)
			)
			(layer "B.Fab")
		)
		(pad "1" smd circle
			(at 0.40005 0 270)
			(size 0 0)
			(layers "B.Cu" "B.Mask" "B.Paste")
			(net "SGPIO_PLD_DO_0")
		)
		(pad "2" smd circle
			(at -0.40005 0 270)
			(size 0 0)
			(layers "B.Cu" "B.Mask" "B.Paste")
			(net "SGPIO_DO_0")
		)
	)
	(footprint ""
		(layer "B.Cu")
		(at 55.336948 -70.418198 90)
		(property "Reference" "R780"
			(at 0 0 90)
			(layer "B.SilkS")
			(hide yes)
			(effects
				(font
					(size 1.27 1.27)
				)
				(justify mirror)
			)
		)
		(property "Value" ""
			(at 0 0 90)
			(layer "B.Fab")
			(effects
				(font
					(size 1.27 1.27)
				)
				(justify mirror)
			)
		)
		(duplicate_pad_numbers_are_jumpers no)
		(fp_line
			(start 0.7874 -0.4064)
			(end -0.7874 -0.4064)
			(stroke
				(width 0.1524)
				(type default)
			)
			(layer "B.SilkS")
		)
		(fp_line
			(start -0.7874 -0.4064)
			(end -0.7874 0.4064)
			(stroke
				(width 0.1524)
				(type default)
			)
			(layer "B.SilkS")
		)
		(fp_line
			(start 0.7874 0.4064)
			(end 0.7874 -0.4064)
			(stroke
				(width 0.1524)
				(type default)
			)
			(layer "B.SilkS")
		)
		(fp_line
			(start -0.7874 0.4064)
			(end 0.7874 0.4064)
			(stroke
				(width 0.1524)
				(type default)
			)
			(layer "B.SilkS")
		)
		(fp_line
			(start 0.67945 -0.305054)
			(end 0.12065 -0.305054)
			(stroke
				(width 0.1)
				(type default)
			)
			(layer "B.Fab")
		)
		(fp_line
			(start 0.12065 -0.305054)
			(end 0.12065 -0.2794)
			(stroke
				(width 0.1)
				(type default)
			)
			(layer "B.Fab")
		)
		(fp_line
			(start -0.12065 -0.3048)
			(end -0.67945 -0.3048)
			(stroke
				(width 0.1)
				(type default)
			)
			(layer "B.Fab")
		)
		(fp_line
			(start -0.67945 -0.3048)
			(end -0.67945 0.3048)
			(stroke
				(width 0.1)
				(type default)
			)
			(layer "B.Fab")
		)
		(fp_line
			(start 0.12065 -0.2794)
			(end -0.12065 -0.2794)
			(stroke
				(width 0.1)
				(type default)
			)
			(layer "B.Fab")
		)
		(fp_line
			(start -0.12065 -0.2794)
			(end -0.12065 -0.3048)
			(stroke
				(width 0.1)
				(type default)
			)
			(layer "B.Fab")
		)
		(fp_line
			(start 0.12065 0.2794)
			(end 0.12065 0.3048)
			(stroke
				(width 0.1)
				(type default)
			)
			(layer "B.Fab")
		)
		(fp_line
			(start -0.120396 0.2794)
			(end 0.12065 0.2794)
			(stroke
				(width 0.1)
				(type default)
			)
			(layer "B.Fab")
		)
		(fp_line
			(start 0.67945 0.3048)
			(end 0.67945 -0.305054)
			(stroke
				(width 0.1)
				(type default)
			)
			(layer "B.Fab")
		)
		(fp_line
			(start 0.12065 0.3048)
			(end 0.67945 0.3048)
			(stroke
				(width 0.1)
				(type default)
			)
			(layer "B.Fab")
		)
		(fp_line
			(start -0.120396 0.3048)
			(end -0.120396 0.2794)
			(stroke
				(width 0.1)
				(type default)
			)
			(layer "B.Fab")
		)
		(fp_line
			(start -0.67945 0.3048)
			(end -0.120396 0.3048)
			(stroke
				(width 0.1)
				(type default)
			)
			(layer "B.Fab")
		)
		(pad "1" smd circle
			(at 0.40005 0 270)
			(size 0 0)
			(layers "B.Cu" "B.Mask" "B.Paste")
			(net "P2V5_AUX")
		)
		(pad "2" smd circle
			(at -0.40005 0 270)
			(size 0 0)
			(layers "B.Cu" "B.Mask" "B.Paste")
			(net "ADCVREFEXT0")
		)
	)
	(footprint ""
		(layer "B.Cu")
		(at 18.259552 -89.98712 180)
		(property "Reference" "C247"
			(at 0 0 0)
			(layer "B.SilkS")
			(hide yes)
			(effects
				(font
					(size 1.27 1.27)
				)
				(justify mirror)
			)
		)
		(property "Value" ""
			(at 0 0 0)
			(layer "B.Fab")
			(effects
				(font
					(size 1.27 1.27)
				)
				(justify mirror)
			)
		)
		(duplicate_pad_numbers_are_jumpers no)
		(fp_line
			(start 0.69215 0.2921)
			(end 0.69215 -0.2921)
			(stroke
				(width 0.1524)
				(type default)
			)
			(layer "B.SilkS")
		)
		(fp_line
			(start 0.69215 -0.2921)
			(end -0.69215 -0.2921)
			(stroke
				(width 0.1524)
				(type default)
			)
			(layer "B.SilkS")
		)
		(fp_line
			(start -0.69215 0.2921)
			(end 0.69215 0.2921)
			(stroke
				(width 0.1524)
				(type default)
			)
			(layer "B.SilkS")
		)
		(fp_line
			(start -0.69215 -0.2921)
			(end -0.69215 0.2921)
			(stroke
				(width 0.1524)
				(type default)
			)
			(layer "B.SilkS")
		)
		(fp_line
			(start 0.51435 0.2794)
			(end 0.51435 -0.2794)
			(stroke
				(width 0.1)
				(type default)
			)
			(layer "B.Fab")
		)
		(fp_line
			(start 0.51435 -0.2794)
			(end -0.51435 -0.2794)
			(stroke
				(width 0.1)
				(type default)
			)
			(layer "B.Fab")
		)
		(fp_line
			(start -0.51435 0.2794)
			(end 0.51435 0.2794)
			(stroke
				(width 0.1)
				(type default)
			)
			(layer "B.Fab")
		)
		(fp_line
			(start -0.51435 -0.2794)
			(end -0.51435 0.2794)
			(stroke
				(width 0.1)
				(type default)
			)
			(layer "B.Fab")
		)
		(pad "1" smd circle
			(at 0.40005 0)
			(size 0 0)
			(layers "B.Cu" "B.Mask" "B.Paste")
			(net "VCCIO0")
		)
		(pad "2" smd circle
			(at -0.40005 0)
			(size 0 0)
			(layers "B.Cu" "B.Mask" "B.Paste")
			(net "GND")
		)
		(zone
			(layer "B.Cu")
			(hatch none 0.5)
			(connect_pads
				(clearance 0)
			)
			(min_thickness 0.25)
			(keepout
				(tracks not_allowed)
				(vias allowed)
				(pads allowed)
				(copperpour not_allowed)
				(footprints allowed)
			)
			(placement
				(enabled no)
				(sheetname "")
			)
			(fill
				(thermal_gap 0.5)
				(thermal_bridge_width 0.5)
				(island_removal_mode 0)
			)
			(polygon
				(pts
					(xy 18.069052 -90.07475) (xy 18.160492 -90.132916) (xy 18.359882 -90.132916) (xy 18.450052 -90.07475)
					(xy 18.450052 -89.89949) (xy 18.359882 -89.84107) (xy 18.160492 -89.84107) (xy 18.069052 -89.899236)
				)
			)
		)
	)
	(footprint ""
		(layer "B.Cu")
		(at 81.129886 -44.038012 180)
		(property "Reference" "R5"
			(at 0 0 0)
			(layer "B.SilkS")
			(hide yes)
			(effects
				(font
					(size 1.27 1.27)
				)
				(justify mirror)
			)
		)
		(property "Value" ""
			(at 0 0 0)
			(layer "B.Fab")
			(effects
				(font
					(size 1.27 1.27)
				)
				(justify mirror)
			)
		)
		(duplicate_pad_numbers_are_jumpers no)
		(fp_line
			(start 0.7874 0.4064)
			(end 0.7874 -0.4064)
			(stroke
				(width 0.1524)
				(type default)
			)
			(layer "B.SilkS")
		)
		(fp_line
			(start 0.7874 -0.4064)
			(end -0.7874 -0.4064)
			(stroke
				(width 0.1524)
				(type default)
			)
			(layer "B.SilkS")
		)
		(fp_line
			(start -0.7874 0.4064)
			(end 0.7874 0.4064)
			(stroke
				(width 0.1524)
				(type default)
			)
			(layer "B.SilkS")
		)
		(fp_line
			(start -0.7874 -0.4064)
			(end -0.7874 0.4064)
			(stroke
				(width 0.1524)
				(type default)
			)
			(layer "B.SilkS")
		)
		(fp_line
			(start 0.67945 0.3048)
			(end 0.67945 -0.305054)
			(stroke
				(width 0.1)
				(type default)
			)
			(layer "B.Fab")
		)
		(fp_line
			(start 0.67945 -0.305054)
			(end 0.12065 -0.305054)
			(stroke
				(width 0.1)
				(type default)
			)
			(layer "B.Fab")
		)
		(fp_line
			(start 0.12065 0.3048)
			(end 0.67945 0.3048)
			(stroke
				(width 0.1)
				(type default)
			)
			(layer "B.Fab")
		)
		(fp_line
			(start 0.12065 0.2794)
			(end 0.12065 0.3048)
			(stroke
				(width 0.1)
				(type default)
			)
			(layer "B.Fab")
		)
		(fp_line
			(start 0.12065 -0.2794)
			(end -0.12065 -0.2794)
			(stroke
				(width 0.1)
				(type default)
			)
			(layer "B.Fab")
		)
		(fp_line
			(start 0.12065 -0.305054)
			(end 0.12065 -0.2794)
			(stroke
				(width 0.1)
				(type default)
			)
			(layer "B.Fab")
		)
		(fp_line
			(start -0.120396 0.3048)
			(end -0.120396 0.2794)
			(stroke
				(width 0.1)
				(type default)
			)
			(layer "B.Fab")
		)
		(fp_line
			(start -0.120396 0.2794)
			(end 0.12065 0.2794)
			(stroke
				(width 0.1)
				(type default)
			)
			(layer "B.Fab")
		)
		(fp_line
			(start -0.12065 -0.2794)
			(end -0.12065 -0.3048)
			(stroke
				(width 0.1)
				(type default)
			)
			(layer "B.Fab")
		)
		(fp_line
			(start -0.12065 -0.3048)
			(end -0.67945 -0.3048)
			(stroke
				(width 0.1)
				(type default)
			)
			(layer "B.Fab")
		)
		(fp_line
			(start -0.67945 0.3048)
			(end -0.120396 0.3048)
			(stroke
				(width 0.1)
				(type default)
			)
			(layer "B.Fab")
		)
		(fp_line
			(start -0.67945 -0.3048)
			(end -0.67945 0.3048)
			(stroke
				(width 0.1)
				(type default)
			)
			(layer "B.Fab")
		)
		(pad "1" smd circle
			(at 0.40005 0)
			(size 0 0)
			(layers "B.Cu" "B.Mask" "B.Paste")
			(net "PD_M_BMC_DDR4_TEN")
		)
		(pad "2" smd circle
			(at -0.40005 0)
			(size 0 0)
			(layers "B.Cu" "B.Mask" "B.Paste")
			(net "GND")
		)
	)
	(footprint ""
		(layer "B.Cu")
		(at 60.537598 -50.711862 90)
		(property "Reference" "C74"
			(at 0 0 90)
			(layer "B.SilkS")
			(hide yes)
			(effects
				(font
					(size 1.27 1.27)
				)
				(justify mirror)
			)
		)
		(property "Value" ""
			(at 0 0 90)
			(layer "B.Fab")
			(effects
				(font
					(size 1.27 1.27)
				)
				(justify mirror)
			)
		)
		(duplicate_pad_numbers_are_jumpers no)
		(fp_line
			(start 0.7874 -0.4064)
			(end -0.7874 -0.4064)
			(stroke
				(width 0.1524)
				(type default)
			)
			(layer "B.SilkS")
		)
		(fp_line
			(start -0.7874 -0.4064)
			(end -0.7874 0.4064)
			(stroke
				(width 0.1524)
				(type default)
			)
			(layer "B.SilkS")
		)
		(fp_line
			(start 0.7874 0.4064)
			(end 0.7874 -0.4064)
			(stroke
				(width 0.1524)
				(type default)
			)
			(layer "B.SilkS")
		)
		(fp_line
			(start -0.7874 0.4064)
			(end 0.7874 0.4064)
			(stroke
				(width 0.1524)
				(type default)
			)
			(layer "B.SilkS")
		)
		(fp_line
			(start 0.67945 -0.305054)
			(end 0.12065 -0.305054)
			(stroke
				(width 0.1)
				(type default)
			)
			(layer "B.Fab")
		)
		(fp_line
			(start 0.12065 -0.305054)
			(end 0.12065 -0.2794)
			(stroke
				(width 0.1)
				(type default)
			)
			(layer "B.Fab")
		)
		(fp_line
			(start -0.12065 -0.3048)
			(end -0.67945 -0.3048)
			(stroke
				(width 0.1)
				(type default)
			)
			(layer "B.Fab")
		)
		(fp_line
			(start -0.67945 -0.3048)
			(end -0.67945 0.3048)
			(stroke
				(width 0.1)
				(type default)
			)
			(layer "B.Fab")
		)
		(fp_line
			(start 0.12065 -0.2794)
			(end -0.12065 -0.2794)
			(stroke
				(width 0.1)
				(type default)
			)
			(layer "B.Fab")
		)
		(fp_line
			(start -0.12065 -0.2794)
			(end -0.12065 -0.3048)
			(stroke
				(width 0.1)
				(type default)
			)
			(layer "B.Fab")
		)
		(fp_line
			(start 0.12065 0.2794)
			(end 0.12065 0.3048)
			(stroke
				(width 0.1)
				(type default)
			)
			(layer "B.Fab")
		)
		(fp_line
			(start -0.120396 0.2794)
			(end 0.12065 0.2794)
			(stroke
				(width 0.1)
				(type default)
			)
			(layer "B.Fab")
		)
		(fp_line
			(start 0.67945 0.3048)
			(end 0.67945 -0.305054)
			(stroke
				(width 0.1)
				(type default)
			)
			(layer "B.Fab")
		)
		(fp_line
			(start 0.12065 0.3048)
			(end 0.67945 0.3048)
			(stroke
				(width 0.1)
				(type default)
			)
			(layer "B.Fab")
		)
		(fp_line
			(start -0.120396 0.3048)
			(end -0.120396 0.2794)
			(stroke
				(width 0.1)
				(type default)
			)
			(layer "B.Fab")
		)
		(fp_line
			(start -0.67945 0.3048)
			(end -0.120396 0.3048)
			(stroke
				(width 0.1)
				(type default)
			)
			(layer "B.Fab")
		)
		(pad "1" smd circle
			(at 0.40005 0 270)
			(size 0 0)
			(layers "B.Cu" "B.Mask" "B.Paste")
			(net "P1V2_AUX")
		)
		(pad "2" smd circle
			(at -0.40005 0 270)
			(size 0 0)
			(layers "B.Cu" "B.Mask" "B.Paste")
			(net "GND")
		)
	)
	(footprint ""
		(layer "B.Cu")
		(at 4.6482 -29.5148)
		(property "Reference" "R765"
			(at 0 0 0)
			(layer "B.SilkS")
			(hide yes)
			(effects
				(font
					(size 1.27 1.27)
				)
				(justify mirror)
			)
		)
		(property "Value" ""
			(at 0 0 0)
			(layer "B.Fab")
			(effects
				(font
					(size 1.27 1.27)
				)
				(justify mirror)
			)
		)
		(duplicate_pad_numbers_are_jumpers no)
		(fp_line
			(start -0.7874 -0.4064)
			(end -0.7874 0.4064)
			(stroke
				(width 0.1524)
				(type default)
			)
			(layer "B.SilkS")
		)
		(fp_line
			(start -0.7874 0.4064)
			(end 0.7874 0.4064)
			(stroke
				(width 0.1524)
				(type default)
			)
			(layer "B.SilkS")
		)
		(fp_line
			(start 0.7874 -0.4064)
			(end -0.7874 -0.4064)
			(stroke
				(width 0.1524)
				(type default)
			)
			(layer "B.SilkS")
		)
		(fp_line
			(start 0.7874 0.4064)
			(end 0.7874 -0.4064)
			(stroke
				(width 0.1524)
				(type default)
			)
			(layer "B.SilkS")
		)
		(fp_line
			(start -0.67945 -0.3048)
			(end -0.67945 0.3048)
			(stroke
				(width 0.1)
				(type default)
			)
			(layer "B.Fab")
		)
		(fp_line
			(start -0.67945 0.3048)
			(end -0.120396 0.3048)
			(stroke
				(width 0.1)
				(type default)
			)
			(layer "B.Fab")
		)
		(fp_line
			(start -0.12065 -0.3048)
			(end -0.67945 -0.3048)
			(stroke
				(width 0.1)
				(type default)
			)
			(layer "B.Fab")
		)
		(fp_line
			(start -0.12065 -0.2794)
			(end -0.12065 -0.3048)
			(stroke
				(width 0.1)
				(type default)
			)
			(layer "B.Fab")
		)
		(fp_line
			(start -0.120396 0.2794)
			(end 0.12065 0.2794)
			(stroke
				(width 0.1)
				(type default)
			)
			(layer "B.Fab")
		)
		(fp_line
			(start -0.120396 0.3048)
			(end -0.120396 0.2794)
			(stroke
				(width 0.1)
				(type default)
			)
			(layer "B.Fab")
		)
		(fp_line
			(start 0.12065 -0.305054)
			(end 0.12065 -0.2794)
			(stroke
				(width 0.1)
				(type default)
			)
			(layer "B.Fab")
		)
		(fp_line
			(start 0.12065 -0.2794)
			(end -0.12065 -0.2794)
			(stroke
				(width 0.1)
				(type default)
			)
			(layer "B.Fab")
		)
		(fp_line
			(start 0.12065 0.2794)
			(end 0.12065 0.3048)
			(stroke
				(width 0.1)
				(type default)
			)
			(layer "B.Fab")
		)
		(fp_line
			(start 0.12065 0.3048)
			(end 0.67945 0.3048)
			(stroke
				(width 0.1)
				(type default)
			)
			(layer "B.Fab")
		)
		(fp_line
			(start 0.67945 -0.305054)
			(end 0.12065 -0.305054)
			(stroke
				(width 0.1)
				(type default)
			)
			(layer "B.Fab")
		)
		(fp_line
			(start 0.67945 0.3048)
			(end 0.67945 -0.305054)
			(stroke
				(width 0.1)
				(type default)
			)
			(layer "B.Fab")
		)
		(pad "1" smd circle
			(at 0.40005 0 180)
			(size 0 0)
			(layers "B.Cu" "B.Mask" "B.Paste")
			(net "P3V3_AUX")
		)
		(pad "2" smd circle
			(at -0.40005 0 180)
			(size 0 0)
			(layers "B.Cu" "B.Mask" "B.Paste")
			(net "UART_BMC_5_TXD_BUF_R")
		)
	)
	(footprint ""
		(layer "B.Cu")
		(at 43.434 -67.818)
		(property "Reference" "R640"
			(at 0 0 0)
			(layer "B.SilkS")
			(hide yes)
			(effects
				(font
					(size 1.27 1.27)
				)
				(justify mirror)
			)
		)
		(property "Value" ""
			(at 0 0 0)
			(layer "B.Fab")
			(effects
				(font
					(size 1.27 1.27)
				)
				(justify mirror)
			)
		)
		(duplicate_pad_numbers_are_jumpers no)
		(fp_line
			(start -0.7874 -0.4064)
			(end -0.7874 0.4064)
			(stroke
				(width 0.1524)
				(type default)
			)
			(layer "B.SilkS")
		)
		(fp_line
			(start -0.7874 0.4064)
			(end 0.7874 0.4064)
			(stroke
				(width 0.1524)
				(type default)
			)
			(layer "B.SilkS")
		)
		(fp_line
			(start 0.7874 -0.4064)
			(end -0.7874 -0.4064)
			(stroke
				(width 0.1524)
				(type default)
			)
			(layer "B.SilkS")
		)
		(fp_line
			(start 0.7874 0.4064)
			(end 0.7874 -0.4064)
			(stroke
				(width 0.1524)
				(type default)
			)
			(layer "B.SilkS")
		)
		(fp_line
			(start -0.67945 -0.3048)
			(end -0.67945 0.3048)
			(stroke
				(width 0.1)
				(type default)
			)
			(layer "B.Fab")
		)
		(fp_line
			(start -0.67945 0.3048)
			(end -0.120396 0.3048)
			(stroke
				(width 0.1)
				(type default)
			)
			(layer "B.Fab")
		)
		(fp_line
			(start -0.12065 -0.3048)
			(end -0.67945 -0.3048)
			(stroke
				(width 0.1)
				(type default)
			)
			(layer "B.Fab")
		)
		(fp_line
			(start -0.12065 -0.2794)
			(end -0.12065 -0.3048)
			(stroke
				(width 0.1)
				(type default)
			)
			(layer "B.Fab")
		)
		(fp_line
			(start -0.120396 0.2794)
			(end 0.12065 0.2794)
			(stroke
				(width 0.1)
				(type default)
			)
			(layer "B.Fab")
		)
		(fp_line
			(start -0.120396 0.3048)
			(end -0.120396 0.2794)
			(stroke
				(width 0.1)
				(type default)
			)
			(layer "B.Fab")
		)
		(fp_line
			(start 0.12065 -0.305054)
			(end 0.12065 -0.2794)
			(stroke
				(width 0.1)
				(type default)
			)
			(layer "B.Fab")
		)
		(fp_line
			(start 0.12065 -0.2794)
			(end -0.12065 -0.2794)
			(stroke
				(width 0.1)
				(type default)
			)
			(layer "B.Fab")
		)
		(fp_line
			(start 0.12065 0.2794)
			(end 0.12065 0.3048)
			(stroke
				(width 0.1)
				(type default)
			)
			(layer "B.Fab")
		)
		(fp_line
			(start 0.12065 0.3048)
			(end 0.67945 0.3048)
			(stroke
				(width 0.1)
				(type default)
			)
			(layer "B.Fab")
		)
		(fp_line
			(start 0.67945 -0.305054)
			(end 0.12065 -0.305054)
			(stroke
				(width 0.1)
				(type default)
			)
			(layer "B.Fab")
		)
		(fp_line
			(start 0.67945 0.3048)
			(end 0.67945 -0.305054)
			(stroke
				(width 0.1)
				(type default)
			)
			(layer "B.Fab")
		)
		(pad "1" smd circle
			(at 0.40005 0 180)
			(size 0 0)
			(layers "B.Cu" "B.Mask" "B.Paste")
			(net "P3V3_AUX")
		)
		(pad "2" smd circle
			(at -0.40005 0 180)
			(size 0 0)
			(layers "B.Cu" "B.Mask" "B.Paste")
			(net "FM_JTAG_BMC_MUX_SEL")
		)
	)
	(footprint ""
		(layer "B.Cu")
		(at 14.7828 -95.5802 180)
		(property "Reference" "R835"
			(at 0 0 0)
			(layer "B.SilkS")
			(hide yes)
			(effects
				(font
					(size 1.27 1.27)
				)
				(justify mirror)
			)
		)
		(property "Value" ""
			(at 0 0 0)
			(layer "B.Fab")
			(effects
				(font
					(size 1.27 1.27)
				)
				(justify mirror)
			)
		)
		(duplicate_pad_numbers_are_jumpers no)
		(fp_line
			(start 0.7874 0.4064)
			(end 0.7874 -0.4064)
			(stroke
				(width 0.1524)
				(type default)
			)
			(layer "B.SilkS")
		)
		(fp_line
			(start 0.7874 -0.4064)
			(end -0.7874 -0.4064)
			(stroke
				(width 0.1524)
				(type default)
			)
			(layer "B.SilkS")
		)
		(fp_line
			(start -0.7874 0.4064)
			(end 0.7874 0.4064)
			(stroke
				(width 0.1524)
				(type default)
			)
			(layer "B.SilkS")
		)
		(fp_line
			(start -0.7874 -0.4064)
			(end -0.7874 0.4064)
			(stroke
				(width 0.1524)
				(type default)
			)
			(layer "B.SilkS")
		)
		(fp_line
			(start 0.67945 0.3048)
			(end 0.67945 -0.305054)
			(stroke
				(width 0.1)
				(type default)
			)
			(layer "B.Fab")
		)
		(fp_line
			(start 0.67945 -0.305054)
			(end 0.12065 -0.305054)
			(stroke
				(width 0.1)
				(type default)
			)
			(layer "B.Fab")
		)
		(fp_line
			(start 0.12065 0.3048)
			(end 0.67945 0.3048)
			(stroke
				(width 0.1)
				(type default)
			)
			(layer "B.Fab")
		)
		(fp_line
			(start 0.12065 0.2794)
			(end 0.12065 0.3048)
			(stroke
				(width 0.1)
				(type default)
			)
			(layer "B.Fab")
		)
		(fp_line
			(start 0.12065 -0.2794)
			(end -0.12065 -0.2794)
			(stroke
				(width 0.1)
				(type default)
			)
			(layer "B.Fab")
		)
		(fp_line
			(start 0.12065 -0.305054)
			(end 0.12065 -0.2794)
			(stroke
				(width 0.1)
				(type default)
			)
			(layer "B.Fab")
		)
		(fp_line
			(start -0.120396 0.3048)
			(end -0.120396 0.2794)
			(stroke
				(width 0.1)
				(type default)
			)
			(layer "B.Fab")
		)
		(fp_line
			(start -0.120396 0.2794)
			(end 0.12065 0.2794)
			(stroke
				(width 0.1)
				(type default)
			)
			(layer "B.Fab")
		)
		(fp_line
			(start -0.12065 -0.2794)
			(end -0.12065 -0.3048)
			(stroke
				(width 0.1)
				(type default)
			)
			(layer "B.Fab")
		)
		(fp_line
			(start -0.12065 -0.3048)
			(end -0.67945 -0.3048)
			(stroke
				(width 0.1)
				(type default)
			)
			(layer "B.Fab")
		)
		(fp_line
			(start -0.67945 0.3048)
			(end -0.120396 0.3048)
			(stroke
				(width 0.1)
				(type default)
			)
			(layer "B.Fab")
		)
		(fp_line
			(start -0.67945 -0.3048)
			(end -0.67945 0.3048)
			(stroke
				(width 0.1)
				(type default)
			)
			(layer "B.Fab")
		)
		(pad "1" smd circle
			(at 0.40005 0)
			(size 0 0)
			(layers "B.Cu" "B.Mask" "B.Paste")
			(net "P3V3_AUX")
		)
		(pad "2" smd circle
			(at -0.40005 0)
			(size 0 0)
			(layers "B.Cu" "B.Mask" "B.Paste")
			(net "FM_ADR_TRIGGER_N")
		)
	)
	(footprint ""
		(layer "B.Cu")
		(at 10.2616 -106.3752 -90)
		(property "Reference" "R811"
			(at 0 0 90)
			(layer "B.SilkS")
			(hide yes)
			(effects
				(font
					(size 1.27 1.27)
				)
				(justify mirror)
			)
		)
		(property "Value" ""
			(at 0 0 90)
			(layer "B.Fab")
			(effects
				(font
					(size 1.27 1.27)
				)
				(justify mirror)
			)
		)
		(duplicate_pad_numbers_are_jumpers no)
		(fp_line
			(start -0.7874 0.4064)
			(end 0.7874 0.4064)
			(stroke
				(width 0.1524)
				(type default)
			)
			(layer "B.SilkS")
		)
		(fp_line
			(start 0.7874 0.4064)
			(end 0.7874 -0.4064)
			(stroke
				(width 0.1524)
				(type default)
			)
			(layer "B.SilkS")
		)
		(fp_line
			(start -0.7874 -0.4064)
			(end -0.7874 0.4064)
			(stroke
				(width 0.1524)
				(type default)
			)
			(layer "B.SilkS")
		)
		(fp_line
			(start 0.7874 -0.4064)
			(end -0.7874 -0.4064)
			(stroke
				(width 0.1524)
				(type default)
			)
			(layer "B.SilkS")
		)
		(fp_line
			(start -0.67945 0.3048)
			(end -0.120396 0.3048)
			(stroke
				(width 0.1)
				(type default)
			)
			(layer "B.Fab")
		)
		(fp_line
			(start -0.120396 0.3048)
			(end -0.120396 0.2794)
			(stroke
				(width 0.1)
				(type default)
			)
			(layer "B.Fab")
		)
		(fp_line
			(start 0.12065 0.3048)
			(end 0.67945 0.3048)
			(stroke
				(width 0.1)
				(type default)
			)
			(layer "B.Fab")
		)
		(fp_line
			(start 0.67945 0.3048)
			(end 0.67945 -0.305054)
			(stroke
				(width 0.1)
				(type default)
			)
			(layer "B.Fab")
		)
		(fp_line
			(start -0.120396 0.2794)
			(end 0.12065 0.2794)
			(stroke
				(width 0.1)
				(type default)
			)
			(layer "B.Fab")
		)
		(fp_line
			(start 0.12065 0.2794)
			(end 0.12065 0.3048)
			(stroke
				(width 0.1)
				(type default)
			)
			(layer "B.Fab")
		)
		(fp_line
			(start -0.12065 -0.2794)
			(end -0.12065 -0.3048)
			(stroke
				(width 0.1)
				(type default)
			)
			(layer "B.Fab")
		)
		(fp_line
			(start 0.12065 -0.2794)
			(end -0.12065 -0.2794)
			(stroke
				(width 0.1)
				(type default)
			)
			(layer "B.Fab")
		)
		(fp_line
			(start -0.67945 -0.3048)
			(end -0.67945 0.3048)
			(stroke
				(width 0.1)
				(type default)
			)
			(layer "B.Fab")
		)
		(fp_line
			(start -0.12065 -0.3048)
			(end -0.67945 -0.3048)
			(stroke
				(width 0.1)
				(type default)
			)
			(layer "B.Fab")
		)
		(fp_line
			(start 0.12065 -0.305054)
			(end 0.12065 -0.2794)
			(stroke
				(width 0.1)
				(type default)
			)
			(layer "B.Fab")
		)
		(fp_line
			(start 0.67945 -0.305054)
			(end 0.12065 -0.305054)
			(stroke
				(width 0.1)
				(type default)
			)
			(layer "B.Fab")
		)
		(pad "1" smd circle
			(at 0.40005 0 90)
			(size 0 0)
			(layers "B.Cu" "B.Mask" "B.Paste")
			(net "PCH_BEEP_LED")
		)
		(pad "2" smd circle
			(at -0.40005 0 90)
			(size 0 0)
			(layers "B.Cu" "B.Mask" "B.Paste")
			(net "PCH_BEEP_R_LED")
		)
	)
	(footprint ""
		(layer "B.Cu")
		(at 78.74 -94.742)
		(property "Reference" "R716"
			(at 0 0 0)
			(layer "B.SilkS")
			(hide yes)
			(effects
				(font
					(size 1.27 1.27)
				)
				(justify mirror)
			)
		)
		(property "Value" ""
			(at 0 0 0)
			(layer "B.Fab")
			(effects
				(font
					(size 1.27 1.27)
				)
				(justify mirror)
			)
		)
		(duplicate_pad_numbers_are_jumpers no)
		(fp_line
			(start -0.7874 -0.4064)
			(end -0.7874 0.4064)
			(stroke
				(width 0.1524)
				(type default)
			)
			(layer "B.SilkS")
		)
		(fp_line
			(start -0.7874 0.4064)
			(end 0.7874 0.4064)
			(stroke
				(width 0.1524)
				(type default)
			)
			(layer "B.SilkS")
		)
		(fp_line
			(start 0.7874 -0.4064)
			(end -0.7874 -0.4064)
			(stroke
				(width 0.1524)
				(type default)
			)
			(layer "B.SilkS")
		)
		(fp_line
			(start 0.7874 0.4064)
			(end 0.7874 -0.4064)
			(stroke
				(width 0.1524)
				(type default)
			)
			(layer "B.SilkS")
		)
		(fp_line
			(start -0.67945 -0.3048)
			(end -0.67945 0.3048)
			(stroke
				(width 0.1)
				(type default)
			)
			(layer "B.Fab")
		)
		(fp_line
			(start -0.67945 0.3048)
			(end -0.120396 0.3048)
			(stroke
				(width 0.1)
				(type default)
			)
			(layer "B.Fab")
		)
		(fp_line
			(start -0.12065 -0.3048)
			(end -0.67945 -0.3048)
			(stroke
				(width 0.1)
				(type default)
			)
			(layer "B.Fab")
		)
		(fp_line
			(start -0.12065 -0.2794)
			(end -0.12065 -0.3048)
			(stroke
				(width 0.1)
				(type default)
			)
			(layer "B.Fab")
		)
		(fp_line
			(start -0.120396 0.2794)
			(end 0.12065 0.2794)
			(stroke
				(width 0.1)
				(type default)
			)
			(layer "B.Fab")
		)
		(fp_line
			(start -0.120396 0.3048)
			(end -0.120396 0.2794)
			(stroke
				(width 0.1)
				(type default)
			)
			(layer "B.Fab")
		)
		(fp_line
			(start 0.12065 -0.305054)
			(end 0.12065 -0.2794)
			(stroke
				(width 0.1)
				(type default)
			)
			(layer "B.Fab")
		)
		(fp_line
			(start 0.12065 -0.2794)
			(end -0.12065 -0.2794)
			(stroke
				(width 0.1)
				(type default)
			)
			(layer "B.Fab")
		)
		(fp_line
			(start 0.12065 0.2794)
			(end 0.12065 0.3048)
			(stroke
				(width 0.1)
				(type default)
			)
			(layer "B.Fab")
		)
		(fp_line
			(start 0.12065 0.3048)
			(end 0.67945 0.3048)
			(stroke
				(width 0.1)
				(type default)
			)
			(layer "B.Fab")
		)
		(fp_line
			(start 0.67945 -0.305054)
			(end 0.12065 -0.305054)
			(stroke
				(width 0.1)
				(type default)
			)
			(layer "B.Fab")
		)
		(fp_line
			(start 0.67945 0.3048)
			(end 0.67945 -0.305054)
			(stroke
				(width 0.1)
				(type default)
			)
			(layer "B.Fab")
		)
		(pad "1" smd circle
			(at 0.40005 0 180)
			(size 0 0)
			(layers "B.Cu" "B.Mask" "B.Paste")
			(net "P5V_AUX")
		)
		(pad "2" smd circle
			(at -0.40005 0 180)
			(size 0 0)
			(layers "B.Cu" "B.Mask" "B.Paste")
			(net "LPC_ESPI_SEL_N")
		)
	)
	(footprint ""
		(layer "B.Cu")
		(at 63.5762 -93.8022 90)
		(property "Reference" "R667"
			(at 0 0 90)
			(layer "B.SilkS")
			(hide yes)
			(effects
				(font
					(size 1.27 1.27)
				)
				(justify mirror)
			)
		)
		(property "Value" ""
			(at 0 0 90)
			(layer "B.Fab")
			(effects
				(font
					(size 1.27 1.27)
				)
				(justify mirror)
			)
		)
		(duplicate_pad_numbers_are_jumpers no)
		(fp_line
			(start 0.7874 -0.4064)
			(end -0.7874 -0.4064)
			(stroke
				(width 0.1524)
				(type default)
			)
			(layer "B.SilkS")
		)
		(fp_line
			(start -0.7874 -0.4064)
			(end -0.7874 0.4064)
			(stroke
				(width 0.1524)
				(type default)
			)
			(layer "B.SilkS")
		)
		(fp_line
			(start 0.7874 0.4064)
			(end 0.7874 -0.4064)
			(stroke
				(width 0.1524)
				(type default)
			)
			(layer "B.SilkS")
		)
		(fp_line
			(start -0.7874 0.4064)
			(end 0.7874 0.4064)
			(stroke
				(width 0.1524)
				(type default)
			)
			(layer "B.SilkS")
		)
		(fp_line
			(start 0.67945 -0.305054)
			(end 0.12065 -0.305054)
			(stroke
				(width 0.1)
				(type default)
			)
			(layer "B.Fab")
		)
		(fp_line
			(start 0.12065 -0.305054)
			(end 0.12065 -0.2794)
			(stroke
				(width 0.1)
				(type default)
			)
			(layer "B.Fab")
		)
		(fp_line
			(start -0.12065 -0.3048)
			(end -0.67945 -0.3048)
			(stroke
				(width 0.1)
				(type default)
			)
			(layer "B.Fab")
		)
		(fp_line
			(start -0.67945 -0.3048)
			(end -0.67945 0.3048)
			(stroke
				(width 0.1)
				(type default)
			)
			(layer "B.Fab")
		)
		(fp_line
			(start 0.12065 -0.2794)
			(end -0.12065 -0.2794)
			(stroke
				(width 0.1)
				(type default)
			)
			(layer "B.Fab")
		)
		(fp_line
			(start -0.12065 -0.2794)
			(end -0.12065 -0.3048)
			(stroke
				(width 0.1)
				(type default)
			)
			(layer "B.Fab")
		)
		(fp_line
			(start 0.12065 0.2794)
			(end 0.12065 0.3048)
			(stroke
				(width 0.1)
				(type default)
			)
			(layer "B.Fab")
		)
		(fp_line
			(start -0.120396 0.2794)
			(end 0.12065 0.2794)
			(stroke
				(width 0.1)
				(type default)
			)
			(layer "B.Fab")
		)
		(fp_line
			(start 0.67945 0.3048)
			(end 0.67945 -0.305054)
			(stroke
				(width 0.1)
				(type default)
			)
			(layer "B.Fab")
		)
		(fp_line
			(start 0.12065 0.3048)
			(end 0.67945 0.3048)
			(stroke
				(width 0.1)
				(type default)
			)
			(layer "B.Fab")
		)
		(fp_line
			(start -0.120396 0.3048)
			(end -0.120396 0.2794)
			(stroke
				(width 0.1)
				(type default)
			)
			(layer "B.Fab")
		)
		(fp_line
			(start -0.67945 0.3048)
			(end -0.120396 0.3048)
			(stroke
				(width 0.1)
				(type default)
			)
			(layer "B.Fab")
		)
		(pad "1" smd circle
			(at 0.40005 0 270)
			(size 0 0)
			(layers "B.Cu" "B.Mask" "B.Paste")
			(net "P3V3_AUX")
		)
		(pad "2" smd circle
			(at -0.40005 0 270)
			(size 0 0)
			(layers "B.Cu" "B.Mask" "B.Paste")
			(net "LED_POSTCODE_INT")
		)
	)
	(footprint ""
		(layer "B.Cu")
		(at 40.887142 -63.756794 -90)
		(property "Reference" "R195"
			(at 0 0 90)
			(layer "B.SilkS")
			(hide yes)
			(effects
				(font
					(size 1.27 1.27)
				)
				(justify mirror)
			)
		)
		(property "Value" ""
			(at 0 0 90)
			(layer "B.Fab")
			(effects
				(font
					(size 1.27 1.27)
				)
				(justify mirror)
			)
		)
		(duplicate_pad_numbers_are_jumpers no)
		(fp_line
			(start -0.7874 0.4064)
			(end 0.7874 0.4064)
			(stroke
				(width 0.1524)
				(type default)
			)
			(layer "B.SilkS")
		)
		(fp_line
			(start 0.7874 0.4064)
			(end 0.7874 -0.4064)
			(stroke
				(width 0.1524)
				(type default)
			)
			(layer "B.SilkS")
		)
		(fp_line
			(start -0.7874 -0.4064)
			(end -0.7874 0.4064)
			(stroke
				(width 0.1524)
				(type default)
			)
			(layer "B.SilkS")
		)
		(fp_line
			(start 0.7874 -0.4064)
			(end -0.7874 -0.4064)
			(stroke
				(width 0.1524)
				(type default)
			)
			(layer "B.SilkS")
		)
		(fp_line
			(start -0.67945 0.3048)
			(end -0.120396 0.3048)
			(stroke
				(width 0.1)
				(type default)
			)
			(layer "B.Fab")
		)
		(fp_line
			(start -0.120396 0.3048)
			(end -0.120396 0.2794)
			(stroke
				(width 0.1)
				(type default)
			)
			(layer "B.Fab")
		)
		(fp_line
			(start 0.12065 0.3048)
			(end 0.67945 0.3048)
			(stroke
				(width 0.1)
				(type default)
			)
			(layer "B.Fab")
		)
		(fp_line
			(start 0.67945 0.3048)
			(end 0.67945 -0.305054)
			(stroke
				(width 0.1)
				(type default)
			)
			(layer "B.Fab")
		)
		(fp_line
			(start -0.120396 0.2794)
			(end 0.12065 0.2794)
			(stroke
				(width 0.1)
				(type default)
			)
			(layer "B.Fab")
		)
		(fp_line
			(start 0.12065 0.2794)
			(end 0.12065 0.3048)
			(stroke
				(width 0.1)
				(type default)
			)
			(layer "B.Fab")
		)
		(fp_line
			(start -0.12065 -0.2794)
			(end -0.12065 -0.3048)
			(stroke
				(width 0.1)
				(type default)
			)
			(layer "B.Fab")
		)
		(fp_line
			(start 0.12065 -0.2794)
			(end -0.12065 -0.2794)
			(stroke
				(width 0.1)
				(type default)
			)
			(layer "B.Fab")
		)
		(fp_line
			(start -0.67945 -0.3048)
			(end -0.67945 0.3048)
			(stroke
				(width 0.1)
				(type default)
			)
			(layer "B.Fab")
		)
		(fp_line
			(start -0.12065 -0.3048)
			(end -0.67945 -0.3048)
			(stroke
				(width 0.1)
				(type default)
			)
			(layer "B.Fab")
		)
		(fp_line
			(start 0.12065 -0.305054)
			(end 0.12065 -0.2794)
			(stroke
				(width 0.1)
				(type default)
			)
			(layer "B.Fab")
		)
		(fp_line
			(start 0.67945 -0.305054)
			(end 0.12065 -0.305054)
			(stroke
				(width 0.1)
				(type default)
			)
			(layer "B.Fab")
		)
		(pad "1" smd circle
			(at 0.40005 0 90)
			(size 0 0)
			(layers "B.Cu" "B.Mask" "B.Paste")
			(net "P1V2_P1V0_I3C_VDDL1")
		)
		(pad "2" smd circle
			(at -0.40005 0 90)
			(size 0 0)
			(layers "B.Cu" "B.Mask" "B.Paste")
			(net "I3C1_SPD_SDA")
		)
	)
	(footprint ""
		(layer "B.Cu")
		(at 25.7048 -94.8182 -90)
		(property "Reference" "R308"
			(at 0 0 90)
			(layer "B.SilkS")
			(hide yes)
			(effects
				(font
					(size 1.27 1.27)
				)
				(justify mirror)
			)
		)
		(property "Value" ""
			(at 0 0 90)
			(layer "B.Fab")
			(effects
				(font
					(size 1.27 1.27)
				)
				(justify mirror)
			)
		)
		(duplicate_pad_numbers_are_jumpers no)
		(fp_line
			(start -0.7874 0.4064)
			(end 0.7874 0.4064)
			(stroke
				(width 0.1524)
				(type default)
			)
			(layer "B.SilkS")
		)
		(fp_line
			(start 0.7874 0.4064)
			(end 0.7874 -0.4064)
			(stroke
				(width 0.1524)
				(type default)
			)
			(layer "B.SilkS")
		)
		(fp_line
			(start -0.7874 -0.4064)
			(end -0.7874 0.4064)
			(stroke
				(width 0.1524)
				(type default)
			)
			(layer "B.SilkS")
		)
		(fp_line
			(start 0.7874 -0.4064)
			(end -0.7874 -0.4064)
			(stroke
				(width 0.1524)
				(type default)
			)
			(layer "B.SilkS")
		)
		(fp_line
			(start -0.67945 0.3048)
			(end -0.120396 0.3048)
			(stroke
				(width 0.1)
				(type default)
			)
			(layer "B.Fab")
		)
		(fp_line
			(start -0.120396 0.3048)
			(end -0.120396 0.2794)
			(stroke
				(width 0.1)
				(type default)
			)
			(layer "B.Fab")
		)
		(fp_line
			(start 0.12065 0.3048)
			(end 0.67945 0.3048)
			(stroke
				(width 0.1)
				(type default)
			)
			(layer "B.Fab")
		)
		(fp_line
			(start 0.67945 0.3048)
			(end 0.67945 -0.305054)
			(stroke
				(width 0.1)
				(type default)
			)
			(layer "B.Fab")
		)
		(fp_line
			(start -0.120396 0.2794)
			(end 0.12065 0.2794)
			(stroke
				(width 0.1)
				(type default)
			)
			(layer "B.Fab")
		)
		(fp_line
			(start 0.12065 0.2794)
			(end 0.12065 0.3048)
			(stroke
				(width 0.1)
				(type default)
			)
			(layer "B.Fab")
		)
		(fp_line
			(start -0.12065 -0.2794)
			(end -0.12065 -0.3048)
			(stroke
				(width 0.1)
				(type default)
			)
			(layer "B.Fab")
		)
		(fp_line
			(start 0.12065 -0.2794)
			(end -0.12065 -0.2794)
			(stroke
				(width 0.1)
				(type default)
			)
			(layer "B.Fab")
		)
		(fp_line
			(start -0.67945 -0.3048)
			(end -0.67945 0.3048)
			(stroke
				(width 0.1)
				(type default)
			)
			(layer "B.Fab")
		)
		(fp_line
			(start -0.12065 -0.3048)
			(end -0.67945 -0.3048)
			(stroke
				(width 0.1)
				(type default)
			)
			(layer "B.Fab")
		)
		(fp_line
			(start 0.12065 -0.305054)
			(end 0.12065 -0.2794)
			(stroke
				(width 0.1)
				(type default)
			)
			(layer "B.Fab")
		)
		(fp_line
			(start 0.67945 -0.305054)
			(end 0.12065 -0.305054)
			(stroke
				(width 0.1)
				(type default)
			)
			(layer "B.Fab")
		)
		(pad "1" smd circle
			(at 0.40005 0 90)
			(size 0 0)
			(layers "B.Cu" "B.Mask" "B.Paste")
			(net "P3V3_AUX")
		)
		(pad "2" smd circle
			(at -0.40005 0 90)
			(size 0 0)
			(layers "B.Cu" "B.Mask" "B.Paste")
			(net "VCCIO3")
		)
	)
	(footprint ""
		(layer "B.Cu")
		(at 31.7754 -20.5232 90)
		(property "Reference" "FS1"
			(at -4.9022 -1.06807 270)
			(unlocked yes)
			(layer "B.SilkS")
			(effects
				(font
					(size 0.7874 0.5842)
					(thickness 0.1524)
				)
				(justify left mirror)
			)
		)
		(property "Value" ""
			(at 0 0 90)
			(layer "B.Fab")
			(effects
				(font
					(size 1.27 1.27)
				)
				(justify mirror)
			)
		)
		(duplicate_pad_numbers_are_jumpers no)
		(fp_line
			(start 2.100326 -1.100074)
			(end -2.100326 -1.100074)
			(stroke
				(width 0.1524)
				(type default)
			)
			(layer "B.SilkS")
		)
		(fp_line
			(start -2.100326 -1.100074)
			(end -2.100326 1.100074)
			(stroke
				(width 0.1524)
				(type default)
			)
			(layer "B.SilkS")
		)
		(fp_line
			(start 2.100326 1.100074)
			(end 2.100326 -1.100074)
			(stroke
				(width 0.1524)
				(type default)
			)
			(layer "B.SilkS")
		)
		(fp_line
			(start -2.100326 1.100074)
			(end 2.100326 1.100074)
			(stroke
				(width 0.1524)
				(type default)
			)
			(layer "B.SilkS")
		)
		(fp_line
			(start 1.778 -1.100074)
			(end 1.778 -0.9652)
			(stroke
				(width 0.1)
				(type default)
			)
			(layer "B.Fab")
		)
		(fp_line
			(start -1.778 -1.100074)
			(end 1.778 -1.100074)
			(stroke
				(width 0.1)
				(type default)
			)
			(layer "B.Fab")
		)
		(fp_line
			(start 2.011426 -0.9652)
			(end 2.011426 0.9652)
			(stroke
				(width 0.1)
				(type default)
			)
			(layer "B.Fab")
		)
		(fp_line
			(start 2.0066 -0.9652)
			(end 2.011426 -0.9652)
			(stroke
				(width 0.1)
				(type default)
			)
			(layer "B.Fab")
		)
		(fp_line
			(start 1.778 -0.9652)
			(end 2.0066 -0.9652)
			(stroke
				(width 0.1)
				(type default)
			)
			(layer "B.Fab")
		)
		(fp_line
			(start -1.778 -0.9652)
			(end -1.778 -1.100074)
			(stroke
				(width 0.1)
				(type default)
			)
			(layer "B.Fab")
		)
		(fp_line
			(start -2.0066 -0.9652)
			(end -1.778 -0.9652)
			(stroke
				(width 0.1)
				(type default)
			)
			(layer "B.Fab")
		)
		(fp_line
			(start -2.010918 -0.9652)
			(end -2.0066 -0.9652)
			(stroke
				(width 0.1)
				(type default)
			)
			(layer "B.Fab")
		)
		(fp_line
			(start 2.011426 0.9652)
			(end 2.0066 0.9652)
			(stroke
				(width 0.1)
				(type default)
			)
			(layer "B.Fab")
		)
		(fp_line
			(start 2.0066 0.9652)
			(end 1.778 0.9652)
			(stroke
				(width 0.1)
				(type default)
			)
			(layer "B.Fab")
		)
		(fp_line
			(start 1.778 0.9652)
			(end 1.778 1.100074)
			(stroke
				(width 0.1)
				(type default)
			)
			(layer "B.Fab")
		)
		(fp_line
			(start -1.778 0.9652)
			(end -2.0066 0.9652)
			(stroke
				(width 0.1)
				(type default)
			)
			(layer "B.Fab")
		)
		(fp_line
			(start -2.0066 0.9652)
			(end -2.010918 0.9652)
			(stroke
				(width 0.1)
				(type default)
			)
			(layer "B.Fab")
		)
		(fp_line
			(start -2.010918 0.9652)
			(end -2.010918 -0.9652)
			(stroke
				(width 0.1)
				(type default)
			)
			(layer "B.Fab")
		)
		(fp_line
			(start 1.778 1.100074)
			(end -1.778 1.100074)
			(stroke
				(width 0.1)
				(type default)
			)
			(layer "B.Fab")
		)
		(fp_line
			(start -1.778 1.100074)
			(end -1.778 0.9652)
			(stroke
				(width 0.1)
				(type default)
			)
			(layer "B.Fab")
		)
		(pad "1" smd rect
			(at 1.450086 0 270)
			(size 1.016 1.8034)
			(layers "B.Cu" "B.Mask" "B.Paste")
			(net "CRT_VCC5_2_D")
		)
		(pad "2" smd rect
			(at -1.450086 0 270)
			(size 1.016 1.8034)
			(layers "B.Cu" "B.Mask" "B.Paste")
			(net "CRT_VCC5_2_FUSE")
		)
	)
	(footprint ""
		(layer "B.Cu")
		(at 44.193968 -65.743074 -90)
		(property "Reference" "R190"
			(at 0 0 90)
			(layer "B.SilkS")
			(hide yes)
			(effects
				(font
					(size 1.27 1.27)
				)
				(justify mirror)
			)
		)
		(property "Value" ""
			(at 0 0 90)
			(layer "B.Fab")
			(effects
				(font
					(size 1.27 1.27)
				)
				(justify mirror)
			)
		)
		(duplicate_pad_numbers_are_jumpers no)
		(fp_line
			(start -0.7874 0.4064)
			(end 0.7874 0.4064)
			(stroke
				(width 0.1524)
				(type default)
			)
			(layer "B.SilkS")
		)
		(fp_line
			(start 0.7874 0.4064)
			(end 0.7874 -0.4064)
			(stroke
				(width 0.1524)
				(type default)
			)
			(layer "B.SilkS")
		)
		(fp_line
			(start -0.7874 -0.4064)
			(end -0.7874 0.4064)
			(stroke
				(width 0.1524)
				(type default)
			)
			(layer "B.SilkS")
		)
		(fp_line
			(start 0.7874 -0.4064)
			(end -0.7874 -0.4064)
			(stroke
				(width 0.1524)
				(type default)
			)
			(layer "B.SilkS")
		)
		(fp_line
			(start -0.67945 0.3048)
			(end -0.120396 0.3048)
			(stroke
				(width 0.1)
				(type default)
			)
			(layer "B.Fab")
		)
		(fp_line
			(start -0.120396 0.3048)
			(end -0.120396 0.2794)
			(stroke
				(width 0.1)
				(type default)
			)
			(layer "B.Fab")
		)
		(fp_line
			(start 0.12065 0.3048)
			(end 0.67945 0.3048)
			(stroke
				(width 0.1)
				(type default)
			)
			(layer "B.Fab")
		)
		(fp_line
			(start 0.67945 0.3048)
			(end 0.67945 -0.305054)
			(stroke
				(width 0.1)
				(type default)
			)
			(layer "B.Fab")
		)
		(fp_line
			(start -0.120396 0.2794)
			(end 0.12065 0.2794)
			(stroke
				(width 0.1)
				(type default)
			)
			(layer "B.Fab")
		)
		(fp_line
			(start 0.12065 0.2794)
			(end 0.12065 0.3048)
			(stroke
				(width 0.1)
				(type default)
			)
			(layer "B.Fab")
		)
		(fp_line
			(start -0.12065 -0.2794)
			(end -0.12065 -0.3048)
			(stroke
				(width 0.1)
				(type default)
			)
			(layer "B.Fab")
		)
		(fp_line
			(start 0.12065 -0.2794)
			(end -0.12065 -0.2794)
			(stroke
				(width 0.1)
				(type default)
			)
			(layer "B.Fab")
		)
		(fp_line
			(start -0.67945 -0.3048)
			(end -0.67945 0.3048)
			(stroke
				(width 0.1)
				(type default)
			)
			(layer "B.Fab")
		)
		(fp_line
			(start -0.12065 -0.3048)
			(end -0.67945 -0.3048)
			(stroke
				(width 0.1)
				(type default)
			)
			(layer "B.Fab")
		)
		(fp_line
			(start 0.12065 -0.305054)
			(end 0.12065 -0.2794)
			(stroke
				(width 0.1)
				(type default)
			)
			(layer "B.Fab")
		)
		(fp_line
			(start 0.67945 -0.305054)
			(end 0.12065 -0.305054)
			(stroke
				(width 0.1)
				(type default)
			)
			(layer "B.Fab")
		)
		(pad "1" smd circle
			(at 0.40005 0 90)
			(size 0 0)
			(layers "B.Cu" "B.Mask" "B.Paste")
			(net "P1V2_P1V0_I3C_VDDL1")
		)
		(pad "2" smd circle
			(at -0.40005 0 90)
			(size 0 0)
			(layers "B.Cu" "B.Mask" "B.Paste")
			(net "I3C2_SPD_SCL")
		)
	)
	(footprint ""
		(layer "B.Cu")
		(at 34.0106 -21.4122)
		(property "Reference" "R92"
			(at 0 0 0)
			(layer "B.SilkS")
			(hide yes)
			(effects
				(font
					(size 1.27 1.27)
				)
				(justify mirror)
			)
		)
		(property "Value" ""
			(at 0 0 0)
			(layer "B.Fab")
			(effects
				(font
					(size 1.27 1.27)
				)
				(justify mirror)
			)
		)
		(duplicate_pad_numbers_are_jumpers no)
		(fp_line
			(start -0.7874 -0.4064)
			(end -0.7874 0.4064)
			(stroke
				(width 0.1524)
				(type default)
			)
			(layer "B.SilkS")
		)
		(fp_line
			(start -0.7874 0.4064)
			(end 0.7874 0.4064)
			(stroke
				(width 0.1524)
				(type default)
			)
			(layer "B.SilkS")
		)
		(fp_line
			(start 0.7874 -0.4064)
			(end -0.7874 -0.4064)
			(stroke
				(width 0.1524)
				(type default)
			)
			(layer "B.SilkS")
		)
		(fp_line
			(start 0.7874 0.4064)
			(end 0.7874 -0.4064)
			(stroke
				(width 0.1524)
				(type default)
			)
			(layer "B.SilkS")
		)
		(fp_line
			(start -0.67945 -0.3048)
			(end -0.67945 0.3048)
			(stroke
				(width 0.1)
				(type default)
			)
			(layer "B.Fab")
		)
		(fp_line
			(start -0.67945 0.3048)
			(end -0.120396 0.3048)
			(stroke
				(width 0.1)
				(type default)
			)
			(layer "B.Fab")
		)
		(fp_line
			(start -0.12065 -0.3048)
			(end -0.67945 -0.3048)
			(stroke
				(width 0.1)
				(type default)
			)
			(layer "B.Fab")
		)
		(fp_line
			(start -0.12065 -0.2794)
			(end -0.12065 -0.3048)
			(stroke
				(width 0.1)
				(type default)
			)
			(layer "B.Fab")
		)
		(fp_line
			(start -0.120396 0.2794)
			(end 0.12065 0.2794)
			(stroke
				(width 0.1)
				(type default)
			)
			(layer "B.Fab")
		)
		(fp_line
			(start -0.120396 0.3048)
			(end -0.120396 0.2794)
			(stroke
				(width 0.1)
				(type default)
			)
			(layer "B.Fab")
		)
		(fp_line
			(start 0.12065 -0.305054)
			(end 0.12065 -0.2794)
			(stroke
				(width 0.1)
				(type default)
			)
			(layer "B.Fab")
		)
		(fp_line
			(start 0.12065 -0.2794)
			(end -0.12065 -0.2794)
			(stroke
				(width 0.1)
				(type default)
			)
			(layer "B.Fab")
		)
		(fp_line
			(start 0.12065 0.2794)
			(end 0.12065 0.3048)
			(stroke
				(width 0.1)
				(type default)
			)
			(layer "B.Fab")
		)
		(fp_line
			(start 0.12065 0.3048)
			(end 0.67945 0.3048)
			(stroke
				(width 0.1)
				(type default)
			)
			(layer "B.Fab")
		)
		(fp_line
			(start 0.67945 -0.305054)
			(end 0.12065 -0.305054)
			(stroke
				(width 0.1)
				(type default)
			)
			(layer "B.Fab")
		)
		(fp_line
			(start 0.67945 0.3048)
			(end 0.67945 -0.305054)
			(stroke
				(width 0.1)
				(type default)
			)
			(layer "B.Fab")
		)
		(pad "1" smd circle
			(at 0.40005 0 180)
			(size 0 0)
			(layers "B.Cu" "B.Mask" "B.Paste")
			(net "CRT_VCC5")
		)
		(pad "2" smd circle
			(at -0.40005 0 180)
			(size 0 0)
			(layers "B.Cu" "B.Mask" "B.Paste")
			(net "V_BMC_LS_DDC_SCL")
		)
	)
	(footprint ""
		(layer "B.Cu")
		(at 50.546 -34.6456 -90)
		(property "Reference" "R152"
			(at 0 0 90)
			(layer "B.SilkS")
			(hide yes)
			(effects
				(font
					(size 1.27 1.27)
				)
				(justify mirror)
			)
		)
		(property "Value" ""
			(at 0 0 90)
			(layer "B.Fab")
			(effects
				(font
					(size 1.27 1.27)
				)
				(justify mirror)
			)
		)
		(duplicate_pad_numbers_are_jumpers no)
		(fp_line
			(start -0.7874 0.4064)
			(end 0.7874 0.4064)
			(stroke
				(width 0.1524)
				(type default)
			)
			(layer "B.SilkS")
		)
		(fp_line
			(start 0.7874 0.4064)
			(end 0.7874 -0.4064)
			(stroke
				(width 0.1524)
				(type default)
			)
			(layer "B.SilkS")
		)
		(fp_line
			(start -0.7874 -0.4064)
			(end -0.7874 0.4064)
			(stroke
				(width 0.1524)
				(type default)
			)
			(layer "B.SilkS")
		)
		(fp_line
			(start 0.7874 -0.4064)
			(end -0.7874 -0.4064)
			(stroke
				(width 0.1524)
				(type default)
			)
			(layer "B.SilkS")
		)
		(fp_line
			(start -0.67945 0.3048)
			(end -0.120396 0.3048)
			(stroke
				(width 0.1)
				(type default)
			)
			(layer "B.Fab")
		)
		(fp_line
			(start -0.120396 0.3048)
			(end -0.120396 0.2794)
			(stroke
				(width 0.1)
				(type default)
			)
			(layer "B.Fab")
		)
		(fp_line
			(start 0.12065 0.3048)
			(end 0.67945 0.3048)
			(stroke
				(width 0.1)
				(type default)
			)
			(layer "B.Fab")
		)
		(fp_line
			(start 0.67945 0.3048)
			(end 0.67945 -0.305054)
			(stroke
				(width 0.1)
				(type default)
			)
			(layer "B.Fab")
		)
		(fp_line
			(start -0.120396 0.2794)
			(end 0.12065 0.2794)
			(stroke
				(width 0.1)
				(type default)
			)
			(layer "B.Fab")
		)
		(fp_line
			(start 0.12065 0.2794)
			(end 0.12065 0.3048)
			(stroke
				(width 0.1)
				(type default)
			)
			(layer "B.Fab")
		)
		(fp_line
			(start -0.12065 -0.2794)
			(end -0.12065 -0.3048)
			(stroke
				(width 0.1)
				(type default)
			)
			(layer "B.Fab")
		)
		(fp_line
			(start 0.12065 -0.2794)
			(end -0.12065 -0.2794)
			(stroke
				(width 0.1)
				(type default)
			)
			(layer "B.Fab")
		)
		(fp_line
			(start -0.67945 -0.3048)
			(end -0.67945 0.3048)
			(stroke
				(width 0.1)
				(type default)
			)
			(layer "B.Fab")
		)
		(fp_line
			(start -0.12065 -0.3048)
			(end -0.67945 -0.3048)
			(stroke
				(width 0.1)
				(type default)
			)
			(layer "B.Fab")
		)
		(fp_line
			(start 0.12065 -0.305054)
			(end 0.12065 -0.2794)
			(stroke
				(width 0.1)
				(type default)
			)
			(layer "B.Fab")
		)
		(fp_line
			(start 0.67945 -0.305054)
			(end 0.12065 -0.305054)
			(stroke
				(width 0.1)
				(type default)
			)
			(layer "B.Fab")
		)
		(pad "1" smd circle
			(at 0.40005 0 90)
			(size 0 0)
			(layers "B.Cu" "B.Mask" "B.Paste")
			(net "SMB_BMC_MM16_SCL")
		)
		(pad "2" smd circle
			(at -0.40005 0 90)
			(size 0 0)
			(layers "B.Cu" "B.Mask" "B.Paste")
			(net "SMB_BMC_MM16_R_SCL")
		)
	)
	(footprint ""
		(layer "B.Cu")
		(at 31.369 -32.131 90)
		(property "Reference" "C208"
			(at 0 0 90)
			(layer "B.SilkS")
			(hide yes)
			(effects
				(font
					(size 1.27 1.27)
				)
				(justify mirror)
			)
		)
		(property "Value" ""
			(at 0 0 90)
			(layer "B.Fab")
			(effects
				(font
					(size 1.27 1.27)
				)
				(justify mirror)
			)
		)
		(duplicate_pad_numbers_are_jumpers no)
		(fp_line
			(start 0.7874 -0.4064)
			(end -0.7874 -0.4064)
			(stroke
				(width 0.1524)
				(type default)
			)
			(layer "B.SilkS")
		)
		(fp_line
			(start -0.7874 -0.4064)
			(end -0.7874 0.4064)
			(stroke
				(width 0.1524)
				(type default)
			)
			(layer "B.SilkS")
		)
		(fp_line
			(start 0.7874 0.4064)
			(end 0.7874 -0.4064)
			(stroke
				(width 0.1524)
				(type default)
			)
			(layer "B.SilkS")
		)
		(fp_line
			(start -0.7874 0.4064)
			(end 0.7874 0.4064)
			(stroke
				(width 0.1524)
				(type default)
			)
			(layer "B.SilkS")
		)
		(fp_line
			(start 0.67945 -0.305054)
			(end 0.12065 -0.305054)
			(stroke
				(width 0.1)
				(type default)
			)
			(layer "B.Fab")
		)
		(fp_line
			(start 0.12065 -0.305054)
			(end 0.12065 -0.2794)
			(stroke
				(width 0.1)
				(type default)
			)
			(layer "B.Fab")
		)
		(fp_line
			(start -0.12065 -0.3048)
			(end -0.67945 -0.3048)
			(stroke
				(width 0.1)
				(type default)
			)
			(layer "B.Fab")
		)
		(fp_line
			(start -0.67945 -0.3048)
			(end -0.67945 0.3048)
			(stroke
				(width 0.1)
				(type default)
			)
			(layer "B.Fab")
		)
		(fp_line
			(start 0.12065 -0.2794)
			(end -0.12065 -0.2794)
			(stroke
				(width 0.1)
				(type default)
			)
			(layer "B.Fab")
		)
		(fp_line
			(start -0.12065 -0.2794)
			(end -0.12065 -0.3048)
			(stroke
				(width 0.1)
				(type default)
			)
			(layer "B.Fab")
		)
		(fp_line
			(start 0.12065 0.2794)
			(end 0.12065 0.3048)
			(stroke
				(width 0.1)
				(type default)
			)
			(layer "B.Fab")
		)
		(fp_line
			(start -0.120396 0.2794)
			(end 0.12065 0.2794)
			(stroke
				(width 0.1)
				(type default)
			)
			(layer "B.Fab")
		)
		(fp_line
			(start 0.67945 0.3048)
			(end 0.67945 -0.305054)
			(stroke
				(width 0.1)
				(type default)
			)
			(layer "B.Fab")
		)
		(fp_line
			(start 0.12065 0.3048)
			(end 0.67945 0.3048)
			(stroke
				(width 0.1)
				(type default)
			)
			(layer "B.Fab")
		)
		(fp_line
			(start -0.120396 0.3048)
			(end -0.120396 0.2794)
			(stroke
				(width 0.1)
				(type default)
			)
			(layer "B.Fab")
		)
		(fp_line
			(start -0.67945 0.3048)
			(end -0.120396 0.3048)
			(stroke
				(width 0.1)
				(type default)
			)
			(layer "B.Fab")
		)
		(pad "1" smd circle
			(at 0.40005 0 270)
			(size 0 0)
			(layers "B.Cu" "B.Mask" "B.Paste")
			(net "V_DACR_IO")
		)
		(pad "2" smd circle
			(at -0.40005 0 270)
			(size 0 0)
			(layers "B.Cu" "B.Mask" "B.Paste")
			(net "GND")
		)
	)
	(footprint ""
		(layer "B.Cu")
		(at 68.608448 -27.489404 180)
		(property "Reference" "R420"
			(at 0 0 0)
			(layer "B.SilkS")
			(hide yes)
			(effects
				(font
					(size 1.27 1.27)
				)
				(justify mirror)
			)
		)
		(property "Value" ""
			(at 0 0 0)
			(layer "B.Fab")
			(effects
				(font
					(size 1.27 1.27)
				)
				(justify mirror)
			)
		)
		(duplicate_pad_numbers_are_jumpers no)
		(fp_line
			(start 0.7874 0.4064)
			(end 0.7874 -0.4064)
			(stroke
				(width 0.1524)
				(type default)
			)
			(layer "B.SilkS")
		)
		(fp_line
			(start 0.7874 -0.4064)
			(end -0.7874 -0.4064)
			(stroke
				(width 0.1524)
				(type default)
			)
			(layer "B.SilkS")
		)
		(fp_line
			(start -0.7874 0.4064)
			(end 0.7874 0.4064)
			(stroke
				(width 0.1524)
				(type default)
			)
			(layer "B.SilkS")
		)
		(fp_line
			(start -0.7874 -0.4064)
			(end -0.7874 0.4064)
			(stroke
				(width 0.1524)
				(type default)
			)
			(layer "B.SilkS")
		)
		(fp_line
			(start 0.67945 0.3048)
			(end 0.67945 -0.305054)
			(stroke
				(width 0.1)
				(type default)
			)
			(layer "B.Fab")
		)
		(fp_line
			(start 0.67945 -0.305054)
			(end 0.12065 -0.305054)
			(stroke
				(width 0.1)
				(type default)
			)
			(layer "B.Fab")
		)
		(fp_line
			(start 0.12065 0.3048)
			(end 0.67945 0.3048)
			(stroke
				(width 0.1)
				(type default)
			)
			(layer "B.Fab")
		)
		(fp_line
			(start 0.12065 0.2794)
			(end 0.12065 0.3048)
			(stroke
				(width 0.1)
				(type default)
			)
			(layer "B.Fab")
		)
		(fp_line
			(start 0.12065 -0.2794)
			(end -0.12065 -0.2794)
			(stroke
				(width 0.1)
				(type default)
			)
			(layer "B.Fab")
		)
		(fp_line
			(start 0.12065 -0.305054)
			(end 0.12065 -0.2794)
			(stroke
				(width 0.1)
				(type default)
			)
			(layer "B.Fab")
		)
		(fp_line
			(start -0.120396 0.3048)
			(end -0.120396 0.2794)
			(stroke
				(width 0.1)
				(type default)
			)
			(layer "B.Fab")
		)
		(fp_line
			(start -0.120396 0.2794)
			(end 0.12065 0.2794)
			(stroke
				(width 0.1)
				(type default)
			)
			(layer "B.Fab")
		)
		(fp_line
			(start -0.12065 -0.2794)
			(end -0.12065 -0.3048)
			(stroke
				(width 0.1)
				(type default)
			)
			(layer "B.Fab")
		)
		(fp_line
			(start -0.12065 -0.3048)
			(end -0.67945 -0.3048)
			(stroke
				(width 0.1)
				(type default)
			)
			(layer "B.Fab")
		)
		(fp_line
			(start -0.67945 0.3048)
			(end -0.120396 0.3048)
			(stroke
				(width 0.1)
				(type default)
			)
			(layer "B.Fab")
		)
		(fp_line
			(start -0.67945 -0.3048)
			(end -0.67945 0.3048)
			(stroke
				(width 0.1)
				(type default)
			)
			(layer "B.Fab")
		)
		(pad "1" smd circle
			(at 0.40005 0)
			(size 0 0)
			(layers "B.Cu" "B.Mask" "B.Paste")
			(net "SMB_BMC_MM16_R2_SCL")
		)
		(pad "2" smd circle
			(at -0.40005 0)
			(size 0 0)
			(layers "B.Cu" "B.Mask" "B.Paste")
			(net "SMB_BMC_MM16_SCL")
		)
	)
	(footprint ""
		(layer "B.Cu")
		(at 39.75735 -38.532308 -90)
		(property "Reference" "C35"
			(at 0 0 90)
			(layer "B.SilkS")
			(hide yes)
			(effects
				(font
					(size 1.27 1.27)
				)
				(justify mirror)
			)
		)
		(property "Value" ""
			(at 0 0 90)
			(layer "B.Fab")
			(effects
				(font
					(size 1.27 1.27)
				)
				(justify mirror)
			)
		)
		(duplicate_pad_numbers_are_jumpers no)
		(fp_line
			(start -0.7874 0.4064)
			(end 0.7874 0.4064)
			(stroke
				(width 0.1524)
				(type default)
			)
			(layer "B.SilkS")
		)
		(fp_line
			(start 0.7874 0.4064)
			(end 0.7874 -0.4064)
			(stroke
				(width 0.1524)
				(type default)
			)
			(layer "B.SilkS")
		)
		(fp_line
			(start -0.7874 -0.4064)
			(end -0.7874 0.4064)
			(stroke
				(width 0.1524)
				(type default)
			)
			(layer "B.SilkS")
		)
		(fp_line
			(start 0.7874 -0.4064)
			(end -0.7874 -0.4064)
			(stroke
				(width 0.1524)
				(type default)
			)
			(layer "B.SilkS")
		)
		(fp_line
			(start -0.67945 0.3048)
			(end -0.120396 0.3048)
			(stroke
				(width 0.1)
				(type default)
			)
			(layer "B.Fab")
		)
		(fp_line
			(start -0.120396 0.3048)
			(end -0.120396 0.2794)
			(stroke
				(width 0.1)
				(type default)
			)
			(layer "B.Fab")
		)
		(fp_line
			(start 0.12065 0.3048)
			(end 0.67945 0.3048)
			(stroke
				(width 0.1)
				(type default)
			)
			(layer "B.Fab")
		)
		(fp_line
			(start 0.67945 0.3048)
			(end 0.67945 -0.305054)
			(stroke
				(width 0.1)
				(type default)
			)
			(layer "B.Fab")
		)
		(fp_line
			(start -0.120396 0.2794)
			(end 0.12065 0.2794)
			(stroke
				(width 0.1)
				(type default)
			)
			(layer "B.Fab")
		)
		(fp_line
			(start 0.12065 0.2794)
			(end 0.12065 0.3048)
			(stroke
				(width 0.1)
				(type default)
			)
			(layer "B.Fab")
		)
		(fp_line
			(start -0.12065 -0.2794)
			(end -0.12065 -0.3048)
			(stroke
				(width 0.1)
				(type default)
			)
			(layer "B.Fab")
		)
		(fp_line
			(start 0.12065 -0.2794)
			(end -0.12065 -0.2794)
			(stroke
				(width 0.1)
				(type default)
			)
			(layer "B.Fab")
		)
		(fp_line
			(start -0.67945 -0.3048)
			(end -0.67945 0.3048)
			(stroke
				(width 0.1)
				(type default)
			)
			(layer "B.Fab")
		)
		(fp_line
			(start -0.12065 -0.3048)
			(end -0.67945 -0.3048)
			(stroke
				(width 0.1)
				(type default)
			)
			(layer "B.Fab")
		)
		(fp_line
			(start 0.12065 -0.305054)
			(end 0.12065 -0.2794)
			(stroke
				(width 0.1)
				(type default)
			)
			(layer "B.Fab")
		)
		(fp_line
			(start 0.67945 -0.305054)
			(end 0.12065 -0.305054)
			(stroke
				(width 0.1)
				(type default)
			)
			(layer "B.Fab")
		)
		(pad "1" smd circle
			(at 0.40005 0 90)
			(size 0 0)
			(layers "B.Cu" "B.Mask" "B.Paste")
			(net "P3V3_P1V8_SD1VDD")
		)
		(pad "2" smd circle
			(at -0.40005 0 90)
			(size 0 0)
			(layers "B.Cu" "B.Mask" "B.Paste")
			(net "GND")
		)
	)
	(footprint ""
		(layer "B.Cu")
		(at 63.9572 -92.2274 180)
		(property "Reference" "R744"
			(at 0 0 0)
			(layer "B.SilkS")
			(hide yes)
			(effects
				(font
					(size 1.27 1.27)
				)
				(justify mirror)
			)
		)
		(property "Value" ""
			(at 0 0 0)
			(layer "B.Fab")
			(effects
				(font
					(size 1.27 1.27)
				)
				(justify mirror)
			)
		)
		(duplicate_pad_numbers_are_jumpers no)
		(fp_line
			(start 0.7874 0.4064)
			(end 0.7874 -0.4064)
			(stroke
				(width 0.1524)
				(type default)
			)
			(layer "B.SilkS")
		)
		(fp_line
			(start 0.7874 -0.4064)
			(end -0.7874 -0.4064)
			(stroke
				(width 0.1524)
				(type default)
			)
			(layer "B.SilkS")
		)
		(fp_line
			(start -0.7874 0.4064)
			(end 0.7874 0.4064)
			(stroke
				(width 0.1524)
				(type default)
			)
			(layer "B.SilkS")
		)
		(fp_line
			(start -0.7874 -0.4064)
			(end -0.7874 0.4064)
			(stroke
				(width 0.1524)
				(type default)
			)
			(layer "B.SilkS")
		)
		(fp_line
			(start 0.67945 0.3048)
			(end 0.67945 -0.305054)
			(stroke
				(width 0.1)
				(type default)
			)
			(layer "B.Fab")
		)
		(fp_line
			(start 0.67945 -0.305054)
			(end 0.12065 -0.305054)
			(stroke
				(width 0.1)
				(type default)
			)
			(layer "B.Fab")
		)
		(fp_line
			(start 0.12065 0.3048)
			(end 0.67945 0.3048)
			(stroke
				(width 0.1)
				(type default)
			)
			(layer "B.Fab")
		)
		(fp_line
			(start 0.12065 0.2794)
			(end 0.12065 0.3048)
			(stroke
				(width 0.1)
				(type default)
			)
			(layer "B.Fab")
		)
		(fp_line
			(start 0.12065 -0.2794)
			(end -0.12065 -0.2794)
			(stroke
				(width 0.1)
				(type default)
			)
			(layer "B.Fab")
		)
		(fp_line
			(start 0.12065 -0.305054)
			(end 0.12065 -0.2794)
			(stroke
				(width 0.1)
				(type default)
			)
			(layer "B.Fab")
		)
		(fp_line
			(start -0.120396 0.3048)
			(end -0.120396 0.2794)
			(stroke
				(width 0.1)
				(type default)
			)
			(layer "B.Fab")
		)
		(fp_line
			(start -0.120396 0.2794)
			(end 0.12065 0.2794)
			(stroke
				(width 0.1)
				(type default)
			)
			(layer "B.Fab")
		)
		(fp_line
			(start -0.12065 -0.2794)
			(end -0.12065 -0.3048)
			(stroke
				(width 0.1)
				(type default)
			)
			(layer "B.Fab")
		)
		(fp_line
			(start -0.12065 -0.3048)
			(end -0.67945 -0.3048)
			(stroke
				(width 0.1)
				(type default)
			)
			(layer "B.Fab")
		)
		(fp_line
			(start -0.67945 0.3048)
			(end -0.120396 0.3048)
			(stroke
				(width 0.1)
				(type default)
			)
			(layer "B.Fab")
		)
		(fp_line
			(start -0.67945 -0.3048)
			(end -0.67945 0.3048)
			(stroke
				(width 0.1)
				(type default)
			)
			(layer "B.Fab")
		)
		(pad "1" smd circle
			(at 0.40005 0)
			(size 0 0)
			(layers "B.Cu" "B.Mask" "B.Paste")
			(net "LED_POSTCODE_A1")
		)
		(pad "2" smd circle
			(at -0.40005 0)
			(size 0 0)
			(layers "B.Cu" "B.Mask" "B.Paste")
			(net "GND")
		)
	)
	(footprint ""
		(layer "B.Cu")
		(at 44.384214 -30.816804 -90)
		(property "Reference" "R251"
			(at 0 0 90)
			(layer "B.SilkS")
			(hide yes)
			(effects
				(font
					(size 1.27 1.27)
				)
				(justify mirror)
			)
		)
		(property "Value" ""
			(at 0 0 90)
			(layer "B.Fab")
			(effects
				(font
					(size 1.27 1.27)
				)
				(justify mirror)
			)
		)
		(duplicate_pad_numbers_are_jumpers no)
		(fp_line
			(start -0.7874 0.4064)
			(end 0.7874 0.4064)
			(stroke
				(width 0.1524)
				(type default)
			)
			(layer "B.SilkS")
		)
		(fp_line
			(start 0.7874 0.4064)
			(end 0.7874 -0.4064)
			(stroke
				(width 0.1524)
				(type default)
			)
			(layer "B.SilkS")
		)
		(fp_line
			(start -0.7874 -0.4064)
			(end -0.7874 0.4064)
			(stroke
				(width 0.1524)
				(type default)
			)
			(layer "B.SilkS")
		)
		(fp_line
			(start 0.7874 -0.4064)
			(end -0.7874 -0.4064)
			(stroke
				(width 0.1524)
				(type default)
			)
			(layer "B.SilkS")
		)
		(fp_line
			(start -0.67945 0.3048)
			(end -0.120396 0.3048)
			(stroke
				(width 0.1)
				(type default)
			)
			(layer "B.Fab")
		)
		(fp_line
			(start -0.120396 0.3048)
			(end -0.120396 0.2794)
			(stroke
				(width 0.1)
				(type default)
			)
			(layer "B.Fab")
		)
		(fp_line
			(start 0.12065 0.3048)
			(end 0.67945 0.3048)
			(stroke
				(width 0.1)
				(type default)
			)
			(layer "B.Fab")
		)
		(fp_line
			(start 0.67945 0.3048)
			(end 0.67945 -0.305054)
			(stroke
				(width 0.1)
				(type default)
			)
			(layer "B.Fab")
		)
		(fp_line
			(start -0.120396 0.2794)
			(end 0.12065 0.2794)
			(stroke
				(width 0.1)
				(type default)
			)
			(layer "B.Fab")
		)
		(fp_line
			(start 0.12065 0.2794)
			(end 0.12065 0.3048)
			(stroke
				(width 0.1)
				(type default)
			)
			(layer "B.Fab")
		)
		(fp_line
			(start -0.12065 -0.2794)
			(end -0.12065 -0.3048)
			(stroke
				(width 0.1)
				(type default)
			)
			(layer "B.Fab")
		)
		(fp_line
			(start 0.12065 -0.2794)
			(end -0.12065 -0.2794)
			(stroke
				(width 0.1)
				(type default)
			)
			(layer "B.Fab")
		)
		(fp_line
			(start -0.67945 -0.3048)
			(end -0.67945 0.3048)
			(stroke
				(width 0.1)
				(type default)
			)
			(layer "B.Fab")
		)
		(fp_line
			(start -0.12065 -0.3048)
			(end -0.67945 -0.3048)
			(stroke
				(width 0.1)
				(type default)
			)
			(layer "B.Fab")
		)
		(fp_line
			(start 0.12065 -0.305054)
			(end 0.12065 -0.2794)
			(stroke
				(width 0.1)
				(type default)
			)
			(layer "B.Fab")
		)
		(fp_line
			(start 0.67945 -0.305054)
			(end 0.12065 -0.305054)
			(stroke
				(width 0.1)
				(type default)
			)
			(layer "B.Fab")
		)
		(pad "1" smd circle
			(at 0.40005 0 90)
			(size 0 0)
			(layers "B.Cu" "B.Mask" "B.Paste")
			(net "P3V3_AUX")
		)
		(pad "2" smd circle
			(at -0.40005 0 90)
			(size 0 0)
			(layers "B.Cu" "B.Mask" "B.Paste")
			(net "SMB_BMC_MM4_SDA")
		)
	)
	(footprint ""
		(layer "B.Cu")
		(at 42.6974 -58.0136)
		(property "Reference" "C75"
			(at 0 0 0)
			(layer "B.SilkS")
			(hide yes)
			(effects
				(font
					(size 1.27 1.27)
				)
				(justify mirror)
			)
		)
		(property "Value" ""
			(at 0 0 0)
			(layer "B.Fab")
			(effects
				(font
					(size 1.27 1.27)
				)
				(justify mirror)
			)
		)
		(duplicate_pad_numbers_are_jumpers no)
		(fp_line
			(start -0.7874 -0.4064)
			(end -0.7874 0.4064)
			(stroke
				(width 0.1524)
				(type default)
			)
			(layer "B.SilkS")
		)
		(fp_line
			(start -0.7874 0.4064)
			(end 0.7874 0.4064)
			(stroke
				(width 0.1524)
				(type default)
			)
			(layer "B.SilkS")
		)
		(fp_line
			(start 0.7874 -0.4064)
			(end -0.7874 -0.4064)
			(stroke
				(width 0.1524)
				(type default)
			)
			(layer "B.SilkS")
		)
		(fp_line
			(start 0.7874 0.4064)
			(end 0.7874 -0.4064)
			(stroke
				(width 0.1524)
				(type default)
			)
			(layer "B.SilkS")
		)
		(fp_line
			(start -0.67945 -0.3048)
			(end -0.67945 0.3048)
			(stroke
				(width 0.1)
				(type default)
			)
			(layer "B.Fab")
		)
		(fp_line
			(start -0.67945 0.3048)
			(end -0.120396 0.3048)
			(stroke
				(width 0.1)
				(type default)
			)
			(layer "B.Fab")
		)
		(fp_line
			(start -0.12065 -0.3048)
			(end -0.67945 -0.3048)
			(stroke
				(width 0.1)
				(type default)
			)
			(layer "B.Fab")
		)
		(fp_line
			(start -0.12065 -0.2794)
			(end -0.12065 -0.3048)
			(stroke
				(width 0.1)
				(type default)
			)
			(layer "B.Fab")
		)
		(fp_line
			(start -0.120396 0.2794)
			(end 0.12065 0.2794)
			(stroke
				(width 0.1)
				(type default)
			)
			(layer "B.Fab")
		)
		(fp_line
			(start -0.120396 0.3048)
			(end -0.120396 0.2794)
			(stroke
				(width 0.1)
				(type default)
			)
			(layer "B.Fab")
		)
		(fp_line
			(start 0.12065 -0.305054)
			(end 0.12065 -0.2794)
			(stroke
				(width 0.1)
				(type default)
			)
			(layer "B.Fab")
		)
		(fp_line
			(start 0.12065 -0.2794)
			(end -0.12065 -0.2794)
			(stroke
				(width 0.1)
				(type default)
			)
			(layer "B.Fab")
		)
		(fp_line
			(start 0.12065 0.2794)
			(end 0.12065 0.3048)
			(stroke
				(width 0.1)
				(type default)
			)
			(layer "B.Fab")
		)
		(fp_line
			(start 0.12065 0.3048)
			(end 0.67945 0.3048)
			(stroke
				(width 0.1)
				(type default)
			)
			(layer "B.Fab")
		)
		(fp_line
			(start 0.67945 -0.305054)
			(end 0.12065 -0.305054)
			(stroke
				(width 0.1)
				(type default)
			)
			(layer "B.Fab")
		)
		(fp_line
			(start 0.67945 0.3048)
			(end 0.67945 -0.305054)
			(stroke
				(width 0.1)
				(type default)
			)
			(layer "B.Fab")
		)
		(pad "1" smd circle
			(at 0.40005 0 180)
			(size 0 0)
			(layers "B.Cu" "B.Mask" "B.Paste")
			(net "A_BMC_ADCAV33")
		)
		(pad "2" smd circle
			(at -0.40005 0 180)
			(size 0 0)
			(layers "B.Cu" "B.Mask" "B.Paste")
			(net "GND")
		)
	)
	(footprint ""
		(layer "B.Cu")
		(at 50.66411 -47.625 -90)
		(property "Reference" "C98"
			(at 0 0 90)
			(layer "B.SilkS")
			(hide yes)
			(effects
				(font
					(size 1.27 1.27)
				)
				(justify mirror)
			)
		)
		(property "Value" ""
			(at 0 0 90)
			(layer "B.Fab")
			(effects
				(font
					(size 1.27 1.27)
				)
				(justify mirror)
			)
		)
		(duplicate_pad_numbers_are_jumpers no)
		(fp_line
			(start -0.7874 0.4064)
			(end 0.7874 0.4064)
			(stroke
				(width 0.1524)
				(type default)
			)
			(layer "B.SilkS")
		)
		(fp_line
			(start 0.7874 0.4064)
			(end 0.7874 -0.4064)
			(stroke
				(width 0.1524)
				(type default)
			)
			(layer "B.SilkS")
		)
		(fp_line
			(start -0.7874 -0.4064)
			(end -0.7874 0.4064)
			(stroke
				(width 0.1524)
				(type default)
			)
			(layer "B.SilkS")
		)
		(fp_line
			(start 0.7874 -0.4064)
			(end -0.7874 -0.4064)
			(stroke
				(width 0.1524)
				(type default)
			)
			(layer "B.SilkS")
		)
		(fp_line
			(start -0.67945 0.3048)
			(end -0.120396 0.3048)
			(stroke
				(width 0.1)
				(type default)
			)
			(layer "B.Fab")
		)
		(fp_line
			(start -0.120396 0.3048)
			(end -0.120396 0.2794)
			(stroke
				(width 0.1)
				(type default)
			)
			(layer "B.Fab")
		)
		(fp_line
			(start 0.12065 0.3048)
			(end 0.67945 0.3048)
			(stroke
				(width 0.1)
				(type default)
			)
			(layer "B.Fab")
		)
		(fp_line
			(start 0.67945 0.3048)
			(end 0.67945 -0.305054)
			(stroke
				(width 0.1)
				(type default)
			)
			(layer "B.Fab")
		)
		(fp_line
			(start -0.120396 0.2794)
			(end 0.12065 0.2794)
			(stroke
				(width 0.1)
				(type default)
			)
			(layer "B.Fab")
		)
		(fp_line
			(start 0.12065 0.2794)
			(end 0.12065 0.3048)
			(stroke
				(width 0.1)
				(type default)
			)
			(layer "B.Fab")
		)
		(fp_line
			(start -0.12065 -0.2794)
			(end -0.12065 -0.3048)
			(stroke
				(width 0.1)
				(type default)
			)
			(layer "B.Fab")
		)
		(fp_line
			(start 0.12065 -0.2794)
			(end -0.12065 -0.2794)
			(stroke
				(width 0.1)
				(type default)
			)
			(layer "B.Fab")
		)
		(fp_line
			(start -0.67945 -0.3048)
			(end -0.67945 0.3048)
			(stroke
				(width 0.1)
				(type default)
			)
			(layer "B.Fab")
		)
		(fp_line
			(start -0.12065 -0.3048)
			(end -0.67945 -0.3048)
			(stroke
				(width 0.1)
				(type default)
			)
			(layer "B.Fab")
		)
		(fp_line
			(start 0.12065 -0.305054)
			(end 0.12065 -0.2794)
			(stroke
				(width 0.1)
				(type default)
			)
			(layer "B.Fab")
		)
		(fp_line
			(start 0.67945 -0.305054)
			(end 0.12065 -0.305054)
			(stroke
				(width 0.1)
				(type default)
			)
			(layer "B.Fab")
		)
		(pad "1" smd circle
			(at 0.40005 0 90)
			(size 0 0)
			(layers "B.Cu" "B.Mask" "B.Paste")
			(net "P1V2_AUX")
		)
		(pad "2" smd circle
			(at -0.40005 0 90)
			(size 0 0)
			(layers "B.Cu" "B.Mask" "B.Paste")
			(net "GND")
		)
	)
	(footprint ""
		(layer "B.Cu")
		(at 16.564864 -58.7502 -90)
		(property "Reference" "R135"
			(at 0 0 90)
			(layer "B.SilkS")
			(hide yes)
			(effects
				(font
					(size 1.27 1.27)
				)
				(justify mirror)
			)
		)
		(property "Value" ""
			(at 0 0 90)
			(layer "B.Fab")
			(effects
				(font
					(size 1.27 1.27)
				)
				(justify mirror)
			)
		)
		(duplicate_pad_numbers_are_jumpers no)
		(fp_line
			(start -0.7874 0.4064)
			(end 0.7874 0.4064)
			(stroke
				(width 0.1524)
				(type default)
			)
			(layer "B.SilkS")
		)
		(fp_line
			(start 0.7874 0.4064)
			(end 0.7874 -0.4064)
			(stroke
				(width 0.1524)
				(type default)
			)
			(layer "B.SilkS")
		)
		(fp_line
			(start -0.7874 -0.4064)
			(end -0.7874 0.4064)
			(stroke
				(width 0.1524)
				(type default)
			)
			(layer "B.SilkS")
		)
		(fp_line
			(start 0.7874 -0.4064)
			(end -0.7874 -0.4064)
			(stroke
				(width 0.1524)
				(type default)
			)
			(layer "B.SilkS")
		)
		(fp_line
			(start -0.67945 0.3048)
			(end -0.120396 0.3048)
			(stroke
				(width 0.1)
				(type default)
			)
			(layer "B.Fab")
		)
		(fp_line
			(start -0.120396 0.3048)
			(end -0.120396 0.2794)
			(stroke
				(width 0.1)
				(type default)
			)
			(layer "B.Fab")
		)
		(fp_line
			(start 0.12065 0.3048)
			(end 0.67945 0.3048)
			(stroke
				(width 0.1)
				(type default)
			)
			(layer "B.Fab")
		)
		(fp_line
			(start 0.67945 0.3048)
			(end 0.67945 -0.305054)
			(stroke
				(width 0.1)
				(type default)
			)
			(layer "B.Fab")
		)
		(fp_line
			(start -0.120396 0.2794)
			(end 0.12065 0.2794)
			(stroke
				(width 0.1)
				(type default)
			)
			(layer "B.Fab")
		)
		(fp_line
			(start 0.12065 0.2794)
			(end 0.12065 0.3048)
			(stroke
				(width 0.1)
				(type default)
			)
			(layer "B.Fab")
		)
		(fp_line
			(start -0.12065 -0.2794)
			(end -0.12065 -0.3048)
			(stroke
				(width 0.1)
				(type default)
			)
			(layer "B.Fab")
		)
		(fp_line
			(start 0.12065 -0.2794)
			(end -0.12065 -0.2794)
			(stroke
				(width 0.1)
				(type default)
			)
			(layer "B.Fab")
		)
		(fp_line
			(start -0.67945 -0.3048)
			(end -0.67945 0.3048)
			(stroke
				(width 0.1)
				(type default)
			)
			(layer "B.Fab")
		)
		(fp_line
			(start -0.12065 -0.3048)
			(end -0.67945 -0.3048)
			(stroke
				(width 0.1)
				(type default)
			)
			(layer "B.Fab")
		)
		(fp_line
			(start 0.12065 -0.305054)
			(end 0.12065 -0.2794)
			(stroke
				(width 0.1)
				(type default)
			)
			(layer "B.Fab")
		)
		(fp_line
			(start 0.67945 -0.305054)
			(end 0.12065 -0.305054)
			(stroke
				(width 0.1)
				(type default)
			)
			(layer "B.Fab")
		)
		(pad "1" smd circle
			(at 0.40005 0 90)
			(size 0 0)
			(layers "B.Cu" "B.Mask" "B.Paste")
			(net "SMB_BMC_MM15_SCL")
		)
		(pad "2" smd circle
			(at -0.40005 0 90)
			(size 0 0)
			(layers "B.Cu" "B.Mask" "B.Paste")
			(net "SMB_BMC_MM15_R1_SCL")
		)
	)
	(footprint ""
		(layer "B.Cu")
		(at 11.9126 -25.9842 180)
		(property "Reference" "R104"
			(at 0 0 0)
			(layer "B.SilkS")
			(hide yes)
			(effects
				(font
					(size 1.27 1.27)
				)
				(justify mirror)
			)
		)
		(property "Value" ""
			(at 0 0 0)
			(layer "B.Fab")
			(effects
				(font
					(size 1.27 1.27)
				)
				(justify mirror)
			)
		)
		(duplicate_pad_numbers_are_jumpers no)
		(fp_line
			(start 0.7874 0.4064)
			(end 0.7874 -0.4064)
			(stroke
				(width 0.1524)
				(type default)
			)
			(layer "B.SilkS")
		)
		(fp_line
			(start 0.7874 -0.4064)
			(end -0.7874 -0.4064)
			(stroke
				(width 0.1524)
				(type default)
			)
			(layer "B.SilkS")
		)
		(fp_line
			(start -0.7874 0.4064)
			(end 0.7874 0.4064)
			(stroke
				(width 0.1524)
				(type default)
			)
			(layer "B.SilkS")
		)
		(fp_line
			(start -0.7874 -0.4064)
			(end -0.7874 0.4064)
			(stroke
				(width 0.1524)
				(type default)
			)
			(layer "B.SilkS")
		)
		(fp_line
			(start 0.67945 0.3048)
			(end 0.67945 -0.305054)
			(stroke
				(width 0.1)
				(type default)
			)
			(layer "B.Fab")
		)
		(fp_line
			(start 0.67945 -0.305054)
			(end 0.12065 -0.305054)
			(stroke
				(width 0.1)
				(type default)
			)
			(layer "B.Fab")
		)
		(fp_line
			(start 0.12065 0.3048)
			(end 0.67945 0.3048)
			(stroke
				(width 0.1)
				(type default)
			)
			(layer "B.Fab")
		)
		(fp_line
			(start 0.12065 0.2794)
			(end 0.12065 0.3048)
			(stroke
				(width 0.1)
				(type default)
			)
			(layer "B.Fab")
		)
		(fp_line
			(start 0.12065 -0.2794)
			(end -0.12065 -0.2794)
			(stroke
				(width 0.1)
				(type default)
			)
			(layer "B.Fab")
		)
		(fp_line
			(start 0.12065 -0.305054)
			(end 0.12065 -0.2794)
			(stroke
				(width 0.1)
				(type default)
			)
			(layer "B.Fab")
		)
		(fp_line
			(start -0.120396 0.3048)
			(end -0.120396 0.2794)
			(stroke
				(width 0.1)
				(type default)
			)
			(layer "B.Fab")
		)
		(fp_line
			(start -0.120396 0.2794)
			(end 0.12065 0.2794)
			(stroke
				(width 0.1)
				(type default)
			)
			(layer "B.Fab")
		)
		(fp_line
			(start -0.12065 -0.2794)
			(end -0.12065 -0.3048)
			(stroke
				(width 0.1)
				(type default)
			)
			(layer "B.Fab")
		)
		(fp_line
			(start -0.12065 -0.3048)
			(end -0.67945 -0.3048)
			(stroke
				(width 0.1)
				(type default)
			)
			(layer "B.Fab")
		)
		(fp_line
			(start -0.67945 0.3048)
			(end -0.120396 0.3048)
			(stroke
				(width 0.1)
				(type default)
			)
			(layer "B.Fab")
		)
		(fp_line
			(start -0.67945 -0.3048)
			(end -0.67945 0.3048)
			(stroke
				(width 0.1)
				(type default)
			)
			(layer "B.Fab")
		)
		(pad "1" smd circle
			(at 0.40005 0)
			(size 0 0)
			(layers "B.Cu" "B.Mask" "B.Paste")
			(net "UART_BMC_5_RXD_BUF_R")
		)
		(pad "2" smd circle
			(at -0.40005 0)
			(size 0 0)
			(layers "B.Cu" "B.Mask" "B.Paste")
			(net "UART_BMC_5_RXD_BUF1")
		)
	)
	(footprint ""
		(layer "B.Cu")
		(at 62.23 -21.082 -90)
		(property "Reference" "U36"
			(at 0.0254 -1.87833 270)
			(unlocked yes)
			(layer "B.SilkS")
			(effects
				(font
					(size 0.7874 0.5842)
					(thickness 0.1524)
				)
				(justify left mirror)
			)
		)
		(property "Value" ""
			(at 0 0 90)
			(layer "B.Fab")
			(effects
				(font
					(size 1.27 1.27)
				)
				(justify mirror)
			)
		)
		(duplicate_pad_numbers_are_jumpers no)
		(fp_line
			(start -1.3462 1.1938)
			(end -1.3462 -1.1938)
			(stroke
				(width 0.1524)
				(type default)
			)
			(layer "B.SilkS")
		)
		(fp_line
			(start 1.3462 1.1938)
			(end -1.3462 1.1938)
			(stroke
				(width 0.1524)
				(type default)
			)
			(layer "B.SilkS")
		)
		(fp_line
			(start -1.3462 -1.1938)
			(end 1.3462 -1.1938)
			(stroke
				(width 0.1524)
				(type default)
			)
			(layer "B.SilkS")
		)
		(fp_line
			(start 1.3462 -1.1938)
			(end 1.3462 1.1684)
			(stroke
				(width 0.1524)
				(type default)
			)
			(layer "B.SilkS")
		)
		(fp_poly
			(pts
				(xy 1.447038 -0.760476) (xy 2.052066 -0.457962) (xy 2.052066 -1.06299)
			)
			(stroke
				(width 0)
				(type default)
			)
			(fill yes)
			(layer "B.SilkS")
		)
		(fp_line
			(start -0.674878 1.124966)
			(end -0.674878 -1.124966)
			(stroke
				(width 0.1)
				(type default)
			)
			(layer "B.Fab")
		)
		(fp_line
			(start 0.674878 1.124966)
			(end -0.674878 1.124966)
			(stroke
				(width 0.1)
				(type default)
			)
			(layer "B.Fab")
		)
		(fp_line
			(start -0.674878 -1.124966)
			(end 0.674878 -1.124966)
			(stroke
				(width 0.1)
				(type default)
			)
			(layer "B.Fab")
		)
		(fp_line
			(start 0.674878 -1.124966)
			(end 0.674878 1.124966)
			(stroke
				(width 0.1)
				(type default)
			)
			(layer "B.Fab")
		)
		(fp_poly
			(pts
				(xy 1.447038 -0.760476) (xy 2.052066 -0.457962) (xy 2.052066 -1.06299)
			)
			(stroke
				(width 0)
				(type default)
			)
			(fill yes)
			(layer "B.Fab")
		)
		(pad "1" smd rect
			(at 0.899922 -0.750062 90)
			(size 0.6096 0.6096)
			(layers "B.Cu" "B.Mask" "B.Paste")
			(net "DEBUG_PORT_PRSNT")
		)
		(pad "2" smd rect
			(at 0.899922 0)
			(size 0.4064 0.6096)
			(layers "B.Cu" "B.Mask" "B.Paste")
			(net "DEBUG_PORT_UART_RX")
		)
		(pad "3" smd rect
			(at 0.899922 0.750062 90)
			(size 0.6096 0.6096)
			(layers "B.Cu" "B.Mask" "B.Paste")
			(net "GND")
		)
		(pad "4" smd rect
			(at -0.899922 0.750062 90)
			(size 0.6096 0.6096)
			(layers "B.Cu" "B.Mask" "B.Paste")
			(net "SPA_SIN_SW_DBG")
		)
		(pad "5" smd rect
			(at -0.899922 -0.750062 90)
			(size 0.6096 0.6096)
			(layers "B.Cu" "B.Mask" "B.Paste")
			(net "P3V3_AUX")
		)
	)
	(footprint ""
		(layer "B.Cu")
		(at 61.423804 -34.637726 -90)
		(property "Reference" "R237"
			(at 0 0 90)
			(layer "B.SilkS")
			(hide yes)
			(effects
				(font
					(size 1.27 1.27)
				)
				(justify mirror)
			)
		)
		(property "Value" ""
			(at 0 0 90)
			(layer "B.Fab")
			(effects
				(font
					(size 1.27 1.27)
				)
				(justify mirror)
			)
		)
		(duplicate_pad_numbers_are_jumpers no)
		(fp_line
			(start -0.7874 0.4064)
			(end 0.7874 0.4064)
			(stroke
				(width 0.1524)
				(type default)
			)
			(layer "B.SilkS")
		)
		(fp_line
			(start 0.7874 0.4064)
			(end 0.7874 -0.4064)
			(stroke
				(width 0.1524)
				(type default)
			)
			(layer "B.SilkS")
		)
		(fp_line
			(start -0.7874 -0.4064)
			(end -0.7874 0.4064)
			(stroke
				(width 0.1524)
				(type default)
			)
			(layer "B.SilkS")
		)
		(fp_line
			(start 0.7874 -0.4064)
			(end -0.7874 -0.4064)
			(stroke
				(width 0.1524)
				(type default)
			)
			(layer "B.SilkS")
		)
		(fp_line
			(start -0.67945 0.3048)
			(end -0.120396 0.3048)
			(stroke
				(width 0.1)
				(type default)
			)
			(layer "B.Fab")
		)
		(fp_line
			(start -0.120396 0.3048)
			(end -0.120396 0.2794)
			(stroke
				(width 0.1)
				(type default)
			)
			(layer "B.Fab")
		)
		(fp_line
			(start 0.12065 0.3048)
			(end 0.67945 0.3048)
			(stroke
				(width 0.1)
				(type default)
			)
			(layer "B.Fab")
		)
		(fp_line
			(start 0.67945 0.3048)
			(end 0.67945 -0.305054)
			(stroke
				(width 0.1)
				(type default)
			)
			(layer "B.Fab")
		)
		(fp_line
			(start -0.120396 0.2794)
			(end 0.12065 0.2794)
			(stroke
				(width 0.1)
				(type default)
			)
			(layer "B.Fab")
		)
		(fp_line
			(start 0.12065 0.2794)
			(end 0.12065 0.3048)
			(stroke
				(width 0.1)
				(type default)
			)
			(layer "B.Fab")
		)
		(fp_line
			(start -0.12065 -0.2794)
			(end -0.12065 -0.3048)
			(stroke
				(width 0.1)
				(type default)
			)
			(layer "B.Fab")
		)
		(fp_line
			(start 0.12065 -0.2794)
			(end -0.12065 -0.2794)
			(stroke
				(width 0.1)
				(type default)
			)
			(layer "B.Fab")
		)
		(fp_line
			(start -0.67945 -0.3048)
			(end -0.67945 0.3048)
			(stroke
				(width 0.1)
				(type default)
			)
			(layer "B.Fab")
		)
		(fp_line
			(start -0.12065 -0.3048)
			(end -0.67945 -0.3048)
			(stroke
				(width 0.1)
				(type default)
			)
			(layer "B.Fab")
		)
		(fp_line
			(start 0.12065 -0.305054)
			(end 0.12065 -0.2794)
			(stroke
				(width 0.1)
				(type default)
			)
			(layer "B.Fab")
		)
		(fp_line
			(start 0.67945 -0.305054)
			(end 0.12065 -0.305054)
			(stroke
				(width 0.1)
				(type default)
			)
			(layer "B.Fab")
		)
		(pad "1" smd circle
			(at 0.40005 0 90)
			(size 0 0)
			(layers "B.Cu" "B.Mask" "B.Paste")
			(net "FM_DBP_BMC_PRDY_N")
		)
		(pad "2" smd circle
			(at -0.40005 0 90)
			(size 0 0)
			(layers "B.Cu" "B.Mask" "B.Paste")
			(net "FM_DBP_BMC_PRDY_R_N")
		)
	)
	(footprint ""
		(layer "B.Cu")
		(at 56.261 -16.764 90)
		(property "Reference" "R707"
			(at 0 0 90)
			(layer "B.SilkS")
			(hide yes)
			(effects
				(font
					(size 1.27 1.27)
				)
				(justify mirror)
			)
		)
		(property "Value" ""
			(at 0 0 90)
			(layer "B.Fab")
			(effects
				(font
					(size 1.27 1.27)
				)
				(justify mirror)
			)
		)
		(duplicate_pad_numbers_are_jumpers no)
		(fp_line
			(start 0.7874 -0.4064)
			(end -0.7874 -0.4064)
			(stroke
				(width 0.1524)
				(type default)
			)
			(layer "B.SilkS")
		)
		(fp_line
			(start -0.7874 -0.4064)
			(end -0.7874 0.4064)
			(stroke
				(width 0.1524)
				(type default)
			)
			(layer "B.SilkS")
		)
		(fp_line
			(start 0.7874 0.4064)
			(end 0.7874 -0.4064)
			(stroke
				(width 0.1524)
				(type default)
			)
			(layer "B.SilkS")
		)
		(fp_line
			(start -0.7874 0.4064)
			(end 0.7874 0.4064)
			(stroke
				(width 0.1524)
				(type default)
			)
			(layer "B.SilkS")
		)
		(fp_line
			(start 0.67945 -0.305054)
			(end 0.12065 -0.305054)
			(stroke
				(width 0.1)
				(type default)
			)
			(layer "B.Fab")
		)
		(fp_line
			(start 0.12065 -0.305054)
			(end 0.12065 -0.2794)
			(stroke
				(width 0.1)
				(type default)
			)
			(layer "B.Fab")
		)
		(fp_line
			(start -0.12065 -0.3048)
			(end -0.67945 -0.3048)
			(stroke
				(width 0.1)
				(type default)
			)
			(layer "B.Fab")
		)
		(fp_line
			(start -0.67945 -0.3048)
			(end -0.67945 0.3048)
			(stroke
				(width 0.1)
				(type default)
			)
			(layer "B.Fab")
		)
		(fp_line
			(start 0.12065 -0.2794)
			(end -0.12065 -0.2794)
			(stroke
				(width 0.1)
				(type default)
			)
			(layer "B.Fab")
		)
		(fp_line
			(start -0.12065 -0.2794)
			(end -0.12065 -0.3048)
			(stroke
				(width 0.1)
				(type default)
			)
			(layer "B.Fab")
		)
		(fp_line
			(start 0.12065 0.2794)
			(end 0.12065 0.3048)
			(stroke
				(width 0.1)
				(type default)
			)
			(layer "B.Fab")
		)
		(fp_line
			(start -0.120396 0.2794)
			(end 0.12065 0.2794)
			(stroke
				(width 0.1)
				(type default)
			)
			(layer "B.Fab")
		)
		(fp_line
			(start 0.67945 0.3048)
			(end 0.67945 -0.305054)
			(stroke
				(width 0.1)
				(type default)
			)
			(layer "B.Fab")
		)
		(fp_line
			(start 0.12065 0.3048)
			(end 0.67945 0.3048)
			(stroke
				(width 0.1)
				(type default)
			)
			(layer "B.Fab")
		)
		(fp_line
			(start -0.120396 0.3048)
			(end -0.120396 0.2794)
			(stroke
				(width 0.1)
				(type default)
			)
			(layer "B.Fab")
		)
		(fp_line
			(start -0.67945 0.3048)
			(end -0.120396 0.3048)
			(stroke
				(width 0.1)
				(type default)
			)
			(layer "B.Fab")
		)
		(pad "1" smd circle
			(at 0.40005 0 270)
			(size 0 0)
			(layers "B.Cu" "B.Mask" "B.Paste")
			(net "FM_DEBUG_PORT_R_PRSNT_N")
		)
		(pad "2" smd circle
			(at -0.40005 0 270)
			(size 0 0)
			(layers "B.Cu" "B.Mask" "B.Paste")
			(net "FM_DEBUG_PORT_PRSNT_N")
		)
	)
	(footprint ""
		(layer "B.Cu")
		(at 22.5552 -106.5022 -90)
		(property "Reference" "R828"
			(at 0 0 90)
			(layer "B.SilkS")
			(hide yes)
			(effects
				(font
					(size 1.27 1.27)
				)
				(justify mirror)
			)
		)
		(property "Value" ""
			(at 0 0 90)
			(layer "B.Fab")
			(effects
				(font
					(size 1.27 1.27)
				)
				(justify mirror)
			)
		)
		(duplicate_pad_numbers_are_jumpers no)
		(fp_line
			(start -0.7874 0.4064)
			(end 0.7874 0.4064)
			(stroke
				(width 0.1524)
				(type default)
			)
			(layer "B.SilkS")
		)
		(fp_line
			(start 0.7874 0.4064)
			(end 0.7874 -0.4064)
			(stroke
				(width 0.1524)
				(type default)
			)
			(layer "B.SilkS")
		)
		(fp_line
			(start -0.7874 -0.4064)
			(end -0.7874 0.4064)
			(stroke
				(width 0.1524)
				(type default)
			)
			(layer "B.SilkS")
		)
		(fp_line
			(start 0.7874 -0.4064)
			(end -0.7874 -0.4064)
			(stroke
				(width 0.1524)
				(type default)
			)
			(layer "B.SilkS")
		)
		(fp_line
			(start -0.67945 0.3048)
			(end -0.120396 0.3048)
			(stroke
				(width 0.1)
				(type default)
			)
			(layer "B.Fab")
		)
		(fp_line
			(start -0.120396 0.3048)
			(end -0.120396 0.2794)
			(stroke
				(width 0.1)
				(type default)
			)
			(layer "B.Fab")
		)
		(fp_line
			(start 0.12065 0.3048)
			(end 0.67945 0.3048)
			(stroke
				(width 0.1)
				(type default)
			)
			(layer "B.Fab")
		)
		(fp_line
			(start 0.67945 0.3048)
			(end 0.67945 -0.305054)
			(stroke
				(width 0.1)
				(type default)
			)
			(layer "B.Fab")
		)
		(fp_line
			(start -0.120396 0.2794)
			(end 0.12065 0.2794)
			(stroke
				(width 0.1)
				(type default)
			)
			(layer "B.Fab")
		)
		(fp_line
			(start 0.12065 0.2794)
			(end 0.12065 0.3048)
			(stroke
				(width 0.1)
				(type default)
			)
			(layer "B.Fab")
		)
		(fp_line
			(start -0.12065 -0.2794)
			(end -0.12065 -0.3048)
			(stroke
				(width 0.1)
				(type default)
			)
			(layer "B.Fab")
		)
		(fp_line
			(start 0.12065 -0.2794)
			(end -0.12065 -0.2794)
			(stroke
				(width 0.1)
				(type default)
			)
			(layer "B.Fab")
		)
		(fp_line
			(start -0.67945 -0.3048)
			(end -0.67945 0.3048)
			(stroke
				(width 0.1)
				(type default)
			)
			(layer "B.Fab")
		)
		(fp_line
			(start -0.12065 -0.3048)
			(end -0.67945 -0.3048)
			(stroke
				(width 0.1)
				(type default)
			)
			(layer "B.Fab")
		)
		(fp_line
			(start 0.12065 -0.305054)
			(end 0.12065 -0.2794)
			(stroke
				(width 0.1)
				(type default)
			)
			(layer "B.Fab")
		)
		(fp_line
			(start 0.67945 -0.305054)
			(end 0.12065 -0.305054)
			(stroke
				(width 0.1)
				(type default)
			)
			(layer "B.Fab")
		)
		(pad "1" smd circle
			(at 0.40005 0 90)
			(size 0 0)
			(layers "B.Cu" "B.Mask" "B.Paste")
			(net "P3V3_AUX")
		)
		(pad "2" smd circle
			(at -0.40005 0 90)
			(size 0 0)
			(layers "B.Cu" "B.Mask" "B.Paste")
			(net "RST_ROT_CPU_N")
		)
	)
	(footprint ""
		(layer "B.Cu")
		(at 15.24 -26.67 -90)
		(property "Reference" "C274"
			(at 0 0 90)
			(layer "B.SilkS")
			(hide yes)
			(effects
				(font
					(size 1.27 1.27)
				)
				(justify mirror)
			)
		)
		(property "Value" ""
			(at 0 0 90)
			(layer "B.Fab")
			(effects
				(font
					(size 1.27 1.27)
				)
				(justify mirror)
			)
		)
		(duplicate_pad_numbers_are_jumpers no)
		(fp_line
			(start -0.7874 0.4064)
			(end 0.7874 0.4064)
			(stroke
				(width 0.1524)
				(type default)
			)
			(layer "B.SilkS")
		)
		(fp_line
			(start 0.7874 0.4064)
			(end 0.7874 -0.4064)
			(stroke
				(width 0.1524)
				(type default)
			)
			(layer "B.SilkS")
		)
		(fp_line
			(start -0.7874 -0.4064)
			(end -0.7874 0.4064)
			(stroke
				(width 0.1524)
				(type default)
			)
			(layer "B.SilkS")
		)
		(fp_line
			(start 0.7874 -0.4064)
			(end -0.7874 -0.4064)
			(stroke
				(width 0.1524)
				(type default)
			)
			(layer "B.SilkS")
		)
		(fp_line
			(start -0.67945 0.3048)
			(end -0.120396 0.3048)
			(stroke
				(width 0.1)
				(type default)
			)
			(layer "B.Fab")
		)
		(fp_line
			(start -0.120396 0.3048)
			(end -0.120396 0.2794)
			(stroke
				(width 0.1)
				(type default)
			)
			(layer "B.Fab")
		)
		(fp_line
			(start 0.12065 0.3048)
			(end 0.67945 0.3048)
			(stroke
				(width 0.1)
				(type default)
			)
			(layer "B.Fab")
		)
		(fp_line
			(start 0.67945 0.3048)
			(end 0.67945 -0.305054)
			(stroke
				(width 0.1)
				(type default)
			)
			(layer "B.Fab")
		)
		(fp_line
			(start -0.120396 0.2794)
			(end 0.12065 0.2794)
			(stroke
				(width 0.1)
				(type default)
			)
			(layer "B.Fab")
		)
		(fp_line
			(start 0.12065 0.2794)
			(end 0.12065 0.3048)
			(stroke
				(width 0.1)
				(type default)
			)
			(layer "B.Fab")
		)
		(fp_line
			(start -0.12065 -0.2794)
			(end -0.12065 -0.3048)
			(stroke
				(width 0.1)
				(type default)
			)
			(layer "B.Fab")
		)
		(fp_line
			(start 0.12065 -0.2794)
			(end -0.12065 -0.2794)
			(stroke
				(width 0.1)
				(type default)
			)
			(layer "B.Fab")
		)
		(fp_line
			(start -0.67945 -0.3048)
			(end -0.67945 0.3048)
			(stroke
				(width 0.1)
				(type default)
			)
			(layer "B.Fab")
		)
		(fp_line
			(start -0.12065 -0.3048)
			(end -0.67945 -0.3048)
			(stroke
				(width 0.1)
				(type default)
			)
			(layer "B.Fab")
		)
		(fp_line
			(start 0.12065 -0.305054)
			(end 0.12065 -0.2794)
			(stroke
				(width 0.1)
				(type default)
			)
			(layer "B.Fab")
		)
		(fp_line
			(start 0.67945 -0.305054)
			(end 0.12065 -0.305054)
			(stroke
				(width 0.1)
				(type default)
			)
			(layer "B.Fab")
		)
		(pad "1" smd circle
			(at 0.40005 0 90)
			(size 0 0)
			(layers "B.Cu" "B.Mask" "B.Paste")
			(net "P3V3_AUX")
		)
		(pad "2" smd circle
			(at -0.40005 0 90)
			(size 0 0)
			(layers "B.Cu" "B.Mask" "B.Paste")
			(net "GND")
		)
	)
	(footprint ""
		(layer "B.Cu")
		(at 85.29955 -41.379394 180)
		(property "Reference" "R364"
			(at 0 0 0)
			(layer "B.SilkS")
			(hide yes)
			(effects
				(font
					(size 1.27 1.27)
				)
				(justify mirror)
			)
		)
		(property "Value" ""
			(at 0 0 0)
			(layer "B.Fab")
			(effects
				(font
					(size 1.27 1.27)
				)
				(justify mirror)
			)
		)
		(duplicate_pad_numbers_are_jumpers no)
		(fp_line
			(start 0.7874 0.4064)
			(end 0.7874 -0.4064)
			(stroke
				(width 0.1524)
				(type default)
			)
			(layer "B.SilkS")
		)
		(fp_line
			(start 0.7874 -0.4064)
			(end -0.7874 -0.4064)
			(stroke
				(width 0.1524)
				(type default)
			)
			(layer "B.SilkS")
		)
		(fp_line
			(start -0.7874 0.4064)
			(end 0.7874 0.4064)
			(stroke
				(width 0.1524)
				(type default)
			)
			(layer "B.SilkS")
		)
		(fp_line
			(start -0.7874 -0.4064)
			(end -0.7874 0.4064)
			(stroke
				(width 0.1524)
				(type default)
			)
			(layer "B.SilkS")
		)
		(fp_line
			(start 0.67945 0.3048)
			(end 0.67945 -0.305054)
			(stroke
				(width 0.1)
				(type default)
			)
			(layer "B.Fab")
		)
		(fp_line
			(start 0.67945 -0.305054)
			(end 0.12065 -0.305054)
			(stroke
				(width 0.1)
				(type default)
			)
			(layer "B.Fab")
		)
		(fp_line
			(start 0.12065 0.3048)
			(end 0.67945 0.3048)
			(stroke
				(width 0.1)
				(type default)
			)
			(layer "B.Fab")
		)
		(fp_line
			(start 0.12065 0.2794)
			(end 0.12065 0.3048)
			(stroke
				(width 0.1)
				(type default)
			)
			(layer "B.Fab")
		)
		(fp_line
			(start 0.12065 -0.2794)
			(end -0.12065 -0.2794)
			(stroke
				(width 0.1)
				(type default)
			)
			(layer "B.Fab")
		)
		(fp_line
			(start 0.12065 -0.305054)
			(end 0.12065 -0.2794)
			(stroke
				(width 0.1)
				(type default)
			)
			(layer "B.Fab")
		)
		(fp_line
			(start -0.120396 0.3048)
			(end -0.120396 0.2794)
			(stroke
				(width 0.1)
				(type default)
			)
			(layer "B.Fab")
		)
		(fp_line
			(start -0.120396 0.2794)
			(end 0.12065 0.2794)
			(stroke
				(width 0.1)
				(type default)
			)
			(layer "B.Fab")
		)
		(fp_line
			(start -0.12065 -0.2794)
			(end -0.12065 -0.3048)
			(stroke
				(width 0.1)
				(type default)
			)
			(layer "B.Fab")
		)
		(fp_line
			(start -0.12065 -0.3048)
			(end -0.67945 -0.3048)
			(stroke
				(width 0.1)
				(type default)
			)
			(layer "B.Fab")
		)
		(fp_line
			(start -0.67945 0.3048)
			(end -0.120396 0.3048)
			(stroke
				(width 0.1)
				(type default)
			)
			(layer "B.Fab")
		)
		(fp_line
			(start -0.67945 -0.3048)
			(end -0.67945 0.3048)
			(stroke
				(width 0.1)
				(type default)
			)
			(layer "B.Fab")
		)
		(pad "1" smd circle
			(at 0.40005 0)
			(size 0 0)
			(layers "B.Cu" "B.Mask" "B.Paste")
			(net "M_BMC_DDR4_MA<13>")
		)
		(pad "2" smd circle
			(at -0.40005 0)
			(size 0 0)
			(layers "B.Cu" "B.Mask" "B.Paste")
			(net "P1V2_AUX")
		)
	)
	(footprint ""
		(layer "B.Cu")
		(at 38.7223 -52.779676 -90)
		(property "Reference" "R278"
			(at 0 0 90)
			(layer "B.SilkS")
			(hide yes)
			(effects
				(font
					(size 1.27 1.27)
				)
				(justify mirror)
			)
		)
		(property "Value" ""
			(at 0 0 90)
			(layer "B.Fab")
			(effects
				(font
					(size 1.27 1.27)
				)
				(justify mirror)
			)
		)
		(duplicate_pad_numbers_are_jumpers no)
		(fp_line
			(start -0.7874 0.4064)
			(end 0.7874 0.4064)
			(stroke
				(width 0.1524)
				(type default)
			)
			(layer "B.SilkS")
		)
		(fp_line
			(start 0.7874 0.4064)
			(end 0.7874 -0.4064)
			(stroke
				(width 0.1524)
				(type default)
			)
			(layer "B.SilkS")
		)
		(fp_line
			(start -0.7874 -0.4064)
			(end -0.7874 0.4064)
			(stroke
				(width 0.1524)
				(type default)
			)
			(layer "B.SilkS")
		)
		(fp_line
			(start 0.7874 -0.4064)
			(end -0.7874 -0.4064)
			(stroke
				(width 0.1524)
				(type default)
			)
			(layer "B.SilkS")
		)
		(fp_line
			(start -0.67945 0.3048)
			(end -0.120396 0.3048)
			(stroke
				(width 0.1)
				(type default)
			)
			(layer "B.Fab")
		)
		(fp_line
			(start -0.120396 0.3048)
			(end -0.120396 0.2794)
			(stroke
				(width 0.1)
				(type default)
			)
			(layer "B.Fab")
		)
		(fp_line
			(start 0.12065 0.3048)
			(end 0.67945 0.3048)
			(stroke
				(width 0.1)
				(type default)
			)
			(layer "B.Fab")
		)
		(fp_line
			(start 0.67945 0.3048)
			(end 0.67945 -0.305054)
			(stroke
				(width 0.1)
				(type default)
			)
			(layer "B.Fab")
		)
		(fp_line
			(start -0.120396 0.2794)
			(end 0.12065 0.2794)
			(stroke
				(width 0.1)
				(type default)
			)
			(layer "B.Fab")
		)
		(fp_line
			(start 0.12065 0.2794)
			(end 0.12065 0.3048)
			(stroke
				(width 0.1)
				(type default)
			)
			(layer "B.Fab")
		)
		(fp_line
			(start -0.12065 -0.2794)
			(end -0.12065 -0.3048)
			(stroke
				(width 0.1)
				(type default)
			)
			(layer "B.Fab")
		)
		(fp_line
			(start 0.12065 -0.2794)
			(end -0.12065 -0.2794)
			(stroke
				(width 0.1)
				(type default)
			)
			(layer "B.Fab")
		)
		(fp_line
			(start -0.67945 -0.3048)
			(end -0.67945 0.3048)
			(stroke
				(width 0.1)
				(type default)
			)
			(layer "B.Fab")
		)
		(fp_line
			(start -0.12065 -0.3048)
			(end -0.67945 -0.3048)
			(stroke
				(width 0.1)
				(type default)
			)
			(layer "B.Fab")
		)
		(fp_line
			(start 0.12065 -0.305054)
			(end 0.12065 -0.2794)
			(stroke
				(width 0.1)
				(type default)
			)
			(layer "B.Fab")
		)
		(fp_line
			(start 0.67945 -0.305054)
			(end 0.12065 -0.305054)
			(stroke
				(width 0.1)
				(type default)
			)
			(layer "B.Fab")
		)
		(pad "1" smd circle
			(at 0.40005 0 90)
			(size 0 0)
			(layers "B.Cu" "B.Mask" "B.Paste")
			(net "P1V2_AUX")
		)
		(pad "2" smd circle
			(at -0.40005 0 90)
			(size 0 0)
			(layers "B.Cu" "B.Mask" "B.Paste")
			(net "P1V2_P1V0_I3C_VDDL1")
		)
	)
	(footprint ""
		(layer "B.Cu")
		(at 37.4015 -100.965)
		(property "Reference" "R467"
			(at 0 0 0)
			(layer "B.SilkS")
			(hide yes)
			(effects
				(font
					(size 1.27 1.27)
				)
				(justify mirror)
			)
		)
		(property "Value" ""
			(at 0 0 0)
			(layer "B.Fab")
			(effects
				(font
					(size 1.27 1.27)
				)
				(justify mirror)
			)
		)
		(duplicate_pad_numbers_are_jumpers no)
		(fp_line
			(start -0.7874 -0.4064)
			(end -0.7874 0.4064)
			(stroke
				(width 0.1524)
				(type default)
			)
			(layer "B.SilkS")
		)
		(fp_line
			(start -0.7874 0.4064)
			(end 0.7874 0.4064)
			(stroke
				(width 0.1524)
				(type default)
			)
			(layer "B.SilkS")
		)
		(fp_line
			(start 0.7874 -0.4064)
			(end -0.7874 -0.4064)
			(stroke
				(width 0.1524)
				(type default)
			)
			(layer "B.SilkS")
		)
		(fp_line
			(start 0.7874 0.4064)
			(end 0.7874 -0.4064)
			(stroke
				(width 0.1524)
				(type default)
			)
			(layer "B.SilkS")
		)
		(fp_line
			(start -0.67945 -0.3048)
			(end -0.67945 0.3048)
			(stroke
				(width 0.1)
				(type default)
			)
			(layer "B.Fab")
		)
		(fp_line
			(start -0.67945 0.3048)
			(end -0.120396 0.3048)
			(stroke
				(width 0.1)
				(type default)
			)
			(layer "B.Fab")
		)
		(fp_line
			(start -0.12065 -0.3048)
			(end -0.67945 -0.3048)
			(stroke
				(width 0.1)
				(type default)
			)
			(layer "B.Fab")
		)
		(fp_line
			(start -0.12065 -0.2794)
			(end -0.12065 -0.3048)
			(stroke
				(width 0.1)
				(type default)
			)
			(layer "B.Fab")
		)
		(fp_line
			(start -0.120396 0.2794)
			(end 0.12065 0.2794)
			(stroke
				(width 0.1)
				(type default)
			)
			(layer "B.Fab")
		)
		(fp_line
			(start -0.120396 0.3048)
			(end -0.120396 0.2794)
			(stroke
				(width 0.1)
				(type default)
			)
			(layer "B.Fab")
		)
		(fp_line
			(start 0.12065 -0.305054)
			(end 0.12065 -0.2794)
			(stroke
				(width 0.1)
				(type default)
			)
			(layer "B.Fab")
		)
		(fp_line
			(start 0.12065 -0.2794)
			(end -0.12065 -0.2794)
			(stroke
				(width 0.1)
				(type default)
			)
			(layer "B.Fab")
		)
		(fp_line
			(start 0.12065 0.2794)
			(end 0.12065 0.3048)
			(stroke
				(width 0.1)
				(type default)
			)
			(layer "B.Fab")
		)
		(fp_line
			(start 0.12065 0.3048)
			(end 0.67945 0.3048)
			(stroke
				(width 0.1)
				(type default)
			)
			(layer "B.Fab")
		)
		(fp_line
			(start 0.67945 -0.305054)
			(end 0.12065 -0.305054)
			(stroke
				(width 0.1)
				(type default)
			)
			(layer "B.Fab")
		)
		(fp_line
			(start 0.67945 0.3048)
			(end 0.67945 -0.305054)
			(stroke
				(width 0.1)
				(type default)
			)
			(layer "B.Fab")
		)
		(pad "1" smd circle
			(at 0.40005 0 180)
			(size 0 0)
			(layers "B.Cu" "B.Mask" "B.Paste")
			(net "PD_BIOS_MUX_EN_N")
		)
		(pad "2" smd circle
			(at -0.40005 0 180)
			(size 0 0)
			(layers "B.Cu" "B.Mask" "B.Paste")
			(net "GND")
		)
	)
	(footprint ""
		(layer "B.Cu")
		(at 68.6054 -50.292)
		(property "Reference" ""
			(at 0 0 0)
			(layer "B.SilkS")
			(hide yes)
			(effects
				(font
					(size 1.27 1.27)
				)
				(justify mirror)
			)
		)
		(property "Value" ""
			(at 0 0 0)
			(layer "B.Fab")
			(effects
				(font
					(size 1.27 1.27)
				)
				(justify mirror)
			)
		)
		(duplicate_pad_numbers_are_jumpers no)
		(pad "1" smd circle
			(at 0 0 180)
			(size 0.9906 0.9906)
			(layers "B.Cu" "B.Mask" "B.Paste")
			(net "Net_134")
		)
		(zone
			(layer "B.Cu")
			(hatch none 0.5)
			(connect_pads
				(clearance 0)
			)
			(min_thickness 0.25)
			(keepout
				(tracks not_allowed)
				(vias allowed)
				(pads allowed)
				(copperpour not_allowed)
				(footprints allowed)
			)
			(placement
				(enabled no)
				(sheetname "")
			)
			(fill
				(thermal_gap 0.5)
				(thermal_bridge_width 0.5)
				(island_removal_mode 0)
			)
			(polygon
				(pts
					(arc
						(start 70.231 -50.292)
						(mid 66.9798 -50.292)
						(end 70.231 -50.292)
					)
				)
			)
		)
	)
	(footprint ""
		(layer "B.Cu")
		(at 7.9756 -27.7368)
		(property "Reference" "U24"
			(at 0.9652 -1.80213 0)
			(unlocked yes)
			(layer "B.SilkS")
			(effects
				(font
					(size 0.7874 0.5842)
					(thickness 0.1524)
				)
				(justify left mirror)
			)
		)
		(property "Value" ""
			(at 0 0 0)
			(layer "B.Fab")
			(effects
				(font
					(size 1.27 1.27)
				)
				(justify mirror)
			)
		)
		(duplicate_pad_numbers_are_jumpers no)
		(fp_line
			(start -1.38176 -1.100074)
			(end -0.592074 -1.100074)
			(stroke
				(width 0.1524)
				(type default)
			)
			(layer "B.SilkS")
		)
		(fp_line
			(start -1.38176 1.100074)
			(end -1.38176 -1.100074)
			(stroke
				(width 0.1524)
				(type default)
			)
			(layer "B.SilkS")
		)
		(fp_line
			(start -0.592074 -1.100074)
			(end 0 -0.508)
			(stroke
				(width 0.1524)
				(type default)
			)
			(layer "B.SilkS")
		)
		(fp_line
			(start 0 -0.508)
			(end 0.592074 -1.100074)
			(stroke
				(width 0.1524)
				(type default)
			)
			(layer "B.SilkS")
		)
		(fp_line
			(start 0.592074 -1.100074)
			(end 1.38176 -1.100074)
			(stroke
				(width 0.1524)
				(type default)
			)
			(layer "B.SilkS")
		)
		(fp_line
			(start 1.38176 -1.100074)
			(end 1.38176 1.100074)
			(stroke
				(width 0.1524)
				(type default)
			)
			(layer "B.SilkS")
		)
		(fp_line
			(start 1.38176 1.100074)
			(end -1.38176 1.100074)
			(stroke
				(width 0.1524)
				(type default)
			)
			(layer "B.SilkS")
		)
		(fp_poly
			(pts
				(xy 1.9431 -0.870204) (xy 1.50241 -0.649986) (xy 1.9431 -0.429768)
			)
			(stroke
				(width 0)
				(type default)
			)
			(fill yes)
			(layer "B.SilkS")
		)
		(fp_line
			(start -0.674878 -1.100074)
			(end 0.674878 -1.100074)
			(stroke
				(width 0.1)
				(type default)
			)
			(layer "B.Fab")
		)
		(fp_line
			(start -0.674878 1.100074)
			(end -0.674878 -1.100074)
			(stroke
				(width 0.1)
				(type default)
			)
			(layer "B.Fab")
		)
		(fp_line
			(start 0.674878 -1.100074)
			(end 0.674878 1.100074)
			(stroke
				(width 0.1)
				(type default)
			)
			(layer "B.Fab")
		)
		(fp_line
			(start 0.674878 1.100074)
			(end -0.674878 1.100074)
			(stroke
				(width 0.1)
				(type default)
			)
			(layer "B.Fab")
		)
		(fp_poly
			(pts
				(xy 1.9431 -0.870204) (xy 1.50241 -0.649986) (xy 1.9431 -0.429768)
			)
			(stroke
				(width 0)
				(type default)
			)
			(fill yes)
			(layer "B.Fab")
		)
		(pad "1" smd rect
			(at 0.94996 -0.649986 270)
			(size 0.4318 0.6096)
			(layers "B.Cu" "B.Mask" "B.Paste")
			(net "UART_BMC_5_TXD_BUF1_R")
		)
		(pad "2" smd rect
			(at 0.94996 0 270)
			(size 0.4318 0.6096)
			(layers "B.Cu" "B.Mask" "B.Paste")
			(net "GND")
		)
		(pad "3" smd rect
			(at 0.94996 0.649986 270)
			(size 0.4318 0.6096)
			(layers "B.Cu" "B.Mask" "B.Paste")
			(net "UART_BMC_5_RXD_BUF")
		)
		(pad "4" smd rect
			(at -0.94996 0.649986 270)
			(size 0.4318 0.6096)
			(layers "B.Cu" "B.Mask" "B.Paste")
			(net "UART_BMC_5_RXD_BUF_R")
		)
		(pad "5" smd rect
			(at -0.94996 0 270)
			(size 0.4318 0.6096)
			(layers "B.Cu" "B.Mask" "B.Paste")
			(net "P3V3_AUX")
		)
		(pad "6" smd rect
			(at -0.94996 -0.649986 270)
			(size 0.4318 0.6096)
			(layers "B.Cu" "B.Mask" "B.Paste")
			(net "UART_BMC_5_TXD_BUF")
		)
	)
	(footprint ""
		(layer "B.Cu")
		(at 58.890662 -71.082662)
		(property "Reference" "C314"
			(at 0 0 0)
			(layer "B.SilkS")
			(hide yes)
			(effects
				(font
					(size 1.27 1.27)
				)
				(justify mirror)
			)
		)
		(property "Value" ""
			(at 0 0 0)
			(layer "B.Fab")
			(effects
				(font
					(size 1.27 1.27)
				)
				(justify mirror)
			)
		)
		(duplicate_pad_numbers_are_jumpers no)
		(fp_line
			(start -0.7874 -0.4064)
			(end -0.7874 0.4064)
			(stroke
				(width 0.1524)
				(type default)
			)
			(layer "B.SilkS")
		)
		(fp_line
			(start -0.7874 0.4064)
			(end 0.7874 0.4064)
			(stroke
				(width 0.1524)
				(type default)
			)
			(layer "B.SilkS")
		)
		(fp_line
			(start 0.7874 -0.4064)
			(end -0.7874 -0.4064)
			(stroke
				(width 0.1524)
				(type default)
			)
			(layer "B.SilkS")
		)
		(fp_line
			(start 0.7874 0.4064)
			(end 0.7874 -0.4064)
			(stroke
				(width 0.1524)
				(type default)
			)
			(layer "B.SilkS")
		)
		(fp_line
			(start -0.67945 -0.3048)
			(end -0.67945 0.3048)
			(stroke
				(width 0.1)
				(type default)
			)
			(layer "B.Fab")
		)
		(fp_line
			(start -0.67945 0.3048)
			(end -0.120396 0.3048)
			(stroke
				(width 0.1)
				(type default)
			)
			(layer "B.Fab")
		)
		(fp_line
			(start -0.12065 -0.3048)
			(end -0.67945 -0.3048)
			(stroke
				(width 0.1)
				(type default)
			)
			(layer "B.Fab")
		)
		(fp_line
			(start -0.12065 -0.2794)
			(end -0.12065 -0.3048)
			(stroke
				(width 0.1)
				(type default)
			)
			(layer "B.Fab")
		)
		(fp_line
			(start -0.120396 0.2794)
			(end 0.12065 0.2794)
			(stroke
				(width 0.1)
				(type default)
			)
			(layer "B.Fab")
		)
		(fp_line
			(start -0.120396 0.3048)
			(end -0.120396 0.2794)
			(stroke
				(width 0.1)
				(type default)
			)
			(layer "B.Fab")
		)
		(fp_line
			(start 0.12065 -0.305054)
			(end 0.12065 -0.2794)
			(stroke
				(width 0.1)
				(type default)
			)
			(layer "B.Fab")
		)
		(fp_line
			(start 0.12065 -0.2794)
			(end -0.12065 -0.2794)
			(stroke
				(width 0.1)
				(type default)
			)
			(layer "B.Fab")
		)
		(fp_line
			(start 0.12065 0.2794)
			(end 0.12065 0.3048)
			(stroke
				(width 0.1)
				(type default)
			)
			(layer "B.Fab")
		)
		(fp_line
			(start 0.12065 0.3048)
			(end 0.67945 0.3048)
			(stroke
				(width 0.1)
				(type default)
			)
			(layer "B.Fab")
		)
		(fp_line
			(start 0.67945 -0.305054)
			(end 0.12065 -0.305054)
			(stroke
				(width 0.1)
				(type default)
			)
			(layer "B.Fab")
		)
		(fp_line
			(start 0.67945 0.3048)
			(end 0.67945 -0.305054)
			(stroke
				(width 0.1)
				(type default)
			)
			(layer "B.Fab")
		)
		(pad "1" smd circle
			(at 0.40005 0 180)
			(size 0 0)
			(layers "B.Cu" "B.Mask" "B.Paste")
			(net "PGPPA_BMC_AUX_SENSOR")
		)
		(pad "2" smd circle
			(at -0.40005 0 180)
			(size 0 0)
			(layers "B.Cu" "B.Mask" "B.Paste")
			(net "GND")
		)
	)
	(footprint ""
		(layer "B.Cu")
		(at 23.85949 -97.187004)
		(property "Reference" "C188"
			(at 0 0 0)
			(layer "B.SilkS")
			(hide yes)
			(effects
				(font
					(size 1.27 1.27)
				)
				(justify mirror)
			)
		)
		(property "Value" ""
			(at 0 0 0)
			(layer "B.Fab")
			(effects
				(font
					(size 1.27 1.27)
				)
				(justify mirror)
			)
		)
		(duplicate_pad_numbers_are_jumpers no)
		(fp_line
			(start -0.69215 -0.2921)
			(end -0.69215 0.2921)
			(stroke
				(width 0.1524)
				(type default)
			)
			(layer "B.SilkS")
		)
		(fp_line
			(start -0.69215 0.2921)
			(end 0.69215 0.2921)
			(stroke
				(width 0.1524)
				(type default)
			)
			(layer "B.SilkS")
		)
		(fp_line
			(start 0.69215 -0.2921)
			(end -0.69215 -0.2921)
			(stroke
				(width 0.1524)
				(type default)
			)
			(layer "B.SilkS")
		)
		(fp_line
			(start 0.69215 0.2921)
			(end 0.69215 -0.2921)
			(stroke
				(width 0.1524)
				(type default)
			)
			(layer "B.SilkS")
		)
		(fp_line
			(start -0.51435 -0.2794)
			(end -0.51435 0.2794)
			(stroke
				(width 0.1)
				(type default)
			)
			(layer "B.Fab")
		)
		(fp_line
			(start -0.51435 0.2794)
			(end 0.51435 0.2794)
			(stroke
				(width 0.1)
				(type default)
			)
			(layer "B.Fab")
		)
		(fp_line
			(start 0.51435 -0.2794)
			(end -0.51435 -0.2794)
			(stroke
				(width 0.1)
				(type default)
			)
			(layer "B.Fab")
		)
		(fp_line
			(start 0.51435 0.2794)
			(end 0.51435 -0.2794)
			(stroke
				(width 0.1)
				(type default)
			)
			(layer "B.Fab")
		)
		(pad "1" smd circle
			(at 0.40005 0 180)
			(size 0 0)
			(layers "B.Cu" "B.Mask" "B.Paste")
			(net "VCCIO2")
		)
		(pad "2" smd circle
			(at -0.40005 0 180)
			(size 0 0)
			(layers "B.Cu" "B.Mask" "B.Paste")
			(net "GND")
		)
		(zone
			(layer "B.Cu")
			(hatch none 0.5)
			(connect_pads
				(clearance 0)
			)
			(min_thickness 0.25)
			(keepout
				(tracks not_allowed)
				(vias allowed)
				(pads allowed)
				(copperpour not_allowed)
				(footprints allowed)
			)
			(placement
				(enabled no)
				(sheetname "")
			)
			(fill
				(thermal_gap 0.5)
				(thermal_bridge_width 0.5)
				(island_removal_mode 0)
			)
			(polygon
				(pts
					(xy 24.04999 -97.099374) (xy 23.95855 -97.041208) (xy 23.75916 -97.041208) (xy 23.66899 -97.099374)
					(xy 23.66899 -97.274634) (xy 23.75916 -97.333054) (xy 23.95855 -97.333054) (xy 24.04999 -97.274888)
				)
			)
		)
	)
	(footprint ""
		(layer "B.Cu")
		(at 28.575 -32.385 90)
		(property "Reference" "C205"
			(at 0 0 90)
			(layer "B.SilkS")
			(hide yes)
			(effects
				(font
					(size 1.27 1.27)
				)
				(justify mirror)
			)
		)
		(property "Value" ""
			(at 0 0 90)
			(layer "B.Fab")
			(effects
				(font
					(size 1.27 1.27)
				)
				(justify mirror)
			)
		)
		(duplicate_pad_numbers_are_jumpers no)
		(fp_line
			(start 0.7874 -0.4064)
			(end -0.7874 -0.4064)
			(stroke
				(width 0.1524)
				(type default)
			)
			(layer "B.SilkS")
		)
		(fp_line
			(start -0.7874 -0.4064)
			(end -0.7874 0.4064)
			(stroke
				(width 0.1524)
				(type default)
			)
			(layer "B.SilkS")
		)
		(fp_line
			(start 0.7874 0.4064)
			(end 0.7874 -0.4064)
			(stroke
				(width 0.1524)
				(type default)
			)
			(layer "B.SilkS")
		)
		(fp_line
			(start -0.7874 0.4064)
			(end 0.7874 0.4064)
			(stroke
				(width 0.1524)
				(type default)
			)
			(layer "B.SilkS")
		)
		(fp_line
			(start 0.67945 -0.305054)
			(end 0.12065 -0.305054)
			(stroke
				(width 0.1)
				(type default)
			)
			(layer "B.Fab")
		)
		(fp_line
			(start 0.12065 -0.305054)
			(end 0.12065 -0.2794)
			(stroke
				(width 0.1)
				(type default)
			)
			(layer "B.Fab")
		)
		(fp_line
			(start -0.12065 -0.3048)
			(end -0.67945 -0.3048)
			(stroke
				(width 0.1)
				(type default)
			)
			(layer "B.Fab")
		)
		(fp_line
			(start -0.67945 -0.3048)
			(end -0.67945 0.3048)
			(stroke
				(width 0.1)
				(type default)
			)
			(layer "B.Fab")
		)
		(fp_line
			(start 0.12065 -0.2794)
			(end -0.12065 -0.2794)
			(stroke
				(width 0.1)
				(type default)
			)
			(layer "B.Fab")
		)
		(fp_line
			(start -0.12065 -0.2794)
			(end -0.12065 -0.3048)
			(stroke
				(width 0.1)
				(type default)
			)
			(layer "B.Fab")
		)
		(fp_line
			(start 0.12065 0.2794)
			(end 0.12065 0.3048)
			(stroke
				(width 0.1)
				(type default)
			)
			(layer "B.Fab")
		)
		(fp_line
			(start -0.120396 0.2794)
			(end 0.12065 0.2794)
			(stroke
				(width 0.1)
				(type default)
			)
			(layer "B.Fab")
		)
		(fp_line
			(start 0.67945 0.3048)
			(end 0.67945 -0.305054)
			(stroke
				(width 0.1)
				(type default)
			)
			(layer "B.Fab")
		)
		(fp_line
			(start 0.12065 0.3048)
			(end 0.67945 0.3048)
			(stroke
				(width 0.1)
				(type default)
			)
			(layer "B.Fab")
		)
		(fp_line
			(start -0.120396 0.3048)
			(end -0.120396 0.2794)
			(stroke
				(width 0.1)
				(type default)
			)
			(layer "B.Fab")
		)
		(fp_line
			(start -0.67945 0.3048)
			(end -0.120396 0.3048)
			(stroke
				(width 0.1)
				(type default)
			)
			(layer "B.Fab")
		)
		(pad "1" smd circle
			(at 0.40005 0 270)
			(size 0 0)
			(layers "B.Cu" "B.Mask" "B.Paste")
			(net "V_DACR")
		)
		(pad "2" smd circle
			(at -0.40005 0 270)
			(size 0 0)
			(layers "B.Cu" "B.Mask" "B.Paste")
			(net "GND")
		)
	)
	(footprint ""
		(layer "B.Cu")
		(at 53.291994 -69.397372 -90)
		(property "Reference" "C303"
			(at 0 0 90)
			(layer "B.SilkS")
			(hide yes)
			(effects
				(font
					(size 1.27 1.27)
				)
				(justify mirror)
			)
		)
		(property "Value" ""
			(at 0 0 90)
			(layer "B.Fab")
			(effects
				(font
					(size 1.27 1.27)
				)
				(justify mirror)
			)
		)
		(duplicate_pad_numbers_are_jumpers no)
		(fp_line
			(start -0.7874 0.4064)
			(end 0.7874 0.4064)
			(stroke
				(width 0.1524)
				(type default)
			)
			(layer "B.SilkS")
		)
		(fp_line
			(start 0.7874 0.4064)
			(end 0.7874 -0.4064)
			(stroke
				(width 0.1524)
				(type default)
			)
			(layer "B.SilkS")
		)
		(fp_line
			(start -0.7874 -0.4064)
			(end -0.7874 0.4064)
			(stroke
				(width 0.1524)
				(type default)
			)
			(layer "B.SilkS")
		)
		(fp_line
			(start 0.7874 -0.4064)
			(end -0.7874 -0.4064)
			(stroke
				(width 0.1524)
				(type default)
			)
			(layer "B.SilkS")
		)
		(fp_line
			(start -0.67945 0.3048)
			(end -0.120396 0.3048)
			(stroke
				(width 0.1)
				(type default)
			)
			(layer "B.Fab")
		)
		(fp_line
			(start -0.120396 0.3048)
			(end -0.120396 0.2794)
			(stroke
				(width 0.1)
				(type default)
			)
			(layer "B.Fab")
		)
		(fp_line
			(start 0.12065 0.3048)
			(end 0.67945 0.3048)
			(stroke
				(width 0.1)
				(type default)
			)
			(layer "B.Fab")
		)
		(fp_line
			(start 0.67945 0.3048)
			(end 0.67945 -0.305054)
			(stroke
				(width 0.1)
				(type default)
			)
			(layer "B.Fab")
		)
		(fp_line
			(start -0.120396 0.2794)
			(end 0.12065 0.2794)
			(stroke
				(width 0.1)
				(type default)
			)
			(layer "B.Fab")
		)
		(fp_line
			(start 0.12065 0.2794)
			(end 0.12065 0.3048)
			(stroke
				(width 0.1)
				(type default)
			)
			(layer "B.Fab")
		)
		(fp_line
			(start -0.12065 -0.2794)
			(end -0.12065 -0.3048)
			(stroke
				(width 0.1)
				(type default)
			)
			(layer "B.Fab")
		)
		(fp_line
			(start 0.12065 -0.2794)
			(end -0.12065 -0.2794)
			(stroke
				(width 0.1)
				(type default)
			)
			(layer "B.Fab")
		)
		(fp_line
			(start -0.67945 -0.3048)
			(end -0.67945 0.3048)
			(stroke
				(width 0.1)
				(type default)
			)
			(layer "B.Fab")
		)
		(fp_line
			(start -0.12065 -0.3048)
			(end -0.67945 -0.3048)
			(stroke
				(width 0.1)
				(type default)
			)
			(layer "B.Fab")
		)
		(fp_line
			(start 0.12065 -0.305054)
			(end 0.12065 -0.2794)
			(stroke
				(width 0.1)
				(type default)
			)
			(layer "B.Fab")
		)
		(fp_line
			(start 0.67945 -0.305054)
			(end 0.12065 -0.305054)
			(stroke
				(width 0.1)
				(type default)
			)
			(layer "B.Fab")
		)
		(pad "1" smd circle
			(at 0.40005 0 90)
			(size 0 0)
			(layers "B.Cu" "B.Mask" "B.Paste")
			(net "P2V5_SENSOR")
		)
		(pad "2" smd circle
			(at -0.40005 0 90)
			(size 0 0)
			(layers "B.Cu" "B.Mask" "B.Paste")
			(net "GND")
		)
	)
	(footprint ""
		(layer "B.Cu")
		(at 54.483 -34.671 90)
		(property "Reference" "R580"
			(at 0 0 90)
			(layer "B.SilkS")
			(hide yes)
			(effects
				(font
					(size 1.27 1.27)
				)
				(justify mirror)
			)
		)
		(property "Value" ""
			(at 0 0 90)
			(layer "B.Fab")
			(effects
				(font
					(size 1.27 1.27)
				)
				(justify mirror)
			)
		)
		(duplicate_pad_numbers_are_jumpers no)
		(fp_line
			(start 0.7874 -0.4064)
			(end -0.7874 -0.4064)
			(stroke
				(width 0.1524)
				(type default)
			)
			(layer "B.SilkS")
		)
		(fp_line
			(start -0.7874 -0.4064)
			(end -0.7874 0.4064)
			(stroke
				(width 0.1524)
				(type default)
			)
			(layer "B.SilkS")
		)
		(fp_line
			(start 0.7874 0.4064)
			(end 0.7874 -0.4064)
			(stroke
				(width 0.1524)
				(type default)
			)
			(layer "B.SilkS")
		)
		(fp_line
			(start -0.7874 0.4064)
			(end 0.7874 0.4064)
			(stroke
				(width 0.1524)
				(type default)
			)
			(layer "B.SilkS")
		)
		(fp_line
			(start 0.67945 -0.305054)
			(end 0.12065 -0.305054)
			(stroke
				(width 0.1)
				(type default)
			)
			(layer "B.Fab")
		)
		(fp_line
			(start 0.12065 -0.305054)
			(end 0.12065 -0.2794)
			(stroke
				(width 0.1)
				(type default)
			)
			(layer "B.Fab")
		)
		(fp_line
			(start -0.12065 -0.3048)
			(end -0.67945 -0.3048)
			(stroke
				(width 0.1)
				(type default)
			)
			(layer "B.Fab")
		)
		(fp_line
			(start -0.67945 -0.3048)
			(end -0.67945 0.3048)
			(stroke
				(width 0.1)
				(type default)
			)
			(layer "B.Fab")
		)
		(fp_line
			(start 0.12065 -0.2794)
			(end -0.12065 -0.2794)
			(stroke
				(width 0.1)
				(type default)
			)
			(layer "B.Fab")
		)
		(fp_line
			(start -0.12065 -0.2794)
			(end -0.12065 -0.3048)
			(stroke
				(width 0.1)
				(type default)
			)
			(layer "B.Fab")
		)
		(fp_line
			(start 0.12065 0.2794)
			(end 0.12065 0.3048)
			(stroke
				(width 0.1)
				(type default)
			)
			(layer "B.Fab")
		)
		(fp_line
			(start -0.120396 0.2794)
			(end 0.12065 0.2794)
			(stroke
				(width 0.1)
				(type default)
			)
			(layer "B.Fab")
		)
		(fp_line
			(start 0.67945 0.3048)
			(end 0.67945 -0.305054)
			(stroke
				(width 0.1)
				(type default)
			)
			(layer "B.Fab")
		)
		(fp_line
			(start 0.12065 0.3048)
			(end 0.67945 0.3048)
			(stroke
				(width 0.1)
				(type default)
			)
			(layer "B.Fab")
		)
		(fp_line
			(start -0.120396 0.3048)
			(end -0.120396 0.2794)
			(stroke
				(width 0.1)
				(type default)
			)
			(layer "B.Fab")
		)
		(fp_line
			(start -0.67945 0.3048)
			(end -0.120396 0.3048)
			(stroke
				(width 0.1)
				(type default)
			)
			(layer "B.Fab")
		)
		(pad "1" smd circle
			(at 0.40005 0 270)
			(size 0 0)
			(layers "B.Cu" "B.Mask" "B.Paste")
			(net "SMB_BMC_MM9_R_SCL")
		)
		(pad "2" smd circle
			(at -0.40005 0 270)
			(size 0 0)
			(layers "B.Cu" "B.Mask" "B.Paste")
			(net "SMB_BMC_MM9_SCL")
		)
	)
	(footprint ""
		(layer "B.Cu")
		(at 61.063378 -46.426628)
		(property "Reference" "C76"
			(at 0 0 0)
			(layer "B.SilkS")
			(hide yes)
			(effects
				(font
					(size 1.27 1.27)
				)
				(justify mirror)
			)
		)
		(property "Value" ""
			(at 0 0 0)
			(layer "B.Fab")
			(effects
				(font
					(size 1.27 1.27)
				)
				(justify mirror)
			)
		)
		(duplicate_pad_numbers_are_jumpers no)
		(fp_line
			(start -0.7874 -0.4064)
			(end -0.7874 0.4064)
			(stroke
				(width 0.1524)
				(type default)
			)
			(layer "B.SilkS")
		)
		(fp_line
			(start -0.7874 0.4064)
			(end 0.7874 0.4064)
			(stroke
				(width 0.1524)
				(type default)
			)
			(layer "B.SilkS")
		)
		(fp_line
			(start 0.7874 -0.4064)
			(end -0.7874 -0.4064)
			(stroke
				(width 0.1524)
				(type default)
			)
			(layer "B.SilkS")
		)
		(fp_line
			(start 0.7874 0.4064)
			(end 0.7874 -0.4064)
			(stroke
				(width 0.1524)
				(type default)
			)
			(layer "B.SilkS")
		)
		(fp_line
			(start -0.67945 -0.3048)
			(end -0.67945 0.3048)
			(stroke
				(width 0.1)
				(type default)
			)
			(layer "B.Fab")
		)
		(fp_line
			(start -0.67945 0.3048)
			(end -0.120396 0.3048)
			(stroke
				(width 0.1)
				(type default)
			)
			(layer "B.Fab")
		)
		(fp_line
			(start -0.12065 -0.3048)
			(end -0.67945 -0.3048)
			(stroke
				(width 0.1)
				(type default)
			)
			(layer "B.Fab")
		)
		(fp_line
			(start -0.12065 -0.2794)
			(end -0.12065 -0.3048)
			(stroke
				(width 0.1)
				(type default)
			)
			(layer "B.Fab")
		)
		(fp_line
			(start -0.120396 0.2794)
			(end 0.12065 0.2794)
			(stroke
				(width 0.1)
				(type default)
			)
			(layer "B.Fab")
		)
		(fp_line
			(start -0.120396 0.3048)
			(end -0.120396 0.2794)
			(stroke
				(width 0.1)
				(type default)
			)
			(layer "B.Fab")
		)
		(fp_line
			(start 0.12065 -0.305054)
			(end 0.12065 -0.2794)
			(stroke
				(width 0.1)
				(type default)
			)
			(layer "B.Fab")
		)
		(fp_line
			(start 0.12065 -0.2794)
			(end -0.12065 -0.2794)
			(stroke
				(width 0.1)
				(type default)
			)
			(layer "B.Fab")
		)
		(fp_line
			(start 0.12065 0.2794)
			(end 0.12065 0.3048)
			(stroke
				(width 0.1)
				(type default)
			)
			(layer "B.Fab")
		)
		(fp_line
			(start 0.12065 0.3048)
			(end 0.67945 0.3048)
			(stroke
				(width 0.1)
				(type default)
			)
			(layer "B.Fab")
		)
		(fp_line
			(start 0.67945 -0.305054)
			(end 0.12065 -0.305054)
			(stroke
				(width 0.1)
				(type default)
			)
			(layer "B.Fab")
		)
		(fp_line
			(start 0.67945 0.3048)
			(end 0.67945 -0.305054)
			(stroke
				(width 0.1)
				(type default)
			)
			(layer "B.Fab")
		)
		(pad "1" smd circle
			(at 0.40005 0 180)
			(size 0 0)
			(layers "B.Cu" "B.Mask" "B.Paste")
			(net "P1V2_AUX")
		)
		(pad "2" smd circle
			(at -0.40005 0 180)
			(size 0 0)
			(layers "B.Cu" "B.Mask" "B.Paste")
			(net "GND")
		)
	)
	(footprint ""
		(layer "B.Cu")
		(at 39.0652 -106.3752 -90)
		(property "Reference" "R73"
			(at 0 0 90)
			(layer "B.SilkS")
			(hide yes)
			(effects
				(font
					(size 1.27 1.27)
				)
				(justify mirror)
			)
		)
		(property "Value" ""
			(at 0 0 90)
			(layer "B.Fab")
			(effects
				(font
					(size 1.27 1.27)
				)
				(justify mirror)
			)
		)
		(duplicate_pad_numbers_are_jumpers no)
		(fp_line
			(start -0.7874 0.4064)
			(end 0.7874 0.4064)
			(stroke
				(width 0.1524)
				(type default)
			)
			(layer "B.SilkS")
		)
		(fp_line
			(start 0.7874 0.4064)
			(end 0.7874 -0.4064)
			(stroke
				(width 0.1524)
				(type default)
			)
			(layer "B.SilkS")
		)
		(fp_line
			(start -0.7874 -0.4064)
			(end -0.7874 0.4064)
			(stroke
				(width 0.1524)
				(type default)
			)
			(layer "B.SilkS")
		)
		(fp_line
			(start 0.7874 -0.4064)
			(end -0.7874 -0.4064)
			(stroke
				(width 0.1524)
				(type default)
			)
			(layer "B.SilkS")
		)
		(fp_line
			(start -0.67945 0.3048)
			(end -0.120396 0.3048)
			(stroke
				(width 0.1)
				(type default)
			)
			(layer "B.Fab")
		)
		(fp_line
			(start -0.120396 0.3048)
			(end -0.120396 0.2794)
			(stroke
				(width 0.1)
				(type default)
			)
			(layer "B.Fab")
		)
		(fp_line
			(start 0.12065 0.3048)
			(end 0.67945 0.3048)
			(stroke
				(width 0.1)
				(type default)
			)
			(layer "B.Fab")
		)
		(fp_line
			(start 0.67945 0.3048)
			(end 0.67945 -0.305054)
			(stroke
				(width 0.1)
				(type default)
			)
			(layer "B.Fab")
		)
		(fp_line
			(start -0.120396 0.2794)
			(end 0.12065 0.2794)
			(stroke
				(width 0.1)
				(type default)
			)
			(layer "B.Fab")
		)
		(fp_line
			(start 0.12065 0.2794)
			(end 0.12065 0.3048)
			(stroke
				(width 0.1)
				(type default)
			)
			(layer "B.Fab")
		)
		(fp_line
			(start -0.12065 -0.2794)
			(end -0.12065 -0.3048)
			(stroke
				(width 0.1)
				(type default)
			)
			(layer "B.Fab")
		)
		(fp_line
			(start 0.12065 -0.2794)
			(end -0.12065 -0.2794)
			(stroke
				(width 0.1)
				(type default)
			)
			(layer "B.Fab")
		)
		(fp_line
			(start -0.67945 -0.3048)
			(end -0.67945 0.3048)
			(stroke
				(width 0.1)
				(type default)
			)
			(layer "B.Fab")
		)
		(fp_line
			(start -0.12065 -0.3048)
			(end -0.67945 -0.3048)
			(stroke
				(width 0.1)
				(type default)
			)
			(layer "B.Fab")
		)
		(fp_line
			(start 0.12065 -0.305054)
			(end 0.12065 -0.2794)
			(stroke
				(width 0.1)
				(type default)
			)
			(layer "B.Fab")
		)
		(fp_line
			(start 0.67945 -0.305054)
			(end 0.12065 -0.305054)
			(stroke
				(width 0.1)
				(type default)
			)
			(layer "B.Fab")
		)
		(pad "1" smd circle
			(at 0.40005 0 90)
			(size 0 0)
			(layers "B.Cu" "B.Mask" "B.Paste")
			(net "P3V3_AUX")
		)
		(pad "2" smd circle
			(at -0.40005 0 90)
			(size 0 0)
			(layers "B.Cu" "B.Mask" "B.Paste")
			(net "SGPIO_LD_1")
		)
	)
	(footprint ""
		(layer "B.Cu")
		(at 83.16722 -48.618394)
		(property "Reference" "R342"
			(at 0 0 0)
			(layer "B.SilkS")
			(hide yes)
			(effects
				(font
					(size 1.27 1.27)
				)
				(justify mirror)
			)
		)
		(property "Value" ""
			(at 0 0 0)
			(layer "B.Fab")
			(effects
				(font
					(size 1.27 1.27)
				)
				(justify mirror)
			)
		)
		(duplicate_pad_numbers_are_jumpers no)
		(fp_line
			(start -0.7874 -0.4064)
			(end -0.7874 0.4064)
			(stroke
				(width 0.1524)
				(type default)
			)
			(layer "B.SilkS")
		)
		(fp_line
			(start -0.7874 0.4064)
			(end 0.7874 0.4064)
			(stroke
				(width 0.1524)
				(type default)
			)
			(layer "B.SilkS")
		)
		(fp_line
			(start 0.7874 -0.4064)
			(end -0.7874 -0.4064)
			(stroke
				(width 0.1524)
				(type default)
			)
			(layer "B.SilkS")
		)
		(fp_line
			(start 0.7874 0.4064)
			(end 0.7874 -0.4064)
			(stroke
				(width 0.1524)
				(type default)
			)
			(layer "B.SilkS")
		)
		(fp_line
			(start -0.67945 -0.3048)
			(end -0.67945 0.3048)
			(stroke
				(width 0.1)
				(type default)
			)
			(layer "B.Fab")
		)
		(fp_line
			(start -0.67945 0.3048)
			(end -0.120396 0.3048)
			(stroke
				(width 0.1)
				(type default)
			)
			(layer "B.Fab")
		)
		(fp_line
			(start -0.12065 -0.3048)
			(end -0.67945 -0.3048)
			(stroke
				(width 0.1)
				(type default)
			)
			(layer "B.Fab")
		)
		(fp_line
			(start -0.12065 -0.2794)
			(end -0.12065 -0.3048)
			(stroke
				(width 0.1)
				(type default)
			)
			(layer "B.Fab")
		)
		(fp_line
			(start -0.120396 0.2794)
			(end 0.12065 0.2794)
			(stroke
				(width 0.1)
				(type default)
			)
			(layer "B.Fab")
		)
		(fp_line
			(start -0.120396 0.3048)
			(end -0.120396 0.2794)
			(stroke
				(width 0.1)
				(type default)
			)
			(layer "B.Fab")
		)
		(fp_line
			(start 0.12065 -0.305054)
			(end 0.12065 -0.2794)
			(stroke
				(width 0.1)
				(type default)
			)
			(layer "B.Fab")
		)
		(fp_line
			(start 0.12065 -0.2794)
			(end -0.12065 -0.2794)
			(stroke
				(width 0.1)
				(type default)
			)
			(layer "B.Fab")
		)
		(fp_line
			(start 0.12065 0.2794)
			(end 0.12065 0.3048)
			(stroke
				(width 0.1)
				(type default)
			)
			(layer "B.Fab")
		)
		(fp_line
			(start 0.12065 0.3048)
			(end 0.67945 0.3048)
			(stroke
				(width 0.1)
				(type default)
			)
			(layer "B.Fab")
		)
		(fp_line
			(start 0.67945 -0.305054)
			(end 0.12065 -0.305054)
			(stroke
				(width 0.1)
				(type default)
			)
			(layer "B.Fab")
		)
		(fp_line
			(start 0.67945 0.3048)
			(end 0.67945 -0.305054)
			(stroke
				(width 0.1)
				(type default)
			)
			(layer "B.Fab")
		)
		(pad "1" smd circle
			(at 0.40005 0 180)
			(size 0 0)
			(layers "B.Cu" "B.Mask" "B.Paste")
			(net "GND")
		)
		(pad "2" smd circle
			(at -0.40005 0 180)
			(size 0 0)
			(layers "B.Cu" "B.Mask" "B.Paste")
			(net "M_BMC_DDR4_MRAS_N")
		)
	)
	(footprint ""
		(layer "B.Cu")
		(at 26.3652 -97.282 -90)
		(property "Reference" "C152"
			(at 0 0 90)
			(layer "B.SilkS")
			(hide yes)
			(effects
				(font
					(size 1.27 1.27)
				)
				(justify mirror)
			)
		)
		(property "Value" ""
			(at 0 0 90)
			(layer "B.Fab")
			(effects
				(font
					(size 1.27 1.27)
				)
				(justify mirror)
			)
		)
		(duplicate_pad_numbers_are_jumpers no)
		(fp_line
			(start -0.7874 0.4064)
			(end 0.7874 0.4064)
			(stroke
				(width 0.1524)
				(type default)
			)
			(layer "B.SilkS")
		)
		(fp_line
			(start 0.7874 0.4064)
			(end 0.7874 -0.4064)
			(stroke
				(width 0.1524)
				(type default)
			)
			(layer "B.SilkS")
		)
		(fp_line
			(start -0.7874 -0.4064)
			(end -0.7874 0.4064)
			(stroke
				(width 0.1524)
				(type default)
			)
			(layer "B.SilkS")
		)
		(fp_line
			(start 0.7874 -0.4064)
			(end -0.7874 -0.4064)
			(stroke
				(width 0.1524)
				(type default)
			)
			(layer "B.SilkS")
		)
		(fp_line
			(start -0.67945 0.3048)
			(end -0.120396 0.3048)
			(stroke
				(width 0.1)
				(type default)
			)
			(layer "B.Fab")
		)
		(fp_line
			(start -0.120396 0.3048)
			(end -0.120396 0.2794)
			(stroke
				(width 0.1)
				(type default)
			)
			(layer "B.Fab")
		)
		(fp_line
			(start 0.12065 0.3048)
			(end 0.67945 0.3048)
			(stroke
				(width 0.1)
				(type default)
			)
			(layer "B.Fab")
		)
		(fp_line
			(start 0.67945 0.3048)
			(end 0.67945 -0.305054)
			(stroke
				(width 0.1)
				(type default)
			)
			(layer "B.Fab")
		)
		(fp_line
			(start -0.120396 0.2794)
			(end 0.12065 0.2794)
			(stroke
				(width 0.1)
				(type default)
			)
			(layer "B.Fab")
		)
		(fp_line
			(start 0.12065 0.2794)
			(end 0.12065 0.3048)
			(stroke
				(width 0.1)
				(type default)
			)
			(layer "B.Fab")
		)
		(fp_line
			(start -0.12065 -0.2794)
			(end -0.12065 -0.3048)
			(stroke
				(width 0.1)
				(type default)
			)
			(layer "B.Fab")
		)
		(fp_line
			(start 0.12065 -0.2794)
			(end -0.12065 -0.2794)
			(stroke
				(width 0.1)
				(type default)
			)
			(layer "B.Fab")
		)
		(fp_line
			(start -0.67945 -0.3048)
			(end -0.67945 0.3048)
			(stroke
				(width 0.1)
				(type default)
			)
			(layer "B.Fab")
		)
		(fp_line
			(start -0.12065 -0.3048)
			(end -0.67945 -0.3048)
			(stroke
				(width 0.1)
				(type default)
			)
			(layer "B.Fab")
		)
		(fp_line
			(start 0.12065 -0.305054)
			(end 0.12065 -0.2794)
			(stroke
				(width 0.1)
				(type default)
			)
			(layer "B.Fab")
		)
		(fp_line
			(start 0.67945 -0.305054)
			(end 0.12065 -0.305054)
			(stroke
				(width 0.1)
				(type default)
			)
			(layer "B.Fab")
		)
		(pad "1" smd circle
			(at 0.40005 0 90)
			(size 0 0)
			(layers "B.Cu" "B.Mask" "B.Paste")
			(net "VCCIO3")
		)
		(pad "2" smd circle
			(at -0.40005 0 90)
			(size 0 0)
			(layers "B.Cu" "B.Mask" "B.Paste")
			(net "GND")
		)
	)
	(footprint ""
		(layer "B.Cu")
		(at 76.982828 -47.21479)
		(property "Reference" "R8"
			(at 0 0 0)
			(layer "B.SilkS")
			(hide yes)
			(effects
				(font
					(size 1.27 1.27)
				)
				(justify mirror)
			)
		)
		(property "Value" ""
			(at 0 0 0)
			(layer "B.Fab")
			(effects
				(font
					(size 1.27 1.27)
				)
				(justify mirror)
			)
		)
		(duplicate_pad_numbers_are_jumpers no)
		(fp_line
			(start -0.7874 -0.4064)
			(end -0.7874 0.4064)
			(stroke
				(width 0.1524)
				(type default)
			)
			(layer "B.SilkS")
		)
		(fp_line
			(start -0.7874 0.4064)
			(end 0.487172 0.4064)
			(stroke
				(width 0.1524)
				(type default)
			)
			(layer "B.SilkS")
		)
		(fp_line
			(start 0.7874 -0.4064)
			(end -0.7874 -0.4064)
			(stroke
				(width 0.1524)
				(type default)
			)
			(layer "B.SilkS")
		)
		(fp_line
			(start 0.7874 0.09779)
			(end 0.7874 -0.4064)
			(stroke
				(width 0.1524)
				(type default)
			)
			(layer "B.SilkS")
		)
		(fp_line
			(start -0.67945 -0.3048)
			(end -0.67945 0.3048)
			(stroke
				(width 0.1)
				(type default)
			)
			(layer "B.Fab")
		)
		(fp_line
			(start -0.67945 0.3048)
			(end -0.120396 0.3048)
			(stroke
				(width 0.1)
				(type default)
			)
			(layer "B.Fab")
		)
		(fp_line
			(start -0.12065 -0.3048)
			(end -0.67945 -0.3048)
			(stroke
				(width 0.1)
				(type default)
			)
			(layer "B.Fab")
		)
		(fp_line
			(start -0.12065 -0.2794)
			(end -0.12065 -0.3048)
			(stroke
				(width 0.1)
				(type default)
			)
			(layer "B.Fab")
		)
		(fp_line
			(start -0.120396 0.2794)
			(end 0.12065 0.2794)
			(stroke
				(width 0.1)
				(type default)
			)
			(layer "B.Fab")
		)
		(fp_line
			(start -0.120396 0.3048)
			(end -0.120396 0.2794)
			(stroke
				(width 0.1)
				(type default)
			)
			(layer "B.Fab")
		)
		(fp_line
			(start 0.12065 -0.305054)
			(end 0.12065 -0.2794)
			(stroke
				(width 0.1)
				(type default)
			)
			(layer "B.Fab")
		)
		(fp_line
			(start 0.12065 -0.2794)
			(end -0.12065 -0.2794)
			(stroke
				(width 0.1)
				(type default)
			)
			(layer "B.Fab")
		)
		(fp_line
			(start 0.12065 0.2794)
			(end 0.12065 0.3048)
			(stroke
				(width 0.1)
				(type default)
			)
			(layer "B.Fab")
		)
		(fp_line
			(start 0.12065 0.3048)
			(end 0.67945 0.3048)
			(stroke
				(width 0.1)
				(type default)
			)
			(layer "B.Fab")
		)
		(fp_line
			(start 0.67945 -0.305054)
			(end 0.12065 -0.305054)
			(stroke
				(width 0.1)
				(type default)
			)
			(layer "B.Fab")
		)
		(fp_line
			(start 0.67945 0.3048)
			(end 0.67945 -0.305054)
			(stroke
				(width 0.1)
				(type default)
			)
			(layer "B.Fab")
		)
		(pad "1" smd circle
			(at 0.40005 0 180)
			(size 0 0)
			(layers "B.Cu" "B.Mask" "B.Paste")
			(net "M_BMC_DDR4_MCLK_DP")
		)
		(pad "2" smd circle
			(at -0.40005 0 180)
			(size 0 0)
			(layers "B.Cu" "B.Mask" "B.Paste")
			(net "M_BMC_DDR4_MCLK_C")
		)
	)
	(footprint ""
		(layer "B.Cu")
		(at 18.415 -17.907 90)
		(property "Reference" "R410"
			(at 0 0 90)
			(layer "B.SilkS")
			(hide yes)
			(effects
				(font
					(size 1.27 1.27)
				)
				(justify mirror)
			)
		)
		(property "Value" ""
			(at 0 0 90)
			(layer "B.Fab")
			(effects
				(font
					(size 1.27 1.27)
				)
				(justify mirror)
			)
		)
		(duplicate_pad_numbers_are_jumpers no)
		(fp_line
			(start 0.7874 -0.4064)
			(end -0.7874 -0.4064)
			(stroke
				(width 0.1524)
				(type default)
			)
			(layer "B.SilkS")
		)
		(fp_line
			(start -0.7874 -0.4064)
			(end -0.7874 0.4064)
			(stroke
				(width 0.1524)
				(type default)
			)
			(layer "B.SilkS")
		)
		(fp_line
			(start 0.7874 0.4064)
			(end 0.7874 -0.4064)
			(stroke
				(width 0.1524)
				(type default)
			)
			(layer "B.SilkS")
		)
		(fp_line
			(start -0.7874 0.4064)
			(end 0.7874 0.4064)
			(stroke
				(width 0.1524)
				(type default)
			)
			(layer "B.SilkS")
		)
		(fp_line
			(start 0.67945 -0.305054)
			(end 0.12065 -0.305054)
			(stroke
				(width 0.1)
				(type default)
			)
			(layer "B.Fab")
		)
		(fp_line
			(start 0.12065 -0.305054)
			(end 0.12065 -0.2794)
			(stroke
				(width 0.1)
				(type default)
			)
			(layer "B.Fab")
		)
		(fp_line
			(start -0.12065 -0.3048)
			(end -0.67945 -0.3048)
			(stroke
				(width 0.1)
				(type default)
			)
			(layer "B.Fab")
		)
		(fp_line
			(start -0.67945 -0.3048)
			(end -0.67945 0.3048)
			(stroke
				(width 0.1)
				(type default)
			)
			(layer "B.Fab")
		)
		(fp_line
			(start 0.12065 -0.2794)
			(end -0.12065 -0.2794)
			(stroke
				(width 0.1)
				(type default)
			)
			(layer "B.Fab")
		)
		(fp_line
			(start -0.12065 -0.2794)
			(end -0.12065 -0.3048)
			(stroke
				(width 0.1)
				(type default)
			)
			(layer "B.Fab")
		)
		(fp_line
			(start 0.12065 0.2794)
			(end 0.12065 0.3048)
			(stroke
				(width 0.1)
				(type default)
			)
			(layer "B.Fab")
		)
		(fp_line
			(start -0.120396 0.2794)
			(end 0.12065 0.2794)
			(stroke
				(width 0.1)
				(type default)
			)
			(layer "B.Fab")
		)
		(fp_line
			(start 0.67945 0.3048)
			(end 0.67945 -0.305054)
			(stroke
				(width 0.1)
				(type default)
			)
			(layer "B.Fab")
		)
		(fp_line
			(start 0.12065 0.3048)
			(end 0.67945 0.3048)
			(stroke
				(width 0.1)
				(type default)
			)
			(layer "B.Fab")
		)
		(fp_line
			(start -0.120396 0.3048)
			(end -0.120396 0.2794)
			(stroke
				(width 0.1)
				(type default)
			)
			(layer "B.Fab")
		)
		(fp_line
			(start -0.67945 0.3048)
			(end -0.120396 0.3048)
			(stroke
				(width 0.1)
				(type default)
			)
			(layer "B.Fab")
		)
		(pad "1" smd circle
			(at 0.40005 0 270)
			(size 0 0)
			(layers "B.Cu" "B.Mask" "B.Paste")
			(net "SMB_TMP421_BMC_MM2_SCL")
		)
		(pad "2" smd circle
			(at -0.40005 0 270)
			(size 0 0)
			(layers "B.Cu" "B.Mask" "B.Paste")
			(net "SMB_BMC_MM2_SCL")
		)
	)
	(footprint ""
		(layer "B.Cu")
		(at 63.9572 -91.2114)
		(property "Reference" "R739"
			(at 0 0 0)
			(layer "B.SilkS")
			(hide yes)
			(effects
				(font
					(size 1.27 1.27)
				)
				(justify mirror)
			)
		)
		(property "Value" ""
			(at 0 0 0)
			(layer "B.Fab")
			(effects
				(font
					(size 1.27 1.27)
				)
				(justify mirror)
			)
		)
		(duplicate_pad_numbers_are_jumpers no)
		(fp_line
			(start -0.7874 -0.4064)
			(end -0.7874 0.4064)
			(stroke
				(width 0.1524)
				(type default)
			)
			(layer "B.SilkS")
		)
		(fp_line
			(start -0.7874 0.4064)
			(end 0.7874 0.4064)
			(stroke
				(width 0.1524)
				(type default)
			)
			(layer "B.SilkS")
		)
		(fp_line
			(start 0.7874 -0.4064)
			(end -0.7874 -0.4064)
			(stroke
				(width 0.1524)
				(type default)
			)
			(layer "B.SilkS")
		)
		(fp_line
			(start 0.7874 0.4064)
			(end 0.7874 -0.4064)
			(stroke
				(width 0.1524)
				(type default)
			)
			(layer "B.SilkS")
		)
		(fp_line
			(start -0.67945 -0.3048)
			(end -0.67945 0.3048)
			(stroke
				(width 0.1)
				(type default)
			)
			(layer "B.Fab")
		)
		(fp_line
			(start -0.67945 0.3048)
			(end -0.120396 0.3048)
			(stroke
				(width 0.1)
				(type default)
			)
			(layer "B.Fab")
		)
		(fp_line
			(start -0.12065 -0.3048)
			(end -0.67945 -0.3048)
			(stroke
				(width 0.1)
				(type default)
			)
			(layer "B.Fab")
		)
		(fp_line
			(start -0.12065 -0.2794)
			(end -0.12065 -0.3048)
			(stroke
				(width 0.1)
				(type default)
			)
			(layer "B.Fab")
		)
		(fp_line
			(start -0.120396 0.2794)
			(end 0.12065 0.2794)
			(stroke
				(width 0.1)
				(type default)
			)
			(layer "B.Fab")
		)
		(fp_line
			(start -0.120396 0.3048)
			(end -0.120396 0.2794)
			(stroke
				(width 0.1)
				(type default)
			)
			(layer "B.Fab")
		)
		(fp_line
			(start 0.12065 -0.305054)
			(end 0.12065 -0.2794)
			(stroke
				(width 0.1)
				(type default)
			)
			(layer "B.Fab")
		)
		(fp_line
			(start 0.12065 -0.2794)
			(end -0.12065 -0.2794)
			(stroke
				(width 0.1)
				(type default)
			)
			(layer "B.Fab")
		)
		(fp_line
			(start 0.12065 0.2794)
			(end 0.12065 0.3048)
			(stroke
				(width 0.1)
				(type default)
			)
			(layer "B.Fab")
		)
		(fp_line
			(start 0.12065 0.3048)
			(end 0.67945 0.3048)
			(stroke
				(width 0.1)
				(type default)
			)
			(layer "B.Fab")
		)
		(fp_line
			(start 0.67945 -0.305054)
			(end 0.12065 -0.305054)
			(stroke
				(width 0.1)
				(type default)
			)
			(layer "B.Fab")
		)
		(fp_line
			(start 0.67945 0.3048)
			(end 0.67945 -0.305054)
			(stroke
				(width 0.1)
				(type default)
			)
			(layer "B.Fab")
		)
		(pad "1" smd circle
			(at 0.40005 0 180)
			(size 0 0)
			(layers "B.Cu" "B.Mask" "B.Paste")
			(net "P3V3_AUX")
		)
		(pad "2" smd circle
			(at -0.40005 0 180)
			(size 0 0)
			(layers "B.Cu" "B.Mask" "B.Paste")
			(net "LED_POSTCODE_A1")
		)
	)
	(footprint ""
		(layer "B.Cu")
		(at 12.319 -101.854 90)
		(property "Reference" "D23"
			(at -0.0762 1.37033 270)
			(unlocked yes)
			(layer "B.SilkS")
			(effects
				(font
					(size 0.7874 0.5842)
					(thickness 0.1524)
				)
				(justify left mirror)
			)
		)
		(property "Value" ""
			(at 0 0 90)
			(layer "B.Fab")
			(effects
				(font
					(size 1.27 1.27)
				)
				(justify mirror)
			)
		)
		(duplicate_pad_numbers_are_jumpers no)
		(fp_line
			(start 2.050796 -0.700024)
			(end -2.050796 -0.700024)
			(stroke
				(width 0.1524)
				(type default)
			)
			(layer "B.SilkS")
		)
		(fp_line
			(start -2.050796 -0.700024)
			(end -2.050796 0.700024)
			(stroke
				(width 0.1524)
				(type default)
			)
			(layer "B.SilkS")
		)
		(fp_line
			(start -2.064004 -0.6985)
			(end -2.229104 -0.6985)
			(stroke
				(width 0.1524)
				(type default)
			)
			(layer "B.SilkS")
		)
		(fp_line
			(start -2.152904 -0.6985)
			(end -2.343404 -0.6985)
			(stroke
				(width 0.1524)
				(type default)
			)
			(layer "B.SilkS")
		)
		(fp_line
			(start -2.229104 -0.6985)
			(end -2.229104 0.6985)
			(stroke
				(width 0.1524)
				(type default)
			)
			(layer "B.SilkS")
		)
		(fp_line
			(start -2.343404 -0.6985)
			(end -2.343404 0.6985)
			(stroke
				(width 0.1524)
				(type default)
			)
			(layer "B.SilkS")
		)
		(fp_line
			(start -2.064004 -0.6731)
			(end -2.064004 -0.6985)
			(stroke
				(width 0.1524)
				(type default)
			)
			(layer "B.SilkS")
		)
		(fp_line
			(start 0.30607 -0.500126)
			(end 0.30607 0.500126)
			(stroke
				(width 0.1524)
				(type default)
			)
			(layer "B.SilkS")
		)
		(fp_line
			(start -0.293878 -0.500126)
			(end -0.293878 0.500126)
			(stroke
				(width 0.1524)
				(type default)
			)
			(layer "B.SilkS")
		)
		(fp_line
			(start -0.193802 0)
			(end 0.30607 -0.500126)
			(stroke
				(width 0.1524)
				(type default)
			)
			(layer "B.SilkS")
		)
		(fp_line
			(start 0.30607 0.500126)
			(end -0.193802 0)
			(stroke
				(width 0.1524)
				(type default)
			)
			(layer "B.SilkS")
		)
		(fp_line
			(start -2.051304 0.635)
			(end -2.152904 0.635)
			(stroke
				(width 0.1524)
				(type default)
			)
			(layer "B.SilkS")
		)
		(fp_line
			(start -2.152904 0.635)
			(end -2.152904 -0.6985)
			(stroke
				(width 0.1524)
				(type default)
			)
			(layer "B.SilkS")
		)
		(fp_line
			(start -2.051304 0.6985)
			(end -2.051304 0.635)
			(stroke
				(width 0.1524)
				(type default)
			)
			(layer "B.SilkS")
		)
		(fp_line
			(start -2.229104 0.6985)
			(end -2.051304 0.6985)
			(stroke
				(width 0.1524)
				(type default)
			)
			(layer "B.SilkS")
		)
		(fp_line
			(start -2.343404 0.6985)
			(end -2.216404 0.6985)
			(stroke
				(width 0.1524)
				(type default)
			)
			(layer "B.SilkS")
		)
		(fp_line
			(start 2.050796 0.700024)
			(end 2.050796 -0.700024)
			(stroke
				(width 0.1524)
				(type default)
			)
			(layer "B.SilkS")
		)
		(fp_line
			(start -2.050796 0.700024)
			(end 2.050796 0.700024)
			(stroke
				(width 0.1524)
				(type default)
			)
			(layer "B.SilkS")
		)
		(fp_line
			(start 0.899922 -0.700024)
			(end -0.899922 -0.700024)
			(stroke
				(width 0.1)
				(type default)
			)
			(layer "B.Fab")
		)
		(fp_line
			(start -0.899922 -0.700024)
			(end -0.899922 0.700024)
			(stroke
				(width 0.1)
				(type default)
			)
			(layer "B.Fab")
		)
		(fp_line
			(start 0.899922 0.700024)
			(end 0.899922 -0.700024)
			(stroke
				(width 0.1)
				(type default)
			)
			(layer "B.Fab")
		)
		(fp_line
			(start -0.899922 0.700024)
			(end 0.899922 0.700024)
			(stroke
				(width 0.1)
				(type default)
			)
			(layer "B.Fab")
		)
		(fp_text user "+"
			(at 3.01625 1.016 0)
			(unlocked yes)
			(layer "B.SilkS")
			(effects
				(font
					(size 1.905 1.4224)
					(thickness 0.1524)
				)
				(justify left mirror)
			)
		)
		(fp_text user "-"
			(at -2.2352 1.36525 270)
			(unlocked yes)
			(layer "B.SilkS")
			(effects
				(font
					(size 1.905 1.4224)
					(thickness 0.1524)
				)
				(justify left mirror)
			)
		)
		(fp_text user "-"
			(at -3.880104 0.23495 270)
			(unlocked yes)
			(layer "B.Fab")
			(effects
				(font
					(size 1.905 1.4224)
					(thickness 0.1524)
				)
				(justify left mirror)
			)
		)
		(fp_text user "+"
			(at 3.123946 0.762 0)
			(unlocked yes)
			(layer "B.Fab")
			(effects
				(font
					(size 1.905 1.4224)
					(thickness 0.1524)
				)
				(justify left mirror)
			)
		)
		(pad "1" smd rect
			(at 1.199896 0)
			(size 0.6604 1.3716)
			(layers "B.Cu" "B.Mask" "B.Paste")
			(net "PWRGD_P5V_AUX")
		)
		(pad "2" smd rect
			(at -1.199896 0 180)
			(size 0.6604 1.3716)
			(layers "B.Cu" "B.Mask" "B.Paste")
			(net "PWRGD_P5V_AUX_R1")
		)
	)
	(footprint ""
		(layer "B.Cu")
		(at 19.472656 -96.012 -90)
		(property "Reference" "C250"
			(at 0 0 90)
			(layer "B.SilkS")
			(hide yes)
			(effects
				(font
					(size 1.27 1.27)
				)
				(justify mirror)
			)
		)
		(property "Value" ""
			(at 0 0 90)
			(layer "B.Fab")
			(effects
				(font
					(size 1.27 1.27)
				)
				(justify mirror)
			)
		)
		(duplicate_pad_numbers_are_jumpers no)
		(fp_line
			(start -0.69215 0.2921)
			(end 0.69215 0.2921)
			(stroke
				(width 0.1524)
				(type default)
			)
			(layer "B.SilkS")
		)
		(fp_line
			(start 0.69215 0.2921)
			(end 0.69215 -0.2921)
			(stroke
				(width 0.1524)
				(type default)
			)
			(layer "B.SilkS")
		)
		(fp_line
			(start -0.69215 -0.2921)
			(end -0.69215 0.2921)
			(stroke
				(width 0.1524)
				(type default)
			)
			(layer "B.SilkS")
		)
		(fp_line
			(start 0.69215 -0.2921)
			(end -0.69215 -0.2921)
			(stroke
				(width 0.1524)
				(type default)
			)
			(layer "B.SilkS")
		)
		(fp_line
			(start -0.51435 0.2794)
			(end 0.51435 0.2794)
			(stroke
				(width 0.1)
				(type default)
			)
			(layer "B.Fab")
		)
		(fp_line
			(start 0.51435 0.2794)
			(end 0.51435 -0.2794)
			(stroke
				(width 0.1)
				(type default)
			)
			(layer "B.Fab")
		)
		(fp_line
			(start -0.51435 -0.2794)
			(end -0.51435 0.2794)
			(stroke
				(width 0.1)
				(type default)
			)
			(layer "B.Fab")
		)
		(fp_line
			(start 0.51435 -0.2794)
			(end -0.51435 -0.2794)
			(stroke
				(width 0.1)
				(type default)
			)
			(layer "B.Fab")
		)
		(pad "1" smd circle
			(at 0.40005 0 90)
			(size 0 0)
			(layers "B.Cu" "B.Mask" "B.Paste")
			(net "PVCCA_AUX_PLD")
		)
		(pad "2" smd circle
			(at -0.40005 0 90)
			(size 0 0)
			(layers "B.Cu" "B.Mask" "B.Paste")
			(net "GND")
		)
		(zone
			(layer "B.Cu")
			(hatch none 0.5)
			(connect_pads
				(clearance 0)
			)
			(min_thickness 0.25)
			(keepout
				(tracks not_allowed)
				(vias allowed)
				(pads allowed)
				(copperpour not_allowed)
				(footprints allowed)
			)
			(placement
				(enabled no)
				(sheetname "")
			)
			(fill
				(thermal_gap 0.5)
				(thermal_bridge_width 0.5)
				(island_removal_mode 0)
			)
			(polygon
				(pts
					(xy 19.385026 -95.8215) (xy 19.32686 -95.91294) (xy 19.32686 -96.11233) (xy 19.385026 -96.2025)
					(xy 19.560286 -96.2025) (xy 19.618706 -96.11233) (xy 19.618706 -95.91294) (xy 19.56054 -95.8215)
				)
			)
		)
	)
	(footprint ""
		(layer "B.Cu")
		(at 61.876686 -30.87751 -90)
		(property "Reference" "R157"
			(at 0 0 90)
			(layer "B.SilkS")
			(hide yes)
			(effects
				(font
					(size 1.27 1.27)
				)
				(justify mirror)
			)
		)
		(property "Value" ""
			(at 0 0 90)
			(layer "B.Fab")
			(effects
				(font
					(size 1.27 1.27)
				)
				(justify mirror)
			)
		)
		(duplicate_pad_numbers_are_jumpers no)
		(fp_line
			(start -0.7874 0.4064)
			(end 0.7874 0.4064)
			(stroke
				(width 0.1524)
				(type default)
			)
			(layer "B.SilkS")
		)
		(fp_line
			(start 0.7874 0.4064)
			(end 0.7874 -0.4064)
			(stroke
				(width 0.1524)
				(type default)
			)
			(layer "B.SilkS")
		)
		(fp_line
			(start -0.7874 -0.4064)
			(end -0.7874 0.4064)
			(stroke
				(width 0.1524)
				(type default)
			)
			(layer "B.SilkS")
		)
		(fp_line
			(start 0.7874 -0.4064)
			(end -0.7874 -0.4064)
			(stroke
				(width 0.1524)
				(type default)
			)
			(layer "B.SilkS")
		)
		(fp_line
			(start -0.67945 0.3048)
			(end -0.120396 0.3048)
			(stroke
				(width 0.1)
				(type default)
			)
			(layer "B.Fab")
		)
		(fp_line
			(start -0.120396 0.3048)
			(end -0.120396 0.2794)
			(stroke
				(width 0.1)
				(type default)
			)
			(layer "B.Fab")
		)
		(fp_line
			(start 0.12065 0.3048)
			(end 0.67945 0.3048)
			(stroke
				(width 0.1)
				(type default)
			)
			(layer "B.Fab")
		)
		(fp_line
			(start 0.67945 0.3048)
			(end 0.67945 -0.305054)
			(stroke
				(width 0.1)
				(type default)
			)
			(layer "B.Fab")
		)
		(fp_line
			(start -0.120396 0.2794)
			(end 0.12065 0.2794)
			(stroke
				(width 0.1)
				(type default)
			)
			(layer "B.Fab")
		)
		(fp_line
			(start 0.12065 0.2794)
			(end 0.12065 0.3048)
			(stroke
				(width 0.1)
				(type default)
			)
			(layer "B.Fab")
		)
		(fp_line
			(start -0.12065 -0.2794)
			(end -0.12065 -0.3048)
			(stroke
				(width 0.1)
				(type default)
			)
			(layer "B.Fab")
		)
		(fp_line
			(start 0.12065 -0.2794)
			(end -0.12065 -0.2794)
			(stroke
				(width 0.1)
				(type default)
			)
			(layer "B.Fab")
		)
		(fp_line
			(start -0.67945 -0.3048)
			(end -0.67945 0.3048)
			(stroke
				(width 0.1)
				(type default)
			)
			(layer "B.Fab")
		)
		(fp_line
			(start -0.12065 -0.3048)
			(end -0.67945 -0.3048)
			(stroke
				(width 0.1)
				(type default)
			)
			(layer "B.Fab")
		)
		(fp_line
			(start 0.12065 -0.305054)
			(end 0.12065 -0.2794)
			(stroke
				(width 0.1)
				(type default)
			)
			(layer "B.Fab")
		)
		(fp_line
			(start 0.67945 -0.305054)
			(end 0.12065 -0.305054)
			(stroke
				(width 0.1)
				(type default)
			)
			(layer "B.Fab")
		)
		(pad "1" smd circle
			(at 0.40005 0 90)
			(size 0 0)
			(layers "B.Cu" "B.Mask" "B.Paste")
			(net "UART_BMC_1_TXD_R")
		)
		(pad "2" smd circle
			(at -0.40005 0 90)
			(size 0 0)
			(layers "B.Cu" "B.Mask" "B.Paste")
			(net "UART_BMC_1_TXD")
		)
	)
	(footprint ""
		(layer "B.Cu")
		(at 49.205896 -47.67072 -90)
		(property "Reference" "C72"
			(at 0 0 90)
			(layer "B.SilkS")
			(hide yes)
			(effects
				(font
					(size 1.27 1.27)
				)
				(justify mirror)
			)
		)
		(property "Value" ""
			(at 0 0 90)
			(layer "B.Fab")
			(effects
				(font
					(size 1.27 1.27)
				)
				(justify mirror)
			)
		)
		(duplicate_pad_numbers_are_jumpers no)
		(fp_line
			(start -0.7874 0.4064)
			(end 0.7874 0.4064)
			(stroke
				(width 0.1524)
				(type default)
			)
			(layer "B.SilkS")
		)
		(fp_line
			(start 0.7874 0.4064)
			(end 0.7874 -0.4064)
			(stroke
				(width 0.1524)
				(type default)
			)
			(layer "B.SilkS")
		)
		(fp_line
			(start -0.7874 -0.4064)
			(end -0.7874 0.4064)
			(stroke
				(width 0.1524)
				(type default)
			)
			(layer "B.SilkS")
		)
		(fp_line
			(start 0.7874 -0.4064)
			(end -0.7874 -0.4064)
			(stroke
				(width 0.1524)
				(type default)
			)
			(layer "B.SilkS")
		)
		(fp_line
			(start -0.67945 0.3048)
			(end -0.120396 0.3048)
			(stroke
				(width 0.1)
				(type default)
			)
			(layer "B.Fab")
		)
		(fp_line
			(start -0.120396 0.3048)
			(end -0.120396 0.2794)
			(stroke
				(width 0.1)
				(type default)
			)
			(layer "B.Fab")
		)
		(fp_line
			(start 0.12065 0.3048)
			(end 0.67945 0.3048)
			(stroke
				(width 0.1)
				(type default)
			)
			(layer "B.Fab")
		)
		(fp_line
			(start 0.67945 0.3048)
			(end 0.67945 -0.305054)
			(stroke
				(width 0.1)
				(type default)
			)
			(layer "B.Fab")
		)
		(fp_line
			(start -0.120396 0.2794)
			(end 0.12065 0.2794)
			(stroke
				(width 0.1)
				(type default)
			)
			(layer "B.Fab")
		)
		(fp_line
			(start 0.12065 0.2794)
			(end 0.12065 0.3048)
			(stroke
				(width 0.1)
				(type default)
			)
			(layer "B.Fab")
		)
		(fp_line
			(start -0.12065 -0.2794)
			(end -0.12065 -0.3048)
			(stroke
				(width 0.1)
				(type default)
			)
			(layer "B.Fab")
		)
		(fp_line
			(start 0.12065 -0.2794)
			(end -0.12065 -0.2794)
			(stroke
				(width 0.1)
				(type default)
			)
			(layer "B.Fab")
		)
		(fp_line
			(start -0.67945 -0.3048)
			(end -0.67945 0.3048)
			(stroke
				(width 0.1)
				(type default)
			)
			(layer "B.Fab")
		)
		(fp_line
			(start -0.12065 -0.3048)
			(end -0.67945 -0.3048)
			(stroke
				(width 0.1)
				(type default)
			)
			(layer "B.Fab")
		)
		(fp_line
			(start 0.12065 -0.305054)
			(end 0.12065 -0.2794)
			(stroke
				(width 0.1)
				(type default)
			)
			(layer "B.Fab")
		)
		(fp_line
			(start 0.67945 -0.305054)
			(end 0.12065 -0.305054)
			(stroke
				(width 0.1)
				(type default)
			)
			(layer "B.Fab")
		)
		(pad "1" smd circle
			(at 0.40005 0 90)
			(size 0 0)
			(layers "B.Cu" "B.Mask" "B.Paste")
			(net "P1V2_AUX")
		)
		(pad "2" smd circle
			(at -0.40005 0 90)
			(size 0 0)
			(layers "B.Cu" "B.Mask" "B.Paste")
			(net "GND")
		)
	)
	(footprint ""
		(layer "B.Cu")
		(at 36.957 -32.766)
		(property "Reference" "L2"
			(at 0 0 0)
			(layer "B.SilkS")
			(hide yes)
			(effects
				(font
					(size 1.27 1.27)
				)
				(justify mirror)
			)
		)
		(property "Value" ""
			(at 0 0 0)
			(layer "B.Fab")
			(effects
				(font
					(size 1.27 1.27)
				)
				(justify mirror)
			)
		)
		(duplicate_pad_numbers_are_jumpers no)
		(fp_line
			(start -1.27 0.5842)
			(end -1.27 -0.5842)
			(stroke
				(width 0.1524)
				(type default)
			)
			(layer "B.SilkS")
		)
		(fp_line
			(start -1.27 0.5842)
			(end 1.27 0.5842)
			(stroke
				(width 0.1524)
				(type default)
			)
			(layer "B.SilkS")
		)
		(fp_line
			(start -0.127 0.5842)
			(end -0.127 -0.5842)
			(stroke
				(width 0.1524)
				(type default)
			)
			(layer "B.SilkS")
		)
		(fp_line
			(start 0.127 0.5842)
			(end 0.127 -0.5842)
			(stroke
				(width 0.1524)
				(type default)
			)
			(layer "B.SilkS")
		)
		(fp_line
			(start 1.27 -0.5842)
			(end -1.27 -0.5842)
			(stroke
				(width 0.1524)
				(type default)
			)
			(layer "B.SilkS")
		)
		(fp_line
			(start 1.27 -0.5588)
			(end 1.27 -0.5842)
			(stroke
				(width 0.1524)
				(type default)
			)
			(layer "B.SilkS")
		)
		(fp_line
			(start 1.27 0.5842)
			(end 1.27 -0.5842)
			(stroke
				(width 0.1524)
				(type default)
			)
			(layer "B.SilkS")
		)
		(fp_line
			(start -1.1938 -0.406654)
			(end -1.1938 0.4064)
			(stroke
				(width 0.1)
				(type default)
			)
			(layer "B.Fab")
		)
		(fp_line
			(start -1.1938 0.4064)
			(end -0.9144 0.4064)
			(stroke
				(width 0.1)
				(type default)
			)
			(layer "B.Fab")
		)
		(fp_line
			(start -0.9144 -0.508)
			(end -0.9144 -0.406654)
			(stroke
				(width 0.1)
				(type default)
			)
			(layer "B.Fab")
		)
		(fp_line
			(start -0.9144 -0.406654)
			(end -1.1938 -0.406654)
			(stroke
				(width 0.1)
				(type default)
			)
			(layer "B.Fab")
		)
		(fp_line
			(start -0.9144 0.4064)
			(end -0.9144 0.508)
			(stroke
				(width 0.1)
				(type default)
			)
			(layer "B.Fab")
		)
		(fp_line
			(start -0.9144 0.508)
			(end 0.9144 0.508)
			(stroke
				(width 0.1)
				(type default)
			)
			(layer "B.Fab")
		)
		(fp_line
			(start 0.9144 -0.508)
			(end -0.9144 -0.508)
			(stroke
				(width 0.1)
				(type default)
			)
			(layer "B.Fab")
		)
		(fp_line
			(start 0.9144 -0.406654)
			(end 0.9144 -0.508)
			(stroke
				(width 0.1)
				(type default)
			)
			(layer "B.Fab")
		)
		(fp_line
			(start 0.9144 0.406654)
			(end 1.194308 0.406654)
			(stroke
				(width 0.1)
				(type default)
			)
			(layer "B.Fab")
		)
		(fp_line
			(start 0.9144 0.508)
			(end 0.9144 0.406654)
			(stroke
				(width 0.1)
				(type default)
			)
			(layer "B.Fab")
		)
		(fp_line
			(start 1.194308 -0.406654)
			(end 0.9144 -0.406654)
			(stroke
				(width 0.1)
				(type default)
			)
			(layer "B.Fab")
		)
		(fp_line
			(start 1.194308 0.406654)
			(end 1.194308 -0.406654)
			(stroke
				(width 0.1)
				(type default)
			)
			(layer "B.Fab")
		)
		(pad "1" smd rect
			(at 0.7366 0 270)
			(size 0.7112 0.8128)
			(layers "B.Cu" "B.Mask" "B.Paste")
			(net "P1V2_AUX")
		)
		(pad "2" smd rect
			(at -0.7366 0 270)
			(size 0.7112 0.8128)
			(layers "B.Cu" "B.Mask" "B.Paste")
			(net "P3V3_STBY_PLLAHVDD")
		)
	)
	(footprint ""
		(layer "B.Cu")
		(at 69.342 -43.307)
		(property "Reference" "L11"
			(at 0 0 0)
			(layer "B.SilkS")
			(hide yes)
			(effects
				(font
					(size 1.27 1.27)
				)
				(justify mirror)
			)
		)
		(property "Value" ""
			(at 0 0 0)
			(layer "B.Fab")
			(effects
				(font
					(size 1.27 1.27)
				)
				(justify mirror)
			)
		)
		(duplicate_pad_numbers_are_jumpers no)
		(fp_line
			(start -1.27 0.5842)
			(end -1.27 -0.5842)
			(stroke
				(width 0.1524)
				(type default)
			)
			(layer "B.SilkS")
		)
		(fp_line
			(start -1.27 0.5842)
			(end 1.27 0.5842)
			(stroke
				(width 0.1524)
				(type default)
			)
			(layer "B.SilkS")
		)
		(fp_line
			(start -0.127 0.5842)
			(end -0.127 -0.5842)
			(stroke
				(width 0.1524)
				(type default)
			)
			(layer "B.SilkS")
		)
		(fp_line
			(start 0.127 0.5842)
			(end 0.127 -0.5842)
			(stroke
				(width 0.1524)
				(type default)
			)
			(layer "B.SilkS")
		)
		(fp_line
			(start 1.27 -0.5842)
			(end -1.27 -0.5842)
			(stroke
				(width 0.1524)
				(type default)
			)
			(layer "B.SilkS")
		)
		(fp_line
			(start 1.27 -0.5588)
			(end 1.27 -0.5842)
			(stroke
				(width 0.1524)
				(type default)
			)
			(layer "B.SilkS")
		)
		(fp_line
			(start 1.27 0.5842)
			(end 1.27 -0.5842)
			(stroke
				(width 0.1524)
				(type default)
			)
			(layer "B.SilkS")
		)
		(fp_line
			(start -1.1938 -0.406654)
			(end -1.1938 0.4064)
			(stroke
				(width 0.1)
				(type default)
			)
			(layer "B.Fab")
		)
		(fp_line
			(start -1.1938 0.4064)
			(end -0.9144 0.4064)
			(stroke
				(width 0.1)
				(type default)
			)
			(layer "B.Fab")
		)
		(fp_line
			(start -0.9144 -0.508)
			(end -0.9144 -0.406654)
			(stroke
				(width 0.1)
				(type default)
			)
			(layer "B.Fab")
		)
		(fp_line
			(start -0.9144 -0.406654)
			(end -1.1938 -0.406654)
			(stroke
				(width 0.1)
				(type default)
			)
			(layer "B.Fab")
		)
		(fp_line
			(start -0.9144 0.4064)
			(end -0.9144 0.508)
			(stroke
				(width 0.1)
				(type default)
			)
			(layer "B.Fab")
		)
		(fp_line
			(start -0.9144 0.508)
			(end 0.9144 0.508)
			(stroke
				(width 0.1)
				(type default)
			)
			(layer "B.Fab")
		)
		(fp_line
			(start 0.9144 -0.508)
			(end -0.9144 -0.508)
			(stroke
				(width 0.1)
				(type default)
			)
			(layer "B.Fab")
		)
		(fp_line
			(start 0.9144 -0.406654)
			(end 0.9144 -0.508)
			(stroke
				(width 0.1)
				(type default)
			)
			(layer "B.Fab")
		)
		(fp_line
			(start 0.9144 0.406654)
			(end 1.194308 0.406654)
			(stroke
				(width 0.1)
				(type default)
			)
			(layer "B.Fab")
		)
		(fp_line
			(start 0.9144 0.508)
			(end 0.9144 0.406654)
			(stroke
				(width 0.1)
				(type default)
			)
			(layer "B.Fab")
		)
		(fp_line
			(start 1.194308 -0.406654)
			(end 0.9144 -0.406654)
			(stroke
				(width 0.1)
				(type default)
			)
			(layer "B.Fab")
		)
		(fp_line
			(start 1.194308 0.406654)
			(end 1.194308 -0.406654)
			(stroke
				(width 0.1)
				(type default)
			)
			(layer "B.Fab")
		)
		(pad "1" smd rect
			(at 0.7366 0 270)
			(size 0.7112 0.8128)
			(layers "B.Cu" "B.Mask" "B.Paste")
			(net "P1V2_AUX")
		)
		(pad "2" smd rect
			(at -0.7366 0 270)
			(size 0.7112 0.8128)
			(layers "B.Cu" "B.Mask" "B.Paste")
			(net "P1V2_STBY_MVDD_CK")
		)
	)
	(footprint ""
		(layer "B.Cu")
		(at 58.77941 -30.867604 -90)
		(property "Reference" "R254"
			(at 0 0 90)
			(layer "B.SilkS")
			(hide yes)
			(effects
				(font
					(size 1.27 1.27)
				)
				(justify mirror)
			)
		)
		(property "Value" ""
			(at 0 0 90)
			(layer "B.Fab")
			(effects
				(font
					(size 1.27 1.27)
				)
				(justify mirror)
			)
		)
		(duplicate_pad_numbers_are_jumpers no)
		(fp_line
			(start -0.7874 0.4064)
			(end 0.7874 0.4064)
			(stroke
				(width 0.1524)
				(type default)
			)
			(layer "B.SilkS")
		)
		(fp_line
			(start 0.7874 0.4064)
			(end 0.7874 -0.4064)
			(stroke
				(width 0.1524)
				(type default)
			)
			(layer "B.SilkS")
		)
		(fp_line
			(start -0.7874 -0.4064)
			(end -0.7874 0.4064)
			(stroke
				(width 0.1524)
				(type default)
			)
			(layer "B.SilkS")
		)
		(fp_line
			(start 0.7874 -0.4064)
			(end -0.7874 -0.4064)
			(stroke
				(width 0.1524)
				(type default)
			)
			(layer "B.SilkS")
		)
		(fp_line
			(start -0.67945 0.3048)
			(end -0.120396 0.3048)
			(stroke
				(width 0.1)
				(type default)
			)
			(layer "B.Fab")
		)
		(fp_line
			(start -0.120396 0.3048)
			(end -0.120396 0.2794)
			(stroke
				(width 0.1)
				(type default)
			)
			(layer "B.Fab")
		)
		(fp_line
			(start 0.12065 0.3048)
			(end 0.67945 0.3048)
			(stroke
				(width 0.1)
				(type default)
			)
			(layer "B.Fab")
		)
		(fp_line
			(start 0.67945 0.3048)
			(end 0.67945 -0.305054)
			(stroke
				(width 0.1)
				(type default)
			)
			(layer "B.Fab")
		)
		(fp_line
			(start -0.120396 0.2794)
			(end 0.12065 0.2794)
			(stroke
				(width 0.1)
				(type default)
			)
			(layer "B.Fab")
		)
		(fp_line
			(start 0.12065 0.2794)
			(end 0.12065 0.3048)
			(stroke
				(width 0.1)
				(type default)
			)
			(layer "B.Fab")
		)
		(fp_line
			(start -0.12065 -0.2794)
			(end -0.12065 -0.3048)
			(stroke
				(width 0.1)
				(type default)
			)
			(layer "B.Fab")
		)
		(fp_line
			(start 0.12065 -0.2794)
			(end -0.12065 -0.2794)
			(stroke
				(width 0.1)
				(type default)
			)
			(layer "B.Fab")
		)
		(fp_line
			(start -0.67945 -0.3048)
			(end -0.67945 0.3048)
			(stroke
				(width 0.1)
				(type default)
			)
			(layer "B.Fab")
		)
		(fp_line
			(start -0.12065 -0.3048)
			(end -0.67945 -0.3048)
			(stroke
				(width 0.1)
				(type default)
			)
			(layer "B.Fab")
		)
		(fp_line
			(start 0.12065 -0.305054)
			(end 0.12065 -0.2794)
			(stroke
				(width 0.1)
				(type default)
			)
			(layer "B.Fab")
		)
		(fp_line
			(start 0.67945 -0.305054)
			(end 0.12065 -0.305054)
			(stroke
				(width 0.1)
				(type default)
			)
			(layer "B.Fab")
		)
		(pad "1" smd circle
			(at 0.40005 0 90)
			(size 0 0)
			(layers "B.Cu" "B.Mask" "B.Paste")
			(net "P3V3_AUX")
		)
		(pad "2" smd circle
			(at -0.40005 0 90)
			(size 0 0)
			(layers "B.Cu" "B.Mask" "B.Paste")
			(net "SMB_BMC_MM6_SCL")
		)
	)
	(footprint ""
		(layer "B.Cu")
		(at 29.3624 -30.35935 -90)
		(property "Reference" "C207"
			(at 0 0 90)
			(layer "B.SilkS")
			(hide yes)
			(effects
				(font
					(size 1.27 1.27)
				)
				(justify mirror)
			)
		)
		(property "Value" ""
			(at 0 0 90)
			(layer "B.Fab")
			(effects
				(font
					(size 1.27 1.27)
				)
				(justify mirror)
			)
		)
		(duplicate_pad_numbers_are_jumpers no)
		(fp_line
			(start -0.7874 0.4064)
			(end 0.7874 0.4064)
			(stroke
				(width 0.1524)
				(type default)
			)
			(layer "B.SilkS")
		)
		(fp_line
			(start 0.7874 0.4064)
			(end 0.7874 -0.4064)
			(stroke
				(width 0.1524)
				(type default)
			)
			(layer "B.SilkS")
		)
		(fp_line
			(start -0.7874 -0.4064)
			(end -0.7874 0.4064)
			(stroke
				(width 0.1524)
				(type default)
			)
			(layer "B.SilkS")
		)
		(fp_line
			(start 0.7874 -0.4064)
			(end -0.7874 -0.4064)
			(stroke
				(width 0.1524)
				(type default)
			)
			(layer "B.SilkS")
		)
		(fp_line
			(start -0.67945 0.3048)
			(end -0.120396 0.3048)
			(stroke
				(width 0.1)
				(type default)
			)
			(layer "B.Fab")
		)
		(fp_line
			(start -0.120396 0.3048)
			(end -0.120396 0.2794)
			(stroke
				(width 0.1)
				(type default)
			)
			(layer "B.Fab")
		)
		(fp_line
			(start 0.12065 0.3048)
			(end 0.67945 0.3048)
			(stroke
				(width 0.1)
				(type default)
			)
			(layer "B.Fab")
		)
		(fp_line
			(start 0.67945 0.3048)
			(end 0.67945 -0.305054)
			(stroke
				(width 0.1)
				(type default)
			)
			(layer "B.Fab")
		)
		(fp_line
			(start -0.120396 0.2794)
			(end 0.12065 0.2794)
			(stroke
				(width 0.1)
				(type default)
			)
			(layer "B.Fab")
		)
		(fp_line
			(start 0.12065 0.2794)
			(end 0.12065 0.3048)
			(stroke
				(width 0.1)
				(type default)
			)
			(layer "B.Fab")
		)
		(fp_line
			(start -0.12065 -0.2794)
			(end -0.12065 -0.3048)
			(stroke
				(width 0.1)
				(type default)
			)
			(layer "B.Fab")
		)
		(fp_line
			(start 0.12065 -0.2794)
			(end -0.12065 -0.2794)
			(stroke
				(width 0.1)
				(type default)
			)
			(layer "B.Fab")
		)
		(fp_line
			(start -0.67945 -0.3048)
			(end -0.67945 0.3048)
			(stroke
				(width 0.1)
				(type default)
			)
			(layer "B.Fab")
		)
		(fp_line
			(start -0.12065 -0.3048)
			(end -0.67945 -0.3048)
			(stroke
				(width 0.1)
				(type default)
			)
			(layer "B.Fab")
		)
		(fp_line
			(start 0.12065 -0.305054)
			(end 0.12065 -0.2794)
			(stroke
				(width 0.1)
				(type default)
			)
			(layer "B.Fab")
		)
		(fp_line
			(start 0.67945 -0.305054)
			(end 0.12065 -0.305054)
			(stroke
				(width 0.1)
				(type default)
			)
			(layer "B.Fab")
		)
		(pad "1" smd circle
			(at 0.40005 0 90)
			(size 0 0)
			(layers "B.Cu" "B.Mask" "B.Paste")
			(net "V_DACB")
		)
		(pad "2" smd circle
			(at -0.40005 0 90)
			(size 0 0)
			(layers "B.Cu" "B.Mask" "B.Paste")
			(net "GND")
		)
	)
	(footprint ""
		(layer "B.Cu")
		(at 59.706256 -54.416198 -90)
		(property "Reference" "C130"
			(at 0 0 90)
			(layer "B.SilkS")
			(hide yes)
			(effects
				(font
					(size 1.27 1.27)
				)
				(justify mirror)
			)
		)
		(property "Value" ""
			(at 0 0 90)
			(layer "B.Fab")
			(effects
				(font
					(size 1.27 1.27)
				)
				(justify mirror)
			)
		)
		(duplicate_pad_numbers_are_jumpers no)
		(fp_line
			(start -0.7874 0.4064)
			(end 0.7874 0.4064)
			(stroke
				(width 0.1524)
				(type default)
			)
			(layer "B.SilkS")
		)
		(fp_line
			(start 0.7874 0.4064)
			(end 0.7874 -0.4064)
			(stroke
				(width 0.1524)
				(type default)
			)
			(layer "B.SilkS")
		)
		(fp_line
			(start -0.7874 -0.4064)
			(end -0.7874 0.4064)
			(stroke
				(width 0.1524)
				(type default)
			)
			(layer "B.SilkS")
		)
		(fp_line
			(start 0.7874 -0.4064)
			(end -0.7874 -0.4064)
			(stroke
				(width 0.1524)
				(type default)
			)
			(layer "B.SilkS")
		)
		(fp_line
			(start -0.67945 0.3048)
			(end -0.120396 0.3048)
			(stroke
				(width 0.1)
				(type default)
			)
			(layer "B.Fab")
		)
		(fp_line
			(start -0.120396 0.3048)
			(end -0.120396 0.2794)
			(stroke
				(width 0.1)
				(type default)
			)
			(layer "B.Fab")
		)
		(fp_line
			(start 0.12065 0.3048)
			(end 0.67945 0.3048)
			(stroke
				(width 0.1)
				(type default)
			)
			(layer "B.Fab")
		)
		(fp_line
			(start 0.67945 0.3048)
			(end 0.67945 -0.305054)
			(stroke
				(width 0.1)
				(type default)
			)
			(layer "B.Fab")
		)
		(fp_line
			(start -0.120396 0.2794)
			(end 0.12065 0.2794)
			(stroke
				(width 0.1)
				(type default)
			)
			(layer "B.Fab")
		)
		(fp_line
			(start 0.12065 0.2794)
			(end 0.12065 0.3048)
			(stroke
				(width 0.1)
				(type default)
			)
			(layer "B.Fab")
		)
		(fp_line
			(start -0.12065 -0.2794)
			(end -0.12065 -0.3048)
			(stroke
				(width 0.1)
				(type default)
			)
			(layer "B.Fab")
		)
		(fp_line
			(start 0.12065 -0.2794)
			(end -0.12065 -0.2794)
			(stroke
				(width 0.1)
				(type default)
			)
			(layer "B.Fab")
		)
		(fp_line
			(start -0.67945 -0.3048)
			(end -0.67945 0.3048)
			(stroke
				(width 0.1)
				(type default)
			)
			(layer "B.Fab")
		)
		(fp_line
			(start -0.12065 -0.3048)
			(end -0.67945 -0.3048)
			(stroke
				(width 0.1)
				(type default)
			)
			(layer "B.Fab")
		)
		(fp_line
			(start 0.12065 -0.305054)
			(end 0.12065 -0.2794)
			(stroke
				(width 0.1)
				(type default)
			)
			(layer "B.Fab")
		)
		(fp_line
			(start 0.67945 -0.305054)
			(end 0.12065 -0.305054)
			(stroke
				(width 0.1)
				(type default)
			)
			(layer "B.Fab")
		)
		(pad "1" smd circle
			(at 0.40005 0 90)
			(size 0 0)
			(layers "B.Cu" "B.Mask" "B.Paste")
			(net "P1V8_STBY_DP_VCC18A")
		)
		(pad "2" smd circle
			(at -0.40005 0 90)
			(size 0 0)
			(layers "B.Cu" "B.Mask" "B.Paste")
			(net "GND")
		)
	)
	(footprint ""
		(layer "B.Cu")
		(at 46.355 -96.8248 90)
		(property "Reference" "C238"
			(at 0 0 90)
			(layer "B.SilkS")
			(hide yes)
			(effects
				(font
					(size 1.27 1.27)
				)
				(justify mirror)
			)
		)
		(property "Value" ""
			(at 0 0 90)
			(layer "B.Fab")
			(effects
				(font
					(size 1.27 1.27)
				)
				(justify mirror)
			)
		)
		(duplicate_pad_numbers_are_jumpers no)
		(fp_line
			(start 0.7874 -0.4064)
			(end -0.7874 -0.4064)
			(stroke
				(width 0.1524)
				(type default)
			)
			(layer "B.SilkS")
		)
		(fp_line
			(start -0.7874 -0.4064)
			(end -0.7874 0.4064)
			(stroke
				(width 0.1524)
				(type default)
			)
			(layer "B.SilkS")
		)
		(fp_line
			(start 0.7874 0.4064)
			(end 0.7874 -0.4064)
			(stroke
				(width 0.1524)
				(type default)
			)
			(layer "B.SilkS")
		)
		(fp_line
			(start -0.7874 0.4064)
			(end 0.7874 0.4064)
			(stroke
				(width 0.1524)
				(type default)
			)
			(layer "B.SilkS")
		)
		(fp_line
			(start 0.67945 -0.305054)
			(end 0.12065 -0.305054)
			(stroke
				(width 0.1)
				(type default)
			)
			(layer "B.Fab")
		)
		(fp_line
			(start 0.12065 -0.305054)
			(end 0.12065 -0.2794)
			(stroke
				(width 0.1)
				(type default)
			)
			(layer "B.Fab")
		)
		(fp_line
			(start -0.12065 -0.3048)
			(end -0.67945 -0.3048)
			(stroke
				(width 0.1)
				(type default)
			)
			(layer "B.Fab")
		)
		(fp_line
			(start -0.67945 -0.3048)
			(end -0.67945 0.3048)
			(stroke
				(width 0.1)
				(type default)
			)
			(layer "B.Fab")
		)
		(fp_line
			(start 0.12065 -0.2794)
			(end -0.12065 -0.2794)
			(stroke
				(width 0.1)
				(type default)
			)
			(layer "B.Fab")
		)
		(fp_line
			(start -0.12065 -0.2794)
			(end -0.12065 -0.3048)
			(stroke
				(width 0.1)
				(type default)
			)
			(layer "B.Fab")
		)
		(fp_line
			(start 0.12065 0.2794)
			(end 0.12065 0.3048)
			(stroke
				(width 0.1)
				(type default)
			)
			(layer "B.Fab")
		)
		(fp_line
			(start -0.120396 0.2794)
			(end 0.12065 0.2794)
			(stroke
				(width 0.1)
				(type default)
			)
			(layer "B.Fab")
		)
		(fp_line
			(start 0.67945 0.3048)
			(end 0.67945 -0.305054)
			(stroke
				(width 0.1)
				(type default)
			)
			(layer "B.Fab")
		)
		(fp_line
			(start 0.12065 0.3048)
			(end 0.67945 0.3048)
			(stroke
				(width 0.1)
				(type default)
			)
			(layer "B.Fab")
		)
		(fp_line
			(start -0.120396 0.3048)
			(end -0.120396 0.2794)
			(stroke
				(width 0.1)
				(type default)
			)
			(layer "B.Fab")
		)
		(fp_line
			(start -0.67945 0.3048)
			(end -0.120396 0.3048)
			(stroke
				(width 0.1)
				(type default)
			)
			(layer "B.Fab")
		)
		(pad "1" smd circle
			(at 0.40005 0 270)
			(size 0 0)
			(layers "B.Cu" "B.Mask" "B.Paste")
			(net "USB3_FPNL_TXP")
		)
		(pad "2" smd circle
			(at -0.40005 0 270)
			(size 0 0)
			(layers "B.Cu" "B.Mask" "B.Paste")
			(net "USB3_01_TXP_C")
		)
	)
	(footprint ""
		(layer "B.Cu")
		(at 26.543 -99.695 45)
		(property "Reference" "C286"
			(at 0 0 45)
			(layer "B.SilkS")
			(hide yes)
			(effects
				(font
					(size 1.27 1.27)
				)
				(justify mirror)
			)
		)
		(property "Value" ""
			(at 0 0 45)
			(layer "B.Fab")
			(effects
				(font
					(size 1.27 1.27)
				)
				(justify mirror)
			)
		)
		(duplicate_pad_numbers_are_jumpers no)
		(fp_line
			(start -0.787389 -0.406267)
			(end -0.787389 0.406267)
			(stroke
				(width 0.1524)
				(type default)
			)
			(layer "B.SilkS")
		)
		(fp_line
			(start -0.787389 0.406267)
			(end 0.787389 0.406267)
			(stroke
				(width 0.1524)
				(type default)
			)
			(layer "B.SilkS")
		)
		(fp_line
			(start 0.787389 -0.406267)
			(end -0.787389 -0.406267)
			(stroke
				(width 0.1524)
				(type default)
			)
			(layer "B.SilkS")
		)
		(fp_line
			(start 0.787389 0.406267)
			(end 0.787389 -0.406267)
			(stroke
				(width 0.1524)
				(type default)
			)
			(layer "B.SilkS")
		)
		(fp_line
			(start -0.679446 -0.30479)
			(end -0.679446 0.30479)
			(stroke
				(width 0.1)
				(type default)
			)
			(layer "B.Fab")
		)
		(fp_line
			(start -0.120515 -0.30479)
			(end -0.679446 -0.30479)
			(stroke
				(width 0.1)
				(type default)
			)
			(layer "B.Fab")
		)
		(fp_line
			(start -0.120695 -0.279466)
			(end -0.120515 -0.30479)
			(stroke
				(width 0.1)
				(type default)
			)
			(layer "B.Fab")
		)
		(fp_line
			(start -0.679446 0.30479)
			(end -0.120515 0.30479)
			(stroke
				(width 0.1)
				(type default)
			)
			(layer "B.Fab")
		)
		(fp_line
			(start 0.120695 -0.304969)
			(end 0.120695 -0.279466)
			(stroke
				(width 0.1)
				(type default)
			)
			(layer "B.Fab")
		)
		(fp_line
			(start 0.120695 -0.279466)
			(end -0.120695 -0.279466)
			(stroke
				(width 0.1)
				(type default)
			)
			(layer "B.Fab")
		)
		(fp_line
			(start -0.120335 0.279466)
			(end 0.120695 0.279466)
			(stroke
				(width 0.1)
				(type default)
			)
			(layer "B.Fab")
		)
		(fp_line
			(start -0.120515 0.30479)
			(end -0.120335 0.279466)
			(stroke
				(width 0.1)
				(type default)
			)
			(layer "B.Fab")
		)
		(fp_line
			(start 0.679446 -0.305149)
			(end 0.120695 -0.304969)
			(stroke
				(width 0.1)
				(type default)
			)
			(layer "B.Fab")
		)
		(fp_line
			(start 0.120695 0.279466)
			(end 0.120515 0.30479)
			(stroke
				(width 0.1)
				(type default)
			)
			(layer "B.Fab")
		)
		(fp_line
			(start 0.120515 0.30479)
			(end 0.679446 0.30479)
			(stroke
				(width 0.1)
				(type default)
			)
			(layer "B.Fab")
		)
		(fp_line
			(start 0.679446 0.30479)
			(end 0.679446 -0.305149)
			(stroke
				(width 0.1)
				(type default)
			)
			(layer "B.Fab")
		)
		(pad "1" smd circle
			(at 0.40005 0 225)
			(size 0 0)
			(layers "B.Cu" "B.Mask" "B.Paste")
			(net "PVCCA_AUX_PLD")
		)
		(pad "2" smd circle
			(at -0.40005 0 225)
			(size 0 0)
			(layers "B.Cu" "B.Mask" "B.Paste")
			(net "GND")
		)
	)
	(footprint ""
		(layer "B.Cu")
		(at 71.034656 -53.215794)
		(property "Reference" "C6"
			(at 0 0 0)
			(layer "B.SilkS")
			(hide yes)
			(effects
				(font
					(size 1.27 1.27)
				)
				(justify mirror)
			)
		)
		(property "Value" ""
			(at 0 0 0)
			(layer "B.Fab")
			(effects
				(font
					(size 1.27 1.27)
				)
				(justify mirror)
			)
		)
		(duplicate_pad_numbers_are_jumpers no)
		(fp_line
			(start -0.7874 -0.4064)
			(end -0.7874 0.4064)
			(stroke
				(width 0.1524)
				(type default)
			)
			(layer "B.SilkS")
		)
		(fp_line
			(start -0.7874 0.4064)
			(end 0.7874 0.4064)
			(stroke
				(width 0.1524)
				(type default)
			)
			(layer "B.SilkS")
		)
		(fp_line
			(start 0.7874 -0.4064)
			(end -0.7874 -0.4064)
			(stroke
				(width 0.1524)
				(type default)
			)
			(layer "B.SilkS")
		)
		(fp_line
			(start 0.7874 0.4064)
			(end 0.7874 -0.4064)
			(stroke
				(width 0.1524)
				(type default)
			)
			(layer "B.SilkS")
		)
		(fp_line
			(start -0.67945 -0.3048)
			(end -0.67945 0.3048)
			(stroke
				(width 0.1)
				(type default)
			)
			(layer "B.Fab")
		)
		(fp_line
			(start -0.67945 0.3048)
			(end -0.120396 0.3048)
			(stroke
				(width 0.1)
				(type default)
			)
			(layer "B.Fab")
		)
		(fp_line
			(start -0.12065 -0.3048)
			(end -0.67945 -0.3048)
			(stroke
				(width 0.1)
				(type default)
			)
			(layer "B.Fab")
		)
		(fp_line
			(start -0.12065 -0.2794)
			(end -0.12065 -0.3048)
			(stroke
				(width 0.1)
				(type default)
			)
			(layer "B.Fab")
		)
		(fp_line
			(start -0.120396 0.2794)
			(end 0.12065 0.2794)
			(stroke
				(width 0.1)
				(type default)
			)
			(layer "B.Fab")
		)
		(fp_line
			(start -0.120396 0.3048)
			(end -0.120396 0.2794)
			(stroke
				(width 0.1)
				(type default)
			)
			(layer "B.Fab")
		)
		(fp_line
			(start 0.12065 -0.305054)
			(end 0.12065 -0.2794)
			(stroke
				(width 0.1)
				(type default)
			)
			(layer "B.Fab")
		)
		(fp_line
			(start 0.12065 -0.2794)
			(end -0.12065 -0.2794)
			(stroke
				(width 0.1)
				(type default)
			)
			(layer "B.Fab")
		)
		(fp_line
			(start 0.12065 0.2794)
			(end 0.12065 0.3048)
			(stroke
				(width 0.1)
				(type default)
			)
			(layer "B.Fab")
		)
		(fp_line
			(start 0.12065 0.3048)
			(end 0.67945 0.3048)
			(stroke
				(width 0.1)
				(type default)
			)
			(layer "B.Fab")
		)
		(fp_line
			(start 0.67945 -0.305054)
			(end 0.12065 -0.305054)
			(stroke
				(width 0.1)
				(type default)
			)
			(layer "B.Fab")
		)
		(fp_line
			(start 0.67945 0.3048)
			(end 0.67945 -0.305054)
			(stroke
				(width 0.1)
				(type default)
			)
			(layer "B.Fab")
		)
		(pad "1" smd circle
			(at 0.40005 0 180)
			(size 0 0)
			(layers "B.Cu" "B.Mask" "B.Paste")
			(net "P2V5_AUX")
		)
		(pad "2" smd circle
			(at -0.40005 0 180)
			(size 0 0)
			(layers "B.Cu" "B.Mask" "B.Paste")
			(net "GND")
		)
	)
	(footprint ""
		(layer "B.Cu")
		(at 83.947 -58.7248 90)
		(property "Reference" "C132"
			(at 0 0 90)
			(layer "B.SilkS")
			(hide yes)
			(effects
				(font
					(size 1.27 1.27)
				)
				(justify mirror)
			)
		)
		(property "Value" ""
			(at 0 0 90)
			(layer "B.Fab")
			(effects
				(font
					(size 1.27 1.27)
				)
				(justify mirror)
			)
		)
		(duplicate_pad_numbers_are_jumpers no)
		(fp_line
			(start 1.2954 -0.5842)
			(end -1.2954 -0.5842)
			(stroke
				(width 0.1524)
				(type default)
			)
			(layer "B.SilkS")
		)
		(fp_line
			(start 0 -0.5842)
			(end 0 0.5842)
			(stroke
				(width 0.1524)
				(type default)
			)
			(layer "B.SilkS")
		)
		(fp_line
			(start -1.2954 -0.5842)
			(end -1.2954 0.5842)
			(stroke
				(width 0.1524)
				(type default)
			)
			(layer "B.SilkS")
		)
		(fp_line
			(start 1.2954 0.5842)
			(end 1.2954 -0.5842)
			(stroke
				(width 0.1524)
				(type default)
			)
			(layer "B.SilkS")
		)
		(fp_line
			(start -1.2954 0.5842)
			(end 1.2954 0.5842)
			(stroke
				(width 0.1524)
				(type default)
			)
			(layer "B.SilkS")
		)
		(fp_line
			(start 0.8636 -0.4572)
			(end -0.8636 -0.4572)
			(stroke
				(width 0.1)
				(type default)
			)
			(layer "B.Fab")
		)
		(fp_line
			(start -0.8636 -0.4572)
			(end -0.8636 -0.4064)
			(stroke
				(width 0.1)
				(type default)
			)
			(layer "B.Fab")
		)
		(fp_line
			(start 1.1938 -0.4064)
			(end 0.8636 -0.4064)
			(stroke
				(width 0.1)
				(type default)
			)
			(layer "B.Fab")
		)
		(fp_line
			(start 0.8636 -0.4064)
			(end 0.8636 -0.4572)
			(stroke
				(width 0.1)
				(type default)
			)
			(layer "B.Fab")
		)
		(fp_line
			(start -0.8636 -0.4064)
			(end -1.1938 -0.4064)
			(stroke
				(width 0.1)
				(type default)
			)
			(layer "B.Fab")
		)
		(fp_line
			(start -1.1938 -0.4064)
			(end -1.1938 0.4064)
			(stroke
				(width 0.1)
				(type default)
			)
			(layer "B.Fab")
		)
		(fp_line
			(start 1.1938 0.4064)
			(end 1.1938 -0.4064)
			(stroke
				(width 0.1)
				(type default)
			)
			(layer "B.Fab")
		)
		(fp_line
			(start 0.8636 0.4064)
			(end 1.1938 0.4064)
			(stroke
				(width 0.1)
				(type default)
			)
			(layer "B.Fab")
		)
		(fp_line
			(start -0.8636 0.4064)
			(end -0.8636 0.4572)
			(stroke
				(width 0.1)
				(type default)
			)
			(layer "B.Fab")
		)
		(fp_line
			(start -1.1938 0.4064)
			(end -0.8636 0.4064)
			(stroke
				(width 0.1)
				(type default)
			)
			(layer "B.Fab")
		)
		(fp_line
			(start 0.8636 0.4572)
			(end 0.8636 0.4064)
			(stroke
				(width 0.1)
				(type default)
			)
			(layer "B.Fab")
		)
		(fp_line
			(start -0.8636 0.4572)
			(end 0.8636 0.4572)
			(stroke
				(width 0.1)
				(type default)
			)
			(layer "B.Fab")
		)
		(pad "1" smd rect
			(at 0.7366 0)
			(size 0.7112 0.8128)
			(layers "B.Cu" "B.Mask" "B.Paste")
			(net "P1V2_AUX")
		)
		(pad "2" smd rect
			(at -0.7366 0)
			(size 0.7112 0.8128)
			(layers "B.Cu" "B.Mask" "B.Paste")
			(net "GND")
		)
	)
	(footprint ""
		(layer "B.Cu")
		(at 16.2814 -83.693 -90)
		(property "Reference" "R163"
			(at 0 0 90)
			(layer "B.SilkS")
			(hide yes)
			(effects
				(font
					(size 1.27 1.27)
				)
				(justify mirror)
			)
		)
		(property "Value" ""
			(at 0 0 90)
			(layer "B.Fab")
			(effects
				(font
					(size 1.27 1.27)
				)
				(justify mirror)
			)
		)
		(duplicate_pad_numbers_are_jumpers no)
		(fp_line
			(start -0.7874 0.4064)
			(end 0.7874 0.4064)
			(stroke
				(width 0.1524)
				(type default)
			)
			(layer "B.SilkS")
		)
		(fp_line
			(start 0.7874 0.4064)
			(end 0.7874 -0.4064)
			(stroke
				(width 0.1524)
				(type default)
			)
			(layer "B.SilkS")
		)
		(fp_line
			(start -0.7874 -0.4064)
			(end -0.7874 0.4064)
			(stroke
				(width 0.1524)
				(type default)
			)
			(layer "B.SilkS")
		)
		(fp_line
			(start 0.7874 -0.4064)
			(end -0.7874 -0.4064)
			(stroke
				(width 0.1524)
				(type default)
			)
			(layer "B.SilkS")
		)
		(fp_line
			(start -0.67945 0.3048)
			(end -0.120396 0.3048)
			(stroke
				(width 0.1)
				(type default)
			)
			(layer "B.Fab")
		)
		(fp_line
			(start -0.120396 0.3048)
			(end -0.120396 0.2794)
			(stroke
				(width 0.1)
				(type default)
			)
			(layer "B.Fab")
		)
		(fp_line
			(start 0.12065 0.3048)
			(end 0.67945 0.3048)
			(stroke
				(width 0.1)
				(type default)
			)
			(layer "B.Fab")
		)
		(fp_line
			(start 0.67945 0.3048)
			(end 0.67945 -0.305054)
			(stroke
				(width 0.1)
				(type default)
			)
			(layer "B.Fab")
		)
		(fp_line
			(start -0.120396 0.2794)
			(end 0.12065 0.2794)
			(stroke
				(width 0.1)
				(type default)
			)
			(layer "B.Fab")
		)
		(fp_line
			(start 0.12065 0.2794)
			(end 0.12065 0.3048)
			(stroke
				(width 0.1)
				(type default)
			)
			(layer "B.Fab")
		)
		(fp_line
			(start -0.12065 -0.2794)
			(end -0.12065 -0.3048)
			(stroke
				(width 0.1)
				(type default)
			)
			(layer "B.Fab")
		)
		(fp_line
			(start 0.12065 -0.2794)
			(end -0.12065 -0.2794)
			(stroke
				(width 0.1)
				(type default)
			)
			(layer "B.Fab")
		)
		(fp_line
			(start -0.67945 -0.3048)
			(end -0.67945 0.3048)
			(stroke
				(width 0.1)
				(type default)
			)
			(layer "B.Fab")
		)
		(fp_line
			(start -0.12065 -0.3048)
			(end -0.67945 -0.3048)
			(stroke
				(width 0.1)
				(type default)
			)
			(layer "B.Fab")
		)
		(fp_line
			(start 0.12065 -0.305054)
			(end 0.12065 -0.2794)
			(stroke
				(width 0.1)
				(type default)
			)
			(layer "B.Fab")
		)
		(fp_line
			(start 0.67945 -0.305054)
			(end 0.12065 -0.305054)
			(stroke
				(width 0.1)
				(type default)
			)
			(layer "B.Fab")
		)
		(pad "1" smd circle
			(at 0.40005 0 90)
			(size 0 0)
			(layers "B.Cu" "B.Mask" "B.Paste")
			(net "P3V3_AUX")
		)
		(pad "2" smd circle
			(at -0.40005 0 90)
			(size 0 0)
			(layers "B.Cu" "B.Mask" "B.Paste")
			(net "FM_CPU_MSMI_CATERR_LVT3_N")
		)
	)
	(footprint ""
		(layer "B.Cu")
		(at 42.926 -19.431 -90)
		(property "Reference" "R205"
			(at 0 0 90)
			(layer "B.SilkS")
			(hide yes)
			(effects
				(font
					(size 1.27 1.27)
				)
				(justify mirror)
			)
		)
		(property "Value" ""
			(at 0 0 90)
			(layer "B.Fab")
			(effects
				(font
					(size 1.27 1.27)
				)
				(justify mirror)
			)
		)
		(duplicate_pad_numbers_are_jumpers no)
		(fp_line
			(start -0.7874 0.4064)
			(end 0.7874 0.4064)
			(stroke
				(width 0.1524)
				(type default)
			)
			(layer "B.SilkS")
		)
		(fp_line
			(start 0.7874 0.4064)
			(end 0.7874 -0.4064)
			(stroke
				(width 0.1524)
				(type default)
			)
			(layer "B.SilkS")
		)
		(fp_line
			(start -0.7874 -0.4064)
			(end -0.7874 0.4064)
			(stroke
				(width 0.1524)
				(type default)
			)
			(layer "B.SilkS")
		)
		(fp_line
			(start 0.7874 -0.4064)
			(end -0.7874 -0.4064)
			(stroke
				(width 0.1524)
				(type default)
			)
			(layer "B.SilkS")
		)
		(fp_line
			(start -0.67945 0.3048)
			(end -0.120396 0.3048)
			(stroke
				(width 0.1)
				(type default)
			)
			(layer "B.Fab")
		)
		(fp_line
			(start -0.120396 0.3048)
			(end -0.120396 0.2794)
			(stroke
				(width 0.1)
				(type default)
			)
			(layer "B.Fab")
		)
		(fp_line
			(start 0.12065 0.3048)
			(end 0.67945 0.3048)
			(stroke
				(width 0.1)
				(type default)
			)
			(layer "B.Fab")
		)
		(fp_line
			(start 0.67945 0.3048)
			(end 0.67945 -0.305054)
			(stroke
				(width 0.1)
				(type default)
			)
			(layer "B.Fab")
		)
		(fp_line
			(start -0.120396 0.2794)
			(end 0.12065 0.2794)
			(stroke
				(width 0.1)
				(type default)
			)
			(layer "B.Fab")
		)
		(fp_line
			(start 0.12065 0.2794)
			(end 0.12065 0.3048)
			(stroke
				(width 0.1)
				(type default)
			)
			(layer "B.Fab")
		)
		(fp_line
			(start -0.12065 -0.2794)
			(end -0.12065 -0.3048)
			(stroke
				(width 0.1)
				(type default)
			)
			(layer "B.Fab")
		)
		(fp_line
			(start 0.12065 -0.2794)
			(end -0.12065 -0.2794)
			(stroke
				(width 0.1)
				(type default)
			)
			(layer "B.Fab")
		)
		(fp_line
			(start -0.67945 -0.3048)
			(end -0.67945 0.3048)
			(stroke
				(width 0.1)
				(type default)
			)
			(layer "B.Fab")
		)
		(fp_line
			(start -0.12065 -0.3048)
			(end -0.67945 -0.3048)
			(stroke
				(width 0.1)
				(type default)
			)
			(layer "B.Fab")
		)
		(fp_line
			(start 0.12065 -0.305054)
			(end 0.12065 -0.2794)
			(stroke
				(width 0.1)
				(type default)
			)
			(layer "B.Fab")
		)
		(fp_line
			(start 0.67945 -0.305054)
			(end 0.12065 -0.305054)
			(stroke
				(width 0.1)
				(type default)
			)
			(layer "B.Fab")
		)
		(pad "1" smd circle
			(at 0.40005 0 90)
			(size 0 0)
			(layers "B.Cu" "B.Mask" "B.Paste")
			(net "DEBUG_PORT_PRSNT_R")
		)
		(pad "2" smd circle
			(at -0.40005 0 90)
			(size 0 0)
			(layers "B.Cu" "B.Mask" "B.Paste")
			(net "GND")
		)
	)
	(footprint ""
		(layer "B.Cu")
		(at 54.308502 -70.420484 90)
		(property "Reference" "R791"
			(at 0 0 90)
			(layer "B.SilkS")
			(hide yes)
			(effects
				(font
					(size 1.27 1.27)
				)
				(justify mirror)
			)
		)
		(property "Value" ""
			(at 0 0 90)
			(layer "B.Fab")
			(effects
				(font
					(size 1.27 1.27)
				)
				(justify mirror)
			)
		)
		(duplicate_pad_numbers_are_jumpers no)
		(fp_line
			(start 0.7874 -0.4064)
			(end -0.7874 -0.4064)
			(stroke
				(width 0.1524)
				(type default)
			)
			(layer "B.SilkS")
		)
		(fp_line
			(start -0.7874 -0.4064)
			(end -0.7874 0.4064)
			(stroke
				(width 0.1524)
				(type default)
			)
			(layer "B.SilkS")
		)
		(fp_line
			(start 0.7874 0.4064)
			(end 0.7874 -0.4064)
			(stroke
				(width 0.1524)
				(type default)
			)
			(layer "B.SilkS")
		)
		(fp_line
			(start -0.7874 0.4064)
			(end 0.7874 0.4064)
			(stroke
				(width 0.1524)
				(type default)
			)
			(layer "B.SilkS")
		)
		(fp_line
			(start 0.67945 -0.305054)
			(end 0.12065 -0.305054)
			(stroke
				(width 0.1)
				(type default)
			)
			(layer "B.Fab")
		)
		(fp_line
			(start 0.12065 -0.305054)
			(end 0.12065 -0.2794)
			(stroke
				(width 0.1)
				(type default)
			)
			(layer "B.Fab")
		)
		(fp_line
			(start -0.12065 -0.3048)
			(end -0.67945 -0.3048)
			(stroke
				(width 0.1)
				(type default)
			)
			(layer "B.Fab")
		)
		(fp_line
			(start -0.67945 -0.3048)
			(end -0.67945 0.3048)
			(stroke
				(width 0.1)
				(type default)
			)
			(layer "B.Fab")
		)
		(fp_line
			(start 0.12065 -0.2794)
			(end -0.12065 -0.2794)
			(stroke
				(width 0.1)
				(type default)
			)
			(layer "B.Fab")
		)
		(fp_line
			(start -0.12065 -0.2794)
			(end -0.12065 -0.3048)
			(stroke
				(width 0.1)
				(type default)
			)
			(layer "B.Fab")
		)
		(fp_line
			(start 0.12065 0.2794)
			(end 0.12065 0.3048)
			(stroke
				(width 0.1)
				(type default)
			)
			(layer "B.Fab")
		)
		(fp_line
			(start -0.120396 0.2794)
			(end 0.12065 0.2794)
			(stroke
				(width 0.1)
				(type default)
			)
			(layer "B.Fab")
		)
		(fp_line
			(start 0.67945 0.3048)
			(end 0.67945 -0.305054)
			(stroke
				(width 0.1)
				(type default)
			)
			(layer "B.Fab")
		)
		(fp_line
			(start 0.12065 0.3048)
			(end 0.67945 0.3048)
			(stroke
				(width 0.1)
				(type default)
			)
			(layer "B.Fab")
		)
		(fp_line
			(start -0.120396 0.3048)
			(end -0.120396 0.2794)
			(stroke
				(width 0.1)
				(type default)
			)
			(layer "B.Fab")
		)
		(fp_line
			(start -0.67945 0.3048)
			(end -0.120396 0.3048)
			(stroke
				(width 0.1)
				(type default)
			)
			(layer "B.Fab")
		)
		(pad "1" smd circle
			(at 0.40005 0 270)
			(size 0 0)
			(layers "B.Cu" "B.Mask" "B.Paste")
			(net "P2V5_AUX")
		)
		(pad "2" smd circle
			(at -0.40005 0 270)
			(size 0 0)
			(layers "B.Cu" "B.Mask" "B.Paste")
			(net "P2V5_SENSOR")
		)
	)
	(footprint ""
		(layer "B.Cu")
		(at 35.052 -106.3625 -90)
		(property "Reference" "R230"
			(at 0 0 90)
			(layer "B.SilkS")
			(hide yes)
			(effects
				(font
					(size 1.27 1.27)
				)
				(justify mirror)
			)
		)
		(property "Value" ""
			(at 0 0 90)
			(layer "B.Fab")
			(effects
				(font
					(size 1.27 1.27)
				)
				(justify mirror)
			)
		)
		(duplicate_pad_numbers_are_jumpers no)
		(fp_line
			(start -0.7874 0.4064)
			(end 0.7874 0.4064)
			(stroke
				(width 0.1524)
				(type default)
			)
			(layer "B.SilkS")
		)
		(fp_line
			(start 0.7874 0.4064)
			(end 0.7874 -0.4064)
			(stroke
				(width 0.1524)
				(type default)
			)
			(layer "B.SilkS")
		)
		(fp_line
			(start -0.7874 -0.4064)
			(end -0.7874 0.4064)
			(stroke
				(width 0.1524)
				(type default)
			)
			(layer "B.SilkS")
		)
		(fp_line
			(start 0.7874 -0.4064)
			(end -0.7874 -0.4064)
			(stroke
				(width 0.1524)
				(type default)
			)
			(layer "B.SilkS")
		)
		(fp_line
			(start -0.67945 0.3048)
			(end -0.120396 0.3048)
			(stroke
				(width 0.1)
				(type default)
			)
			(layer "B.Fab")
		)
		(fp_line
			(start -0.120396 0.3048)
			(end -0.120396 0.2794)
			(stroke
				(width 0.1)
				(type default)
			)
			(layer "B.Fab")
		)
		(fp_line
			(start 0.12065 0.3048)
			(end 0.67945 0.3048)
			(stroke
				(width 0.1)
				(type default)
			)
			(layer "B.Fab")
		)
		(fp_line
			(start 0.67945 0.3048)
			(end 0.67945 -0.305054)
			(stroke
				(width 0.1)
				(type default)
			)
			(layer "B.Fab")
		)
		(fp_line
			(start -0.120396 0.2794)
			(end 0.12065 0.2794)
			(stroke
				(width 0.1)
				(type default)
			)
			(layer "B.Fab")
		)
		(fp_line
			(start 0.12065 0.2794)
			(end 0.12065 0.3048)
			(stroke
				(width 0.1)
				(type default)
			)
			(layer "B.Fab")
		)
		(fp_line
			(start -0.12065 -0.2794)
			(end -0.12065 -0.3048)
			(stroke
				(width 0.1)
				(type default)
			)
			(layer "B.Fab")
		)
		(fp_line
			(start 0.12065 -0.2794)
			(end -0.12065 -0.2794)
			(stroke
				(width 0.1)
				(type default)
			)
			(layer "B.Fab")
		)
		(fp_line
			(start -0.67945 -0.3048)
			(end -0.67945 0.3048)
			(stroke
				(width 0.1)
				(type default)
			)
			(layer "B.Fab")
		)
		(fp_line
			(start -0.12065 -0.3048)
			(end -0.67945 -0.3048)
			(stroke
				(width 0.1)
				(type default)
			)
			(layer "B.Fab")
		)
		(fp_line
			(start 0.12065 -0.305054)
			(end 0.12065 -0.2794)
			(stroke
				(width 0.1)
				(type default)
			)
			(layer "B.Fab")
		)
		(fp_line
			(start 0.67945 -0.305054)
			(end 0.12065 -0.305054)
			(stroke
				(width 0.1)
				(type default)
			)
			(layer "B.Fab")
		)
		(pad "1" smd circle
			(at 0.40005 0 90)
			(size 0 0)
			(layers "B.Cu" "B.Mask" "B.Paste")
			(net "P3V3_AUX")
		)
		(pad "2" smd circle
			(at -0.40005 0 90)
			(size 0 0)
			(layers "B.Cu" "B.Mask" "B.Paste")
			(net "JTAG_MB_TDO")
		)
	)
	(footprint ""
		(layer "B.Cu")
		(at 72.799194 -55.399686 90)
		(property "Reference" "C108"
			(at 0 0 90)
			(layer "B.SilkS")
			(hide yes)
			(effects
				(font
					(size 1.27 1.27)
				)
				(justify mirror)
			)
		)
		(property "Value" ""
			(at 0 0 90)
			(layer "B.Fab")
			(effects
				(font
					(size 1.27 1.27)
				)
				(justify mirror)
			)
		)
		(duplicate_pad_numbers_are_jumpers no)
		(fp_line
			(start 0.7874 -0.4064)
			(end -0.7874 -0.4064)
			(stroke
				(width 0.1524)
				(type default)
			)
			(layer "B.SilkS")
		)
		(fp_line
			(start -0.7874 -0.4064)
			(end -0.7874 0.4064)
			(stroke
				(width 0.1524)
				(type default)
			)
			(layer "B.SilkS")
		)
		(fp_line
			(start 0.7874 0.4064)
			(end 0.7874 -0.4064)
			(stroke
				(width 0.1524)
				(type default)
			)
			(layer "B.SilkS")
		)
		(fp_line
			(start -0.7874 0.4064)
			(end 0.7874 0.4064)
			(stroke
				(width 0.1524)
				(type default)
			)
			(layer "B.SilkS")
		)
		(fp_line
			(start 0.67945 -0.305054)
			(end 0.12065 -0.305054)
			(stroke
				(width 0.1)
				(type default)
			)
			(layer "B.Fab")
		)
		(fp_line
			(start 0.12065 -0.305054)
			(end 0.12065 -0.2794)
			(stroke
				(width 0.1)
				(type default)
			)
			(layer "B.Fab")
		)
		(fp_line
			(start -0.12065 -0.3048)
			(end -0.67945 -0.3048)
			(stroke
				(width 0.1)
				(type default)
			)
			(layer "B.Fab")
		)
		(fp_line
			(start -0.67945 -0.3048)
			(end -0.67945 0.3048)
			(stroke
				(width 0.1)
				(type default)
			)
			(layer "B.Fab")
		)
		(fp_line
			(start 0.12065 -0.2794)
			(end -0.12065 -0.2794)
			(stroke
				(width 0.1)
				(type default)
			)
			(layer "B.Fab")
		)
		(fp_line
			(start -0.12065 -0.2794)
			(end -0.12065 -0.3048)
			(stroke
				(width 0.1)
				(type default)
			)
			(layer "B.Fab")
		)
		(fp_line
			(start 0.12065 0.2794)
			(end 0.12065 0.3048)
			(stroke
				(width 0.1)
				(type default)
			)
			(layer "B.Fab")
		)
		(fp_line
			(start -0.120396 0.2794)
			(end 0.12065 0.2794)
			(stroke
				(width 0.1)
				(type default)
			)
			(layer "B.Fab")
		)
		(fp_line
			(start 0.67945 0.3048)
			(end 0.67945 -0.305054)
			(stroke
				(width 0.1)
				(type default)
			)
			(layer "B.Fab")
		)
		(fp_line
			(start 0.12065 0.3048)
			(end 0.67945 0.3048)
			(stroke
				(width 0.1)
				(type default)
			)
			(layer "B.Fab")
		)
		(fp_line
			(start -0.120396 0.3048)
			(end -0.120396 0.2794)
			(stroke
				(width 0.1)
				(type default)
			)
			(layer "B.Fab")
		)
		(fp_line
			(start -0.67945 0.3048)
			(end -0.120396 0.3048)
			(stroke
				(width 0.1)
				(type default)
			)
			(layer "B.Fab")
		)
		(pad "1" smd circle
			(at 0.40005 0 270)
			(size 0 0)
			(layers "B.Cu" "B.Mask" "B.Paste")
			(net "P1V0_AUX")
		)
		(pad "2" smd circle
			(at -0.40005 0 270)
			(size 0 0)
			(layers "B.Cu" "B.Mask" "B.Paste")
			(net "GND")
		)
	)
	(footprint ""
		(layer "B.Cu")
		(at 47.10938 -24.1173 -90)
		(property "Reference" "R670"
			(at 0 0 90)
			(layer "B.SilkS")
			(hide yes)
			(effects
				(font
					(size 1.27 1.27)
				)
				(justify mirror)
			)
		)
		(property "Value" ""
			(at 0 0 90)
			(layer "B.Fab")
			(effects
				(font
					(size 1.27 1.27)
				)
				(justify mirror)
			)
		)
		(duplicate_pad_numbers_are_jumpers no)
		(fp_line
			(start -0.7874 0.4064)
			(end 0.7874 0.4064)
			(stroke
				(width 0.1524)
				(type default)
			)
			(layer "B.SilkS")
		)
		(fp_line
			(start 0.7874 0.4064)
			(end 0.7874 -0.4064)
			(stroke
				(width 0.1524)
				(type default)
			)
			(layer "B.SilkS")
		)
		(fp_line
			(start -0.7874 -0.4064)
			(end -0.7874 0.4064)
			(stroke
				(width 0.1524)
				(type default)
			)
			(layer "B.SilkS")
		)
		(fp_line
			(start 0.7874 -0.4064)
			(end -0.7874 -0.4064)
			(stroke
				(width 0.1524)
				(type default)
			)
			(layer "B.SilkS")
		)
		(fp_line
			(start -0.67945 0.3048)
			(end -0.120396 0.3048)
			(stroke
				(width 0.1)
				(type default)
			)
			(layer "B.Fab")
		)
		(fp_line
			(start -0.120396 0.3048)
			(end -0.120396 0.2794)
			(stroke
				(width 0.1)
				(type default)
			)
			(layer "B.Fab")
		)
		(fp_line
			(start 0.12065 0.3048)
			(end 0.67945 0.3048)
			(stroke
				(width 0.1)
				(type default)
			)
			(layer "B.Fab")
		)
		(fp_line
			(start 0.67945 0.3048)
			(end 0.67945 -0.305054)
			(stroke
				(width 0.1)
				(type default)
			)
			(layer "B.Fab")
		)
		(fp_line
			(start -0.120396 0.2794)
			(end 0.12065 0.2794)
			(stroke
				(width 0.1)
				(type default)
			)
			(layer "B.Fab")
		)
		(fp_line
			(start 0.12065 0.2794)
			(end 0.12065 0.3048)
			(stroke
				(width 0.1)
				(type default)
			)
			(layer "B.Fab")
		)
		(fp_line
			(start -0.12065 -0.2794)
			(end -0.12065 -0.3048)
			(stroke
				(width 0.1)
				(type default)
			)
			(layer "B.Fab")
		)
		(fp_line
			(start 0.12065 -0.2794)
			(end -0.12065 -0.2794)
			(stroke
				(width 0.1)
				(type default)
			)
			(layer "B.Fab")
		)
		(fp_line
			(start -0.67945 -0.3048)
			(end -0.67945 0.3048)
			(stroke
				(width 0.1)
				(type default)
			)
			(layer "B.Fab")
		)
		(fp_line
			(start -0.12065 -0.3048)
			(end -0.67945 -0.3048)
			(stroke
				(width 0.1)
				(type default)
			)
			(layer "B.Fab")
		)
		(fp_line
			(start 0.12065 -0.305054)
			(end 0.12065 -0.2794)
			(stroke
				(width 0.1)
				(type default)
			)
			(layer "B.Fab")
		)
		(fp_line
			(start 0.67945 -0.305054)
			(end 0.12065 -0.305054)
			(stroke
				(width 0.1)
				(type default)
			)
			(layer "B.Fab")
		)
		(pad "1" smd circle
			(at 0.40005 0 90)
			(size 0 0)
			(layers "B.Cu" "B.Mask" "B.Paste")
			(net "DEBUG_PORT_PRSNT_BUF_R_EN")
		)
		(pad "2" smd circle
			(at -0.40005 0 90)
			(size 0 0)
			(layers "B.Cu" "B.Mask" "B.Paste")
			(net "DEBUG_PORT_PRSNT_BUF_EN")
		)
	)
	(footprint ""
		(layer "B.Cu")
		(at 61.3918 -24.257 90)
		(property "Reference" "R193"
			(at 0 0 90)
			(layer "B.SilkS")
			(hide yes)
			(effects
				(font
					(size 1.27 1.27)
				)
				(justify mirror)
			)
		)
		(property "Value" ""
			(at 0 0 90)
			(layer "B.Fab")
			(effects
				(font
					(size 1.27 1.27)
				)
				(justify mirror)
			)
		)
		(duplicate_pad_numbers_are_jumpers no)
		(fp_line
			(start 0.7874 -0.4064)
			(end -0.7874 -0.4064)
			(stroke
				(width 0.1524)
				(type default)
			)
			(layer "B.SilkS")
		)
		(fp_line
			(start -0.7874 -0.4064)
			(end -0.7874 0.4064)
			(stroke
				(width 0.1524)
				(type default)
			)
			(layer "B.SilkS")
		)
		(fp_line
			(start 0.7874 0.4064)
			(end 0.7874 -0.4064)
			(stroke
				(width 0.1524)
				(type default)
			)
			(layer "B.SilkS")
		)
		(fp_line
			(start -0.7874 0.4064)
			(end 0.7874 0.4064)
			(stroke
				(width 0.1524)
				(type default)
			)
			(layer "B.SilkS")
		)
		(fp_line
			(start 0.67945 -0.305054)
			(end 0.12065 -0.305054)
			(stroke
				(width 0.1)
				(type default)
			)
			(layer "B.Fab")
		)
		(fp_line
			(start 0.12065 -0.305054)
			(end 0.12065 -0.2794)
			(stroke
				(width 0.1)
				(type default)
			)
			(layer "B.Fab")
		)
		(fp_line
			(start -0.12065 -0.3048)
			(end -0.67945 -0.3048)
			(stroke
				(width 0.1)
				(type default)
			)
			(layer "B.Fab")
		)
		(fp_line
			(start -0.67945 -0.3048)
			(end -0.67945 0.3048)
			(stroke
				(width 0.1)
				(type default)
			)
			(layer "B.Fab")
		)
		(fp_line
			(start 0.12065 -0.2794)
			(end -0.12065 -0.2794)
			(stroke
				(width 0.1)
				(type default)
			)
			(layer "B.Fab")
		)
		(fp_line
			(start -0.12065 -0.2794)
			(end -0.12065 -0.3048)
			(stroke
				(width 0.1)
				(type default)
			)
			(layer "B.Fab")
		)
		(fp_line
			(start 0.12065 0.2794)
			(end 0.12065 0.3048)
			(stroke
				(width 0.1)
				(type default)
			)
			(layer "B.Fab")
		)
		(fp_line
			(start -0.120396 0.2794)
			(end 0.12065 0.2794)
			(stroke
				(width 0.1)
				(type default)
			)
			(layer "B.Fab")
		)
		(fp_line
			(start 0.67945 0.3048)
			(end 0.67945 -0.305054)
			(stroke
				(width 0.1)
				(type default)
			)
			(layer "B.Fab")
		)
		(fp_line
			(start 0.12065 0.3048)
			(end 0.67945 0.3048)
			(stroke
				(width 0.1)
				(type default)
			)
			(layer "B.Fab")
		)
		(fp_line
			(start -0.120396 0.3048)
			(end -0.120396 0.2794)
			(stroke
				(width 0.1)
				(type default)
			)
			(layer "B.Fab")
		)
		(fp_line
			(start -0.67945 0.3048)
			(end -0.120396 0.3048)
			(stroke
				(width 0.1)
				(type default)
			)
			(layer "B.Fab")
		)
		(pad "1" smd circle
			(at 0.40005 0 270)
			(size 0 0)
			(layers "B.Cu" "B.Mask" "B.Paste")
			(net "P3V3_AUX")
		)
		(pad "2" smd circle
			(at -0.40005 0 270)
			(size 0 0)
			(layers "B.Cu" "B.Mask" "B.Paste")
			(net "SPA_SIN_SW_DBG")
		)
	)
	(footprint ""
		(layer "B.Cu")
		(at 32.6644 -71.882 180)
		(property "Reference" "R628"
			(at 0 0 0)
			(layer "B.SilkS")
			(hide yes)
			(effects
				(font
					(size 1.27 1.27)
				)
				(justify mirror)
			)
		)
		(property "Value" ""
			(at 0 0 0)
			(layer "B.Fab")
			(effects
				(font
					(size 1.27 1.27)
				)
				(justify mirror)
			)
		)
		(duplicate_pad_numbers_are_jumpers no)
		(fp_line
			(start 0.7874 0.4064)
			(end 0.7874 -0.4064)
			(stroke
				(width 0.1524)
				(type default)
			)
			(layer "B.SilkS")
		)
		(fp_line
			(start 0.7874 -0.4064)
			(end -0.7874 -0.4064)
			(stroke
				(width 0.1524)
				(type default)
			)
			(layer "B.SilkS")
		)
		(fp_line
			(start -0.7874 0.4064)
			(end 0.7874 0.4064)
			(stroke
				(width 0.1524)
				(type default)
			)
			(layer "B.SilkS")
		)
		(fp_line
			(start -0.7874 -0.4064)
			(end -0.7874 0.4064)
			(stroke
				(width 0.1524)
				(type default)
			)
			(layer "B.SilkS")
		)
		(fp_line
			(start 0.67945 0.3048)
			(end 0.67945 -0.305054)
			(stroke
				(width 0.1)
				(type default)
			)
			(layer "B.Fab")
		)
		(fp_line
			(start 0.67945 -0.305054)
			(end 0.12065 -0.305054)
			(stroke
				(width 0.1)
				(type default)
			)
			(layer "B.Fab")
		)
		(fp_line
			(start 0.12065 0.3048)
			(end 0.67945 0.3048)
			(stroke
				(width 0.1)
				(type default)
			)
			(layer "B.Fab")
		)
		(fp_line
			(start 0.12065 0.2794)
			(end 0.12065 0.3048)
			(stroke
				(width 0.1)
				(type default)
			)
			(layer "B.Fab")
		)
		(fp_line
			(start 0.12065 -0.2794)
			(end -0.12065 -0.2794)
			(stroke
				(width 0.1)
				(type default)
			)
			(layer "B.Fab")
		)
		(fp_line
			(start 0.12065 -0.305054)
			(end 0.12065 -0.2794)
			(stroke
				(width 0.1)
				(type default)
			)
			(layer "B.Fab")
		)
		(fp_line
			(start -0.120396 0.3048)
			(end -0.120396 0.2794)
			(stroke
				(width 0.1)
				(type default)
			)
			(layer "B.Fab")
		)
		(fp_line
			(start -0.120396 0.2794)
			(end 0.12065 0.2794)
			(stroke
				(width 0.1)
				(type default)
			)
			(layer "B.Fab")
		)
		(fp_line
			(start -0.12065 -0.2794)
			(end -0.12065 -0.3048)
			(stroke
				(width 0.1)
				(type default)
			)
			(layer "B.Fab")
		)
		(fp_line
			(start -0.12065 -0.3048)
			(end -0.67945 -0.3048)
			(stroke
				(width 0.1)
				(type default)
			)
			(layer "B.Fab")
		)
		(fp_line
			(start -0.67945 0.3048)
			(end -0.120396 0.3048)
			(stroke
				(width 0.1)
				(type default)
			)
			(layer "B.Fab")
		)
		(fp_line
			(start -0.67945 -0.3048)
			(end -0.67945 0.3048)
			(stroke
				(width 0.1)
				(type default)
			)
			(layer "B.Fab")
		)
		(pad "1" smd circle
			(at 0.40005 0)
			(size 0 0)
			(layers "B.Cu" "B.Mask" "B.Paste")
			(net "SPA_SIN_SW_DBG")
		)
		(pad "2" smd circle
			(at -0.40005 0)
			(size 0 0)
			(layers "B.Cu" "B.Mask" "B.Paste")
			(net "SPA_SIN_SW_DBG_R")
		)
	)
	(footprint ""
		(layer "B.Cu")
		(at 25.060656 -97.5868 -90)
		(property "Reference" "C260"
			(at 0 0 90)
			(layer "B.SilkS")
			(hide yes)
			(effects
				(font
					(size 1.27 1.27)
				)
				(justify mirror)
			)
		)
		(property "Value" ""
			(at 0 0 90)
			(layer "B.Fab")
			(effects
				(font
					(size 1.27 1.27)
				)
				(justify mirror)
			)
		)
		(duplicate_pad_numbers_are_jumpers no)
		(fp_line
			(start -0.69215 0.2921)
			(end 0.69215 0.2921)
			(stroke
				(width 0.1524)
				(type default)
			)
			(layer "B.SilkS")
		)
		(fp_line
			(start 0.69215 0.2921)
			(end 0.69215 -0.2921)
			(stroke
				(width 0.1524)
				(type default)
			)
			(layer "B.SilkS")
		)
		(fp_line
			(start -0.69215 -0.2921)
			(end -0.69215 0.2921)
			(stroke
				(width 0.1524)
				(type default)
			)
			(layer "B.SilkS")
		)
		(fp_line
			(start 0.69215 -0.2921)
			(end -0.69215 -0.2921)
			(stroke
				(width 0.1524)
				(type default)
			)
			(layer "B.SilkS")
		)
		(fp_line
			(start -0.51435 0.2794)
			(end 0.51435 0.2794)
			(stroke
				(width 0.1)
				(type default)
			)
			(layer "B.Fab")
		)
		(fp_line
			(start 0.51435 0.2794)
			(end 0.51435 -0.2794)
			(stroke
				(width 0.1)
				(type default)
			)
			(layer "B.Fab")
		)
		(fp_line
			(start -0.51435 -0.2794)
			(end -0.51435 0.2794)
			(stroke
				(width 0.1)
				(type default)
			)
			(layer "B.Fab")
		)
		(fp_line
			(start 0.51435 -0.2794)
			(end -0.51435 -0.2794)
			(stroke
				(width 0.1)
				(type default)
			)
			(layer "B.Fab")
		)
		(pad "1" smd circle
			(at 0.40005 0 90)
			(size 0 0)
			(layers "B.Cu" "B.Mask" "B.Paste")
			(net "VCCIO2")
		)
		(pad "2" smd circle
			(at -0.40005 0 90)
			(size 0 0)
			(layers "B.Cu" "B.Mask" "B.Paste")
			(net "GND")
		)
		(zone
			(layer "B.Cu")
			(hatch none 0.5)
			(connect_pads
				(clearance 0)
			)
			(min_thickness 0.25)
			(keepout
				(tracks not_allowed)
				(vias allowed)
				(pads allowed)
				(copperpour not_allowed)
				(footprints allowed)
			)
			(placement
				(enabled no)
				(sheetname "")
			)
			(fill
				(thermal_gap 0.5)
				(thermal_bridge_width 0.5)
				(island_removal_mode 0)
			)
			(polygon
				(pts
					(xy 24.973026 -97.3963) (xy 24.91486 -97.48774) (xy 24.91486 -97.68713) (xy 24.973026 -97.7773)
					(xy 25.148286 -97.7773) (xy 25.206706 -97.68713) (xy 25.206706 -97.48774) (xy 25.14854 -97.3963)
				)
			)
		)
	)
	(footprint ""
		(layer "B.Cu")
		(at 83.16722 -40.490394)
		(property "Reference" "R340"
			(at 0 0 0)
			(layer "B.SilkS")
			(hide yes)
			(effects
				(font
					(size 1.27 1.27)
				)
				(justify mirror)
			)
		)
		(property "Value" ""
			(at 0 0 0)
			(layer "B.Fab")
			(effects
				(font
					(size 1.27 1.27)
				)
				(justify mirror)
			)
		)
		(duplicate_pad_numbers_are_jumpers no)
		(fp_line
			(start -0.7874 -0.4064)
			(end -0.7874 0.4064)
			(stroke
				(width 0.1524)
				(type default)
			)
			(layer "B.SilkS")
		)
		(fp_line
			(start -0.7874 0.4064)
			(end 0.7874 0.4064)
			(stroke
				(width 0.1524)
				(type default)
			)
			(layer "B.SilkS")
		)
		(fp_line
			(start 0.7874 -0.4064)
			(end -0.7874 -0.4064)
			(stroke
				(width 0.1524)
				(type default)
			)
			(layer "B.SilkS")
		)
		(fp_line
			(start 0.7874 0.4064)
			(end 0.7874 -0.4064)
			(stroke
				(width 0.1524)
				(type default)
			)
			(layer "B.SilkS")
		)
		(fp_line
			(start -0.67945 -0.3048)
			(end -0.67945 0.3048)
			(stroke
				(width 0.1)
				(type default)
			)
			(layer "B.Fab")
		)
		(fp_line
			(start -0.67945 0.3048)
			(end -0.120396 0.3048)
			(stroke
				(width 0.1)
				(type default)
			)
			(layer "B.Fab")
		)
		(fp_line
			(start -0.12065 -0.3048)
			(end -0.67945 -0.3048)
			(stroke
				(width 0.1)
				(type default)
			)
			(layer "B.Fab")
		)
		(fp_line
			(start -0.12065 -0.2794)
			(end -0.12065 -0.3048)
			(stroke
				(width 0.1)
				(type default)
			)
			(layer "B.Fab")
		)
		(fp_line
			(start -0.120396 0.2794)
			(end 0.12065 0.2794)
			(stroke
				(width 0.1)
				(type default)
			)
			(layer "B.Fab")
		)
		(fp_line
			(start -0.120396 0.3048)
			(end -0.120396 0.2794)
			(stroke
				(width 0.1)
				(type default)
			)
			(layer "B.Fab")
		)
		(fp_line
			(start 0.12065 -0.305054)
			(end 0.12065 -0.2794)
			(stroke
				(width 0.1)
				(type default)
			)
			(layer "B.Fab")
		)
		(fp_line
			(start 0.12065 -0.2794)
			(end -0.12065 -0.2794)
			(stroke
				(width 0.1)
				(type default)
			)
			(layer "B.Fab")
		)
		(fp_line
			(start 0.12065 0.2794)
			(end 0.12065 0.3048)
			(stroke
				(width 0.1)
				(type default)
			)
			(layer "B.Fab")
		)
		(fp_line
			(start 0.12065 0.3048)
			(end 0.67945 0.3048)
			(stroke
				(width 0.1)
				(type default)
			)
			(layer "B.Fab")
		)
		(fp_line
			(start 0.67945 -0.305054)
			(end 0.12065 -0.305054)
			(stroke
				(width 0.1)
				(type default)
			)
			(layer "B.Fab")
		)
		(fp_line
			(start 0.67945 0.3048)
			(end 0.67945 -0.305054)
			(stroke
				(width 0.1)
				(type default)
			)
			(layer "B.Fab")
		)
		(pad "1" smd circle
			(at 0.40005 0 180)
			(size 0 0)
			(layers "B.Cu" "B.Mask" "B.Paste")
			(net "GND")
		)
		(pad "2" smd circle
			(at -0.40005 0 180)
			(size 0 0)
			(layers "B.Cu" "B.Mask" "B.Paste")
			(net "M_BMC_DDR4_MWE_N")
		)
	)
	(footprint ""
		(layer "B.Cu")
		(at 56.134 -62.4332 180)
		(property "Reference" "R401"
			(at 0 0 0)
			(layer "B.SilkS")
			(hide yes)
			(effects
				(font
					(size 1.27 1.27)
				)
				(justify mirror)
			)
		)
		(property "Value" ""
			(at 0 0 0)
			(layer "B.Fab")
			(effects
				(font
					(size 1.27 1.27)
				)
				(justify mirror)
			)
		)
		(duplicate_pad_numbers_are_jumpers no)
		(fp_line
			(start 0.7874 0.4064)
			(end 0.7874 -0.4064)
			(stroke
				(width 0.1524)
				(type default)
			)
			(layer "B.SilkS")
		)
		(fp_line
			(start 0.7874 -0.4064)
			(end -0.7874 -0.4064)
			(stroke
				(width 0.1524)
				(type default)
			)
			(layer "B.SilkS")
		)
		(fp_line
			(start -0.7874 0.4064)
			(end 0.7874 0.4064)
			(stroke
				(width 0.1524)
				(type default)
			)
			(layer "B.SilkS")
		)
		(fp_line
			(start -0.7874 -0.4064)
			(end -0.7874 0.4064)
			(stroke
				(width 0.1524)
				(type default)
			)
			(layer "B.SilkS")
		)
		(fp_line
			(start 0.67945 0.3048)
			(end 0.67945 -0.305054)
			(stroke
				(width 0.1)
				(type default)
			)
			(layer "B.Fab")
		)
		(fp_line
			(start 0.67945 -0.305054)
			(end 0.12065 -0.305054)
			(stroke
				(width 0.1)
				(type default)
			)
			(layer "B.Fab")
		)
		(fp_line
			(start 0.12065 0.3048)
			(end 0.67945 0.3048)
			(stroke
				(width 0.1)
				(type default)
			)
			(layer "B.Fab")
		)
		(fp_line
			(start 0.12065 0.2794)
			(end 0.12065 0.3048)
			(stroke
				(width 0.1)
				(type default)
			)
			(layer "B.Fab")
		)
		(fp_line
			(start 0.12065 -0.2794)
			(end -0.12065 -0.2794)
			(stroke
				(width 0.1)
				(type default)
			)
			(layer "B.Fab")
		)
		(fp_line
			(start 0.12065 -0.305054)
			(end 0.12065 -0.2794)
			(stroke
				(width 0.1)
				(type default)
			)
			(layer "B.Fab")
		)
		(fp_line
			(start -0.120396 0.3048)
			(end -0.120396 0.2794)
			(stroke
				(width 0.1)
				(type default)
			)
			(layer "B.Fab")
		)
		(fp_line
			(start -0.120396 0.2794)
			(end 0.12065 0.2794)
			(stroke
				(width 0.1)
				(type default)
			)
			(layer "B.Fab")
		)
		(fp_line
			(start -0.12065 -0.2794)
			(end -0.12065 -0.3048)
			(stroke
				(width 0.1)
				(type default)
			)
			(layer "B.Fab")
		)
		(fp_line
			(start -0.12065 -0.3048)
			(end -0.67945 -0.3048)
			(stroke
				(width 0.1)
				(type default)
			)
			(layer "B.Fab")
		)
		(fp_line
			(start -0.67945 0.3048)
			(end -0.120396 0.3048)
			(stroke
				(width 0.1)
				(type default)
			)
			(layer "B.Fab")
		)
		(fp_line
			(start -0.67945 -0.3048)
			(end -0.67945 0.3048)
			(stroke
				(width 0.1)
				(type default)
			)
			(layer "B.Fab")
		)
		(pad "1" smd circle
			(at 0.40005 0)
			(size 0 0)
			(layers "B.Cu" "B.Mask" "B.Paste")
			(net "PU_BMC_FWSPIABR_N")
		)
		(pad "2" smd circle
			(at -0.40005 0)
			(size 0 0)
			(layers "B.Cu" "B.Mask" "B.Paste")
			(net "PU_BMC_FWSPIABR_N_R")
		)
	)
	(footprint ""
		(layer "B.Cu")
		(at 47.607474 -30.857698 -90)
		(property "Reference" "R248"
			(at 0 0 90)
			(layer "B.SilkS")
			(hide yes)
			(effects
				(font
					(size 1.27 1.27)
				)
				(justify mirror)
			)
		)
		(property "Value" ""
			(at 0 0 90)
			(layer "B.Fab")
			(effects
				(font
					(size 1.27 1.27)
				)
				(justify mirror)
			)
		)
		(duplicate_pad_numbers_are_jumpers no)
		(fp_line
			(start -0.7874 0.4064)
			(end 0.7874 0.4064)
			(stroke
				(width 0.1524)
				(type default)
			)
			(layer "B.SilkS")
		)
		(fp_line
			(start 0.7874 0.4064)
			(end 0.7874 -0.4064)
			(stroke
				(width 0.1524)
				(type default)
			)
			(layer "B.SilkS")
		)
		(fp_line
			(start -0.7874 -0.4064)
			(end -0.7874 0.4064)
			(stroke
				(width 0.1524)
				(type default)
			)
			(layer "B.SilkS")
		)
		(fp_line
			(start 0.7874 -0.4064)
			(end -0.7874 -0.4064)
			(stroke
				(width 0.1524)
				(type default)
			)
			(layer "B.SilkS")
		)
		(fp_line
			(start -0.67945 0.3048)
			(end -0.120396 0.3048)
			(stroke
				(width 0.1)
				(type default)
			)
			(layer "B.Fab")
		)
		(fp_line
			(start -0.120396 0.3048)
			(end -0.120396 0.2794)
			(stroke
				(width 0.1)
				(type default)
			)
			(layer "B.Fab")
		)
		(fp_line
			(start 0.12065 0.3048)
			(end 0.67945 0.3048)
			(stroke
				(width 0.1)
				(type default)
			)
			(layer "B.Fab")
		)
		(fp_line
			(start 0.67945 0.3048)
			(end 0.67945 -0.305054)
			(stroke
				(width 0.1)
				(type default)
			)
			(layer "B.Fab")
		)
		(fp_line
			(start -0.120396 0.2794)
			(end 0.12065 0.2794)
			(stroke
				(width 0.1)
				(type default)
			)
			(layer "B.Fab")
		)
		(fp_line
			(start 0.12065 0.2794)
			(end 0.12065 0.3048)
			(stroke
				(width 0.1)
				(type default)
			)
			(layer "B.Fab")
		)
		(fp_line
			(start -0.12065 -0.2794)
			(end -0.12065 -0.3048)
			(stroke
				(width 0.1)
				(type default)
			)
			(layer "B.Fab")
		)
		(fp_line
			(start 0.12065 -0.2794)
			(end -0.12065 -0.2794)
			(stroke
				(width 0.1)
				(type default)
			)
			(layer "B.Fab")
		)
		(fp_line
			(start -0.67945 -0.3048)
			(end -0.67945 0.3048)
			(stroke
				(width 0.1)
				(type default)
			)
			(layer "B.Fab")
		)
		(fp_line
			(start -0.12065 -0.3048)
			(end -0.67945 -0.3048)
			(stroke
				(width 0.1)
				(type default)
			)
			(layer "B.Fab")
		)
		(fp_line
			(start 0.12065 -0.305054)
			(end 0.12065 -0.2794)
			(stroke
				(width 0.1)
				(type default)
			)
			(layer "B.Fab")
		)
		(fp_line
			(start 0.67945 -0.305054)
			(end 0.12065 -0.305054)
			(stroke
				(width 0.1)
				(type default)
			)
			(layer "B.Fab")
		)
		(pad "1" smd circle
			(at 0.40005 0 90)
			(size 0 0)
			(layers "B.Cu" "B.Mask" "B.Paste")
			(net "P3V3_AUX")
		)
		(pad "2" smd circle
			(at -0.40005 0 90)
			(size 0 0)
			(layers "B.Cu" "B.Mask" "B.Paste")
			(net "SMB_BMC_MM3_SCL")
		)
	)
	(footprint ""
		(layer "B.Cu")
		(at 56.695848 -49.246028)
		(property "Reference" "C109"
			(at 0 0 0)
			(layer "B.SilkS")
			(hide yes)
			(effects
				(font
					(size 1.27 1.27)
				)
				(justify mirror)
			)
		)
		(property "Value" ""
			(at 0 0 0)
			(layer "B.Fab")
			(effects
				(font
					(size 1.27 1.27)
				)
				(justify mirror)
			)
		)
		(duplicate_pad_numbers_are_jumpers no)
		(fp_line
			(start -0.7874 -0.4064)
			(end -0.7874 0.4064)
			(stroke
				(width 0.1524)
				(type default)
			)
			(layer "B.SilkS")
		)
		(fp_line
			(start -0.7874 0.4064)
			(end 0.7874 0.4064)
			(stroke
				(width 0.1524)
				(type default)
			)
			(layer "B.SilkS")
		)
		(fp_line
			(start 0.7874 -0.4064)
			(end -0.7874 -0.4064)
			(stroke
				(width 0.1524)
				(type default)
			)
			(layer "B.SilkS")
		)
		(fp_line
			(start 0.7874 0.4064)
			(end 0.7874 -0.4064)
			(stroke
				(width 0.1524)
				(type default)
			)
			(layer "B.SilkS")
		)
		(fp_line
			(start -0.67945 -0.3048)
			(end -0.67945 0.3048)
			(stroke
				(width 0.1)
				(type default)
			)
			(layer "B.Fab")
		)
		(fp_line
			(start -0.67945 0.3048)
			(end -0.120396 0.3048)
			(stroke
				(width 0.1)
				(type default)
			)
			(layer "B.Fab")
		)
		(fp_line
			(start -0.12065 -0.3048)
			(end -0.67945 -0.3048)
			(stroke
				(width 0.1)
				(type default)
			)
			(layer "B.Fab")
		)
		(fp_line
			(start -0.12065 -0.2794)
			(end -0.12065 -0.3048)
			(stroke
				(width 0.1)
				(type default)
			)
			(layer "B.Fab")
		)
		(fp_line
			(start -0.120396 0.2794)
			(end 0.12065 0.2794)
			(stroke
				(width 0.1)
				(type default)
			)
			(layer "B.Fab")
		)
		(fp_line
			(start -0.120396 0.3048)
			(end -0.120396 0.2794)
			(stroke
				(width 0.1)
				(type default)
			)
			(layer "B.Fab")
		)
		(fp_line
			(start 0.12065 -0.305054)
			(end 0.12065 -0.2794)
			(stroke
				(width 0.1)
				(type default)
			)
			(layer "B.Fab")
		)
		(fp_line
			(start 0.12065 -0.2794)
			(end -0.12065 -0.2794)
			(stroke
				(width 0.1)
				(type default)
			)
			(layer "B.Fab")
		)
		(fp_line
			(start 0.12065 0.2794)
			(end 0.12065 0.3048)
			(stroke
				(width 0.1)
				(type default)
			)
			(layer "B.Fab")
		)
		(fp_line
			(start 0.12065 0.3048)
			(end 0.67945 0.3048)
			(stroke
				(width 0.1)
				(type default)
			)
			(layer "B.Fab")
		)
		(fp_line
			(start 0.67945 -0.305054)
			(end 0.12065 -0.305054)
			(stroke
				(width 0.1)
				(type default)
			)
			(layer "B.Fab")
		)
		(fp_line
			(start 0.67945 0.3048)
			(end 0.67945 -0.305054)
			(stroke
				(width 0.1)
				(type default)
			)
			(layer "B.Fab")
		)
		(pad "1" smd circle
			(at 0.40005 0 180)
			(size 0 0)
			(layers "B.Cu" "B.Mask" "B.Paste")
			(net "P1V8_AUX")
		)
		(pad "2" smd circle
			(at -0.40005 0 180)
			(size 0 0)
			(layers "B.Cu" "B.Mask" "B.Paste")
			(net "GND")
		)
	)
	(footprint ""
		(layer "B.Cu")
		(at 50.23866 -69.397372 90)
		(property "Reference" "R789"
			(at 0 0 90)
			(layer "B.SilkS")
			(hide yes)
			(effects
				(font
					(size 1.27 1.27)
				)
				(justify mirror)
			)
		)
		(property "Value" ""
			(at 0 0 90)
			(layer "B.Fab")
			(effects
				(font
					(size 1.27 1.27)
				)
				(justify mirror)
			)
		)
		(duplicate_pad_numbers_are_jumpers no)
		(fp_line
			(start 0.7874 -0.4064)
			(end -0.7874 -0.4064)
			(stroke
				(width 0.1524)
				(type default)
			)
			(layer "B.SilkS")
		)
		(fp_line
			(start -0.7874 -0.4064)
			(end -0.7874 0.4064)
			(stroke
				(width 0.1524)
				(type default)
			)
			(layer "B.SilkS")
		)
		(fp_line
			(start 0.7874 0.4064)
			(end 0.7874 -0.4064)
			(stroke
				(width 0.1524)
				(type default)
			)
			(layer "B.SilkS")
		)
		(fp_line
			(start -0.7874 0.4064)
			(end 0.7874 0.4064)
			(stroke
				(width 0.1524)
				(type default)
			)
			(layer "B.SilkS")
		)
		(fp_line
			(start 0.67945 -0.305054)
			(end 0.12065 -0.305054)
			(stroke
				(width 0.1)
				(type default)
			)
			(layer "B.Fab")
		)
		(fp_line
			(start 0.12065 -0.305054)
			(end 0.12065 -0.2794)
			(stroke
				(width 0.1)
				(type default)
			)
			(layer "B.Fab")
		)
		(fp_line
			(start -0.12065 -0.3048)
			(end -0.67945 -0.3048)
			(stroke
				(width 0.1)
				(type default)
			)
			(layer "B.Fab")
		)
		(fp_line
			(start -0.67945 -0.3048)
			(end -0.67945 0.3048)
			(stroke
				(width 0.1)
				(type default)
			)
			(layer "B.Fab")
		)
		(fp_line
			(start 0.12065 -0.2794)
			(end -0.12065 -0.2794)
			(stroke
				(width 0.1)
				(type default)
			)
			(layer "B.Fab")
		)
		(fp_line
			(start -0.12065 -0.2794)
			(end -0.12065 -0.3048)
			(stroke
				(width 0.1)
				(type default)
			)
			(layer "B.Fab")
		)
		(fp_line
			(start 0.12065 0.2794)
			(end 0.12065 0.3048)
			(stroke
				(width 0.1)
				(type default)
			)
			(layer "B.Fab")
		)
		(fp_line
			(start -0.120396 0.2794)
			(end 0.12065 0.2794)
			(stroke
				(width 0.1)
				(type default)
			)
			(layer "B.Fab")
		)
		(fp_line
			(start 0.67945 0.3048)
			(end 0.67945 -0.305054)
			(stroke
				(width 0.1)
				(type default)
			)
			(layer "B.Fab")
		)
		(fp_line
			(start 0.12065 0.3048)
			(end 0.67945 0.3048)
			(stroke
				(width 0.1)
				(type default)
			)
			(layer "B.Fab")
		)
		(fp_line
			(start -0.120396 0.3048)
			(end -0.120396 0.2794)
			(stroke
				(width 0.1)
				(type default)
			)
			(layer "B.Fab")
		)
		(fp_line
			(start -0.67945 0.3048)
			(end -0.120396 0.3048)
			(stroke
				(width 0.1)
				(type default)
			)
			(layer "B.Fab")
		)
		(pad "1" smd circle
			(at 0.40005 0 270)
			(size 0 0)
			(layers "B.Cu" "B.Mask" "B.Paste")
			(net "P3V3_AUX")
		)
		(pad "2" smd circle
			(at -0.40005 0 270)
			(size 0 0)
			(layers "B.Cu" "B.Mask" "B.Paste")
			(net "P3V3_SENSOR")
		)
	)
	(footprint ""
		(layer "B.Cu")
		(at 14.097 -20.447 -90)
		(property "Reference" "R814"
			(at 0 0 90)
			(layer "B.SilkS")
			(hide yes)
			(effects
				(font
					(size 1.27 1.27)
				)
				(justify mirror)
			)
		)
		(property "Value" ""
			(at 0 0 90)
			(layer "B.Fab")
			(effects
				(font
					(size 1.27 1.27)
				)
				(justify mirror)
			)
		)
		(duplicate_pad_numbers_are_jumpers no)
		(fp_line
			(start -0.7874 0.4064)
			(end 0.7874 0.4064)
			(stroke
				(width 0.1524)
				(type default)
			)
			(layer "B.SilkS")
		)
		(fp_line
			(start 0.7874 0.4064)
			(end 0.7874 -0.4064)
			(stroke
				(width 0.1524)
				(type default)
			)
			(layer "B.SilkS")
		)
		(fp_line
			(start -0.7874 -0.4064)
			(end -0.7874 0.4064)
			(stroke
				(width 0.1524)
				(type default)
			)
			(layer "B.SilkS")
		)
		(fp_line
			(start 0.7874 -0.4064)
			(end -0.7874 -0.4064)
			(stroke
				(width 0.1524)
				(type default)
			)
			(layer "B.SilkS")
		)
		(fp_line
			(start -0.67945 0.3048)
			(end -0.120396 0.3048)
			(stroke
				(width 0.1)
				(type default)
			)
			(layer "B.Fab")
		)
		(fp_line
			(start -0.120396 0.3048)
			(end -0.120396 0.2794)
			(stroke
				(width 0.1)
				(type default)
			)
			(layer "B.Fab")
		)
		(fp_line
			(start 0.12065 0.3048)
			(end 0.67945 0.3048)
			(stroke
				(width 0.1)
				(type default)
			)
			(layer "B.Fab")
		)
		(fp_line
			(start 0.67945 0.3048)
			(end 0.67945 -0.305054)
			(stroke
				(width 0.1)
				(type default)
			)
			(layer "B.Fab")
		)
		(fp_line
			(start -0.120396 0.2794)
			(end 0.12065 0.2794)
			(stroke
				(width 0.1)
				(type default)
			)
			(layer "B.Fab")
		)
		(fp_line
			(start 0.12065 0.2794)
			(end 0.12065 0.3048)
			(stroke
				(width 0.1)
				(type default)
			)
			(layer "B.Fab")
		)
		(fp_line
			(start -0.12065 -0.2794)
			(end -0.12065 -0.3048)
			(stroke
				(width 0.1)
				(type default)
			)
			(layer "B.Fab")
		)
		(fp_line
			(start 0.12065 -0.2794)
			(end -0.12065 -0.2794)
			(stroke
				(width 0.1)
				(type default)
			)
			(layer "B.Fab")
		)
		(fp_line
			(start -0.67945 -0.3048)
			(end -0.67945 0.3048)
			(stroke
				(width 0.1)
				(type default)
			)
			(layer "B.Fab")
		)
		(fp_line
			(start -0.12065 -0.3048)
			(end -0.67945 -0.3048)
			(stroke
				(width 0.1)
				(type default)
			)
			(layer "B.Fab")
		)
		(fp_line
			(start 0.12065 -0.305054)
			(end 0.12065 -0.2794)
			(stroke
				(width 0.1)
				(type default)
			)
			(layer "B.Fab")
		)
		(fp_line
			(start 0.67945 -0.305054)
			(end 0.12065 -0.305054)
			(stroke
				(width 0.1)
				(type default)
			)
			(layer "B.Fab")
		)
		(pad "1" smd circle
			(at 0.40005 0 90)
			(size 0 0)
			(layers "B.Cu" "B.Mask" "B.Paste")
			(net "P5V_AUX")
		)
		(pad "2" smd circle
			(at -0.40005 0 90)
			(size 0 0)
			(layers "B.Cu" "B.Mask" "B.Paste")
			(net "PWR_LED_BUF_N_R")
		)
	)
	(footprint ""
		(layer "B.Cu")
		(at 69.102478 -65.406016 90)
		(property "Reference" "L14"
			(at 0 0 90)
			(layer "B.SilkS")
			(hide yes)
			(effects
				(font
					(size 1.27 1.27)
				)
				(justify mirror)
			)
		)
		(property "Value" ""
			(at 0 0 90)
			(layer "B.Fab")
			(effects
				(font
					(size 1.27 1.27)
				)
				(justify mirror)
			)
		)
		(duplicate_pad_numbers_are_jumpers no)
		(fp_line
			(start 1.27 -0.5842)
			(end -1.27 -0.5842)
			(stroke
				(width 0.1524)
				(type default)
			)
			(layer "B.SilkS")
		)
		(fp_line
			(start 1.27 -0.5588)
			(end 1.27 -0.5842)
			(stroke
				(width 0.1524)
				(type default)
			)
			(layer "B.SilkS")
		)
		(fp_line
			(start 1.27 0.5842)
			(end 1.27 -0.5842)
			(stroke
				(width 0.1524)
				(type default)
			)
			(layer "B.SilkS")
		)
		(fp_line
			(start 0.127 0.5842)
			(end 0.127 -0.5842)
			(stroke
				(width 0.1524)
				(type default)
			)
			(layer "B.SilkS")
		)
		(fp_line
			(start -0.127 0.5842)
			(end -0.127 -0.5842)
			(stroke
				(width 0.1524)
				(type default)
			)
			(layer "B.SilkS")
		)
		(fp_line
			(start -1.27 0.5842)
			(end -1.27 -0.5842)
			(stroke
				(width 0.1524)
				(type default)
			)
			(layer "B.SilkS")
		)
		(fp_line
			(start -1.27 0.5842)
			(end 1.27 0.5842)
			(stroke
				(width 0.1524)
				(type default)
			)
			(layer "B.SilkS")
		)
		(fp_line
			(start 0.9144 -0.508)
			(end -0.9144 -0.508)
			(stroke
				(width 0.1)
				(type default)
			)
			(layer "B.Fab")
		)
		(fp_line
			(start -0.9144 -0.508)
			(end -0.9144 -0.406654)
			(stroke
				(width 0.1)
				(type default)
			)
			(layer "B.Fab")
		)
		(fp_line
			(start 1.194308 -0.406654)
			(end 0.9144 -0.406654)
			(stroke
				(width 0.1)
				(type default)
			)
			(layer "B.Fab")
		)
		(fp_line
			(start 0.9144 -0.406654)
			(end 0.9144 -0.508)
			(stroke
				(width 0.1)
				(type default)
			)
			(layer "B.Fab")
		)
		(fp_line
			(start -0.9144 -0.406654)
			(end -1.1938 -0.406654)
			(stroke
				(width 0.1)
				(type default)
			)
			(layer "B.Fab")
		)
		(fp_line
			(start -1.1938 -0.406654)
			(end -1.1938 0.4064)
			(stroke
				(width 0.1)
				(type default)
			)
			(layer "B.Fab")
		)
		(fp_line
			(start -0.9144 0.4064)
			(end -0.9144 0.508)
			(stroke
				(width 0.1)
				(type default)
			)
			(layer "B.Fab")
		)
		(fp_line
			(start -1.1938 0.4064)
			(end -0.9144 0.4064)
			(stroke
				(width 0.1)
				(type default)
			)
			(layer "B.Fab")
		)
		(fp_line
			(start 1.194308 0.406654)
			(end 1.194308 -0.406654)
			(stroke
				(width 0.1)
				(type default)
			)
			(layer "B.Fab")
		)
		(fp_line
			(start 0.9144 0.406654)
			(end 1.194308 0.406654)
			(stroke
				(width 0.1)
				(type default)
			)
			(layer "B.Fab")
		)
		(fp_line
			(start 0.9144 0.508)
			(end 0.9144 0.406654)
			(stroke
				(width 0.1)
				(type default)
			)
			(layer "B.Fab")
		)
		(fp_line
			(start -0.9144 0.508)
			(end 0.9144 0.508)
			(stroke
				(width 0.1)
				(type default)
			)
			(layer "B.Fab")
		)
		(pad "1" smd rect
			(at 0.7366 0)
			(size 0.7112 0.8128)
			(layers "B.Cu" "B.Mask" "B.Paste")
			(net "P1V8_AUX")
		)
		(pad "2" smd rect
			(at -0.7366 0)
			(size 0.7112 0.8128)
			(layers "B.Cu" "B.Mask" "B.Paste")
			(net "P1V8_STBY_RC_VCC18A")
		)
	)
	(footprint ""
		(layer "B.Cu")
		(at 49.1617 -43.986704 90)
		(property "Reference" "C36"
			(at 0 0 90)
			(layer "B.SilkS")
			(hide yes)
			(effects
				(font
					(size 1.27 1.27)
				)
				(justify mirror)
			)
		)
		(property "Value" ""
			(at 0 0 90)
			(layer "B.Fab")
			(effects
				(font
					(size 1.27 1.27)
				)
				(justify mirror)
			)
		)
		(duplicate_pad_numbers_are_jumpers no)
		(fp_line
			(start 0.7874 -0.4064)
			(end -0.7874 -0.4064)
			(stroke
				(width 0.1524)
				(type default)
			)
			(layer "B.SilkS")
		)
		(fp_line
			(start -0.7874 -0.4064)
			(end -0.7874 0.4064)
			(stroke
				(width 0.1524)
				(type default)
			)
			(layer "B.SilkS")
		)
		(fp_line
			(start 0.7874 0.4064)
			(end 0.7874 -0.4064)
			(stroke
				(width 0.1524)
				(type default)
			)
			(layer "B.SilkS")
		)
		(fp_line
			(start -0.7874 0.4064)
			(end 0.7874 0.4064)
			(stroke
				(width 0.1524)
				(type default)
			)
			(layer "B.SilkS")
		)
		(fp_line
			(start 0.67945 -0.305054)
			(end 0.12065 -0.305054)
			(stroke
				(width 0.1)
				(type default)
			)
			(layer "B.Fab")
		)
		(fp_line
			(start 0.12065 -0.305054)
			(end 0.12065 -0.2794)
			(stroke
				(width 0.1)
				(type default)
			)
			(layer "B.Fab")
		)
		(fp_line
			(start -0.12065 -0.3048)
			(end -0.67945 -0.3048)
			(stroke
				(width 0.1)
				(type default)
			)
			(layer "B.Fab")
		)
		(fp_line
			(start -0.67945 -0.3048)
			(end -0.67945 0.3048)
			(stroke
				(width 0.1)
				(type default)
			)
			(layer "B.Fab")
		)
		(fp_line
			(start 0.12065 -0.2794)
			(end -0.12065 -0.2794)
			(stroke
				(width 0.1)
				(type default)
			)
			(layer "B.Fab")
		)
		(fp_line
			(start -0.12065 -0.2794)
			(end -0.12065 -0.3048)
			(stroke
				(width 0.1)
				(type default)
			)
			(layer "B.Fab")
		)
		(fp_line
			(start 0.12065 0.2794)
			(end 0.12065 0.3048)
			(stroke
				(width 0.1)
				(type default)
			)
			(layer "B.Fab")
		)
		(fp_line
			(start -0.120396 0.2794)
			(end 0.12065 0.2794)
			(stroke
				(width 0.1)
				(type default)
			)
			(layer "B.Fab")
		)
		(fp_line
			(start 0.67945 0.3048)
			(end 0.67945 -0.305054)
			(stroke
				(width 0.1)
				(type default)
			)
			(layer "B.Fab")
		)
		(fp_line
			(start 0.12065 0.3048)
			(end 0.67945 0.3048)
			(stroke
				(width 0.1)
				(type default)
			)
			(layer "B.Fab")
		)
		(fp_line
			(start -0.120396 0.3048)
			(end -0.120396 0.2794)
			(stroke
				(width 0.1)
				(type default)
			)
			(layer "B.Fab")
		)
		(fp_line
			(start -0.67945 0.3048)
			(end -0.120396 0.3048)
			(stroke
				(width 0.1)
				(type default)
			)
			(layer "B.Fab")
		)
		(pad "1" smd circle
			(at 0.40005 0 270)
			(size 0 0)
			(layers "B.Cu" "B.Mask" "B.Paste")
			(net "P3V3_P1V8_SD1VDD")
		)
		(pad "2" smd circle
			(at -0.40005 0 270)
			(size 0 0)
			(layers "B.Cu" "B.Mask" "B.Paste")
			(net "GND")
		)
	)
	(footprint ""
		(layer "B.Cu")
		(at 55.1688 -61.0108 90)
		(property "Reference" "R680"
			(at 0 0 90)
			(layer "B.SilkS")
			(hide yes)
			(effects
				(font
					(size 1.27 1.27)
				)
				(justify mirror)
			)
		)
		(property "Value" ""
			(at 0 0 90)
			(layer "B.Fab")
			(effects
				(font
					(size 1.27 1.27)
				)
				(justify mirror)
			)
		)
		(duplicate_pad_numbers_are_jumpers no)
		(fp_line
			(start 0.7874 -0.4064)
			(end -0.7874 -0.4064)
			(stroke
				(width 0.1524)
				(type default)
			)
			(layer "B.SilkS")
		)
		(fp_line
			(start -0.7874 -0.4064)
			(end -0.7874 0.4064)
			(stroke
				(width 0.1524)
				(type default)
			)
			(layer "B.SilkS")
		)
		(fp_line
			(start 0.7874 0.4064)
			(end 0.7874 -0.4064)
			(stroke
				(width 0.1524)
				(type default)
			)
			(layer "B.SilkS")
		)
		(fp_line
			(start -0.7874 0.4064)
			(end 0.7874 0.4064)
			(stroke
				(width 0.1524)
				(type default)
			)
			(layer "B.SilkS")
		)
		(fp_line
			(start 0.67945 -0.305054)
			(end 0.12065 -0.305054)
			(stroke
				(width 0.1)
				(type default)
			)
			(layer "B.Fab")
		)
		(fp_line
			(start 0.12065 -0.305054)
			(end 0.12065 -0.2794)
			(stroke
				(width 0.1)
				(type default)
			)
			(layer "B.Fab")
		)
		(fp_line
			(start -0.12065 -0.3048)
			(end -0.67945 -0.3048)
			(stroke
				(width 0.1)
				(type default)
			)
			(layer "B.Fab")
		)
		(fp_line
			(start -0.67945 -0.3048)
			(end -0.67945 0.3048)
			(stroke
				(width 0.1)
				(type default)
			)
			(layer "B.Fab")
		)
		(fp_line
			(start 0.12065 -0.2794)
			(end -0.12065 -0.2794)
			(stroke
				(width 0.1)
				(type default)
			)
			(layer "B.Fab")
		)
		(fp_line
			(start -0.12065 -0.2794)
			(end -0.12065 -0.3048)
			(stroke
				(width 0.1)
				(type default)
			)
			(layer "B.Fab")
		)
		(fp_line
			(start 0.12065 0.2794)
			(end 0.12065 0.3048)
			(stroke
				(width 0.1)
				(type default)
			)
			(layer "B.Fab")
		)
		(fp_line
			(start -0.120396 0.2794)
			(end 0.12065 0.2794)
			(stroke
				(width 0.1)
				(type default)
			)
			(layer "B.Fab")
		)
		(fp_line
			(start 0.67945 0.3048)
			(end 0.67945 -0.305054)
			(stroke
				(width 0.1)
				(type default)
			)
			(layer "B.Fab")
		)
		(fp_line
			(start 0.12065 0.3048)
			(end 0.67945 0.3048)
			(stroke
				(width 0.1)
				(type default)
			)
			(layer "B.Fab")
		)
		(fp_line
			(start -0.120396 0.3048)
			(end -0.120396 0.2794)
			(stroke
				(width 0.1)
				(type default)
			)
			(layer "B.Fab")
		)
		(fp_line
			(start -0.67945 0.3048)
			(end -0.120396 0.3048)
			(stroke
				(width 0.1)
				(type default)
			)
			(layer "B.Fab")
		)
		(pad "1" smd circle
			(at 0.40005 0 270)
			(size 0 0)
			(layers "B.Cu" "B.Mask" "B.Paste")
			(net "SPI_BMC_MISO_IO1_R")
		)
		(pad "2" smd circle
			(at -0.40005 0 270)
			(size 0 0)
			(layers "B.Cu" "B.Mask" "B.Paste")
			(net "QSPI_2_PLD_IO1")
		)
	)
	(footprint ""
		(layer "B.Cu")
		(at 14.7828 -94.6404 180)
		(property "Reference" "R51"
			(at 0 0 0)
			(layer "B.SilkS")
			(hide yes)
			(effects
				(font
					(size 1.27 1.27)
				)
				(justify mirror)
			)
		)
		(property "Value" ""
			(at 0 0 0)
			(layer "B.Fab")
			(effects
				(font
					(size 1.27 1.27)
				)
				(justify mirror)
			)
		)
		(duplicate_pad_numbers_are_jumpers no)
		(fp_line
			(start 0.7874 0.4064)
			(end 0.7874 -0.4064)
			(stroke
				(width 0.1524)
				(type default)
			)
			(layer "B.SilkS")
		)
		(fp_line
			(start 0.7874 -0.4064)
			(end -0.7874 -0.4064)
			(stroke
				(width 0.1524)
				(type default)
			)
			(layer "B.SilkS")
		)
		(fp_line
			(start -0.7874 0.4064)
			(end 0.7874 0.4064)
			(stroke
				(width 0.1524)
				(type default)
			)
			(layer "B.SilkS")
		)
		(fp_line
			(start -0.7874 -0.4064)
			(end -0.7874 0.4064)
			(stroke
				(width 0.1524)
				(type default)
			)
			(layer "B.SilkS")
		)
		(fp_line
			(start 0.67945 0.3048)
			(end 0.67945 -0.305054)
			(stroke
				(width 0.1)
				(type default)
			)
			(layer "B.Fab")
		)
		(fp_line
			(start 0.67945 -0.305054)
			(end 0.12065 -0.305054)
			(stroke
				(width 0.1)
				(type default)
			)
			(layer "B.Fab")
		)
		(fp_line
			(start 0.12065 0.3048)
			(end 0.67945 0.3048)
			(stroke
				(width 0.1)
				(type default)
			)
			(layer "B.Fab")
		)
		(fp_line
			(start 0.12065 0.2794)
			(end 0.12065 0.3048)
			(stroke
				(width 0.1)
				(type default)
			)
			(layer "B.Fab")
		)
		(fp_line
			(start 0.12065 -0.2794)
			(end -0.12065 -0.2794)
			(stroke
				(width 0.1)
				(type default)
			)
			(layer "B.Fab")
		)
		(fp_line
			(start 0.12065 -0.305054)
			(end 0.12065 -0.2794)
			(stroke
				(width 0.1)
				(type default)
			)
			(layer "B.Fab")
		)
		(fp_line
			(start -0.120396 0.3048)
			(end -0.120396 0.2794)
			(stroke
				(width 0.1)
				(type default)
			)
			(layer "B.Fab")
		)
		(fp_line
			(start -0.120396 0.2794)
			(end 0.12065 0.2794)
			(stroke
				(width 0.1)
				(type default)
			)
			(layer "B.Fab")
		)
		(fp_line
			(start -0.12065 -0.2794)
			(end -0.12065 -0.3048)
			(stroke
				(width 0.1)
				(type default)
			)
			(layer "B.Fab")
		)
		(fp_line
			(start -0.12065 -0.3048)
			(end -0.67945 -0.3048)
			(stroke
				(width 0.1)
				(type default)
			)
			(layer "B.Fab")
		)
		(fp_line
			(start -0.67945 0.3048)
			(end -0.120396 0.3048)
			(stroke
				(width 0.1)
				(type default)
			)
			(layer "B.Fab")
		)
		(fp_line
			(start -0.67945 -0.3048)
			(end -0.67945 0.3048)
			(stroke
				(width 0.1)
				(type default)
			)
			(layer "B.Fab")
		)
		(pad "1" smd circle
			(at 0.40005 0)
			(size 0 0)
			(layers "B.Cu" "B.Mask" "B.Paste")
			(net "H_CPU0_PROCHOT_LVC1_N")
		)
		(pad "2" smd circle
			(at -0.40005 0)
			(size 0 0)
			(layers "B.Cu" "B.Mask" "B.Paste")
			(net "H_CPU0_PROCHOT_LVC1_R_N")
		)
	)
	(footprint ""
		(layer "B.Cu")
		(at 61.2648 -42.3926 -90)
		(property "Reference" "C68"
			(at 0 0 90)
			(layer "B.SilkS")
			(hide yes)
			(effects
				(font
					(size 1.27 1.27)
				)
				(justify mirror)
			)
		)
		(property "Value" ""
			(at 0 0 90)
			(layer "B.Fab")
			(effects
				(font
					(size 1.27 1.27)
				)
				(justify mirror)
			)
		)
		(duplicate_pad_numbers_are_jumpers no)
		(fp_line
			(start -0.7874 0.4064)
			(end 0.7874 0.4064)
			(stroke
				(width 0.1524)
				(type default)
			)
			(layer "B.SilkS")
		)
		(fp_line
			(start 0.7874 0.4064)
			(end 0.7874 -0.4064)
			(stroke
				(width 0.1524)
				(type default)
			)
			(layer "B.SilkS")
		)
		(fp_line
			(start -0.7874 -0.4064)
			(end -0.7874 0.4064)
			(stroke
				(width 0.1524)
				(type default)
			)
			(layer "B.SilkS")
		)
		(fp_line
			(start 0.7874 -0.4064)
			(end -0.7874 -0.4064)
			(stroke
				(width 0.1524)
				(type default)
			)
			(layer "B.SilkS")
		)
		(fp_line
			(start -0.67945 0.3048)
			(end -0.120396 0.3048)
			(stroke
				(width 0.1)
				(type default)
			)
			(layer "B.Fab")
		)
		(fp_line
			(start -0.120396 0.3048)
			(end -0.120396 0.2794)
			(stroke
				(width 0.1)
				(type default)
			)
			(layer "B.Fab")
		)
		(fp_line
			(start 0.12065 0.3048)
			(end 0.67945 0.3048)
			(stroke
				(width 0.1)
				(type default)
			)
			(layer "B.Fab")
		)
		(fp_line
			(start 0.67945 0.3048)
			(end 0.67945 -0.305054)
			(stroke
				(width 0.1)
				(type default)
			)
			(layer "B.Fab")
		)
		(fp_line
			(start -0.120396 0.2794)
			(end 0.12065 0.2794)
			(stroke
				(width 0.1)
				(type default)
			)
			(layer "B.Fab")
		)
		(fp_line
			(start 0.12065 0.2794)
			(end 0.12065 0.3048)
			(stroke
				(width 0.1)
				(type default)
			)
			(layer "B.Fab")
		)
		(fp_line
			(start -0.12065 -0.2794)
			(end -0.12065 -0.3048)
			(stroke
				(width 0.1)
				(type default)
			)
			(layer "B.Fab")
		)
		(fp_line
			(start 0.12065 -0.2794)
			(end -0.12065 -0.2794)
			(stroke
				(width 0.1)
				(type default)
			)
			(layer "B.Fab")
		)
		(fp_line
			(start -0.67945 -0.3048)
			(end -0.67945 0.3048)
			(stroke
				(width 0.1)
				(type default)
			)
			(layer "B.Fab")
		)
		(fp_line
			(start -0.12065 -0.3048)
			(end -0.67945 -0.3048)
			(stroke
				(width 0.1)
				(type default)
			)
			(layer "B.Fab")
		)
		(fp_line
			(start 0.12065 -0.305054)
			(end 0.12065 -0.2794)
			(stroke
				(width 0.1)
				(type default)
			)
			(layer "B.Fab")
		)
		(fp_line
			(start 0.67945 -0.305054)
			(end 0.12065 -0.305054)
			(stroke
				(width 0.1)
				(type default)
			)
			(layer "B.Fab")
		)
		(pad "1" smd circle
			(at 0.40005 0 90)
			(size 0 0)
			(layers "B.Cu" "B.Mask" "B.Paste")
			(net "P1V0_STBY_PLAVDD")
		)
		(pad "2" smd circle
			(at -0.40005 0 90)
			(size 0 0)
			(layers "B.Cu" "B.Mask" "B.Paste")
			(net "GND")
		)
	)
	(footprint ""
		(layer "B.Cu")
		(at 68.58 -13.462)
		(property "Reference" "R882"
			(at 0 0 0)
			(layer "B.SilkS")
			(hide yes)
			(effects
				(font
					(size 1.27 1.27)
				)
				(justify mirror)
			)
		)
		(property "Value" ""
			(at 0 0 0)
			(layer "B.Fab")
			(effects
				(font
					(size 1.27 1.27)
				)
				(justify mirror)
			)
		)
		(duplicate_pad_numbers_are_jumpers no)
		(fp_line
			(start -0.7874 -0.4064)
			(end -0.7874 0.4064)
			(stroke
				(width 0.1524)
				(type default)
			)
			(layer "B.SilkS")
		)
		(fp_line
			(start -0.7874 0.4064)
			(end 0.7874 0.4064)
			(stroke
				(width 0.1524)
				(type default)
			)
			(layer "B.SilkS")
		)
		(fp_line
			(start 0.7874 -0.4064)
			(end -0.7874 -0.4064)
			(stroke
				(width 0.1524)
				(type default)
			)
			(layer "B.SilkS")
		)
		(fp_line
			(start 0.7874 0.4064)
			(end 0.7874 -0.4064)
			(stroke
				(width 0.1524)
				(type default)
			)
			(layer "B.SilkS")
		)
		(fp_line
			(start -0.67945 -0.3048)
			(end -0.67945 0.3048)
			(stroke
				(width 0.1)
				(type default)
			)
			(layer "B.Fab")
		)
		(fp_line
			(start -0.67945 0.3048)
			(end -0.120396 0.3048)
			(stroke
				(width 0.1)
				(type default)
			)
			(layer "B.Fab")
		)
		(fp_line
			(start -0.12065 -0.3048)
			(end -0.67945 -0.3048)
			(stroke
				(width 0.1)
				(type default)
			)
			(layer "B.Fab")
		)
		(fp_line
			(start -0.12065 -0.2794)
			(end -0.12065 -0.3048)
			(stroke
				(width 0.1)
				(type default)
			)
			(layer "B.Fab")
		)
		(fp_line
			(start -0.120396 0.2794)
			(end 0.12065 0.2794)
			(stroke
				(width 0.1)
				(type default)
			)
			(layer "B.Fab")
		)
		(fp_line
			(start -0.120396 0.3048)
			(end -0.120396 0.2794)
			(stroke
				(width 0.1)
				(type default)
			)
			(layer "B.Fab")
		)
		(fp_line
			(start 0.12065 -0.305054)
			(end 0.12065 -0.2794)
			(stroke
				(width 0.1)
				(type default)
			)
			(layer "B.Fab")
		)
		(fp_line
			(start 0.12065 -0.2794)
			(end -0.12065 -0.2794)
			(stroke
				(width 0.1)
				(type default)
			)
			(layer "B.Fab")
		)
		(fp_line
			(start 0.12065 0.2794)
			(end 0.12065 0.3048)
			(stroke
				(width 0.1)
				(type default)
			)
			(layer "B.Fab")
		)
		(fp_line
			(start 0.12065 0.3048)
			(end 0.67945 0.3048)
			(stroke
				(width 0.1)
				(type default)
			)
			(layer "B.Fab")
		)
		(fp_line
			(start 0.67945 -0.305054)
			(end 0.12065 -0.305054)
			(stroke
				(width 0.1)
				(type default)
			)
			(layer "B.Fab")
		)
		(fp_line
			(start 0.67945 0.3048)
			(end 0.67945 -0.305054)
			(stroke
				(width 0.1)
				(type default)
			)
			(layer "B.Fab")
		)
		(pad "1" smd circle
			(at 0.40005 0 180)
			(size 0 0)
			(layers "B.Cu" "B.Mask" "B.Paste")
			(net "REAR_AC_PWR_BTN")
		)
		(pad "2" smd circle
			(at -0.40005 0 180)
			(size 0 0)
			(layers "B.Cu" "B.Mask" "B.Paste")
			(net "REAR_AC_PWR_BMC_BTN_N")
		)
	)
	(footprint ""
		(layer "B.Cu")
		(at 30.3784 -95.7072)
		(property "Reference" "C337"
			(at 0 0 0)
			(layer "B.SilkS")
			(hide yes)
			(effects
				(font
					(size 1.27 1.27)
				)
				(justify mirror)
			)
		)
		(property "Value" ""
			(at 0 0 0)
			(layer "B.Fab")
			(effects
				(font
					(size 1.27 1.27)
				)
				(justify mirror)
			)
		)
		(duplicate_pad_numbers_are_jumpers no)
		(fp_line
			(start -0.7874 -0.4064)
			(end -0.7874 0.4064)
			(stroke
				(width 0.1524)
				(type default)
			)
			(layer "B.SilkS")
		)
		(fp_line
			(start -0.7874 0.4064)
			(end 0.7874 0.4064)
			(stroke
				(width 0.1524)
				(type default)
			)
			(layer "B.SilkS")
		)
		(fp_line
			(start 0.7874 -0.4064)
			(end -0.7874 -0.4064)
			(stroke
				(width 0.1524)
				(type default)
			)
			(layer "B.SilkS")
		)
		(fp_line
			(start 0.7874 0.4064)
			(end 0.7874 -0.4064)
			(stroke
				(width 0.1524)
				(type default)
			)
			(layer "B.SilkS")
		)
		(fp_line
			(start -0.67945 -0.3048)
			(end -0.67945 0.3048)
			(stroke
				(width 0.1)
				(type default)
			)
			(layer "B.Fab")
		)
		(fp_line
			(start -0.67945 0.3048)
			(end -0.120396 0.3048)
			(stroke
				(width 0.1)
				(type default)
			)
			(layer "B.Fab")
		)
		(fp_line
			(start -0.12065 -0.3048)
			(end -0.67945 -0.3048)
			(stroke
				(width 0.1)
				(type default)
			)
			(layer "B.Fab")
		)
		(fp_line
			(start -0.12065 -0.2794)
			(end -0.12065 -0.3048)
			(stroke
				(width 0.1)
				(type default)
			)
			(layer "B.Fab")
		)
		(fp_line
			(start -0.120396 0.2794)
			(end 0.12065 0.2794)
			(stroke
				(width 0.1)
				(type default)
			)
			(layer "B.Fab")
		)
		(fp_line
			(start -0.120396 0.3048)
			(end -0.120396 0.2794)
			(stroke
				(width 0.1)
				(type default)
			)
			(layer "B.Fab")
		)
		(fp_line
			(start 0.12065 -0.305054)
			(end 0.12065 -0.2794)
			(stroke
				(width 0.1)
				(type default)
			)
			(layer "B.Fab")
		)
		(fp_line
			(start 0.12065 -0.2794)
			(end -0.12065 -0.2794)
			(stroke
				(width 0.1)
				(type default)
			)
			(layer "B.Fab")
		)
		(fp_line
			(start 0.12065 0.2794)
			(end 0.12065 0.3048)
			(stroke
				(width 0.1)
				(type default)
			)
			(layer "B.Fab")
		)
		(fp_line
			(start 0.12065 0.3048)
			(end 0.67945 0.3048)
			(stroke
				(width 0.1)
				(type default)
			)
			(layer "B.Fab")
		)
		(fp_line
			(start 0.67945 -0.305054)
			(end 0.12065 -0.305054)
			(stroke
				(width 0.1)
				(type default)
			)
			(layer "B.Fab")
		)
		(fp_line
			(start 0.67945 0.3048)
			(end 0.67945 -0.305054)
			(stroke
				(width 0.1)
				(type default)
			)
			(layer "B.Fab")
		)
		(pad "1" smd circle
			(at 0.40005 0 180)
			(size 0 0)
			(layers "B.Cu" "B.Mask" "B.Paste")
			(net "P3V3_AUX")
		)
		(pad "2" smd circle
			(at -0.40005 0 180)
			(size 0 0)
			(layers "B.Cu" "B.Mask" "B.Paste")
			(net "GND")
		)
	)
	(footprint ""
		(layer "B.Cu")
		(at 39.647114 -61.627766)
		(property "Reference" "R804"
			(at 0 0 0)
			(layer "B.SilkS")
			(hide yes)
			(effects
				(font
					(size 1.27 1.27)
				)
				(justify mirror)
			)
		)
		(property "Value" ""
			(at 0 0 0)
			(layer "B.Fab")
			(effects
				(font
					(size 1.27 1.27)
				)
				(justify mirror)
			)
		)
		(duplicate_pad_numbers_are_jumpers no)
		(fp_line
			(start -0.7874 -0.4064)
			(end -0.7874 0.4064)
			(stroke
				(width 0.1524)
				(type default)
			)
			(layer "B.SilkS")
		)
		(fp_line
			(start -0.7874 0.4064)
			(end 0.7874 0.4064)
			(stroke
				(width 0.1524)
				(type default)
			)
			(layer "B.SilkS")
		)
		(fp_line
			(start 0.7874 -0.4064)
			(end -0.7874 -0.4064)
			(stroke
				(width 0.1524)
				(type default)
			)
			(layer "B.SilkS")
		)
		(fp_line
			(start 0.7874 0.4064)
			(end 0.7874 -0.4064)
			(stroke
				(width 0.1524)
				(type default)
			)
			(layer "B.SilkS")
		)
		(fp_line
			(start -0.67945 -0.3048)
			(end -0.67945 0.3048)
			(stroke
				(width 0.1)
				(type default)
			)
			(layer "B.Fab")
		)
		(fp_line
			(start -0.67945 0.3048)
			(end -0.120396 0.3048)
			(stroke
				(width 0.1)
				(type default)
			)
			(layer "B.Fab")
		)
		(fp_line
			(start -0.12065 -0.3048)
			(end -0.67945 -0.3048)
			(stroke
				(width 0.1)
				(type default)
			)
			(layer "B.Fab")
		)
		(fp_line
			(start -0.12065 -0.2794)
			(end -0.12065 -0.3048)
			(stroke
				(width 0.1)
				(type default)
			)
			(layer "B.Fab")
		)
		(fp_line
			(start -0.120396 0.2794)
			(end 0.12065 0.2794)
			(stroke
				(width 0.1)
				(type default)
			)
			(layer "B.Fab")
		)
		(fp_line
			(start -0.120396 0.3048)
			(end -0.120396 0.2794)
			(stroke
				(width 0.1)
				(type default)
			)
			(layer "B.Fab")
		)
		(fp_line
			(start 0.12065 -0.305054)
			(end 0.12065 -0.2794)
			(stroke
				(width 0.1)
				(type default)
			)
			(layer "B.Fab")
		)
		(fp_line
			(start 0.12065 -0.2794)
			(end -0.12065 -0.2794)
			(stroke
				(width 0.1)
				(type default)
			)
			(layer "B.Fab")
		)
		(fp_line
			(start 0.12065 0.2794)
			(end 0.12065 0.3048)
			(stroke
				(width 0.1)
				(type default)
			)
			(layer "B.Fab")
		)
		(fp_line
			(start 0.12065 0.3048)
			(end 0.67945 0.3048)
			(stroke
				(width 0.1)
				(type default)
			)
			(layer "B.Fab")
		)
		(fp_line
			(start 0.67945 -0.305054)
			(end 0.12065 -0.305054)
			(stroke
				(width 0.1)
				(type default)
			)
			(layer "B.Fab")
		)
		(fp_line
			(start 0.67945 0.3048)
			(end 0.67945 -0.305054)
			(stroke
				(width 0.1)
				(type default)
			)
			(layer "B.Fab")
		)
		(pad "1" smd circle
			(at 0.40005 0 180)
			(size 0 0)
			(layers "B.Cu" "B.Mask" "B.Paste")
			(net "SYS_BMC_PWRBTN_R1_N")
		)
		(pad "2" smd circle
			(at -0.40005 0 180)
			(size 0 0)
			(layers "B.Cu" "B.Mask" "B.Paste")
			(net "SYS_BMC_PWRBTN_R_N")
		)
	)
	(footprint ""
		(layer "B.Cu")
		(at 25.019 -91.44)
		(property "Reference" "R305"
			(at 0 0 0)
			(layer "B.SilkS")
			(hide yes)
			(effects
				(font
					(size 1.27 1.27)
				)
				(justify mirror)
			)
		)
		(property "Value" ""
			(at 0 0 0)
			(layer "B.Fab")
			(effects
				(font
					(size 1.27 1.27)
				)
				(justify mirror)
			)
		)
		(duplicate_pad_numbers_are_jumpers no)
		(fp_line
			(start -0.7874 -0.4064)
			(end -0.7874 0.4064)
			(stroke
				(width 0.1524)
				(type default)
			)
			(layer "B.SilkS")
		)
		(fp_line
			(start -0.7874 0.4064)
			(end 0.7874 0.4064)
			(stroke
				(width 0.1524)
				(type default)
			)
			(layer "B.SilkS")
		)
		(fp_line
			(start 0.7874 -0.4064)
			(end -0.7874 -0.4064)
			(stroke
				(width 0.1524)
				(type default)
			)
			(layer "B.SilkS")
		)
		(fp_line
			(start 0.7874 0.4064)
			(end 0.7874 -0.4064)
			(stroke
				(width 0.1524)
				(type default)
			)
			(layer "B.SilkS")
		)
		(fp_line
			(start -0.67945 -0.3048)
			(end -0.67945 0.3048)
			(stroke
				(width 0.1)
				(type default)
			)
			(layer "B.Fab")
		)
		(fp_line
			(start -0.67945 0.3048)
			(end -0.120396 0.3048)
			(stroke
				(width 0.1)
				(type default)
			)
			(layer "B.Fab")
		)
		(fp_line
			(start -0.12065 -0.3048)
			(end -0.67945 -0.3048)
			(stroke
				(width 0.1)
				(type default)
			)
			(layer "B.Fab")
		)
		(fp_line
			(start -0.12065 -0.2794)
			(end -0.12065 -0.3048)
			(stroke
				(width 0.1)
				(type default)
			)
			(layer "B.Fab")
		)
		(fp_line
			(start -0.120396 0.2794)
			(end 0.12065 0.2794)
			(stroke
				(width 0.1)
				(type default)
			)
			(layer "B.Fab")
		)
		(fp_line
			(start -0.120396 0.3048)
			(end -0.120396 0.2794)
			(stroke
				(width 0.1)
				(type default)
			)
			(layer "B.Fab")
		)
		(fp_line
			(start 0.12065 -0.305054)
			(end 0.12065 -0.2794)
			(stroke
				(width 0.1)
				(type default)
			)
			(layer "B.Fab")
		)
		(fp_line
			(start 0.12065 -0.2794)
			(end -0.12065 -0.2794)
			(stroke
				(width 0.1)
				(type default)
			)
			(layer "B.Fab")
		)
		(fp_line
			(start 0.12065 0.2794)
			(end 0.12065 0.3048)
			(stroke
				(width 0.1)
				(type default)
			)
			(layer "B.Fab")
		)
		(fp_line
			(start 0.12065 0.3048)
			(end 0.67945 0.3048)
			(stroke
				(width 0.1)
				(type default)
			)
			(layer "B.Fab")
		)
		(fp_line
			(start 0.67945 -0.305054)
			(end 0.12065 -0.305054)
			(stroke
				(width 0.1)
				(type default)
			)
			(layer "B.Fab")
		)
		(fp_line
			(start 0.67945 0.3048)
			(end 0.67945 -0.305054)
			(stroke
				(width 0.1)
				(type default)
			)
			(layer "B.Fab")
		)
		(pad "1" smd circle
			(at 0.40005 0 180)
			(size 0 0)
			(layers "B.Cu" "B.Mask" "B.Paste")
			(net "P3V3_AUX")
		)
		(pad "2" smd circle
			(at -0.40005 0 180)
			(size 0 0)
			(layers "B.Cu" "B.Mask" "B.Paste")
			(net "VCCIO0")
		)
	)
	(footprint ""
		(layer "B.Cu")
		(at 41.859454 -65.776094 -90)
		(property "Reference" "R194"
			(at 0 0 90)
			(layer "B.SilkS")
			(hide yes)
			(effects
				(font
					(size 1.27 1.27)
				)
				(justify mirror)
			)
		)
		(property "Value" ""
			(at 0 0 90)
			(layer "B.Fab")
			(effects
				(font
					(size 1.27 1.27)
				)
				(justify mirror)
			)
		)
		(duplicate_pad_numbers_are_jumpers no)
		(fp_line
			(start -0.7874 0.4064)
			(end 0.7874 0.4064)
			(stroke
				(width 0.1524)
				(type default)
			)
			(layer "B.SilkS")
		)
		(fp_line
			(start 0.7874 0.4064)
			(end 0.7874 -0.4064)
			(stroke
				(width 0.1524)
				(type default)
			)
			(layer "B.SilkS")
		)
		(fp_line
			(start -0.7874 -0.4064)
			(end -0.7874 0.4064)
			(stroke
				(width 0.1524)
				(type default)
			)
			(layer "B.SilkS")
		)
		(fp_line
			(start 0.7874 -0.4064)
			(end -0.7874 -0.4064)
			(stroke
				(width 0.1524)
				(type default)
			)
			(layer "B.SilkS")
		)
		(fp_line
			(start -0.67945 0.3048)
			(end -0.120396 0.3048)
			(stroke
				(width 0.1)
				(type default)
			)
			(layer "B.Fab")
		)
		(fp_line
			(start -0.120396 0.3048)
			(end -0.120396 0.2794)
			(stroke
				(width 0.1)
				(type default)
			)
			(layer "B.Fab")
		)
		(fp_line
			(start 0.12065 0.3048)
			(end 0.67945 0.3048)
			(stroke
				(width 0.1)
				(type default)
			)
			(layer "B.Fab")
		)
		(fp_line
			(start 0.67945 0.3048)
			(end 0.67945 -0.305054)
			(stroke
				(width 0.1)
				(type default)
			)
			(layer "B.Fab")
		)
		(fp_line
			(start -0.120396 0.2794)
			(end 0.12065 0.2794)
			(stroke
				(width 0.1)
				(type default)
			)
			(layer "B.Fab")
		)
		(fp_line
			(start 0.12065 0.2794)
			(end 0.12065 0.3048)
			(stroke
				(width 0.1)
				(type default)
			)
			(layer "B.Fab")
		)
		(fp_line
			(start -0.12065 -0.2794)
			(end -0.12065 -0.3048)
			(stroke
				(width 0.1)
				(type default)
			)
			(layer "B.Fab")
		)
		(fp_line
			(start 0.12065 -0.2794)
			(end -0.12065 -0.2794)
			(stroke
				(width 0.1)
				(type default)
			)
			(layer "B.Fab")
		)
		(fp_line
			(start -0.67945 -0.3048)
			(end -0.67945 0.3048)
			(stroke
				(width 0.1)
				(type default)
			)
			(layer "B.Fab")
		)
		(fp_line
			(start -0.12065 -0.3048)
			(end -0.67945 -0.3048)
			(stroke
				(width 0.1)
				(type default)
			)
			(layer "B.Fab")
		)
		(fp_line
			(start 0.12065 -0.305054)
			(end 0.12065 -0.2794)
			(stroke
				(width 0.1)
				(type default)
			)
			(layer "B.Fab")
		)
		(fp_line
			(start 0.67945 -0.305054)
			(end 0.12065 -0.305054)
			(stroke
				(width 0.1)
				(type default)
			)
			(layer "B.Fab")
		)
		(pad "1" smd circle
			(at 0.40005 0 90)
			(size 0 0)
			(layers "B.Cu" "B.Mask" "B.Paste")
			(net "P1V2_P1V0_I3C_VDDL1")
		)
		(pad "2" smd circle
			(at -0.40005 0 90)
			(size 0 0)
			(layers "B.Cu" "B.Mask" "B.Paste")
			(net "I3C1_SPD_SCL")
		)
	)
	(footprint ""
		(layer "B.Cu")
		(at 50.858674 -72.842374)
		(property "Reference" "R793"
			(at 0 0 0)
			(layer "B.SilkS")
			(hide yes)
			(effects
				(font
					(size 1.27 1.27)
				)
				(justify mirror)
			)
		)
		(property "Value" ""
			(at 0 0 0)
			(layer "B.Fab")
			(effects
				(font
					(size 1.27 1.27)
				)
				(justify mirror)
			)
		)
		(duplicate_pad_numbers_are_jumpers no)
		(fp_line
			(start -0.7874 -0.4064)
			(end -0.7874 0.4064)
			(stroke
				(width 0.1524)
				(type default)
			)
			(layer "B.SilkS")
		)
		(fp_line
			(start -0.7874 0.4064)
			(end 0.7874 0.4064)
			(stroke
				(width 0.1524)
				(type default)
			)
			(layer "B.SilkS")
		)
		(fp_line
			(start 0.7874 -0.4064)
			(end -0.7874 -0.4064)
			(stroke
				(width 0.1524)
				(type default)
			)
			(layer "B.SilkS")
		)
		(fp_line
			(start 0.7874 0.4064)
			(end 0.7874 -0.4064)
			(stroke
				(width 0.1524)
				(type default)
			)
			(layer "B.SilkS")
		)
		(fp_line
			(start -0.67945 -0.3048)
			(end -0.67945 0.3048)
			(stroke
				(width 0.1)
				(type default)
			)
			(layer "B.Fab")
		)
		(fp_line
			(start -0.67945 0.3048)
			(end -0.120396 0.3048)
			(stroke
				(width 0.1)
				(type default)
			)
			(layer "B.Fab")
		)
		(fp_line
			(start -0.12065 -0.3048)
			(end -0.67945 -0.3048)
			(stroke
				(width 0.1)
				(type default)
			)
			(layer "B.Fab")
		)
		(fp_line
			(start -0.12065 -0.2794)
			(end -0.12065 -0.3048)
			(stroke
				(width 0.1)
				(type default)
			)
			(layer "B.Fab")
		)
		(fp_line
			(start -0.120396 0.2794)
			(end 0.12065 0.2794)
			(stroke
				(width 0.1)
				(type default)
			)
			(layer "B.Fab")
		)
		(fp_line
			(start -0.120396 0.3048)
			(end -0.120396 0.2794)
			(stroke
				(width 0.1)
				(type default)
			)
			(layer "B.Fab")
		)
		(fp_line
			(start 0.12065 -0.305054)
			(end 0.12065 -0.2794)
			(stroke
				(width 0.1)
				(type default)
			)
			(layer "B.Fab")
		)
		(fp_line
			(start 0.12065 -0.2794)
			(end -0.12065 -0.2794)
			(stroke
				(width 0.1)
				(type default)
			)
			(layer "B.Fab")
		)
		(fp_line
			(start 0.12065 0.2794)
			(end 0.12065 0.3048)
			(stroke
				(width 0.1)
				(type default)
			)
			(layer "B.Fab")
		)
		(fp_line
			(start 0.12065 0.3048)
			(end 0.67945 0.3048)
			(stroke
				(width 0.1)
				(type default)
			)
			(layer "B.Fab")
		)
		(fp_line
			(start 0.67945 -0.305054)
			(end 0.12065 -0.305054)
			(stroke
				(width 0.1)
				(type default)
			)
			(layer "B.Fab")
		)
		(fp_line
			(start 0.67945 0.3048)
			(end 0.67945 -0.305054)
			(stroke
				(width 0.1)
				(type default)
			)
			(layer "B.Fab")
		)
		(pad "1" smd circle
			(at 0.40005 0 180)
			(size 0 0)
			(layers "B.Cu" "B.Mask" "B.Paste")
			(net "P1V8_AUX")
		)
		(pad "2" smd circle
			(at -0.40005 0 180)
			(size 0 0)
			(layers "B.Cu" "B.Mask" "B.Paste")
			(net "P1V8_SENSOR")
		)
	)
	(footprint ""
		(layer "B.Cu")
		(at 57.687464 -63.861696 90)
		(property "Reference" "R802"
			(at 0 0 90)
			(layer "B.SilkS")
			(hide yes)
			(effects
				(font
					(size 1.27 1.27)
				)
				(justify mirror)
			)
		)
		(property "Value" ""
			(at 0 0 90)
			(layer "B.Fab")
			(effects
				(font
					(size 1.27 1.27)
				)
				(justify mirror)
			)
		)
		(duplicate_pad_numbers_are_jumpers no)
		(fp_line
			(start 0.7874 -0.4064)
			(end -0.7874 -0.4064)
			(stroke
				(width 0.1524)
				(type default)
			)
			(layer "B.SilkS")
		)
		(fp_line
			(start -0.7874 -0.4064)
			(end -0.7874 0.4064)
			(stroke
				(width 0.1524)
				(type default)
			)
			(layer "B.SilkS")
		)
		(fp_line
			(start 0.7874 0.4064)
			(end 0.7874 -0.4064)
			(stroke
				(width 0.1524)
				(type default)
			)
			(layer "B.SilkS")
		)
		(fp_line
			(start -0.7874 0.4064)
			(end 0.7874 0.4064)
			(stroke
				(width 0.1524)
				(type default)
			)
			(layer "B.SilkS")
		)
		(fp_line
			(start 0.67945 -0.305054)
			(end 0.12065 -0.305054)
			(stroke
				(width 0.1)
				(type default)
			)
			(layer "B.Fab")
		)
		(fp_line
			(start 0.12065 -0.305054)
			(end 0.12065 -0.2794)
			(stroke
				(width 0.1)
				(type default)
			)
			(layer "B.Fab")
		)
		(fp_line
			(start -0.12065 -0.3048)
			(end -0.67945 -0.3048)
			(stroke
				(width 0.1)
				(type default)
			)
			(layer "B.Fab")
		)
		(fp_line
			(start -0.67945 -0.3048)
			(end -0.67945 0.3048)
			(stroke
				(width 0.1)
				(type default)
			)
			(layer "B.Fab")
		)
		(fp_line
			(start 0.12065 -0.2794)
			(end -0.12065 -0.2794)
			(stroke
				(width 0.1)
				(type default)
			)
			(layer "B.Fab")
		)
		(fp_line
			(start -0.12065 -0.2794)
			(end -0.12065 -0.3048)
			(stroke
				(width 0.1)
				(type default)
			)
			(layer "B.Fab")
		)
		(fp_line
			(start 0.12065 0.2794)
			(end 0.12065 0.3048)
			(stroke
				(width 0.1)
				(type default)
			)
			(layer "B.Fab")
		)
		(fp_line
			(start -0.120396 0.2794)
			(end 0.12065 0.2794)
			(stroke
				(width 0.1)
				(type default)
			)
			(layer "B.Fab")
		)
		(fp_line
			(start 0.67945 0.3048)
			(end 0.67945 -0.305054)
			(stroke
				(width 0.1)
				(type default)
			)
			(layer "B.Fab")
		)
		(fp_line
			(start 0.12065 0.3048)
			(end 0.67945 0.3048)
			(stroke
				(width 0.1)
				(type default)
			)
			(layer "B.Fab")
		)
		(fp_line
			(start -0.120396 0.3048)
			(end -0.120396 0.2794)
			(stroke
				(width 0.1)
				(type default)
			)
			(layer "B.Fab")
		)
		(fp_line
			(start -0.67945 0.3048)
			(end -0.120396 0.3048)
			(stroke
				(width 0.1)
				(type default)
			)
			(layer "B.Fab")
		)
		(pad "1" smd circle
			(at 0.40005 0 270)
			(size 0 0)
			(layers "B.Cu" "B.Mask" "B.Paste")
			(net "SPI_BMC_BOOT_CS1_R_N")
		)
		(pad "2" smd circle
			(at -0.40005 0 270)
			(size 0 0)
			(layers "B.Cu" "B.Mask" "B.Paste")
			(net "SPI_BMC_BOOT_CS1_R1_N")
		)
	)
	(footprint ""
		(layer "B.Cu")
		(at 70.104 -41.656 90)
		(property "Reference" "C225"
			(at 0 0 90)
			(layer "B.SilkS")
			(hide yes)
			(effects
				(font
					(size 1.27 1.27)
				)
				(justify mirror)
			)
		)
		(property "Value" ""
			(at 0 0 90)
			(layer "B.Fab")
			(effects
				(font
					(size 1.27 1.27)
				)
				(justify mirror)
			)
		)
		(duplicate_pad_numbers_are_jumpers no)
		(fp_line
			(start 0.7874 -0.4064)
			(end -0.7874 -0.4064)
			(stroke
				(width 0.1524)
				(type default)
			)
			(layer "B.SilkS")
		)
		(fp_line
			(start -0.7874 -0.4064)
			(end -0.7874 0.4064)
			(stroke
				(width 0.1524)
				(type default)
			)
			(layer "B.SilkS")
		)
		(fp_line
			(start 0.7874 0.4064)
			(end 0.7874 -0.4064)
			(stroke
				(width 0.1524)
				(type default)
			)
			(layer "B.SilkS")
		)
		(fp_line
			(start -0.7874 0.4064)
			(end 0.7874 0.4064)
			(stroke
				(width 0.1524)
				(type default)
			)
			(layer "B.SilkS")
		)
		(fp_line
			(start 0.67945 -0.305054)
			(end 0.12065 -0.305054)
			(stroke
				(width 0.1)
				(type default)
			)
			(layer "B.Fab")
		)
		(fp_line
			(start 0.12065 -0.305054)
			(end 0.12065 -0.2794)
			(stroke
				(width 0.1)
				(type default)
			)
			(layer "B.Fab")
		)
		(fp_line
			(start -0.12065 -0.3048)
			(end -0.67945 -0.3048)
			(stroke
				(width 0.1)
				(type default)
			)
			(layer "B.Fab")
		)
		(fp_line
			(start -0.67945 -0.3048)
			(end -0.67945 0.3048)
			(stroke
				(width 0.1)
				(type default)
			)
			(layer "B.Fab")
		)
		(fp_line
			(start 0.12065 -0.2794)
			(end -0.12065 -0.2794)
			(stroke
				(width 0.1)
				(type default)
			)
			(layer "B.Fab")
		)
		(fp_line
			(start -0.12065 -0.2794)
			(end -0.12065 -0.3048)
			(stroke
				(width 0.1)
				(type default)
			)
			(layer "B.Fab")
		)
		(fp_line
			(start 0.12065 0.2794)
			(end 0.12065 0.3048)
			(stroke
				(width 0.1)
				(type default)
			)
			(layer "B.Fab")
		)
		(fp_line
			(start -0.120396 0.2794)
			(end 0.12065 0.2794)
			(stroke
				(width 0.1)
				(type default)
			)
			(layer "B.Fab")
		)
		(fp_line
			(start 0.67945 0.3048)
			(end 0.67945 -0.305054)
			(stroke
				(width 0.1)
				(type default)
			)
			(layer "B.Fab")
		)
		(fp_line
			(start 0.12065 0.3048)
			(end 0.67945 0.3048)
			(stroke
				(width 0.1)
				(type default)
			)
			(layer "B.Fab")
		)
		(fp_line
			(start -0.120396 0.3048)
			(end -0.120396 0.2794)
			(stroke
				(width 0.1)
				(type default)
			)
			(layer "B.Fab")
		)
		(fp_line
			(start -0.67945 0.3048)
			(end -0.120396 0.3048)
			(stroke
				(width 0.1)
				(type default)
			)
			(layer "B.Fab")
		)
		(pad "1" smd circle
			(at 0.40005 0 270)
			(size 0 0)
			(layers "B.Cu" "B.Mask" "B.Paste")
			(net "P1V2_AUX")
		)
		(pad "2" smd circle
			(at -0.40005 0 270)
			(size 0 0)
			(layers "B.Cu" "B.Mask" "B.Paste")
			(net "GND")
		)
	)
	(footprint ""
		(layer "B.Cu")
		(at 64.643 -13.081 180)
		(property "Reference" "R630"
			(at 0 0 0)
			(layer "B.SilkS")
			(hide yes)
			(effects
				(font
					(size 1.27 1.27)
				)
				(justify mirror)
			)
		)
		(property "Value" ""
			(at 0 0 0)
			(layer "B.Fab")
			(effects
				(font
					(size 1.27 1.27)
				)
				(justify mirror)
			)
		)
		(duplicate_pad_numbers_are_jumpers no)
		(fp_line
			(start 0.7874 0.4064)
			(end 0.7874 -0.4064)
			(stroke
				(width 0.1524)
				(type default)
			)
			(layer "B.SilkS")
		)
		(fp_line
			(start 0.7874 -0.4064)
			(end -0.7874 -0.4064)
			(stroke
				(width 0.1524)
				(type default)
			)
			(layer "B.SilkS")
		)
		(fp_line
			(start -0.7874 0.4064)
			(end 0.7874 0.4064)
			(stroke
				(width 0.1524)
				(type default)
			)
			(layer "B.SilkS")
		)
		(fp_line
			(start -0.7874 -0.4064)
			(end -0.7874 0.4064)
			(stroke
				(width 0.1524)
				(type default)
			)
			(layer "B.SilkS")
		)
		(fp_line
			(start 0.67945 0.3048)
			(end 0.67945 -0.305054)
			(stroke
				(width 0.1)
				(type default)
			)
			(layer "B.Fab")
		)
		(fp_line
			(start 0.67945 -0.305054)
			(end 0.12065 -0.305054)
			(stroke
				(width 0.1)
				(type default)
			)
			(layer "B.Fab")
		)
		(fp_line
			(start 0.12065 0.3048)
			(end 0.67945 0.3048)
			(stroke
				(width 0.1)
				(type default)
			)
			(layer "B.Fab")
		)
		(fp_line
			(start 0.12065 0.2794)
			(end 0.12065 0.3048)
			(stroke
				(width 0.1)
				(type default)
			)
			(layer "B.Fab")
		)
		(fp_line
			(start 0.12065 -0.2794)
			(end -0.12065 -0.2794)
			(stroke
				(width 0.1)
				(type default)
			)
			(layer "B.Fab")
		)
		(fp_line
			(start 0.12065 -0.305054)
			(end 0.12065 -0.2794)
			(stroke
				(width 0.1)
				(type default)
			)
			(layer "B.Fab")
		)
		(fp_line
			(start -0.120396 0.3048)
			(end -0.120396 0.2794)
			(stroke
				(width 0.1)
				(type default)
			)
			(layer "B.Fab")
		)
		(fp_line
			(start -0.120396 0.2794)
			(end 0.12065 0.2794)
			(stroke
				(width 0.1)
				(type default)
			)
			(layer "B.Fab")
		)
		(fp_line
			(start -0.12065 -0.2794)
			(end -0.12065 -0.3048)
			(stroke
				(width 0.1)
				(type default)
			)
			(layer "B.Fab")
		)
		(fp_line
			(start -0.12065 -0.3048)
			(end -0.67945 -0.3048)
			(stroke
				(width 0.1)
				(type default)
			)
			(layer "B.Fab")
		)
		(fp_line
			(start -0.67945 0.3048)
			(end -0.120396 0.3048)
			(stroke
				(width 0.1)
				(type default)
			)
			(layer "B.Fab")
		)
		(fp_line
			(start -0.67945 -0.3048)
			(end -0.67945 0.3048)
			(stroke
				(width 0.1)
				(type default)
			)
			(layer "B.Fab")
		)
		(pad "1" smd circle
			(at 0.40005 0)
			(size 0 0)
			(layers "B.Cu" "B.Mask" "B.Paste")
			(net "P3V3_AUX")
		)
		(pad "2" smd circle
			(at -0.40005 0)
			(size 0 0)
			(layers "B.Cu" "B.Mask" "B.Paste")
			(net "PU_J13_P1")
		)
	)
	(footprint ""
		(layer "B.Cu")
		(at 52.384452 -60.134246 90)
		(property "Reference" "C279"
			(at 0 0 90)
			(layer "B.SilkS")
			(hide yes)
			(effects
				(font
					(size 1.27 1.27)
				)
				(justify mirror)
			)
		)
		(property "Value" ""
			(at 0 0 90)
			(layer "B.Fab")
			(effects
				(font
					(size 1.27 1.27)
				)
				(justify mirror)
			)
		)
		(duplicate_pad_numbers_are_jumpers no)
		(fp_line
			(start 0.7874 -0.4064)
			(end -0.7874 -0.4064)
			(stroke
				(width 0.1524)
				(type default)
			)
			(layer "B.SilkS")
		)
		(fp_line
			(start -0.7874 -0.4064)
			(end -0.7874 0.4064)
			(stroke
				(width 0.1524)
				(type default)
			)
			(layer "B.SilkS")
		)
		(fp_line
			(start 0.7874 0.4064)
			(end 0.7874 -0.4064)
			(stroke
				(width 0.1524)
				(type default)
			)
			(layer "B.SilkS")
		)
		(fp_line
			(start -0.7874 0.4064)
			(end 0.7874 0.4064)
			(stroke
				(width 0.1524)
				(type default)
			)
			(layer "B.SilkS")
		)
		(fp_line
			(start 0.67945 -0.305054)
			(end 0.12065 -0.305054)
			(stroke
				(width 0.1)
				(type default)
			)
			(layer "B.Fab")
		)
		(fp_line
			(start 0.12065 -0.305054)
			(end 0.12065 -0.2794)
			(stroke
				(width 0.1)
				(type default)
			)
			(layer "B.Fab")
		)
		(fp_line
			(start -0.12065 -0.3048)
			(end -0.67945 -0.3048)
			(stroke
				(width 0.1)
				(type default)
			)
			(layer "B.Fab")
		)
		(fp_line
			(start -0.67945 -0.3048)
			(end -0.67945 0.3048)
			(stroke
				(width 0.1)
				(type default)
			)
			(layer "B.Fab")
		)
		(fp_line
			(start 0.12065 -0.2794)
			(end -0.12065 -0.2794)
			(stroke
				(width 0.1)
				(type default)
			)
			(layer "B.Fab")
		)
		(fp_line
			(start -0.12065 -0.2794)
			(end -0.12065 -0.3048)
			(stroke
				(width 0.1)
				(type default)
			)
			(layer "B.Fab")
		)
		(fp_line
			(start 0.12065 0.2794)
			(end 0.12065 0.3048)
			(stroke
				(width 0.1)
				(type default)
			)
			(layer "B.Fab")
		)
		(fp_line
			(start -0.120396 0.2794)
			(end 0.12065 0.2794)
			(stroke
				(width 0.1)
				(type default)
			)
			(layer "B.Fab")
		)
		(fp_line
			(start 0.67945 0.3048)
			(end 0.67945 -0.305054)
			(stroke
				(width 0.1)
				(type default)
			)
			(layer "B.Fab")
		)
		(fp_line
			(start 0.12065 0.3048)
			(end 0.67945 0.3048)
			(stroke
				(width 0.1)
				(type default)
			)
			(layer "B.Fab")
		)
		(fp_line
			(start -0.120396 0.3048)
			(end -0.120396 0.2794)
			(stroke
				(width 0.1)
				(type default)
			)
			(layer "B.Fab")
		)
		(fp_line
			(start -0.67945 0.3048)
			(end -0.120396 0.3048)
			(stroke
				(width 0.1)
				(type default)
			)
			(layer "B.Fab")
		)
		(pad "1" smd circle
			(at 0.40005 0 270)
			(size 0 0)
			(layers "B.Cu" "B.Mask" "B.Paste")
			(net "ADCVREFEXT1")
		)
		(pad "2" smd circle
			(at -0.40005 0 270)
			(size 0 0)
			(layers "B.Cu" "B.Mask" "B.Paste")
			(net "GND")
		)
	)
	(footprint ""
		(layer "B.Cu")
		(at 45.5676 -4.1148 -90)
		(property "Reference" "R18"
			(at 0 0 90)
			(layer "B.SilkS")
			(hide yes)
			(effects
				(font
					(size 1.27 1.27)
				)
				(justify mirror)
			)
		)
		(property "Value" ""
			(at 0 0 90)
			(layer "B.Fab")
			(effects
				(font
					(size 1.27 1.27)
				)
				(justify mirror)
			)
		)
		(duplicate_pad_numbers_are_jumpers no)
		(fp_line
			(start -0.7874 0.4064)
			(end 0.7874 0.4064)
			(stroke
				(width 0.1524)
				(type default)
			)
			(layer "B.SilkS")
		)
		(fp_line
			(start 0.7874 0.4064)
			(end 0.7874 -0.4064)
			(stroke
				(width 0.1524)
				(type default)
			)
			(layer "B.SilkS")
		)
		(fp_line
			(start -0.7874 -0.4064)
			(end -0.7874 0.4064)
			(stroke
				(width 0.1524)
				(type default)
			)
			(layer "B.SilkS")
		)
		(fp_line
			(start 0.7874 -0.4064)
			(end -0.7874 -0.4064)
			(stroke
				(width 0.1524)
				(type default)
			)
			(layer "B.SilkS")
		)
		(fp_line
			(start -0.67945 0.3048)
			(end -0.120396 0.3048)
			(stroke
				(width 0.1)
				(type default)
			)
			(layer "B.Fab")
		)
		(fp_line
			(start -0.120396 0.3048)
			(end -0.120396 0.2794)
			(stroke
				(width 0.1)
				(type default)
			)
			(layer "B.Fab")
		)
		(fp_line
			(start 0.12065 0.3048)
			(end 0.67945 0.3048)
			(stroke
				(width 0.1)
				(type default)
			)
			(layer "B.Fab")
		)
		(fp_line
			(start 0.67945 0.3048)
			(end 0.67945 -0.305054)
			(stroke
				(width 0.1)
				(type default)
			)
			(layer "B.Fab")
		)
		(fp_line
			(start -0.120396 0.2794)
			(end 0.12065 0.2794)
			(stroke
				(width 0.1)
				(type default)
			)
			(layer "B.Fab")
		)
		(fp_line
			(start 0.12065 0.2794)
			(end 0.12065 0.3048)
			(stroke
				(width 0.1)
				(type default)
			)
			(layer "B.Fab")
		)
		(fp_line
			(start -0.12065 -0.2794)
			(end -0.12065 -0.3048)
			(stroke
				(width 0.1)
				(type default)
			)
			(layer "B.Fab")
		)
		(fp_line
			(start 0.12065 -0.2794)
			(end -0.12065 -0.2794)
			(stroke
				(width 0.1)
				(type default)
			)
			(layer "B.Fab")
		)
		(fp_line
			(start -0.67945 -0.3048)
			(end -0.67945 0.3048)
			(stroke
				(width 0.1)
				(type default)
			)
			(layer "B.Fab")
		)
		(fp_line
			(start -0.12065 -0.3048)
			(end -0.67945 -0.3048)
			(stroke
				(width 0.1)
				(type default)
			)
			(layer "B.Fab")
		)
		(fp_line
			(start 0.12065 -0.305054)
			(end 0.12065 -0.2794)
			(stroke
				(width 0.1)
				(type default)
			)
			(layer "B.Fab")
		)
		(fp_line
			(start 0.67945 -0.305054)
			(end 0.12065 -0.305054)
			(stroke
				(width 0.1)
				(type default)
			)
			(layer "B.Fab")
		)
		(pad "1" smd circle
			(at 0.40005 0 90)
			(size 0 0)
			(layers "B.Cu" "B.Mask" "B.Paste")
			(net "P5V_AUX")
		)
		(pad "2" smd circle
			(at -0.40005 0 90)
			(size 0 0)
			(layers "B.Cu" "B.Mask" "B.Paste")
			(net "BMC_DDC_BUF_PWR")
		)
	)
	(footprint ""
		(layer "B.Cu")
		(at 51.255168 -69.397372 -90)
		(property "Reference" "R790"
			(at 0 0 90)
			(layer "B.SilkS")
			(hide yes)
			(effects
				(font
					(size 1.27 1.27)
				)
				(justify mirror)
			)
		)
		(property "Value" ""
			(at 0 0 90)
			(layer "B.Fab")
			(effects
				(font
					(size 1.27 1.27)
				)
				(justify mirror)
			)
		)
		(duplicate_pad_numbers_are_jumpers no)
		(fp_line
			(start -0.7874 0.4064)
			(end 0.7874 0.4064)
			(stroke
				(width 0.1524)
				(type default)
			)
			(layer "B.SilkS")
		)
		(fp_line
			(start 0.7874 0.4064)
			(end 0.7874 -0.4064)
			(stroke
				(width 0.1524)
				(type default)
			)
			(layer "B.SilkS")
		)
		(fp_line
			(start -0.7874 -0.4064)
			(end -0.7874 0.4064)
			(stroke
				(width 0.1524)
				(type default)
			)
			(layer "B.SilkS")
		)
		(fp_line
			(start 0.7874 -0.4064)
			(end -0.7874 -0.4064)
			(stroke
				(width 0.1524)
				(type default)
			)
			(layer "B.SilkS")
		)
		(fp_line
			(start -0.67945 0.3048)
			(end -0.120396 0.3048)
			(stroke
				(width 0.1)
				(type default)
			)
			(layer "B.Fab")
		)
		(fp_line
			(start -0.120396 0.3048)
			(end -0.120396 0.2794)
			(stroke
				(width 0.1)
				(type default)
			)
			(layer "B.Fab")
		)
		(fp_line
			(start 0.12065 0.3048)
			(end 0.67945 0.3048)
			(stroke
				(width 0.1)
				(type default)
			)
			(layer "B.Fab")
		)
		(fp_line
			(start 0.67945 0.3048)
			(end 0.67945 -0.305054)
			(stroke
				(width 0.1)
				(type default)
			)
			(layer "B.Fab")
		)
		(fp_line
			(start -0.120396 0.2794)
			(end 0.12065 0.2794)
			(stroke
				(width 0.1)
				(type default)
			)
			(layer "B.Fab")
		)
		(fp_line
			(start 0.12065 0.2794)
			(end 0.12065 0.3048)
			(stroke
				(width 0.1)
				(type default)
			)
			(layer "B.Fab")
		)
		(fp_line
			(start -0.12065 -0.2794)
			(end -0.12065 -0.3048)
			(stroke
				(width 0.1)
				(type default)
			)
			(layer "B.Fab")
		)
		(fp_line
			(start 0.12065 -0.2794)
			(end -0.12065 -0.2794)
			(stroke
				(width 0.1)
				(type default)
			)
			(layer "B.Fab")
		)
		(fp_line
			(start -0.67945 -0.3048)
			(end -0.67945 0.3048)
			(stroke
				(width 0.1)
				(type default)
			)
			(layer "B.Fab")
		)
		(fp_line
			(start -0.12065 -0.3048)
			(end -0.67945 -0.3048)
			(stroke
				(width 0.1)
				(type default)
			)
			(layer "B.Fab")
		)
		(fp_line
			(start 0.12065 -0.305054)
			(end 0.12065 -0.2794)
			(stroke
				(width 0.1)
				(type default)
			)
			(layer "B.Fab")
		)
		(fp_line
			(start 0.67945 -0.305054)
			(end 0.12065 -0.305054)
			(stroke
				(width 0.1)
				(type default)
			)
			(layer "B.Fab")
		)
		(pad "1" smd circle
			(at 0.40005 0 90)
			(size 0 0)
			(layers "B.Cu" "B.Mask" "B.Paste")
			(net "P3V3_SENSOR")
		)
		(pad "2" smd circle
			(at -0.40005 0 90)
			(size 0 0)
			(layers "B.Cu" "B.Mask" "B.Paste")
			(net "GND")
		)
	)
	(footprint ""
		(layer "B.Cu")
		(at 28.702 -37.581078 90)
		(property "Reference" "D9"
			(at -3.799078 -2.71907 270)
			(unlocked yes)
			(layer "B.SilkS")
			(effects
				(font
					(size 0.7874 0.5842)
					(thickness 0.1524)
				)
				(justify left mirror)
			)
		)
		(property "Value" ""
			(at 0 0 90)
			(layer "B.Fab")
			(effects
				(font
					(size 1.27 1.27)
				)
				(justify mirror)
			)
		)
		(duplicate_pad_numbers_are_jumpers no)
		(fp_line
			(start 2.262378 -0.899922)
			(end 2.262378 0.899922)
			(stroke
				(width 0.1524)
				(type default)
			)
			(layer "B.SilkS")
		)
		(fp_line
			(start -2.567178 -0.899922)
			(end 2.262378 -0.899922)
			(stroke
				(width 0.1524)
				(type default)
			)
			(layer "B.SilkS")
		)
		(fp_line
			(start 0.3175 -0.508)
			(end 0.3175 0.508)
			(stroke
				(width 0.1524)
				(type default)
			)
			(layer "B.SilkS")
		)
		(fp_line
			(start -0.3175 -0.508)
			(end -0.3175 0.508)
			(stroke
				(width 0.1524)
				(type default)
			)
			(layer "B.SilkS")
		)
		(fp_line
			(start 0.8255 0)
			(end 0.3175 0)
			(stroke
				(width 0.1524)
				(type default)
			)
			(layer "B.SilkS")
		)
		(fp_line
			(start -0.3175 0)
			(end 0.3175 -0.508)
			(stroke
				(width 0.1524)
				(type default)
			)
			(layer "B.SilkS")
		)
		(fp_line
			(start -0.3175 0)
			(end -0.8255 0)
			(stroke
				(width 0.1524)
				(type default)
			)
			(layer "B.SilkS")
		)
		(fp_line
			(start 0.3175 0.508)
			(end -0.3175 0)
			(stroke
				(width 0.1524)
				(type default)
			)
			(layer "B.SilkS")
		)
		(fp_line
			(start 2.262378 0.899922)
			(end -2.567178 0.899922)
			(stroke
				(width 0.1524)
				(type default)
			)
			(layer "B.SilkS")
		)
		(fp_line
			(start -2.567178 0.899922)
			(end -2.567178 -0.899922)
			(stroke
				(width 0.1524)
				(type default)
			)
			(layer "B.SilkS")
		)
		(fp_poly
			(pts
				(xy -2.567178 -0.899922) (xy -2.186178 -0.899922) (xy -2.186178 0.899922) (xy -2.567178 0.899922)
			)
			(stroke
				(width 0)
				(type default)
			)
			(fill yes)
			(layer "B.SilkS")
		)
		(fp_line
			(start 1.400048 -0.899922)
			(end 1.400048 0.899922)
			(stroke
				(width 0.1)
				(type default)
			)
			(layer "B.Fab")
		)
		(fp_line
			(start -1.400048 -0.899922)
			(end 1.400048 -0.899922)
			(stroke
				(width 0.1)
				(type default)
			)
			(layer "B.Fab")
		)
		(fp_line
			(start 1.400048 0.899922)
			(end -1.400048 0.899922)
			(stroke
				(width 0.1)
				(type default)
			)
			(layer "B.Fab")
		)
		(fp_line
			(start -1.400048 0.899922)
			(end -1.400048 -0.899922)
			(stroke
				(width 0.1)
				(type default)
			)
			(layer "B.Fab")
		)
		(fp_text user "+"
			(at 3.19405 0.0254 0)
			(unlocked yes)
			(layer "B.SilkS")
			(effects
				(font
					(size 1.905 1.4224)
					(thickness 0.1524)
				)
				(justify left mirror)
			)
		)
		(fp_text user "-"
			(at -3.937762 0.241046 270)
			(unlocked yes)
			(layer "B.SilkS")
			(effects
				(font
					(size 1.905 1.4224)
					(thickness 0.1524)
				)
				(justify left mirror)
			)
		)
		(fp_text user "-"
			(at -3.937762 0.241046 270)
			(unlocked yes)
			(layer "B.Fab")
			(effects
				(font
					(size 1.905 1.4224)
					(thickness 0.1524)
				)
				(justify left mirror)
			)
		)
		(fp_text user "+"
			(at 3.29565 0.6858 0)
			(unlocked yes)
			(layer "B.Fab")
			(effects
				(font
					(size 1.905 1.4224)
					(thickness 0.1524)
				)
				(justify left mirror)
			)
		)
		(pad "A" smd rect
			(at 1.640078 0 270)
			(size 0.9906 1.2192)
			(layers "B.Cu" "B.Mask" "B.Paste")
			(net "P5V_AUX")
		)
		(pad "C" smd rect
			(at -1.640078 0 270)
			(size 0.9906 1.2192)
			(layers "B.Cu" "B.Mask" "B.Paste")
			(net "CRT_VCC5")
		)
	)
	(footprint ""
		(layer "B.Cu")
		(at 101.29012 29.261562 90)
		(property "Reference" "J28"
			(at -1.218438 -2.89179 270)
			(unlocked yes)
			(layer "B.SilkS")
			(effects
				(font
					(size 0.7874 0.5842)
					(thickness 0.1524)
				)
				(justify left mirror)
			)
		)
		(property "Value" ""
			(at 0 0 90)
			(layer "B.Fab")
			(effects
				(font
					(size 1.27 1.27)
				)
				(justify mirror)
			)
		)
		(duplicate_pad_numbers_are_jumpers no)
		(fp_line
			(start 1.2192 -2.1082)
			(end -1.2192 -2.1082)
			(stroke
				(width 0.1524)
				(type default)
			)
			(layer "B.SilkS")
		)
		(fp_line
			(start -1.2192 -2.1082)
			(end -1.2192 -0.831596)
			(stroke
				(width 0.1524)
				(type default)
			)
			(layer "B.SilkS")
		)
		(fp_line
			(start -1.2192 0.909574)
			(end -1.2192 2.1082)
			(stroke
				(width 0.1524)
				(type default)
			)
			(layer "B.SilkS")
		)
		(fp_line
			(start 1.2192 2.1082)
			(end 1.2192 -2.1082)
			(stroke
				(width 0.1524)
				(type default)
			)
			(layer "B.SilkS")
		)
		(fp_line
			(start -1.2192 2.1082)
			(end 1.2192 2.1082)
			(stroke
				(width 0.1524)
				(type default)
			)
			(layer "B.SilkS")
		)
		(pad "" np_thru_hole circle
			(at -3.4671 -1.27)
			(size 1.0414 1.0414)
			(drill 1.0414)
			(layers "*.Cu" "*.Mask")
			(clearance 0.381)
			(thermal_gap 0.381)
		)
		(pad "" np_thru_hole circle
			(at -3.4671 1.27)
			(size 1.0414 1.0414)
			(drill 1.0414)
			(layers "*.Cu" "*.Mask")
			(clearance 0.381)
			(thermal_gap 0.381)
		)
		(pad "" np_thru_hole circle
			(at 2.8829 -1.27)
			(size 1.0414 1.0414)
			(drill 1.0414)
			(layers "*.Cu" "*.Mask")
			(clearance 0.381)
			(thermal_gap 0.381)
		)
		(pad "" np_thru_hole circle
			(at 2.8829 1.27)
			(size 1.0414 1.0414)
			(drill 1.0414)
			(layers "*.Cu" "*.Mask")
			(clearance 0.381)
			(thermal_gap 0.381)
		)
		(pad "1" smd rect
			(at -0.8255 -0.249936)
			(size 0.3048 0.508)
			(layers "B.Cu" "B.Mask" "B.Paste")
			(net "85_10INCH_IN1_DN")
		)
		(pad "2" smd rect
			(at -0.8255 0.249936)
			(size 0.3048 0.508)
			(layers "B.Cu" "B.Mask" "B.Paste")
			(net "85_10INCH_IN1_DP")
		)
		(pad "3" smd circle
			(at 0 0 270)
			(size 0 0)
			(layers "B.Cu" "B.Mask" "B.Paste")
			(net "GND_P1")
		)
		(zone
			(layers "F.Cu" "B.Cu" "In1.Cu" "In2.Cu" "In3.Cu" "In4.Cu" "In5.Cu" "In6.Cu"
				"In7.Cu" "In8.Cu" "In9.Cu" "In10.Cu"
			)
			(hatch none 0.5)
			(connect_pads
				(clearance 0)
			)
			(min_thickness 0.25)
			(keepout
				(tracks not_allowed)
				(vias allowed)
				(pads allowed)
				(copperpour not_allowed)
				(footprints allowed)
			)
			(placement
				(enabled no)
				(sheetname "")
			)
			(fill
				(thermal_gap 0.5)
				(thermal_bridge_width 0.5)
				(island_removal_mode 0)
			)
			(polygon
				(pts
					(arc
						(start 100.94722 26.378662)
						(mid 99.09302 26.378662)
						(end 100.94722 26.378662)
					)
				)
			)
		)
		(zone
			(layers "F.Cu" "B.Cu" "In1.Cu" "In2.Cu" "In3.Cu" "In4.Cu" "In5.Cu" "In6.Cu"
				"In7.Cu" "In8.Cu" "In9.Cu" "In10.Cu"
			)
			(hatch none 0.5)
			(connect_pads
				(clearance 0)
			)
			(min_thickness 0.25)
			(keepout
				(tracks not_allowed)
				(vias allowed)
				(pads allowed)
				(copperpour not_allowed)
				(footprints allowed)
			)
			(placement
				(enabled no)
				(sheetname "")
			)
			(fill
				(thermal_gap 0.5)
				(thermal_bridge_width 0.5)
				(island_removal_mode 0)
			)
			(polygon
				(pts
					(arc
						(start 100.94722 32.728662)
						(mid 99.09302 32.728662)
						(end 100.94722 32.728662)
					)
				)
			)
		)
		(zone
			(layers "F.Cu" "B.Cu" "In1.Cu" "In2.Cu" "In3.Cu" "In4.Cu" "In5.Cu" "In6.Cu"
				"In7.Cu" "In8.Cu" "In9.Cu" "In10.Cu"
			)
			(hatch none 0.5)
			(connect_pads
				(clearance 0)
			)
			(min_thickness 0.25)
			(keepout
				(tracks not_allowed)
				(vias allowed)
				(pads allowed)
				(copperpour not_allowed)
				(footprints allowed)
			)
			(placement
				(enabled no)
				(sheetname "")
			)
			(fill
				(thermal_gap 0.5)
				(thermal_bridge_width 0.5)
				(island_removal_mode 0)
			)
			(polygon
				(pts
					(arc
						(start 103.48722 26.378662)
						(mid 101.63302 26.378662)
						(end 103.48722 26.378662)
					)
				)
			)
		)
		(zone
			(layers "F.Cu" "B.Cu" "In1.Cu" "In2.Cu" "In3.Cu" "In4.Cu" "In5.Cu" "In6.Cu"
				"In7.Cu" "In8.Cu" "In9.Cu" "In10.Cu"
			)
			(hatch none 0.5)
			(connect_pads
				(clearance 0)
			)
			(min_thickness 0.25)
			(keepout
				(tracks not_allowed)
				(vias allowed)
				(pads allowed)
				(copperpour not_allowed)
				(footprints allowed)
			)
			(placement
				(enabled no)
				(sheetname "")
			)
			(fill
				(thermal_gap 0.5)
				(thermal_bridge_width 0.5)
				(island_removal_mode 0)
			)
			(polygon
				(pts
					(arc
						(start 103.48722 32.728662)
						(mid 101.63302 32.728662)
						(end 103.48722 32.728662)
					)
				)
			)
		)
		(zone
			(layer "B.Cu")
			(hatch none 0.5)
			(connect_pads
				(clearance 0)
			)
			(min_thickness 0.25)
			(keepout
				(tracks not_allowed)
				(vias allowed)
				(pads allowed)
				(copperpour not_allowed)
				(footprints allowed)
			)
			(placement
				(enabled no)
				(sheetname "")
			)
			(fill
				(thermal_gap 0.5)
				(thermal_bridge_width 0.5)
				(island_removal_mode 0)
			)
			(polygon
				(pts
					(xy 100.74148 30.379162) (xy 100.836984 30.379162) (xy 100.836984 29.782262) (xy 101.243384 29.782262)
					(xy 101.243384 30.379162) (xy 101.336856 30.379162) (xy 101.336856 29.782262) (xy 101.743256 29.782262)
					(xy 101.743256 30.379162) (xy 101.83876 30.379162) (xy 101.83876 29.680662) (xy 100.74148 29.680662)
				)
			)
		)
	)
	(footprint ""
		(layer "B.Cu")
		(at 12.319 -91.44 180)
		(property "Reference" "R271"
			(at 0 0 0)
			(layer "B.SilkS")
			(hide yes)
			(effects
				(font
					(size 1.27 1.27)
				)
				(justify mirror)
			)
		)
		(property "Value" ""
			(at 0 0 0)
			(layer "B.Fab")
			(effects
				(font
					(size 1.27 1.27)
				)
				(justify mirror)
			)
		)
		(duplicate_pad_numbers_are_jumpers no)
		(fp_line
			(start 0.7874 0.4064)
			(end 0.7874 -0.4064)
			(stroke
				(width 0.1524)
				(type default)
			)
			(layer "B.SilkS")
		)
		(fp_line
			(start 0.7874 -0.4064)
			(end -0.7874 -0.4064)
			(stroke
				(width 0.1524)
				(type default)
			)
			(layer "B.SilkS")
		)
		(fp_line
			(start -0.7874 0.4064)
			(end 0.7874 0.4064)
			(stroke
				(width 0.1524)
				(type default)
			)
			(layer "B.SilkS")
		)
		(fp_line
			(start -0.7874 -0.4064)
			(end -0.7874 0.4064)
			(stroke
				(width 0.1524)
				(type default)
			)
			(layer "B.SilkS")
		)
		(fp_line
			(start 0.67945 0.3048)
			(end 0.67945 -0.305054)
			(stroke
				(width 0.1)
				(type default)
			)
			(layer "B.Fab")
		)
		(fp_line
			(start 0.67945 -0.305054)
			(end 0.12065 -0.305054)
			(stroke
				(width 0.1)
				(type default)
			)
			(layer "B.Fab")
		)
		(fp_line
			(start 0.12065 0.3048)
			(end 0.67945 0.3048)
			(stroke
				(width 0.1)
				(type default)
			)
			(layer "B.Fab")
		)
		(fp_line
			(start 0.12065 0.2794)
			(end 0.12065 0.3048)
			(stroke
				(width 0.1)
				(type default)
			)
			(layer "B.Fab")
		)
		(fp_line
			(start 0.12065 -0.2794)
			(end -0.12065 -0.2794)
			(stroke
				(width 0.1)
				(type default)
			)
			(layer "B.Fab")
		)
		(fp_line
			(start 0.12065 -0.305054)
			(end 0.12065 -0.2794)
			(stroke
				(width 0.1)
				(type default)
			)
			(layer "B.Fab")
		)
		(fp_line
			(start -0.120396 0.3048)
			(end -0.120396 0.2794)
			(stroke
				(width 0.1)
				(type default)
			)
			(layer "B.Fab")
		)
		(fp_line
			(start -0.120396 0.2794)
			(end 0.12065 0.2794)
			(stroke
				(width 0.1)
				(type default)
			)
			(layer "B.Fab")
		)
		(fp_line
			(start -0.12065 -0.2794)
			(end -0.12065 -0.3048)
			(stroke
				(width 0.1)
				(type default)
			)
			(layer "B.Fab")
		)
		(fp_line
			(start -0.12065 -0.3048)
			(end -0.67945 -0.3048)
			(stroke
				(width 0.1)
				(type default)
			)
			(layer "B.Fab")
		)
		(fp_line
			(start -0.67945 0.3048)
			(end -0.120396 0.3048)
			(stroke
				(width 0.1)
				(type default)
			)
			(layer "B.Fab")
		)
		(fp_line
			(start -0.67945 -0.3048)
			(end -0.67945 0.3048)
			(stroke
				(width 0.1)
				(type default)
			)
			(layer "B.Fab")
		)
		(pad "1" smd circle
			(at 0.40005 0)
			(size 0 0)
			(layers "B.Cu" "B.Mask" "B.Paste")
			(net "RST_BMC_SELF_HW")
		)
		(pad "2" smd circle
			(at -0.40005 0)
			(size 0 0)
			(layers "B.Cu" "B.Mask" "B.Paste")
			(net "RST_BMC_SELF_HW_R2")
		)
	)
	(footprint ""
		(layer "B.Cu")
		(at 101.267768 119.38635 -90)
		(property "Reference" "J30"
			(at 6.08965 -1.448562 270)
			(unlocked yes)
			(layer "B.SilkS")
			(effects
				(font
					(size 0.7874 0.5842)
					(thickness 0.1524)
				)
				(justify left mirror)
			)
		)
		(property "Value" ""
			(at 0 0 90)
			(layer "B.Fab")
			(effects
				(font
					(size 1.27 1.27)
				)
				(justify mirror)
			)
		)
		(duplicate_pad_numbers_are_jumpers no)
		(fp_line
			(start -1.2192 2.1082)
			(end 1.2192 2.1082)
			(stroke
				(width 0.1524)
				(type default)
			)
			(layer "B.SilkS")
		)
		(fp_line
			(start 1.2192 2.1082)
			(end 1.2192 -2.1082)
			(stroke
				(width 0.1524)
				(type default)
			)
			(layer "B.SilkS")
		)
		(fp_line
			(start -1.2192 0.818388)
			(end -1.2192 2.1082)
			(stroke
				(width 0.1524)
				(type default)
			)
			(layer "B.SilkS")
		)
		(fp_line
			(start -1.2192 -2.1082)
			(end -1.2192 -0.821944)
			(stroke
				(width 0.1524)
				(type default)
			)
			(layer "B.SilkS")
		)
		(fp_line
			(start 1.2192 -2.1082)
			(end -1.2192 -2.1082)
			(stroke
				(width 0.1524)
				(type default)
			)
			(layer "B.SilkS")
		)
		(pad "" np_thru_hole circle
			(at -3.4671 -1.27 180)
			(size 1.0414 1.0414)
			(drill 1.0414)
			(layers "*.Cu" "*.Mask")
			(clearance 0.381)
			(thermal_gap 0.381)
		)
		(pad "" np_thru_hole circle
			(at -3.4671 1.27 180)
			(size 1.0414 1.0414)
			(drill 1.0414)
			(layers "*.Cu" "*.Mask")
			(clearance 0.381)
			(thermal_gap 0.381)
		)
		(pad "" np_thru_hole circle
			(at 2.8829 -1.27 180)
			(size 1.0414 1.0414)
			(drill 1.0414)
			(layers "*.Cu" "*.Mask")
			(clearance 0.381)
			(thermal_gap 0.381)
		)
		(pad "" np_thru_hole circle
			(at 2.8829 1.27 180)
			(size 1.0414 1.0414)
			(drill 1.0414)
			(layers "*.Cu" "*.Mask")
			(clearance 0.381)
			(thermal_gap 0.381)
		)
		(pad "1" smd rect
			(at -0.8255 -0.249936 180)
			(size 0.3048 0.508)
			(layers "B.Cu" "B.Mask" "B.Paste")
			(net "85_10INCH_IN1_DP")
		)
		(pad "2" smd rect
			(at -0.8255 0.249936 180)
			(size 0.3048 0.508)
			(layers "B.Cu" "B.Mask" "B.Paste")
			(net "85_10INCH_IN1_DN")
		)
		(pad "3" smd circle
			(at 0 0 90)
			(size 0 0)
			(layers "B.Cu" "B.Mask" "B.Paste")
			(net "GND_P1")
		)
		(zone
			(layers "F.Cu" "B.Cu" "In1.Cu" "In2.Cu" "In3.Cu" "In4.Cu" "In5.Cu" "In6.Cu"
				"In7.Cu" "In8.Cu" "In9.Cu" "In10.Cu"
			)
			(hatch none 0.5)
			(connect_pads
				(clearance 0)
			)
			(min_thickness 0.25)
			(keepout
				(tracks not_allowed)
				(vias allowed)
				(pads allowed)
				(copperpour not_allowed)
				(footprints allowed)
			)
			(placement
				(enabled no)
				(sheetname "")
			)
			(fill
				(thermal_gap 0.5)
				(thermal_bridge_width 0.5)
				(island_removal_mode 0)
			)
			(polygon
				(pts
					(arc
						(start 100.924868 115.91925)
						(mid 99.070668 115.91925)
						(end 100.924868 115.91925)
					)
				)
			)
		)
		(zone
			(layers "F.Cu" "B.Cu" "In1.Cu" "In2.Cu" "In3.Cu" "In4.Cu" "In5.Cu" "In6.Cu"
				"In7.Cu" "In8.Cu" "In9.Cu" "In10.Cu"
			)
			(hatch none 0.5)
			(connect_pads
				(clearance 0)
			)
			(min_thickness 0.25)
			(keepout
				(tracks not_allowed)
				(vias allowed)
				(pads allowed)
				(copperpour not_allowed)
				(footprints allowed)
			)
			(placement
				(enabled no)
				(sheetname "")
			)
			(fill
				(thermal_gap 0.5)
				(thermal_bridge_width 0.5)
				(island_removal_mode 0)
			)
			(polygon
				(pts
					(arc
						(start 100.924868 122.26925)
						(mid 99.070668 122.26925)
						(end 100.924868 122.26925)
					)
				)
			)
		)
		(zone
			(layers "F.Cu" "B.Cu" "In1.Cu" "In2.Cu" "In3.Cu" "In4.Cu" "In5.Cu" "In6.Cu"
				"In7.Cu" "In8.Cu" "In9.Cu" "In10.Cu"
			)
			(hatch none 0.5)
			(connect_pads
				(clearance 0)
			)
			(min_thickness 0.25)
			(keepout
				(tracks not_allowed)
				(vias allowed)
				(pads allowed)
				(copperpour not_allowed)
				(footprints allowed)
			)
			(placement
				(enabled no)
				(sheetname "")
			)
			(fill
				(thermal_gap 0.5)
				(thermal_bridge_width 0.5)
				(island_removal_mode 0)
			)
			(polygon
				(pts
					(arc
						(start 103.464868 115.91925)
						(mid 101.610668 115.91925)
						(end 103.464868 115.91925)
					)
				)
			)
		)
		(zone
			(layers "F.Cu" "B.Cu" "In1.Cu" "In2.Cu" "In3.Cu" "In4.Cu" "In5.Cu" "In6.Cu"
				"In7.Cu" "In8.Cu" "In9.Cu" "In10.Cu"
			)
			(hatch none 0.5)
			(connect_pads
				(clearance 0)
			)
			(min_thickness 0.25)
			(keepout
				(tracks not_allowed)
				(vias allowed)
				(pads allowed)
				(copperpour not_allowed)
				(footprints allowed)
			)
			(placement
				(enabled no)
				(sheetname "")
			)
			(fill
				(thermal_gap 0.5)
				(thermal_bridge_width 0.5)
				(island_removal_mode 0)
			)
			(polygon
				(pts
					(arc
						(start 103.464868 122.26925)
						(mid 101.610668 122.26925)
						(end 103.464868 122.26925)
					)
				)
			)
		)
		(zone
			(layer "B.Cu")
			(hatch none 0.5)
			(connect_pads
				(clearance 0)
			)
			(min_thickness 0.25)
			(keepout
				(tracks not_allowed)
				(vias allowed)
				(pads allowed)
				(copperpour not_allowed)
				(footprints allowed)
			)
			(placement
				(enabled no)
				(sheetname "")
			)
			(fill
				(thermal_gap 0.5)
				(thermal_bridge_width 0.5)
				(island_removal_mode 0)
			)
			(polygon
				(pts
					(xy 101.816408 118.26875) (xy 101.720904 118.26875) (xy 101.720904 118.86565) (xy 101.314504 118.86565)
					(xy 101.314504 118.26875) (xy 101.221032 118.26875) (xy 101.221032 118.86565) (xy 100.814632 118.86565)
					(xy 100.814632 118.26875) (xy 100.719128 118.26875) (xy 100.719128 118.96725) (xy 101.816408 118.96725)
				)
			)
		)
	)
	(footprint ""
		(layer "B.Cu")
		(at 43.9674 -106.299 180)
		(property "Reference" "U48"
			(at 2.31267 -0.762 270)
			(unlocked yes)
			(layer "B.SilkS")
			(effects
				(font
					(size 0.7874 0.5842)
					(thickness 0.1524)
				)
				(justify left mirror)
			)
		)
		(property "Value" ""
			(at 0 0 0)
			(layer "B.Fab")
			(effects
				(font
					(size 1.27 1.27)
				)
				(justify mirror)
			)
		)
		(duplicate_pad_numbers_are_jumpers no)
		(fp_line
			(start 1.584198 1.500124)
			(end -1.584198 1.500124)
			(stroke
				(width 0.1524)
				(type default)
			)
			(layer "B.SilkS")
		)
		(fp_line
			(start 1.584198 -1.500124)
			(end 1.584198 1.500124)
			(stroke
				(width 0.1524)
				(type default)
			)
			(layer "B.SilkS")
		)
		(fp_line
			(start -1.584198 1.500124)
			(end -1.584198 -1.500124)
			(stroke
				(width 0.1524)
				(type default)
			)
			(layer "B.SilkS")
		)
		(fp_line
			(start -1.584198 -1.500124)
			(end 1.584198 -1.500124)
			(stroke
				(width 0.1524)
				(type default)
			)
			(layer "B.SilkS")
		)
		(fp_line
			(start 0.700024 1.500124)
			(end -0.700024 1.500124)
			(stroke
				(width 0.1)
				(type default)
			)
			(layer "B.Fab")
		)
		(fp_line
			(start 0.700024 -1.500124)
			(end 0.700024 1.500124)
			(stroke
				(width 0.1)
				(type default)
			)
			(layer "B.Fab")
		)
		(fp_line
			(start -0.700024 1.500124)
			(end -0.700024 -1.500124)
			(stroke
				(width 0.1)
				(type default)
			)
			(layer "B.Fab")
		)
		(fp_line
			(start -0.700024 -1.500124)
			(end 0.700024 -1.500124)
			(stroke
				(width 0.1)
				(type default)
			)
			(layer "B.Fab")
		)
		(pad "1" smd rect
			(at 0.999998 -0.94996 90)
			(size 0.8128 0.9144)
			(layers "B.Cu" "B.Mask" "B.Paste")
			(net "P3V_BAT_R")
		)
		(pad "2" smd rect
			(at 0.999998 0.94996 90)
			(size 0.8128 0.9144)
			(layers "B.Cu" "B.Mask" "B.Paste")
			(net "P3V3_AUX")
		)
		(pad "3" smd rect
			(at -0.999998 0 90)
			(size 0.8128 0.9144)
			(layers "B.Cu" "B.Mask" "B.Paste")
			(net "P3V3_RTC_AUX")
		)
	)
	(footprint ""
		(layer "B.Cu")
		(at 26.924 -34.925)
		(property "Reference" "ME1"
			(at 0 0 0)
			(layer "B.SilkS")
			(hide yes)
			(effects
				(font
					(size 1.27 1.27)
				)
				(justify mirror)
			)
		)
		(property "Value" ""
			(at 0 0 0)
			(layer "B.Fab")
			(effects
				(font
					(size 1.27 1.27)
				)
				(justify mirror)
			)
		)
		(duplicate_pad_numbers_are_jumpers no)
		(fp_line
			(start -25.833324 -4.120134)
			(end -24.394668 -2.739898)
			(stroke
				(width 0.1)
				(type default)
			)
			(layer "B.SilkS")
		)
		(fp_line
			(start -25.833324 -4.120134)
			(end -24.394668 -2.739898)
			(stroke
				(width 0.1)
				(type default)
			)
			(layer "B.SilkS")
		)
		(fp_line
			(start -25.83307 -4.062222)
			(end -24.432514 -2.718816)
			(stroke
				(width 0.1)
				(type default)
			)
			(layer "B.SilkS")
		)
		(fp_line
			(start -25.83307 -4.062222)
			(end -24.432514 -2.718816)
			(stroke
				(width 0.1)
				(type default)
			)
			(layer "B.SilkS")
		)
		(fp_line
			(start -25.827736 -3.99923)
			(end -24.468836 -2.695448)
			(stroke
				(width 0.1)
				(type default)
			)
			(layer "B.SilkS")
		)
		(fp_line
			(start -25.827736 -3.99923)
			(end -24.468836 -2.695448)
			(stroke
				(width 0.1)
				(type default)
			)
			(layer "B.SilkS")
		)
		(fp_line
			(start -25.826466 -4.170934)
			(end -24.35606 -2.760472)
			(stroke
				(width 0.1)
				(type default)
			)
			(layer "B.SilkS")
		)
		(fp_line
			(start -25.826466 -4.170934)
			(end -24.35606 -2.760472)
			(stroke
				(width 0.1)
				(type default)
			)
			(layer "B.SilkS")
		)
		(fp_line
			(start -25.822656 -3.936492)
			(end -24.487886 -2.656332)
			(stroke
				(width 0.1)
				(type default)
			)
			(layer "B.SilkS")
		)
		(fp_line
			(start -25.822656 -3.936492)
			(end -24.487886 -2.656332)
			(stroke
				(width 0.1)
				(type default)
			)
			(layer "B.SilkS")
		)
		(fp_line
			(start -25.819608 -4.222242)
			(end -24.31415 -2.777998)
			(stroke
				(width 0.1)
				(type default)
			)
			(layer "B.SilkS")
		)
		(fp_line
			(start -25.819608 -4.222242)
			(end -24.31415 -2.777998)
			(stroke
				(width 0.1)
				(type default)
			)
			(layer "B.SilkS")
		)
		(fp_line
			(start -25.817576 -3.874008)
			(end -24.475948 -2.58699)
			(stroke
				(width 0.1)
				(type default)
			)
			(layer "B.SilkS")
		)
		(fp_line
			(start -25.817576 -3.874008)
			(end -24.475948 -2.58699)
			(stroke
				(width 0.1)
				(type default)
			)
			(layer "B.SilkS")
		)
		(fp_line
			(start -25.81275 -3.811524)
			(end -24.46401 -2.517648)
			(stroke
				(width 0.1)
				(type default)
			)
			(layer "B.SilkS")
		)
		(fp_line
			(start -25.81275 -3.811524)
			(end -24.46401 -2.517648)
			(stroke
				(width 0.1)
				(type default)
			)
			(layer "B.SilkS")
		)
		(fp_line
			(start -25.812242 -4.273296)
			(end -24.27097 -2.794508)
			(stroke
				(width 0.1)
				(type default)
			)
			(layer "B.SilkS")
		)
		(fp_line
			(start -25.812242 -4.273296)
			(end -24.27097 -2.794508)
			(stroke
				(width 0.1)
				(type default)
			)
			(layer "B.SilkS")
		)
		(fp_line
			(start -25.806146 -3.74777)
			(end -24.451564 -2.448306)
			(stroke
				(width 0.1)
				(type default)
			)
			(layer "B.SilkS")
		)
		(fp_line
			(start -25.806146 -3.74777)
			(end -24.451564 -2.448306)
			(stroke
				(width 0.1)
				(type default)
			)
			(layer "B.SilkS")
		)
		(fp_line
			(start -25.805384 -4.324096)
			(end -24.225504 -2.808478)
			(stroke
				(width 0.1)
				(type default)
			)
			(layer "B.SilkS")
		)
		(fp_line
			(start -25.805384 -4.324096)
			(end -24.225504 -2.808478)
			(stroke
				(width 0.1)
				(type default)
			)
			(layer "B.SilkS")
		)
		(fp_line
			(start -25.798526 -4.37515)
			(end -24.17826 -2.82067)
			(stroke
				(width 0.1)
				(type default)
			)
			(layer "B.SilkS")
		)
		(fp_line
			(start -25.798526 -4.37515)
			(end -24.17826 -2.82067)
			(stroke
				(width 0.1)
				(type default)
			)
			(layer "B.SilkS")
		)
		(fp_line
			(start -25.793954 -3.678174)
			(end -25.806146 -3.74777)
			(stroke
				(width 0.1)
				(type default)
			)
			(layer "B.SilkS")
		)
		(fp_line
			(start -25.793954 -3.678174)
			(end -25.806146 -3.74777)
			(stroke
				(width 0.1)
				(type default)
			)
			(layer "B.SilkS")
		)
		(fp_line
			(start -25.793954 -3.678174)
			(end -24.439372 -2.37871)
			(stroke
				(width 0.1)
				(type default)
			)
			(layer "B.SilkS")
		)
		(fp_line
			(start -25.793954 -3.678174)
			(end -24.439372 -2.37871)
			(stroke
				(width 0.1)
				(type default)
			)
			(layer "B.SilkS")
		)
		(fp_line
			(start -25.786588 -4.421378)
			(end -24.12873 -2.831084)
			(stroke
				(width 0.1)
				(type default)
			)
			(layer "B.SilkS")
		)
		(fp_line
			(start -25.786588 -4.421378)
			(end -24.12873 -2.831084)
			(stroke
				(width 0.1)
				(type default)
			)
			(layer "B.SilkS")
		)
		(fp_line
			(start -25.782016 -3.609086)
			(end -25.793954 -3.678174)
			(stroke
				(width 0.1)
				(type default)
			)
			(layer "B.SilkS")
		)
		(fp_line
			(start -25.782016 -3.609086)
			(end -25.793954 -3.678174)
			(stroke
				(width 0.1)
				(type default)
			)
			(layer "B.SilkS")
		)
		(fp_line
			(start -25.782016 -3.609086)
			(end -24.427434 -2.309368)
			(stroke
				(width 0.1)
				(type default)
			)
			(layer "B.SilkS")
		)
		(fp_line
			(start -25.782016 -3.609086)
			(end -24.427434 -2.309368)
			(stroke
				(width 0.1)
				(type default)
			)
			(layer "B.SilkS")
		)
		(fp_line
			(start -25.769824 -3.539744)
			(end -25.782016 -3.609086)
			(stroke
				(width 0.1)
				(type default)
			)
			(layer "B.SilkS")
		)
		(fp_line
			(start -25.769824 -3.539744)
			(end -25.782016 -3.609086)
			(stroke
				(width 0.1)
				(type default)
			)
			(layer "B.SilkS")
		)
		(fp_line
			(start -25.769824 -3.539744)
			(end -24.414988 -2.24028)
			(stroke
				(width 0.1)
				(type default)
			)
			(layer "B.SilkS")
		)
		(fp_line
			(start -25.769824 -3.539744)
			(end -24.414988 -2.24028)
			(stroke
				(width 0.1)
				(type default)
			)
			(layer "B.SilkS")
		)
		(fp_line
			(start -25.769316 -4.46278)
			(end -24.076914 -2.839466)
			(stroke
				(width 0.1)
				(type default)
			)
			(layer "B.SilkS")
		)
		(fp_line
			(start -25.769316 -4.46278)
			(end -24.076914 -2.839466)
			(stroke
				(width 0.1)
				(type default)
			)
			(layer "B.SilkS")
		)
		(fp_line
			(start -25.757632 -3.470402)
			(end -25.769824 -3.539744)
			(stroke
				(width 0.1)
				(type default)
			)
			(layer "B.SilkS")
		)
		(fp_line
			(start -25.757632 -3.470402)
			(end -25.769824 -3.539744)
			(stroke
				(width 0.1)
				(type default)
			)
			(layer "B.SilkS")
		)
		(fp_line
			(start -25.757632 -3.470402)
			(end -24.402796 -2.170938)
			(stroke
				(width 0.1)
				(type default)
			)
			(layer "B.SilkS")
		)
		(fp_line
			(start -25.757632 -3.470402)
			(end -24.402796 -2.170938)
			(stroke
				(width 0.1)
				(type default)
			)
			(layer "B.SilkS")
		)
		(fp_line
			(start -25.752298 -4.503928)
			(end -24.024336 -2.846324)
			(stroke
				(width 0.1)
				(type default)
			)
			(layer "B.SilkS")
		)
		(fp_line
			(start -25.752298 -4.503928)
			(end -24.024336 -2.846324)
			(stroke
				(width 0.1)
				(type default)
			)
			(layer "B.SilkS")
		)
		(fp_line
			(start -25.74544 -3.400806)
			(end -25.757632 -3.470402)
			(stroke
				(width 0.1)
				(type default)
			)
			(layer "B.SilkS")
		)
		(fp_line
			(start -25.74544 -3.400806)
			(end -25.757632 -3.470402)
			(stroke
				(width 0.1)
				(type default)
			)
			(layer "B.SilkS")
		)
		(fp_line
			(start -25.74544 -3.400806)
			(end -23.034752 -0.800608)
			(stroke
				(width 0.1)
				(type default)
			)
			(layer "B.SilkS")
		)
		(fp_line
			(start -25.74544 -3.400806)
			(end -23.034752 -0.800608)
			(stroke
				(width 0.1)
				(type default)
			)
			(layer "B.SilkS")
		)
		(fp_line
			(start -25.735534 -4.54533)
			(end -23.969472 -2.85115)
			(stroke
				(width 0.1)
				(type default)
			)
			(layer "B.SilkS")
		)
		(fp_line
			(start -25.735534 -4.54533)
			(end -23.969472 -2.85115)
			(stroke
				(width 0.1)
				(type default)
			)
			(layer "B.SilkS")
		)
		(fp_line
			(start -25.733502 -3.331464)
			(end -25.74544 -3.400806)
			(stroke
				(width 0.1)
				(type default)
			)
			(layer "B.SilkS")
		)
		(fp_line
			(start -25.733502 -3.331464)
			(end -25.74544 -3.400806)
			(stroke
				(width 0.1)
				(type default)
			)
			(layer "B.SilkS")
		)
		(fp_line
			(start -25.721056 -3.262122)
			(end -25.733502 -3.331464)
			(stroke
				(width 0.1)
				(type default)
			)
			(layer "B.SilkS")
		)
		(fp_line
			(start -25.721056 -3.262122)
			(end -25.733502 -3.331464)
			(stroke
				(width 0.1)
				(type default)
			)
			(layer "B.SilkS")
		)
		(fp_line
			(start -25.718516 -4.586986)
			(end -23.913084 -2.85496)
			(stroke
				(width 0.1)
				(type default)
			)
			(layer "B.SilkS")
		)
		(fp_line
			(start -25.718516 -4.586986)
			(end -23.913084 -2.85496)
			(stroke
				(width 0.1)
				(type default)
			)
			(layer "B.SilkS")
		)
		(fp_line
			(start -25.708864 -3.19278)
			(end -25.721056 -3.262122)
			(stroke
				(width 0.1)
				(type default)
			)
			(layer "B.SilkS")
		)
		(fp_line
			(start -25.708864 -3.19278)
			(end -25.721056 -3.262122)
			(stroke
				(width 0.1)
				(type default)
			)
			(layer "B.SilkS")
		)
		(fp_line
			(start -25.701498 -4.628388)
			(end -24.658574 -3.627882)
			(stroke
				(width 0.1)
				(type default)
			)
			(layer "B.SilkS")
		)
		(fp_line
			(start -25.701498 -4.628388)
			(end -24.658574 -3.627882)
			(stroke
				(width 0.1)
				(type default)
			)
			(layer "B.SilkS")
		)
		(fp_line
			(start -25.696926 -3.123184)
			(end -25.708864 -3.19278)
			(stroke
				(width 0.1)
				(type default)
			)
			(layer "B.SilkS")
		)
		(fp_line
			(start -25.696926 -3.123184)
			(end -25.708864 -3.19278)
			(stroke
				(width 0.1)
				(type default)
			)
			(layer "B.SilkS")
		)
		(fp_line
			(start -25.68448 -3.054096)
			(end -25.696926 -3.123184)
			(stroke
				(width 0.1)
				(type default)
			)
			(layer "B.SilkS")
		)
		(fp_line
			(start -25.68448 -3.054096)
			(end -25.696926 -3.123184)
			(stroke
				(width 0.1)
				(type default)
			)
			(layer "B.SilkS")
		)
		(fp_line
			(start -25.681686 -4.66725)
			(end -24.67102 -3.697478)
			(stroke
				(width 0.1)
				(type default)
			)
			(layer "B.SilkS")
		)
		(fp_line
			(start -25.681686 -4.66725)
			(end -24.67102 -3.697478)
			(stroke
				(width 0.1)
				(type default)
			)
			(layer "B.SilkS")
		)
		(fp_line
			(start -25.672542 -2.984754)
			(end -25.68448 -3.054096)
			(stroke
				(width 0.1)
				(type default)
			)
			(layer "B.SilkS")
		)
		(fp_line
			(start -25.672542 -2.984754)
			(end -25.68448 -3.054096)
			(stroke
				(width 0.1)
				(type default)
			)
			(layer "B.SilkS")
		)
		(fp_line
			(start -25.66035 -2.915412)
			(end -25.672542 -2.984754)
			(stroke
				(width 0.1)
				(type default)
			)
			(layer "B.SilkS")
		)
		(fp_line
			(start -25.66035 -2.915412)
			(end -25.672542 -2.984754)
			(stroke
				(width 0.1)
				(type default)
			)
			(layer "B.SilkS")
		)
		(fp_line
			(start -25.656286 -4.70027)
			(end -24.682958 -3.76682)
			(stroke
				(width 0.1)
				(type default)
			)
			(layer "B.SilkS")
		)
		(fp_line
			(start -25.656286 -4.70027)
			(end -24.682958 -3.76682)
			(stroke
				(width 0.1)
				(type default)
			)
			(layer "B.SilkS")
		)
		(fp_line
			(start -25.648412 -2.845816)
			(end -25.66035 -2.915412)
			(stroke
				(width 0.1)
				(type default)
			)
			(layer "B.SilkS")
		)
		(fp_line
			(start -25.648412 -2.845816)
			(end -25.66035 -2.915412)
			(stroke
				(width 0.1)
				(type default)
			)
			(layer "B.SilkS")
		)
		(fp_line
			(start -25.635966 -2.776474)
			(end -25.648412 -2.845816)
			(stroke
				(width 0.1)
				(type default)
			)
			(layer "B.SilkS")
		)
		(fp_line
			(start -25.635966 -2.776474)
			(end -25.648412 -2.845816)
			(stroke
				(width 0.1)
				(type default)
			)
			(layer "B.SilkS")
		)
		(fp_line
			(start -25.630378 -4.73329)
			(end -24.690324 -3.83159)
			(stroke
				(width 0.1)
				(type default)
			)
			(layer "B.SilkS")
		)
		(fp_line
			(start -25.630378 -4.73329)
			(end -24.690324 -3.83159)
			(stroke
				(width 0.1)
				(type default)
			)
			(layer "B.SilkS")
		)
		(fp_line
			(start -25.623774 -2.707132)
			(end -25.635966 -2.776474)
			(stroke
				(width 0.1)
				(type default)
			)
			(layer "B.SilkS")
		)
		(fp_line
			(start -25.623774 -2.707132)
			(end -25.635966 -2.776474)
			(stroke
				(width 0.1)
				(type default)
			)
			(layer "B.SilkS")
		)
		(fp_line
			(start -25.611836 -2.63779)
			(end -25.623774 -2.707132)
			(stroke
				(width 0.1)
				(type default)
			)
			(layer "B.SilkS")
		)
		(fp_line
			(start -25.611836 -2.63779)
			(end -25.623774 -2.707132)
			(stroke
				(width 0.1)
				(type default)
			)
			(layer "B.SilkS")
		)
		(fp_line
			(start -25.60447 -4.766564)
			(end -24.695658 -3.894328)
			(stroke
				(width 0.1)
				(type default)
			)
			(layer "B.SilkS")
		)
		(fp_line
			(start -25.60447 -4.766564)
			(end -24.695658 -3.894328)
			(stroke
				(width 0.1)
				(type default)
			)
			(layer "B.SilkS")
		)
		(fp_line
			(start -25.59939 -2.568194)
			(end -25.611836 -2.63779)
			(stroke
				(width 0.1)
				(type default)
			)
			(layer "B.SilkS")
		)
		(fp_line
			(start -25.59939 -2.568194)
			(end -25.611836 -2.63779)
			(stroke
				(width 0.1)
				(type default)
			)
			(layer "B.SilkS")
		)
		(fp_line
			(start -25.587452 -2.498852)
			(end -25.59939 -2.568194)
			(stroke
				(width 0.1)
				(type default)
			)
			(layer "B.SilkS")
		)
		(fp_line
			(start -25.587452 -2.498852)
			(end -25.59939 -2.568194)
			(stroke
				(width 0.1)
				(type default)
			)
			(layer "B.SilkS")
		)
		(fp_line
			(start -25.57907 -4.79933)
			(end -24.690324 -3.946652)
			(stroke
				(width 0.1)
				(type default)
			)
			(layer "B.SilkS")
		)
		(fp_line
			(start -25.57907 -4.79933)
			(end -24.690324 -3.946652)
			(stroke
				(width 0.1)
				(type default)
			)
			(layer "B.SilkS")
		)
		(fp_line
			(start -25.57526 -2.429764)
			(end -25.587452 -2.498852)
			(stroke
				(width 0.1)
				(type default)
			)
			(layer "B.SilkS")
		)
		(fp_line
			(start -25.57526 -2.429764)
			(end -25.587452 -2.498852)
			(stroke
				(width 0.1)
				(type default)
			)
			(layer "B.SilkS")
		)
		(fp_line
			(start -25.57526 -2.429764)
			(end -24.220424 -1.130046)
			(stroke
				(width 0.1)
				(type default)
			)
			(layer "B.SilkS")
		)
		(fp_line
			(start -25.57526 -2.429764)
			(end -24.220424 -1.130046)
			(stroke
				(width 0.1)
				(type default)
			)
			(layer "B.SilkS")
		)
		(fp_line
			(start -25.563322 -2.360422)
			(end -25.57526 -2.429764)
			(stroke
				(width 0.1)
				(type default)
			)
			(layer "B.SilkS")
		)
		(fp_line
			(start -25.563322 -2.360422)
			(end -25.57526 -2.429764)
			(stroke
				(width 0.1)
				(type default)
			)
			(layer "B.SilkS")
		)
		(fp_line
			(start -25.553162 -4.83235)
			(end -24.683974 -3.998722)
			(stroke
				(width 0.1)
				(type default)
			)
			(layer "B.SilkS")
		)
		(fp_line
			(start -25.553162 -4.83235)
			(end -24.683974 -3.998722)
			(stroke
				(width 0.1)
				(type default)
			)
			(layer "B.SilkS")
		)
		(fp_line
			(start -25.550876 -2.290826)
			(end -25.563322 -2.360422)
			(stroke
				(width 0.1)
				(type default)
			)
			(layer "B.SilkS")
		)
		(fp_line
			(start -25.550876 -2.290826)
			(end -25.563322 -2.360422)
			(stroke
				(width 0.1)
				(type default)
			)
			(layer "B.SilkS")
		)
		(fp_line
			(start -25.538684 -2.221484)
			(end -25.550876 -2.290826)
			(stroke
				(width 0.1)
				(type default)
			)
			(layer "B.SilkS")
		)
		(fp_line
			(start -25.538684 -2.221484)
			(end -25.550876 -2.290826)
			(stroke
				(width 0.1)
				(type default)
			)
			(layer "B.SilkS")
		)
		(fp_line
			(start -25.527508 -4.865624)
			(end -24.669242 -4.042156)
			(stroke
				(width 0.1)
				(type default)
			)
			(layer "B.SilkS")
		)
		(fp_line
			(start -25.527508 -4.865624)
			(end -24.669242 -4.042156)
			(stroke
				(width 0.1)
				(type default)
			)
			(layer "B.SilkS")
		)
		(fp_line
			(start -25.526746 -2.152142)
			(end -25.538684 -2.221484)
			(stroke
				(width 0.1)
				(type default)
			)
			(layer "B.SilkS")
		)
		(fp_line
			(start -25.526746 -2.152142)
			(end -25.538684 -2.221484)
			(stroke
				(width 0.1)
				(type default)
			)
			(layer "B.SilkS")
		)
		(fp_line
			(start -25.5143 -2.0828)
			(end -25.526746 -2.152142)
			(stroke
				(width 0.1)
				(type default)
			)
			(layer "B.SilkS")
		)
		(fp_line
			(start -25.5143 -2.0828)
			(end -25.526746 -2.152142)
			(stroke
				(width 0.1)
				(type default)
			)
			(layer "B.SilkS")
		)
		(fp_line
			(start -25.502362 -2.013204)
			(end -25.5143 -2.0828)
			(stroke
				(width 0.1)
				(type default)
			)
			(layer "B.SilkS")
		)
		(fp_line
			(start -25.502362 -2.013204)
			(end -25.5143 -2.0828)
			(stroke
				(width 0.1)
				(type default)
			)
			(layer "B.SilkS")
		)
		(fp_line
			(start -25.49525 -4.892294)
			(end -24.65451 -4.085844)
			(stroke
				(width 0.1)
				(type default)
			)
			(layer "B.SilkS")
		)
		(fp_line
			(start -25.49525 -4.892294)
			(end -24.65451 -4.085844)
			(stroke
				(width 0.1)
				(type default)
			)
			(layer "B.SilkS")
		)
		(fp_line
			(start -25.49017 -1.943862)
			(end -25.502362 -2.013204)
			(stroke
				(width 0.1)
				(type default)
			)
			(layer "B.SilkS")
		)
		(fp_line
			(start -25.49017 -1.943862)
			(end -25.502362 -2.013204)
			(stroke
				(width 0.1)
				(type default)
			)
			(layer "B.SilkS")
		)
		(fp_line
			(start -25.478232 -1.874774)
			(end -25.49017 -1.943862)
			(stroke
				(width 0.1)
				(type default)
			)
			(layer "B.SilkS")
		)
		(fp_line
			(start -25.478232 -1.874774)
			(end -25.49017 -1.943862)
			(stroke
				(width 0.1)
				(type default)
			)
			(layer "B.SilkS")
		)
		(fp_line
			(start -25.465786 -1.805178)
			(end -25.478232 -1.874774)
			(stroke
				(width 0.1)
				(type default)
			)
			(layer "B.SilkS")
		)
		(fp_line
			(start -25.465786 -1.805178)
			(end -25.478232 -1.874774)
			(stroke
				(width 0.1)
				(type default)
			)
			(layer "B.SilkS")
		)
		(fp_line
			(start -25.461722 -4.917694)
			(end -24.631904 -4.121912)
			(stroke
				(width 0.1)
				(type default)
			)
			(layer "B.SilkS")
		)
		(fp_line
			(start -25.461722 -4.917694)
			(end -24.631904 -4.121912)
			(stroke
				(width 0.1)
				(type default)
			)
			(layer "B.SilkS")
		)
		(fp_line
			(start -25.453594 -1.735836)
			(end -25.465786 -1.805178)
			(stroke
				(width 0.1)
				(type default)
			)
			(layer "B.SilkS")
		)
		(fp_line
			(start -25.453594 -1.735836)
			(end -25.465786 -1.805178)
			(stroke
				(width 0.1)
				(type default)
			)
			(layer "B.SilkS")
		)
		(fp_line
			(start -25.441656 -1.666494)
			(end -25.453594 -1.735836)
			(stroke
				(width 0.1)
				(type default)
			)
			(layer "B.SilkS")
		)
		(fp_line
			(start -25.441656 -1.666494)
			(end -25.453594 -1.735836)
			(stroke
				(width 0.1)
				(type default)
			)
			(layer "B.SilkS")
		)
		(fp_line
			(start -25.42921 -1.597406)
			(end -25.441656 -1.666494)
			(stroke
				(width 0.1)
				(type default)
			)
			(layer "B.SilkS")
		)
		(fp_line
			(start -25.42921 -1.597406)
			(end -25.441656 -1.666494)
			(stroke
				(width 0.1)
				(type default)
			)
			(layer "B.SilkS")
		)
		(fp_line
			(start -25.428194 -4.943094)
			(end -24.609044 -4.157218)
			(stroke
				(width 0.1)
				(type default)
			)
			(layer "B.SilkS")
		)
		(fp_line
			(start -25.428194 -4.943094)
			(end -24.609044 -4.157218)
			(stroke
				(width 0.1)
				(type default)
			)
			(layer "B.SilkS")
		)
		(fp_line
			(start -25.417272 -1.52781)
			(end -25.42921 -1.597406)
			(stroke
				(width 0.1)
				(type default)
			)
			(layer "B.SilkS")
		)
		(fp_line
			(start -25.417272 -1.52781)
			(end -25.42921 -1.597406)
			(stroke
				(width 0.1)
				(type default)
			)
			(layer "B.SilkS")
		)
		(fp_line
			(start -25.40508 -1.458214)
			(end -25.417272 -1.52781)
			(stroke
				(width 0.1)
				(type default)
			)
			(layer "B.SilkS")
		)
		(fp_line
			(start -25.40508 -1.458214)
			(end -25.417272 -1.52781)
			(stroke
				(width 0.1)
				(type default)
			)
			(layer "B.SilkS")
		)
		(fp_line
			(start -25.394412 -4.968494)
			(end -24.580596 -4.187952)
			(stroke
				(width 0.1)
				(type default)
			)
			(layer "B.SilkS")
		)
		(fp_line
			(start -25.394412 -4.968494)
			(end -24.580596 -4.187952)
			(stroke
				(width 0.1)
				(type default)
			)
			(layer "B.SilkS")
		)
		(fp_line
			(start -25.392634 -1.388872)
			(end -25.40508 -1.458214)
			(stroke
				(width 0.1)
				(type default)
			)
			(layer "B.SilkS")
		)
		(fp_line
			(start -25.392634 -1.388872)
			(end -25.40508 -1.458214)
			(stroke
				(width 0.1)
				(type default)
			)
			(layer "B.SilkS")
		)
		(fp_line
			(start -25.380696 -1.319784)
			(end -25.392634 -1.388872)
			(stroke
				(width 0.1)
				(type default)
			)
			(layer "B.SilkS")
		)
		(fp_line
			(start -25.380696 -1.319784)
			(end -25.392634 -1.388872)
			(stroke
				(width 0.1)
				(type default)
			)
			(layer "B.SilkS")
		)
		(fp_line
			(start -25.368504 -1.250188)
			(end -25.380696 -1.319784)
			(stroke
				(width 0.1)
				(type default)
			)
			(layer "B.SilkS")
		)
		(fp_line
			(start -25.368504 -1.250188)
			(end -25.380696 -1.319784)
			(stroke
				(width 0.1)
				(type default)
			)
			(layer "B.SilkS")
		)
		(fp_line
			(start -25.36063 -4.994148)
			(end -24.549354 -4.215892)
			(stroke
				(width 0.1)
				(type default)
			)
			(layer "B.SilkS")
		)
		(fp_line
			(start -25.36063 -4.994148)
			(end -24.549354 -4.215892)
			(stroke
				(width 0.1)
				(type default)
			)
			(layer "B.SilkS")
		)
		(fp_line
			(start -25.356058 -1.180592)
			(end -25.368504 -1.250188)
			(stroke
				(width 0.1)
				(type default)
			)
			(layer "B.SilkS")
		)
		(fp_line
			(start -25.356058 -1.180592)
			(end -25.368504 -1.250188)
			(stroke
				(width 0.1)
				(type default)
			)
			(layer "B.SilkS")
		)
		(fp_line
			(start -25.34412 -1.111504)
			(end -25.356058 -1.180592)
			(stroke
				(width 0.1)
				(type default)
			)
			(layer "B.SilkS")
		)
		(fp_line
			(start -25.34412 -1.111504)
			(end -25.356058 -1.180592)
			(stroke
				(width 0.1)
				(type default)
			)
			(layer "B.SilkS")
		)
		(fp_line
			(start -25.332182 -1.042416)
			(end -25.34412 -1.111504)
			(stroke
				(width 0.1)
				(type default)
			)
			(layer "B.SilkS")
		)
		(fp_line
			(start -25.332182 -1.042416)
			(end -25.34412 -1.111504)
			(stroke
				(width 0.1)
				(type default)
			)
			(layer "B.SilkS")
		)
		(fp_line
			(start -25.327356 -5.019294)
			(end -24.516334 -4.2418)
			(stroke
				(width 0.1)
				(type default)
			)
			(layer "B.SilkS")
		)
		(fp_line
			(start -25.327356 -5.019294)
			(end -24.516334 -4.2418)
			(stroke
				(width 0.1)
				(type default)
			)
			(layer "B.SilkS")
		)
		(fp_line
			(start -25.31999 -0.97282)
			(end -25.332182 -1.042416)
			(stroke
				(width 0.1)
				(type default)
			)
			(layer "B.SilkS")
		)
		(fp_line
			(start -25.31999 -0.97282)
			(end -25.332182 -1.042416)
			(stroke
				(width 0.1)
				(type default)
			)
			(layer "B.SilkS")
		)
		(fp_line
			(start -25.307544 -0.903224)
			(end -25.31999 -0.97282)
			(stroke
				(width 0.1)
				(type default)
			)
			(layer "B.SilkS")
		)
		(fp_line
			(start -25.307544 -0.903224)
			(end -25.31999 -0.97282)
			(stroke
				(width 0.1)
				(type default)
			)
			(layer "B.SilkS")
		)
		(fp_line
			(start -25.304242 -0.882904)
			(end -25.307544 -0.903224)
			(stroke
				(width 0.1)
				(type default)
			)
			(layer "B.SilkS")
		)
		(fp_line
			(start -25.304242 -0.882904)
			(end -25.307544 -0.903224)
			(stroke
				(width 0.1)
				(type default)
			)
			(layer "B.SilkS")
		)
		(fp_line
			(start -25.29205 -5.043424)
			(end -24.477726 -4.26212)
			(stroke
				(width 0.1)
				(type default)
			)
			(layer "B.SilkS")
		)
		(fp_line
			(start -25.29205 -5.043424)
			(end -24.477726 -4.26212)
			(stroke
				(width 0.1)
				(type default)
			)
			(layer "B.SilkS")
		)
		(fp_line
			(start -25.286462 -0.882904)
			(end -25.307544 -0.903224)
			(stroke
				(width 0.1)
				(type default)
			)
			(layer "B.SilkS")
		)
		(fp_line
			(start -25.286462 -0.882904)
			(end -25.307544 -0.903224)
			(stroke
				(width 0.1)
				(type default)
			)
			(layer "B.SilkS")
		)
		(fp_line
			(start -25.286462 -0.882904)
			(end -25.304242 -0.882904)
			(stroke
				(width 0.1)
				(type default)
			)
			(layer "B.SilkS")
		)
		(fp_line
			(start -25.286462 -0.882904)
			(end -25.304242 -0.882904)
			(stroke
				(width 0.1)
				(type default)
			)
			(layer "B.SilkS")
		)
		(fp_line
			(start -25.250648 -5.061712)
			(end -24.438356 -4.28244)
			(stroke
				(width 0.1)
				(type default)
			)
			(layer "B.SilkS")
		)
		(fp_line
			(start -25.250648 -5.061712)
			(end -24.438356 -4.28244)
			(stroke
				(width 0.1)
				(type default)
			)
			(layer "B.SilkS")
		)
		(fp_line
			(start -25.226264 -0.882904)
			(end -25.31999 -0.97282)
			(stroke
				(width 0.1)
				(type default)
			)
			(layer "B.SilkS")
		)
		(fp_line
			(start -25.226264 -0.882904)
			(end -25.31999 -0.97282)
			(stroke
				(width 0.1)
				(type default)
			)
			(layer "B.SilkS")
		)
		(fp_line
			(start -25.226264 -0.882904)
			(end -25.286462 -0.882904)
			(stroke
				(width 0.1)
				(type default)
			)
			(layer "B.SilkS")
		)
		(fp_line
			(start -25.226264 -0.882904)
			(end -25.286462 -0.882904)
			(stroke
				(width 0.1)
				(type default)
			)
			(layer "B.SilkS")
		)
		(fp_line
			(start -25.2095 -5.08)
			(end -24.393398 -4.296918)
			(stroke
				(width 0.1)
				(type default)
			)
			(layer "B.SilkS")
		)
		(fp_line
			(start -25.2095 -5.08)
			(end -24.393398 -4.296918)
			(stroke
				(width 0.1)
				(type default)
			)
			(layer "B.SilkS")
		)
		(fp_line
			(start -25.168352 -5.098034)
			(end -24.346408 -4.309618)
			(stroke
				(width 0.1)
				(type default)
			)
			(layer "B.SilkS")
		)
		(fp_line
			(start -25.168352 -5.098034)
			(end -24.346408 -4.309618)
			(stroke
				(width 0.1)
				(type default)
			)
			(layer "B.SilkS")
		)
		(fp_line
			(start -25.166066 -0.882904)
			(end -25.332182 -1.042416)
			(stroke
				(width 0.1)
				(type default)
			)
			(layer "B.SilkS")
		)
		(fp_line
			(start -25.166066 -0.882904)
			(end -25.332182 -1.042416)
			(stroke
				(width 0.1)
				(type default)
			)
			(layer "B.SilkS")
		)
		(fp_line
			(start -25.166066 -0.882904)
			(end -25.226264 -0.882904)
			(stroke
				(width 0.1)
				(type default)
			)
			(layer "B.SilkS")
		)
		(fp_line
			(start -25.166066 -0.882904)
			(end -25.226264 -0.882904)
			(stroke
				(width 0.1)
				(type default)
			)
			(layer "B.SilkS")
		)
		(fp_line
			(start -25.127458 -5.116322)
			(end -24.297132 -4.320032)
			(stroke
				(width 0.1)
				(type default)
			)
			(layer "B.SilkS")
		)
		(fp_line
			(start -25.127458 -5.116322)
			(end -24.297132 -4.320032)
			(stroke
				(width 0.1)
				(type default)
			)
			(layer "B.SilkS")
		)
		(fp_line
			(start -25.106122 -0.882904)
			(end -25.34412 -1.111504)
			(stroke
				(width 0.1)
				(type default)
			)
			(layer "B.SilkS")
		)
		(fp_line
			(start -25.106122 -0.882904)
			(end -25.34412 -1.111504)
			(stroke
				(width 0.1)
				(type default)
			)
			(layer "B.SilkS")
		)
		(fp_line
			(start -25.106122 -0.882904)
			(end -25.166066 -0.882904)
			(stroke
				(width 0.1)
				(type default)
			)
			(layer "B.SilkS")
		)
		(fp_line
			(start -25.106122 -0.882904)
			(end -25.166066 -0.882904)
			(stroke
				(width 0.1)
				(type default)
			)
			(layer "B.SilkS")
		)
		(fp_line
			(start -25.086056 -5.13461)
			(end -24.241252 -4.32435)
			(stroke
				(width 0.1)
				(type default)
			)
			(layer "B.SilkS")
		)
		(fp_line
			(start -25.086056 -5.13461)
			(end -24.241252 -4.32435)
			(stroke
				(width 0.1)
				(type default)
			)
			(layer "B.SilkS")
		)
		(fp_line
			(start -25.04567 -0.882904)
			(end -25.356058 -1.180592)
			(stroke
				(width 0.1)
				(type default)
			)
			(layer "B.SilkS")
		)
		(fp_line
			(start -25.04567 -0.882904)
			(end -25.356058 -1.180592)
			(stroke
				(width 0.1)
				(type default)
			)
			(layer "B.SilkS")
		)
		(fp_line
			(start -25.04567 -0.882904)
			(end -25.106122 -0.882904)
			(stroke
				(width 0.1)
				(type default)
			)
			(layer "B.SilkS")
		)
		(fp_line
			(start -25.04567 -0.882904)
			(end -25.106122 -0.882904)
			(stroke
				(width 0.1)
				(type default)
			)
			(layer "B.SilkS")
		)
		(fp_line
			(start -25.045162 -5.152898)
			(end -24.18588 -4.328922)
			(stroke
				(width 0.1)
				(type default)
			)
			(layer "B.SilkS")
		)
		(fp_line
			(start -25.045162 -5.152898)
			(end -24.18588 -4.328922)
			(stroke
				(width 0.1)
				(type default)
			)
			(layer "B.SilkS")
		)
		(fp_line
			(start -24.99995 -5.16763)
			(end -24.12619 -4.329176)
			(stroke
				(width 0.1)
				(type default)
			)
			(layer "B.SilkS")
		)
		(fp_line
			(start -24.99995 -5.16763)
			(end -24.12619 -4.329176)
			(stroke
				(width 0.1)
				(type default)
			)
			(layer "B.SilkS")
		)
		(fp_line
			(start -24.985472 -0.882904)
			(end -25.368504 -1.250188)
			(stroke
				(width 0.1)
				(type default)
			)
			(layer "B.SilkS")
		)
		(fp_line
			(start -24.985472 -0.882904)
			(end -25.368504 -1.250188)
			(stroke
				(width 0.1)
				(type default)
			)
			(layer "B.SilkS")
		)
		(fp_line
			(start -24.985472 -0.882904)
			(end -25.04567 -0.882904)
			(stroke
				(width 0.1)
				(type default)
			)
			(layer "B.SilkS")
		)
		(fp_line
			(start -24.985472 -0.882904)
			(end -25.04567 -0.882904)
			(stroke
				(width 0.1)
				(type default)
			)
			(layer "B.SilkS")
		)
		(fp_line
			(start -24.95169 -5.178552)
			(end -24.064976 -4.327906)
			(stroke
				(width 0.1)
				(type default)
			)
			(layer "B.SilkS")
		)
		(fp_line
			(start -24.95169 -5.178552)
			(end -24.064976 -4.327906)
			(stroke
				(width 0.1)
				(type default)
			)
			(layer "B.SilkS")
		)
		(fp_line
			(start -24.925274 -0.882904)
			(end -25.380696 -1.319784)
			(stroke
				(width 0.1)
				(type default)
			)
			(layer "B.SilkS")
		)
		(fp_line
			(start -24.925274 -0.882904)
			(end -25.380696 -1.319784)
			(stroke
				(width 0.1)
				(type default)
			)
			(layer "B.SilkS")
		)
		(fp_line
			(start -24.925274 -0.882904)
			(end -24.985472 -0.882904)
			(stroke
				(width 0.1)
				(type default)
			)
			(layer "B.SilkS")
		)
		(fp_line
			(start -24.925274 -0.882904)
			(end -24.985472 -0.882904)
			(stroke
				(width 0.1)
				(type default)
			)
			(layer "B.SilkS")
		)
		(fp_line
			(start -24.903176 -5.189728)
			(end -24.003254 -4.32689)
			(stroke
				(width 0.1)
				(type default)
			)
			(layer "B.SilkS")
		)
		(fp_line
			(start -24.903176 -5.189728)
			(end -24.003254 -4.32689)
			(stroke
				(width 0.1)
				(type default)
			)
			(layer "B.SilkS")
		)
		(fp_line
			(start -24.86533 -0.882904)
			(end -25.392634 -1.388872)
			(stroke
				(width 0.1)
				(type default)
			)
			(layer "B.SilkS")
		)
		(fp_line
			(start -24.86533 -0.882904)
			(end -25.392634 -1.388872)
			(stroke
				(width 0.1)
				(type default)
			)
			(layer "B.SilkS")
		)
		(fp_line
			(start -24.86533 -0.882904)
			(end -24.925274 -0.882904)
			(stroke
				(width 0.1)
				(type default)
			)
			(layer "B.SilkS")
		)
		(fp_line
			(start -24.86533 -0.882904)
			(end -24.925274 -0.882904)
			(stroke
				(width 0.1)
				(type default)
			)
			(layer "B.SilkS")
		)
		(fp_line
			(start -24.854154 -5.200904)
			(end -23.9395 -4.323334)
			(stroke
				(width 0.1)
				(type default)
			)
			(layer "B.SilkS")
		)
		(fp_line
			(start -24.854154 -5.200904)
			(end -23.9395 -4.323334)
			(stroke
				(width 0.1)
				(type default)
			)
			(layer "B.SilkS")
		)
		(fp_line
			(start -24.805894 -5.21208)
			(end -23.87473 -4.318762)
			(stroke
				(width 0.1)
				(type default)
			)
			(layer "B.SilkS")
		)
		(fp_line
			(start -24.805894 -5.21208)
			(end -23.87473 -4.318762)
			(stroke
				(width 0.1)
				(type default)
			)
			(layer "B.SilkS")
		)
		(fp_line
			(start -24.805386 -0.882904)
			(end -25.40508 -1.458214)
			(stroke
				(width 0.1)
				(type default)
			)
			(layer "B.SilkS")
		)
		(fp_line
			(start -24.805386 -0.882904)
			(end -25.40508 -1.458214)
			(stroke
				(width 0.1)
				(type default)
			)
			(layer "B.SilkS")
		)
		(fp_line
			(start -24.805386 -0.882904)
			(end -24.86533 -0.882904)
			(stroke
				(width 0.1)
				(type default)
			)
			(layer "B.SilkS")
		)
		(fp_line
			(start -24.805386 -0.882904)
			(end -24.86533 -0.882904)
			(stroke
				(width 0.1)
				(type default)
			)
			(layer "B.SilkS")
		)
		(fp_line
			(start -24.75738 -5.223256)
			(end -23.809452 -4.313936)
			(stroke
				(width 0.1)
				(type default)
			)
			(layer "B.SilkS")
		)
		(fp_line
			(start -24.75738 -5.223256)
			(end -23.809452 -4.313936)
			(stroke
				(width 0.1)
				(type default)
			)
			(layer "B.SilkS")
		)
		(fp_line
			(start -24.744934 -0.882904)
			(end -25.417272 -1.52781)
			(stroke
				(width 0.1)
				(type default)
			)
			(layer "B.SilkS")
		)
		(fp_line
			(start -24.744934 -0.882904)
			(end -25.417272 -1.52781)
			(stroke
				(width 0.1)
				(type default)
			)
			(layer "B.SilkS")
		)
		(fp_line
			(start -24.744934 -0.882904)
			(end -24.805386 -0.882904)
			(stroke
				(width 0.1)
				(type default)
			)
			(layer "B.SilkS")
		)
		(fp_line
			(start -24.744934 -0.882904)
			(end -24.805386 -0.882904)
			(stroke
				(width 0.1)
				(type default)
			)
			(layer "B.SilkS")
		)
		(fp_line
			(start -24.708866 -5.234432)
			(end -23.739856 -4.304792)
			(stroke
				(width 0.1)
				(type default)
			)
			(layer "B.SilkS")
		)
		(fp_line
			(start -24.708866 -5.234432)
			(end -23.739856 -4.304792)
			(stroke
				(width 0.1)
				(type default)
			)
			(layer "B.SilkS")
		)
		(fp_line
			(start -24.684736 -0.882904)
			(end -25.42921 -1.597406)
			(stroke
				(width 0.1)
				(type default)
			)
			(layer "B.SilkS")
		)
		(fp_line
			(start -24.684736 -0.882904)
			(end -25.42921 -1.597406)
			(stroke
				(width 0.1)
				(type default)
			)
			(layer "B.SilkS")
		)
		(fp_line
			(start -24.684736 -0.882904)
			(end -24.744934 -0.882904)
			(stroke
				(width 0.1)
				(type default)
			)
			(layer "B.SilkS")
		)
		(fp_line
			(start -24.684736 -0.882904)
			(end -24.744934 -0.882904)
			(stroke
				(width 0.1)
				(type default)
			)
			(layer "B.SilkS")
		)
		(fp_line
			(start -24.682958 -3.76682)
			(end -24.67102 -3.697478)
			(stroke
				(width 0.1)
				(type default)
			)
			(layer "B.SilkS")
		)
		(fp_line
			(start -24.682958 -3.76682)
			(end -24.67102 -3.697478)
			(stroke
				(width 0.1)
				(type default)
			)
			(layer "B.SilkS")
		)
		(fp_line
			(start -24.67102 -3.697478)
			(end -24.658574 -3.627882)
			(stroke
				(width 0.1)
				(type default)
			)
			(layer "B.SilkS")
		)
		(fp_line
			(start -24.67102 -3.697478)
			(end -24.658574 -3.627882)
			(stroke
				(width 0.1)
				(type default)
			)
			(layer "B.SilkS")
		)
		(fp_line
			(start -24.653748 -5.239258)
			(end -23.67026 -4.295902)
			(stroke
				(width 0.1)
				(type default)
			)
			(layer "B.SilkS")
		)
		(fp_line
			(start -24.653748 -5.239258)
			(end -23.67026 -4.295902)
			(stroke
				(width 0.1)
				(type default)
			)
			(layer "B.SilkS")
		)
		(fp_line
			(start -24.624538 -0.882904)
			(end -25.441656 -1.666494)
			(stroke
				(width 0.1)
				(type default)
			)
			(layer "B.SilkS")
		)
		(fp_line
			(start -24.624538 -0.882904)
			(end -25.441656 -1.666494)
			(stroke
				(width 0.1)
				(type default)
			)
			(layer "B.SilkS")
		)
		(fp_line
			(start -24.624538 -0.882904)
			(end -24.684736 -0.882904)
			(stroke
				(width 0.1)
				(type default)
			)
			(layer "B.SilkS")
		)
		(fp_line
			(start -24.624538 -0.882904)
			(end -24.684736 -0.882904)
			(stroke
				(width 0.1)
				(type default)
			)
			(layer "B.SilkS")
		)
		(fp_line
			(start -24.614886 -3.586226)
			(end -23.855426 -2.857754)
			(stroke
				(width 0.1)
				(type default)
			)
			(layer "B.SilkS")
		)
		(fp_line
			(start -24.614886 -3.586226)
			(end -23.855426 -2.857754)
			(stroke
				(width 0.1)
				(type default)
			)
			(layer "B.SilkS")
		)
		(fp_line
			(start -24.597614 -5.243068)
			(end -23.594822 -4.280916)
			(stroke
				(width 0.1)
				(type default)
			)
			(layer "B.SilkS")
		)
		(fp_line
			(start -24.597614 -5.243068)
			(end -23.594822 -4.280916)
			(stroke
				(width 0.1)
				(type default)
			)
			(layer "B.SilkS")
		)
		(fp_line
			(start -24.5745 -3.605276)
			(end -23.797006 -2.859024)
			(stroke
				(width 0.1)
				(type default)
			)
			(layer "B.SilkS")
		)
		(fp_line
			(start -24.5745 -3.605276)
			(end -23.797006 -2.859024)
			(stroke
				(width 0.1)
				(type default)
			)
			(layer "B.SilkS")
		)
		(fp_line
			(start -24.564594 -0.882904)
			(end -25.453594 -1.735836)
			(stroke
				(width 0.1)
				(type default)
			)
			(layer "B.SilkS")
		)
		(fp_line
			(start -24.564594 -0.882904)
			(end -25.453594 -1.735836)
			(stroke
				(width 0.1)
				(type default)
			)
			(layer "B.SilkS")
		)
		(fp_line
			(start -24.564594 -0.882904)
			(end -24.624538 -0.882904)
			(stroke
				(width 0.1)
				(type default)
			)
			(layer "B.SilkS")
		)
		(fp_line
			(start -24.564594 -0.882904)
			(end -24.624538 -0.882904)
			(stroke
				(width 0.1)
				(type default)
			)
			(layer "B.SilkS")
		)
		(fp_line
			(start -24.541734 -5.246878)
			(end -23.518114 -4.265168)
			(stroke
				(width 0.1)
				(type default)
			)
			(layer "B.SilkS")
		)
		(fp_line
			(start -24.541734 -5.246878)
			(end -23.518114 -4.265168)
			(stroke
				(width 0.1)
				(type default)
			)
			(layer "B.SilkS")
		)
		(fp_line
			(start -24.534114 -3.624072)
			(end -23.73757 -2.859786)
			(stroke
				(width 0.1)
				(type default)
			)
			(layer "B.SilkS")
		)
		(fp_line
			(start -24.534114 -3.624072)
			(end -23.73757 -2.859786)
			(stroke
				(width 0.1)
				(type default)
			)
			(layer "B.SilkS")
		)
		(fp_line
			(start -24.504142 -0.882904)
			(end -25.465786 -1.805178)
			(stroke
				(width 0.1)
				(type default)
			)
			(layer "B.SilkS")
		)
		(fp_line
			(start -24.504142 -0.882904)
			(end -25.465786 -1.805178)
			(stroke
				(width 0.1)
				(type default)
			)
			(layer "B.SilkS")
		)
		(fp_line
			(start -24.504142 -0.882904)
			(end -24.564594 -0.882904)
			(stroke
				(width 0.1)
				(type default)
			)
			(layer "B.SilkS")
		)
		(fp_line
			(start -24.504142 -0.882904)
			(end -24.564594 -0.882904)
			(stroke
				(width 0.1)
				(type default)
			)
			(layer "B.SilkS")
		)
		(fp_line
			(start -24.491696 -3.64109)
			(end -23.668482 -2.85115)
			(stroke
				(width 0.1)
				(type default)
			)
			(layer "B.SilkS")
		)
		(fp_line
			(start -24.491696 -3.64109)
			(end -23.668482 -2.85115)
			(stroke
				(width 0.1)
				(type default)
			)
			(layer "B.SilkS")
		)
		(fp_line
			(start -24.487886 -2.656332)
			(end -24.475948 -2.58699)
			(stroke
				(width 0.1)
				(type default)
			)
			(layer "B.SilkS")
		)
		(fp_line
			(start -24.487886 -2.656332)
			(end -24.475948 -2.58699)
			(stroke
				(width 0.1)
				(type default)
			)
			(layer "B.SilkS")
		)
		(fp_line
			(start -24.485346 -5.250942)
			(end -23.433532 -4.2418)
			(stroke
				(width 0.1)
				(type default)
			)
			(layer "B.SilkS")
		)
		(fp_line
			(start -24.485346 -5.250942)
			(end -23.433532 -4.2418)
			(stroke
				(width 0.1)
				(type default)
			)
			(layer "B.SilkS")
		)
		(fp_line
			(start -24.475948 -2.58699)
			(end -24.46401 -2.517648)
			(stroke
				(width 0.1)
				(type default)
			)
			(layer "B.SilkS")
		)
		(fp_line
			(start -24.475948 -2.58699)
			(end -24.46401 -2.517648)
			(stroke
				(width 0.1)
				(type default)
			)
			(layer "B.SilkS")
		)
		(fp_line
			(start -24.46401 -2.517648)
			(end -24.451564 -2.448306)
			(stroke
				(width 0.1)
				(type default)
			)
			(layer "B.SilkS")
		)
		(fp_line
			(start -24.46401 -2.517648)
			(end -24.451564 -2.448306)
			(stroke
				(width 0.1)
				(type default)
			)
			(layer "B.SilkS")
		)
		(fp_line
			(start -24.451564 -2.448306)
			(end -24.439372 -2.37871)
			(stroke
				(width 0.1)
				(type default)
			)
			(layer "B.SilkS")
		)
		(fp_line
			(start -24.451564 -2.448306)
			(end -24.439372 -2.37871)
			(stroke
				(width 0.1)
				(type default)
			)
			(layer "B.SilkS")
		)
		(fp_line
			(start -24.44623 -3.655568)
			(end -23.598886 -2.842514)
			(stroke
				(width 0.1)
				(type default)
			)
			(layer "B.SilkS")
		)
		(fp_line
			(start -24.44623 -3.655568)
			(end -23.598886 -2.842514)
			(stroke
				(width 0.1)
				(type default)
			)
			(layer "B.SilkS")
		)
		(fp_line
			(start -24.443944 -0.882904)
			(end -25.478232 -1.874774)
			(stroke
				(width 0.1)
				(type default)
			)
			(layer "B.SilkS")
		)
		(fp_line
			(start -24.443944 -0.882904)
			(end -25.478232 -1.874774)
			(stroke
				(width 0.1)
				(type default)
			)
			(layer "B.SilkS")
		)
		(fp_line
			(start -24.443944 -0.882904)
			(end -24.504142 -0.882904)
			(stroke
				(width 0.1)
				(type default)
			)
			(layer "B.SilkS")
		)
		(fp_line
			(start -24.443944 -0.882904)
			(end -24.504142 -0.882904)
			(stroke
				(width 0.1)
				(type default)
			)
			(layer "B.SilkS")
		)
		(fp_line
			(start -24.439372 -2.37871)
			(end -24.427434 -2.309368)
			(stroke
				(width 0.1)
				(type default)
			)
			(layer "B.SilkS")
		)
		(fp_line
			(start -24.439372 -2.37871)
			(end -24.427434 -2.309368)
			(stroke
				(width 0.1)
				(type default)
			)
			(layer "B.SilkS")
		)
		(fp_line
			(start -24.427434 -2.309368)
			(end -24.414988 -2.24028)
			(stroke
				(width 0.1)
				(type default)
			)
			(layer "B.SilkS")
		)
		(fp_line
			(start -24.427434 -2.309368)
			(end -24.414988 -2.24028)
			(stroke
				(width 0.1)
				(type default)
			)
			(layer "B.SilkS")
		)
		(fp_line
			(start -24.414988 -2.24028)
			(end -24.402796 -2.170938)
			(stroke
				(width 0.1)
				(type default)
			)
			(layer "B.SilkS")
		)
		(fp_line
			(start -24.414988 -2.24028)
			(end -24.402796 -2.170938)
			(stroke
				(width 0.1)
				(type default)
			)
			(layer "B.SilkS")
		)
		(fp_line
			(start -24.384 -0.882904)
			(end -25.49017 -1.943862)
			(stroke
				(width 0.1)
				(type default)
			)
			(layer "B.SilkS")
		)
		(fp_line
			(start -24.384 -0.882904)
			(end -25.49017 -1.943862)
			(stroke
				(width 0.1)
				(type default)
			)
			(layer "B.SilkS")
		)
		(fp_line
			(start -24.384 -0.882904)
			(end -24.443944 -0.882904)
			(stroke
				(width 0.1)
				(type default)
			)
			(layer "B.SilkS")
		)
		(fp_line
			(start -24.384 -0.882904)
			(end -24.443944 -0.882904)
			(stroke
				(width 0.1)
				(type default)
			)
			(layer "B.SilkS")
		)
		(fp_line
			(start -24.324056 -0.882904)
			(end -25.502362 -2.013204)
			(stroke
				(width 0.1)
				(type default)
			)
			(layer "B.SilkS")
		)
		(fp_line
			(start -24.324056 -0.882904)
			(end -25.502362 -2.013204)
			(stroke
				(width 0.1)
				(type default)
			)
			(layer "B.SilkS")
		)
		(fp_line
			(start -24.324056 -0.882904)
			(end -24.384 -0.882904)
			(stroke
				(width 0.1)
				(type default)
			)
			(layer "B.SilkS")
		)
		(fp_line
			(start -24.324056 -0.882904)
			(end -24.384 -0.882904)
			(stroke
				(width 0.1)
				(type default)
			)
			(layer "B.SilkS")
		)
		(fp_line
			(start -24.263858 -0.882904)
			(end -25.5143 -2.0828)
			(stroke
				(width 0.1)
				(type default)
			)
			(layer "B.SilkS")
		)
		(fp_line
			(start -24.263858 -0.882904)
			(end -25.5143 -2.0828)
			(stroke
				(width 0.1)
				(type default)
			)
			(layer "B.SilkS")
		)
		(fp_line
			(start -24.263858 -0.882904)
			(end -24.324056 -0.882904)
			(stroke
				(width 0.1)
				(type default)
			)
			(layer "B.SilkS")
		)
		(fp_line
			(start -24.263858 -0.882904)
			(end -24.324056 -0.882904)
			(stroke
				(width 0.1)
				(type default)
			)
			(layer "B.SilkS")
		)
		(fp_line
			(start -24.220424 -1.130046)
			(end -24.208232 -1.06045)
			(stroke
				(width 0.1)
				(type default)
			)
			(layer "B.SilkS")
		)
		(fp_line
			(start -24.220424 -1.130046)
			(end -24.208232 -1.06045)
			(stroke
				(width 0.1)
				(type default)
			)
			(layer "B.SilkS")
		)
		(fp_line
			(start -24.208232 -1.06045)
			(end -25.563322 -2.360422)
			(stroke
				(width 0.1)
				(type default)
			)
			(layer "B.SilkS")
		)
		(fp_line
			(start -24.208232 -1.06045)
			(end -25.563322 -2.360422)
			(stroke
				(width 0.1)
				(type default)
			)
			(layer "B.SilkS")
		)
		(fp_line
			(start -24.208232 -1.06045)
			(end -24.195786 -0.991108)
			(stroke
				(width 0.1)
				(type default)
			)
			(layer "B.SilkS")
		)
		(fp_line
			(start -24.208232 -1.06045)
			(end -24.195786 -0.991108)
			(stroke
				(width 0.1)
				(type default)
			)
			(layer "B.SilkS")
		)
		(fp_line
			(start -24.203406 -0.882904)
			(end -25.526746 -2.152142)
			(stroke
				(width 0.1)
				(type default)
			)
			(layer "B.SilkS")
		)
		(fp_line
			(start -24.203406 -0.882904)
			(end -25.526746 -2.152142)
			(stroke
				(width 0.1)
				(type default)
			)
			(layer "B.SilkS")
		)
		(fp_line
			(start -24.203406 -0.882904)
			(end -24.263858 -0.882904)
			(stroke
				(width 0.1)
				(type default)
			)
			(layer "B.SilkS")
		)
		(fp_line
			(start -24.203406 -0.882904)
			(end -24.263858 -0.882904)
			(stroke
				(width 0.1)
				(type default)
			)
			(layer "B.SilkS")
		)
		(fp_line
			(start -24.195786 -0.991108)
			(end -25.550876 -2.290826)
			(stroke
				(width 0.1)
				(type default)
			)
			(layer "B.SilkS")
		)
		(fp_line
			(start -24.195786 -0.991108)
			(end -25.550876 -2.290826)
			(stroke
				(width 0.1)
				(type default)
			)
			(layer "B.SilkS")
		)
		(fp_line
			(start -24.195786 -0.991108)
			(end -24.183848 -0.921512)
			(stroke
				(width 0.1)
				(type default)
			)
			(layer "B.SilkS")
		)
		(fp_line
			(start -24.195786 -0.991108)
			(end -24.183848 -0.921512)
			(stroke
				(width 0.1)
				(type default)
			)
			(layer "B.SilkS")
		)
		(fp_line
			(start -24.183848 -0.921512)
			(end -25.538684 -2.221484)
			(stroke
				(width 0.1)
				(type default)
			)
			(layer "B.SilkS")
		)
		(fp_line
			(start -24.183848 -0.921512)
			(end -25.538684 -2.221484)
			(stroke
				(width 0.1)
				(type default)
			)
			(layer "B.SilkS")
		)
		(fp_line
			(start -24.183848 -0.921512)
			(end -24.17699 -0.882904)
			(stroke
				(width 0.1)
				(type default)
			)
			(layer "B.SilkS")
		)
		(fp_line
			(start -24.183848 -0.921512)
			(end -24.17699 -0.882904)
			(stroke
				(width 0.1)
				(type default)
			)
			(layer "B.SilkS")
		)
		(fp_line
			(start -24.17699 -0.882904)
			(end -24.203406 -0.882904)
			(stroke
				(width 0.1)
				(type default)
			)
			(layer "B.SilkS")
		)
		(fp_line
			(start -24.17699 -0.882904)
			(end -24.203406 -0.882904)
			(stroke
				(width 0.1)
				(type default)
			)
			(layer "B.SilkS")
		)
		(fp_line
			(start -24.122888 -1.094232)
			(end -25.587452 -2.498852)
			(stroke
				(width 0.1)
				(type default)
			)
			(layer "B.SilkS")
		)
		(fp_line
			(start -24.122888 -1.094232)
			(end -25.587452 -2.498852)
			(stroke
				(width 0.1)
				(type default)
			)
			(layer "B.SilkS")
		)
		(fp_line
			(start -23.951692 -0.987552)
			(end -25.59939 -2.568194)
			(stroke
				(width 0.1)
				(type default)
			)
			(layer "B.SilkS")
		)
		(fp_line
			(start -23.951692 -0.987552)
			(end -25.59939 -2.568194)
			(stroke
				(width 0.1)
				(type default)
			)
			(layer "B.SilkS")
		)
		(fp_line
			(start -23.831296 -0.929894)
			(end -25.611836 -2.63779)
			(stroke
				(width 0.1)
				(type default)
			)
			(layer "B.SilkS")
		)
		(fp_line
			(start -23.831296 -0.929894)
			(end -25.611836 -2.63779)
			(stroke
				(width 0.1)
				(type default)
			)
			(layer "B.SilkS")
		)
		(fp_line
			(start -23.728426 -0.888746)
			(end -25.623774 -2.707132)
			(stroke
				(width 0.1)
				(type default)
			)
			(layer "B.SilkS")
		)
		(fp_line
			(start -23.728426 -0.888746)
			(end -25.623774 -2.707132)
			(stroke
				(width 0.1)
				(type default)
			)
			(layer "B.SilkS")
		)
		(fp_line
			(start -23.683468 -3.731514)
			(end -21.836634 -1.95961)
			(stroke
				(width 0.1)
				(type default)
			)
			(layer "B.SilkS")
		)
		(fp_line
			(start -23.683468 -3.731514)
			(end -21.836634 -1.95961)
			(stroke
				(width 0.1)
				(type default)
			)
			(layer "B.SilkS")
		)
		(fp_line
			(start -23.642828 -0.864616)
			(end -25.635966 -2.776474)
			(stroke
				(width 0.1)
				(type default)
			)
			(layer "B.SilkS")
		)
		(fp_line
			(start -23.642828 -0.864616)
			(end -25.635966 -2.776474)
			(stroke
				(width 0.1)
				(type default)
			)
			(layer "B.SilkS")
		)
		(fp_line
			(start -23.557484 -0.840232)
			(end -25.648412 -2.845816)
			(stroke
				(width 0.1)
				(type default)
			)
			(layer "B.SilkS")
		)
		(fp_line
			(start -23.557484 -0.840232)
			(end -25.648412 -2.845816)
			(stroke
				(width 0.1)
				(type default)
			)
			(layer "B.SilkS")
		)
		(fp_line
			(start -23.530052 -2.833878)
			(end -24.401272 -3.669538)
			(stroke
				(width 0.1)
				(type default)
			)
			(layer "B.SilkS")
		)
		(fp_line
			(start -23.530052 -2.833878)
			(end -24.401272 -3.669538)
			(stroke
				(width 0.1)
				(type default)
			)
			(layer "B.SilkS")
		)
		(fp_line
			(start -23.476458 -0.82042)
			(end -25.66035 -2.915412)
			(stroke
				(width 0.1)
				(type default)
			)
			(layer "B.SilkS")
		)
		(fp_line
			(start -23.476458 -0.82042)
			(end -25.66035 -2.915412)
			(stroke
				(width 0.1)
				(type default)
			)
			(layer "B.SilkS")
		)
		(fp_line
			(start -23.46071 -2.825242)
			(end -24.35606 -3.684016)
			(stroke
				(width 0.1)
				(type default)
			)
			(layer "B.SilkS")
		)
		(fp_line
			(start -23.46071 -2.825242)
			(end -24.35606 -3.684016)
			(stroke
				(width 0.1)
				(type default)
			)
			(layer "B.SilkS")
		)
		(fp_line
			(start -23.409402 -0.813562)
			(end -25.672542 -2.984754)
			(stroke
				(width 0.1)
				(type default)
			)
			(layer "B.SilkS")
		)
		(fp_line
			(start -23.409402 -0.813562)
			(end -25.672542 -2.984754)
			(stroke
				(width 0.1)
				(type default)
			)
			(layer "B.SilkS")
		)
		(fp_line
			(start -23.34895 -2.775712)
			(end -24.307546 -3.695192)
			(stroke
				(width 0.1)
				(type default)
			)
			(layer "B.SilkS")
		)
		(fp_line
			(start -23.34895 -2.775712)
			(end -24.307546 -3.695192)
			(stroke
				(width 0.1)
				(type default)
			)
			(layer "B.SilkS")
		)
		(fp_line
			(start -23.344632 -4.214114)
			(end -24.429212 -5.254752)
			(stroke
				(width 0.1)
				(type default)
			)
			(layer "B.SilkS")
		)
		(fp_line
			(start -23.344632 -4.214114)
			(end -24.429212 -5.254752)
			(stroke
				(width 0.1)
				(type default)
			)
			(layer "B.SilkS")
		)
		(fp_line
			(start -23.3426 -0.807466)
			(end -25.68448 -3.054096)
			(stroke
				(width 0.1)
				(type default)
			)
			(layer "B.SilkS")
		)
		(fp_line
			(start -23.3426 -0.807466)
			(end -25.68448 -3.054096)
			(stroke
				(width 0.1)
				(type default)
			)
			(layer "B.SilkS")
		)
		(fp_line
			(start -23.275798 -0.800608)
			(end -25.696926 -3.123184)
			(stroke
				(width 0.1)
				(type default)
			)
			(layer "B.SilkS")
		)
		(fp_line
			(start -23.275798 -0.800608)
			(end -25.696926 -3.123184)
			(stroke
				(width 0.1)
				(type default)
			)
			(layer "B.SilkS")
		)
		(fp_line
			(start -23.249382 -4.180586)
			(end -24.372824 -5.258562)
			(stroke
				(width 0.1)
				(type default)
			)
			(layer "B.SilkS")
		)
		(fp_line
			(start -23.249382 -4.180586)
			(end -24.372824 -5.258562)
			(stroke
				(width 0.1)
				(type default)
			)
			(layer "B.SilkS")
		)
		(fp_line
			(start -23.23084 -2.720086)
			(end -24.256492 -3.704082)
			(stroke
				(width 0.1)
				(type default)
			)
			(layer "B.SilkS")
		)
		(fp_line
			(start -23.23084 -2.720086)
			(end -24.256492 -3.704082)
			(stroke
				(width 0.1)
				(type default)
			)
			(layer "B.SilkS")
		)
		(fp_line
			(start -23.208488 -0.794258)
			(end -25.708864 -3.19278)
			(stroke
				(width 0.1)
				(type default)
			)
			(layer "B.SilkS")
		)
		(fp_line
			(start -23.208488 -0.794258)
			(end -25.708864 -3.19278)
			(stroke
				(width 0.1)
				(type default)
			)
			(layer "B.SilkS")
		)
		(fp_line
			(start -23.149306 -0.79502)
			(end -25.721056 -3.262122)
			(stroke
				(width 0.1)
				(type default)
			)
			(layer "B.SilkS")
		)
		(fp_line
			(start -23.149306 -0.79502)
			(end -25.721056 -3.262122)
			(stroke
				(width 0.1)
				(type default)
			)
			(layer "B.SilkS")
		)
		(fp_line
			(start -23.143718 -4.136898)
			(end -24.31542 -5.260848)
			(stroke
				(width 0.1)
				(type default)
			)
			(layer "B.SilkS")
		)
		(fp_line
			(start -23.143718 -4.136898)
			(end -24.31542 -5.260848)
			(stroke
				(width 0.1)
				(type default)
			)
			(layer "B.SilkS")
		)
		(fp_line
			(start -23.091394 -0.797052)
			(end -25.733502 -3.331464)
			(stroke
				(width 0.1)
				(type default)
			)
			(layer "B.SilkS")
		)
		(fp_line
			(start -23.091394 -0.797052)
			(end -25.733502 -3.331464)
			(stroke
				(width 0.1)
				(type default)
			)
			(layer "B.SilkS")
		)
		(fp_line
			(start -23.029672 -4.085336)
			(end -24.253444 -5.25907)
			(stroke
				(width 0.1)
				(type default)
			)
			(layer "B.SilkS")
		)
		(fp_line
			(start -23.029672 -4.085336)
			(end -24.253444 -5.25907)
			(stroke
				(width 0.1)
				(type default)
			)
			(layer "B.SilkS")
		)
		(fp_line
			(start -22.981158 -0.806704)
			(end -24.158956 -1.93675)
			(stroke
				(width 0.1)
				(type default)
			)
			(layer "B.SilkS")
		)
		(fp_line
			(start -22.981158 -0.806704)
			(end -24.158956 -1.93675)
			(stroke
				(width 0.1)
				(type default)
			)
			(layer "B.SilkS")
		)
		(fp_line
			(start -22.938486 -4.055364)
			(end -24.191468 -5.257546)
			(stroke
				(width 0.1)
				(type default)
			)
			(layer "B.SilkS")
		)
		(fp_line
			(start -22.938486 -4.055364)
			(end -24.191468 -5.257546)
			(stroke
				(width 0.1)
				(type default)
			)
			(layer "B.SilkS")
		)
		(fp_line
			(start -22.927818 -0.813308)
			(end -24.013668 -1.854962)
			(stroke
				(width 0.1)
				(type default)
			)
			(layer "B.SilkS")
		)
		(fp_line
			(start -22.927818 -0.813308)
			(end -24.013668 -1.854962)
			(stroke
				(width 0.1)
				(type default)
			)
			(layer "B.SilkS")
		)
		(fp_line
			(start -22.92223 -4.097782)
			(end -24.129492 -5.255768)
			(stroke
				(width 0.1)
				(type default)
			)
			(layer "B.SilkS")
		)
		(fp_line
			(start -22.92223 -4.097782)
			(end -24.129492 -5.255768)
			(stroke
				(width 0.1)
				(type default)
			)
			(layer "B.SilkS")
		)
		(fp_line
			(start -22.92223 -4.097782)
			(end -22.938486 -4.055364)
			(stroke
				(width 0.1)
				(type default)
			)
			(layer "B.SilkS")
		)
		(fp_line
			(start -22.92223 -4.097782)
			(end -22.938486 -4.055364)
			(stroke
				(width 0.1)
				(type default)
			)
			(layer "B.SilkS")
		)
		(fp_line
			(start -22.906482 -4.139946)
			(end -24.066246 -5.252974)
			(stroke
				(width 0.1)
				(type default)
			)
			(layer "B.SilkS")
		)
		(fp_line
			(start -22.906482 -4.139946)
			(end -24.066246 -5.252974)
			(stroke
				(width 0.1)
				(type default)
			)
			(layer "B.SilkS")
		)
		(fp_line
			(start -22.906482 -4.139946)
			(end -22.92223 -4.097782)
			(stroke
				(width 0.1)
				(type default)
			)
			(layer "B.SilkS")
		)
		(fp_line
			(start -22.906482 -4.139946)
			(end -22.92223 -4.097782)
			(stroke
				(width 0.1)
				(type default)
			)
			(layer "B.SilkS")
		)
		(fp_line
			(start -22.89048 -4.182618)
			(end -24.000206 -5.246878)
			(stroke
				(width 0.1)
				(type default)
			)
			(layer "B.SilkS")
		)
		(fp_line
			(start -22.89048 -4.182618)
			(end -24.000206 -5.246878)
			(stroke
				(width 0.1)
				(type default)
			)
			(layer "B.SilkS")
		)
		(fp_line
			(start -22.89048 -4.182618)
			(end -22.906482 -4.139946)
			(stroke
				(width 0.1)
				(type default)
			)
			(layer "B.SilkS")
		)
		(fp_line
			(start -22.89048 -4.182618)
			(end -22.906482 -4.139946)
			(stroke
				(width 0.1)
				(type default)
			)
			(layer "B.SilkS")
		)
		(fp_line
			(start -22.87651 -0.821436)
			(end -23.916894 -1.819656)
			(stroke
				(width 0.1)
				(type default)
			)
			(layer "B.SilkS")
		)
		(fp_line
			(start -22.87651 -0.821436)
			(end -23.916894 -1.819656)
			(stroke
				(width 0.1)
				(type default)
			)
			(layer "B.SilkS")
		)
		(fp_line
			(start -22.874224 -4.225036)
			(end -23.933658 -5.241036)
			(stroke
				(width 0.1)
				(type default)
			)
			(layer "B.SilkS")
		)
		(fp_line
			(start -22.874224 -4.225036)
			(end -23.933658 -5.241036)
			(stroke
				(width 0.1)
				(type default)
			)
			(layer "B.SilkS")
		)
		(fp_line
			(start -22.874224 -4.225036)
			(end -22.89048 -4.182618)
			(stroke
				(width 0.1)
				(type default)
			)
			(layer "B.SilkS")
		)
		(fp_line
			(start -22.874224 -4.225036)
			(end -22.89048 -4.182618)
			(stroke
				(width 0.1)
				(type default)
			)
			(layer "B.SilkS")
		)
		(fp_line
			(start -22.858476 -4.267454)
			(end -23.86711 -5.235194)
			(stroke
				(width 0.1)
				(type default)
			)
			(layer "B.SilkS")
		)
		(fp_line
			(start -22.858476 -4.267454)
			(end -23.86711 -5.235194)
			(stroke
				(width 0.1)
				(type default)
			)
			(layer "B.SilkS")
		)
		(fp_line
			(start -22.858476 -4.267454)
			(end -22.874224 -4.225036)
			(stroke
				(width 0.1)
				(type default)
			)
			(layer "B.SilkS")
		)
		(fp_line
			(start -22.858476 -4.267454)
			(end -22.874224 -4.225036)
			(stroke
				(width 0.1)
				(type default)
			)
			(layer "B.SilkS")
		)
		(fp_line
			(start -22.842728 -4.309618)
			(end -23.796498 -5.22478)
			(stroke
				(width 0.1)
				(type default)
			)
			(layer "B.SilkS")
		)
		(fp_line
			(start -22.842728 -4.309618)
			(end -23.796498 -5.22478)
			(stroke
				(width 0.1)
				(type default)
			)
			(layer "B.SilkS")
		)
		(fp_line
			(start -22.842728 -4.309618)
			(end -22.858476 -4.267454)
			(stroke
				(width 0.1)
				(type default)
			)
			(layer "B.SilkS")
		)
		(fp_line
			(start -22.842728 -4.309618)
			(end -22.858476 -4.267454)
			(stroke
				(width 0.1)
				(type default)
			)
			(layer "B.SilkS")
		)
		(fp_line
			(start -22.826726 -0.831596)
			(end -23.82012 -1.78435)
			(stroke
				(width 0.1)
				(type default)
			)
			(layer "B.SilkS")
		)
		(fp_line
			(start -22.826726 -0.831596)
			(end -23.82012 -1.78435)
			(stroke
				(width 0.1)
				(type default)
			)
			(layer "B.SilkS")
		)
		(fp_line
			(start -22.826472 -4.352036)
			(end -23.724616 -5.21335)
			(stroke
				(width 0.1)
				(type default)
			)
			(layer "B.SilkS")
		)
		(fp_line
			(start -22.826472 -4.352036)
			(end -23.724616 -5.21335)
			(stroke
				(width 0.1)
				(type default)
			)
			(layer "B.SilkS")
		)
		(fp_line
			(start -22.826472 -4.352036)
			(end -22.842728 -4.309618)
			(stroke
				(width 0.1)
				(type default)
			)
			(layer "B.SilkS")
		)
		(fp_line
			(start -22.826472 -4.352036)
			(end -22.842728 -4.309618)
			(stroke
				(width 0.1)
				(type default)
			)
			(layer "B.SilkS")
		)
		(fp_line
			(start -22.81047 -4.394708)
			(end -23.652226 -5.20192)
			(stroke
				(width 0.1)
				(type default)
			)
			(layer "B.SilkS")
		)
		(fp_line
			(start -22.81047 -4.394708)
			(end -23.652226 -5.20192)
			(stroke
				(width 0.1)
				(type default)
			)
			(layer "B.SilkS")
		)
		(fp_line
			(start -22.81047 -4.394708)
			(end -22.826472 -4.352036)
			(stroke
				(width 0.1)
				(type default)
			)
			(layer "B.SilkS")
		)
		(fp_line
			(start -22.81047 -4.394708)
			(end -22.826472 -4.352036)
			(stroke
				(width 0.1)
				(type default)
			)
			(layer "B.SilkS")
		)
		(fp_line
			(start -22.794722 -4.436872)
			(end -23.573994 -5.184648)
			(stroke
				(width 0.1)
				(type default)
			)
			(layer "B.SilkS")
		)
		(fp_line
			(start -22.794722 -4.436872)
			(end -23.573994 -5.184648)
			(stroke
				(width 0.1)
				(type default)
			)
			(layer "B.SilkS")
		)
		(fp_line
			(start -22.794722 -4.436872)
			(end -22.81047 -4.394708)
			(stroke
				(width 0.1)
				(type default)
			)
			(layer "B.SilkS")
		)
		(fp_line
			(start -22.794722 -4.436872)
			(end -22.81047 -4.394708)
			(stroke
				(width 0.1)
				(type default)
			)
			(layer "B.SilkS")
		)
		(fp_line
			(start -22.778466 -4.47929)
			(end -23.494746 -5.166106)
			(stroke
				(width 0.1)
				(type default)
			)
			(layer "B.SilkS")
		)
		(fp_line
			(start -22.778466 -4.47929)
			(end -23.494746 -5.166106)
			(stroke
				(width 0.1)
				(type default)
			)
			(layer "B.SilkS")
		)
		(fp_line
			(start -22.778466 -4.47929)
			(end -22.794722 -4.436872)
			(stroke
				(width 0.1)
				(type default)
			)
			(layer "B.SilkS")
		)
		(fp_line
			(start -22.778466 -4.47929)
			(end -22.794722 -4.436872)
			(stroke
				(width 0.1)
				(type default)
			)
			(layer "B.SilkS")
		)
		(fp_line
			(start -22.777196 -0.841756)
			(end -23.748238 -1.773682)
			(stroke
				(width 0.1)
				(type default)
			)
			(layer "B.SilkS")
		)
		(fp_line
			(start -22.777196 -0.841756)
			(end -23.748238 -1.773682)
			(stroke
				(width 0.1)
				(type default)
			)
			(layer "B.SilkS")
		)
		(fp_line
			(start -22.762718 -4.521708)
			(end -23.412704 -5.145278)
			(stroke
				(width 0.1)
				(type default)
			)
			(layer "B.SilkS")
		)
		(fp_line
			(start -22.762718 -4.521708)
			(end -23.412704 -5.145278)
			(stroke
				(width 0.1)
				(type default)
			)
			(layer "B.SilkS")
		)
		(fp_line
			(start -22.762718 -4.521708)
			(end -22.778466 -4.47929)
			(stroke
				(width 0.1)
				(type default)
			)
			(layer "B.SilkS")
		)
		(fp_line
			(start -22.762718 -4.521708)
			(end -22.778466 -4.47929)
			(stroke
				(width 0.1)
				(type default)
			)
			(layer "B.SilkS")
		)
		(fp_line
			(start -22.74697 -4.564126)
			(end -23.32355 -5.117592)
			(stroke
				(width 0.1)
				(type default)
			)
			(layer "B.SilkS")
		)
		(fp_line
			(start -22.74697 -4.564126)
			(end -23.32355 -5.117592)
			(stroke
				(width 0.1)
				(type default)
			)
			(layer "B.SilkS")
		)
		(fp_line
			(start -22.74697 -4.564126)
			(end -22.762718 -4.521708)
			(stroke
				(width 0.1)
				(type default)
			)
			(layer "B.SilkS")
		)
		(fp_line
			(start -22.74697 -4.564126)
			(end -22.762718 -4.521708)
			(stroke
				(width 0.1)
				(type default)
			)
			(layer "B.SilkS")
		)
		(fp_line
			(start -22.730714 -4.606544)
			(end -23.234396 -5.089652)
			(stroke
				(width 0.1)
				(type default)
			)
			(layer "B.SilkS")
		)
		(fp_line
			(start -22.730714 -4.606544)
			(end -23.234396 -5.089652)
			(stroke
				(width 0.1)
				(type default)
			)
			(layer "B.SilkS")
		)
		(fp_line
			(start -22.730714 -4.606544)
			(end -22.74697 -4.564126)
			(stroke
				(width 0.1)
				(type default)
			)
			(layer "B.SilkS")
		)
		(fp_line
			(start -22.730714 -4.606544)
			(end -22.74697 -4.564126)
			(stroke
				(width 0.1)
				(type default)
			)
			(layer "B.SilkS")
		)
		(fp_line
			(start -22.729952 -0.85471)
			(end -23.67915 -1.765046)
			(stroke
				(width 0.1)
				(type default)
			)
			(layer "B.SilkS")
		)
		(fp_line
			(start -22.729952 -0.85471)
			(end -23.67915 -1.765046)
			(stroke
				(width 0.1)
				(type default)
			)
			(layer "B.SilkS")
		)
		(fp_line
			(start -22.714712 -4.648962)
			(end -23.13432 -5.051298)
			(stroke
				(width 0.1)
				(type default)
			)
			(layer "B.SilkS")
		)
		(fp_line
			(start -22.714712 -4.648962)
			(end -23.13432 -5.051298)
			(stroke
				(width 0.1)
				(type default)
			)
			(layer "B.SilkS")
		)
		(fp_line
			(start -22.714712 -4.648962)
			(end -22.730714 -4.606544)
			(stroke
				(width 0.1)
				(type default)
			)
			(layer "B.SilkS")
		)
		(fp_line
			(start -22.714712 -4.648962)
			(end -22.730714 -4.606544)
			(stroke
				(width 0.1)
				(type default)
			)
			(layer "B.SilkS")
		)
		(fp_line
			(start -22.698964 -4.69138)
			(end -23.03272 -5.01142)
			(stroke
				(width 0.1)
				(type default)
			)
			(layer "B.SilkS")
		)
		(fp_line
			(start -22.698964 -4.69138)
			(end -23.03272 -5.01142)
			(stroke
				(width 0.1)
				(type default)
			)
			(layer "B.SilkS")
		)
		(fp_line
			(start -22.698964 -4.69138)
			(end -22.714712 -4.648962)
			(stroke
				(width 0.1)
				(type default)
			)
			(layer "B.SilkS")
		)
		(fp_line
			(start -22.698964 -4.69138)
			(end -22.714712 -4.648962)
			(stroke
				(width 0.1)
				(type default)
			)
			(layer "B.SilkS")
		)
		(fp_line
			(start -22.684232 -0.868172)
			(end -23.610316 -1.756664)
			(stroke
				(width 0.1)
				(type default)
			)
			(layer "B.SilkS")
		)
		(fp_line
			(start -22.684232 -0.868172)
			(end -23.610316 -1.756664)
			(stroke
				(width 0.1)
				(type default)
			)
			(layer "B.SilkS")
		)
		(fp_line
			(start -22.682708 -4.733798)
			(end -22.919436 -4.960874)
			(stroke
				(width 0.1)
				(type default)
			)
			(layer "B.SilkS")
		)
		(fp_line
			(start -22.682708 -4.733798)
			(end -22.919436 -4.960874)
			(stroke
				(width 0.1)
				(type default)
			)
			(layer "B.SilkS")
		)
		(fp_line
			(start -22.682708 -4.733798)
			(end -22.698964 -4.69138)
			(stroke
				(width 0.1)
				(type default)
			)
			(layer "B.SilkS")
		)
		(fp_line
			(start -22.682708 -4.733798)
			(end -22.698964 -4.69138)
			(stroke
				(width 0.1)
				(type default)
			)
			(layer "B.SilkS")
		)
		(fp_line
			(start -22.66696 -4.776216)
			(end -22.802088 -4.905756)
			(stroke
				(width 0.1)
				(type default)
			)
			(layer "B.SilkS")
		)
		(fp_line
			(start -22.66696 -4.776216)
			(end -22.802088 -4.905756)
			(stroke
				(width 0.1)
				(type default)
			)
			(layer "B.SilkS")
		)
		(fp_line
			(start -22.66696 -4.776216)
			(end -22.682708 -4.733798)
			(stroke
				(width 0.1)
				(type default)
			)
			(layer "B.SilkS")
		)
		(fp_line
			(start -22.66696 -4.776216)
			(end -22.682708 -4.733798)
			(stroke
				(width 0.1)
				(type default)
			)
			(layer "B.SilkS")
		)
		(fp_line
			(start -22.651212 -4.81838)
			(end -22.676358 -4.842764)
			(stroke
				(width 0.1)
				(type default)
			)
			(layer "B.SilkS")
		)
		(fp_line
			(start -22.651212 -4.81838)
			(end -22.676358 -4.842764)
			(stroke
				(width 0.1)
				(type default)
			)
			(layer "B.SilkS")
		)
		(fp_line
			(start -22.651212 -4.81838)
			(end -22.66696 -4.776216)
			(stroke
				(width 0.1)
				(type default)
			)
			(layer "B.SilkS")
		)
		(fp_line
			(start -22.651212 -4.81838)
			(end -22.66696 -4.776216)
			(stroke
				(width 0.1)
				(type default)
			)
			(layer "B.SilkS")
		)
		(fp_line
			(start -22.638258 -0.881888)
			(end -23.54199 -1.74879)
			(stroke
				(width 0.1)
				(type default)
			)
			(layer "B.SilkS")
		)
		(fp_line
			(start -22.638258 -0.881888)
			(end -23.54199 -1.74879)
			(stroke
				(width 0.1)
				(type default)
			)
			(layer "B.SilkS")
		)
		(fp_line
			(start -22.595332 -0.898398)
			(end -23.48611 -1.752854)
			(stroke
				(width 0.1)
				(type default)
			)
			(layer "B.SilkS")
		)
		(fp_line
			(start -22.595332 -0.898398)
			(end -23.48611 -1.752854)
			(stroke
				(width 0.1)
				(type default)
			)
			(layer "B.SilkS")
		)
		(fp_line
			(start -22.552914 -0.91567)
			(end -23.430484 -1.757172)
			(stroke
				(width 0.1)
				(type default)
			)
			(layer "B.SilkS")
		)
		(fp_line
			(start -22.552914 -0.91567)
			(end -23.430484 -1.757172)
			(stroke
				(width 0.1)
				(type default)
			)
			(layer "B.SilkS")
		)
		(fp_line
			(start -22.510496 -0.932688)
			(end -23.375366 -1.761998)
			(stroke
				(width 0.1)
				(type default)
			)
			(layer "B.SilkS")
		)
		(fp_line
			(start -22.510496 -0.932688)
			(end -23.375366 -1.761998)
			(stroke
				(width 0.1)
				(type default)
			)
			(layer "B.SilkS")
		)
		(fp_line
			(start -22.470872 -0.952246)
			(end -23.328122 -1.774444)
			(stroke
				(width 0.1)
				(type default)
			)
			(layer "B.SilkS")
		)
		(fp_line
			(start -22.470872 -0.952246)
			(end -23.328122 -1.774444)
			(stroke
				(width 0.1)
				(type default)
			)
			(layer "B.SilkS")
		)
		(fp_line
			(start -22.43201 -0.97282)
			(end -23.280878 -1.786636)
			(stroke
				(width 0.1)
				(type default)
			)
			(layer "B.SilkS")
		)
		(fp_line
			(start -22.43201 -0.97282)
			(end -23.280878 -1.786636)
			(stroke
				(width 0.1)
				(type default)
			)
			(layer "B.SilkS")
		)
		(fp_line
			(start -22.393402 -0.993394)
			(end -23.235666 -1.801622)
			(stroke
				(width 0.1)
				(type default)
			)
			(layer "B.SilkS")
		)
		(fp_line
			(start -22.393402 -0.993394)
			(end -23.235666 -1.801622)
			(stroke
				(width 0.1)
				(type default)
			)
			(layer "B.SilkS")
		)
		(fp_line
			(start -22.356572 -1.015746)
			(end -23.197058 -1.821942)
			(stroke
				(width 0.1)
				(type default)
			)
			(layer "B.SilkS")
		)
		(fp_line
			(start -22.356572 -1.015746)
			(end -23.197058 -1.821942)
			(stroke
				(width 0.1)
				(type default)
			)
			(layer "B.SilkS")
		)
		(fp_line
			(start -22.321774 -1.039622)
			(end -23.158196 -1.842262)
			(stroke
				(width 0.1)
				(type default)
			)
			(layer "B.SilkS")
		)
		(fp_line
			(start -22.321774 -1.039622)
			(end -23.158196 -1.842262)
			(stroke
				(width 0.1)
				(type default)
			)
			(layer "B.SilkS")
		)
		(fp_line
			(start -22.286214 -1.063752)
			(end -23.124414 -1.867916)
			(stroke
				(width 0.1)
				(type default)
			)
			(layer "B.SilkS")
		)
		(fp_line
			(start -22.286214 -1.063752)
			(end -23.124414 -1.867916)
			(stroke
				(width 0.1)
				(type default)
			)
			(layer "B.SilkS")
		)
		(fp_line
			(start -22.252432 -1.089152)
			(end -23.094188 -1.896364)
			(stroke
				(width 0.1)
				(type default)
			)
			(layer "B.SilkS")
		)
		(fp_line
			(start -22.252432 -1.089152)
			(end -23.094188 -1.896364)
			(stroke
				(width 0.1)
				(type default)
			)
			(layer "B.SilkS")
		)
		(fp_line
			(start -22.22119 -1.11633)
			(end -23.06447 -1.925828)
			(stroke
				(width 0.1)
				(type default)
			)
			(layer "B.SilkS")
		)
		(fp_line
			(start -22.22119 -1.11633)
			(end -23.06447 -1.925828)
			(stroke
				(width 0.1)
				(type default)
			)
			(layer "B.SilkS")
		)
		(fp_line
			(start -22.18944 -1.143762)
			(end -23.042372 -1.96215)
			(stroke
				(width 0.1)
				(type default)
			)
			(layer "B.SilkS")
		)
		(fp_line
			(start -22.18944 -1.143762)
			(end -23.042372 -1.96215)
			(stroke
				(width 0.1)
				(type default)
			)
			(layer "B.SilkS")
		)
		(fp_line
			(start -22.158452 -1.171956)
			(end -23.020782 -1.99898)
			(stroke
				(width 0.1)
				(type default)
			)
			(layer "B.SilkS")
		)
		(fp_line
			(start -22.158452 -1.171956)
			(end -23.020782 -1.99898)
			(stroke
				(width 0.1)
				(type default)
			)
			(layer "B.SilkS")
		)
		(fp_line
			(start -22.130512 -1.202944)
			(end -23.005542 -2.042414)
			(stroke
				(width 0.1)
				(type default)
			)
			(layer "B.SilkS")
		)
		(fp_line
			(start -22.130512 -1.202944)
			(end -23.005542 -2.042414)
			(stroke
				(width 0.1)
				(type default)
			)
			(layer "B.SilkS")
		)
		(fp_line
			(start -22.10308 -1.233932)
			(end -22.992588 -2.087372)
			(stroke
				(width 0.1)
				(type default)
			)
			(layer "B.SilkS")
		)
		(fp_line
			(start -22.10308 -1.233932)
			(end -22.992588 -2.087372)
			(stroke
				(width 0.1)
				(type default)
			)
			(layer "B.SilkS")
		)
		(fp_line
			(start -22.077934 -2.883408)
			(end -22.662896 -3.444748)
			(stroke
				(width 0.1)
				(type default)
			)
			(layer "B.SilkS")
		)
		(fp_line
			(start -22.077934 -2.883408)
			(end -22.662896 -3.444748)
			(stroke
				(width 0.1)
				(type default)
			)
			(layer "B.SilkS")
		)
		(fp_line
			(start -22.07514 -1.265174)
			(end -22.985222 -2.137918)
			(stroke
				(width 0.1)
				(type default)
			)
			(layer "B.SilkS")
		)
		(fp_line
			(start -22.07514 -1.265174)
			(end -22.985222 -2.137918)
			(stroke
				(width 0.1)
				(type default)
			)
			(layer "B.SilkS")
		)
		(fp_line
			(start -22.05101 -1.299464)
			(end -22.981158 -2.19202)
			(stroke
				(width 0.1)
				(type default)
			)
			(layer "B.SilkS")
		)
		(fp_line
			(start -22.05101 -1.299464)
			(end -22.981158 -2.19202)
			(stroke
				(width 0.1)
				(type default)
			)
			(layer "B.SilkS")
		)
		(fp_line
			(start -22.02688 -1.334262)
			(end -22.984206 -2.252726)
			(stroke
				(width 0.1)
				(type default)
			)
			(layer "B.SilkS")
		)
		(fp_line
			(start -22.02688 -1.334262)
			(end -22.984206 -2.252726)
			(stroke
				(width 0.1)
				(type default)
			)
			(layer "B.SilkS")
		)
		(fp_line
			(start -22.017228 -2.767838)
			(end -22.802342 -3.521202)
			(stroke
				(width 0.1)
				(type default)
			)
			(layer "B.SilkS")
		)
		(fp_line
			(start -22.017228 -2.767838)
			(end -22.802342 -3.521202)
			(stroke
				(width 0.1)
				(type default)
			)
			(layer "B.SilkS")
		)
		(fp_line
			(start -22.003004 -1.36906)
			(end -22.99081 -2.31648)
			(stroke
				(width 0.1)
				(type default)
			)
			(layer "B.SilkS")
		)
		(fp_line
			(start -22.003004 -1.36906)
			(end -22.99081 -2.31648)
			(stroke
				(width 0.1)
				(type default)
			)
			(layer "B.SilkS")
		)
		(fp_line
			(start -21.981922 -1.406652)
			(end -23.020782 -2.403094)
			(stroke
				(width 0.1)
				(type default)
			)
			(layer "B.SilkS")
		)
		(fp_line
			(start -21.981922 -1.406652)
			(end -23.020782 -2.403094)
			(stroke
				(width 0.1)
				(type default)
			)
			(layer "B.SilkS")
		)
		(fp_line
			(start -21.962364 -1.445514)
			(end -23.052786 -2.491486)
			(stroke
				(width 0.1)
				(type default)
			)
			(layer "B.SilkS")
		)
		(fp_line
			(start -21.962364 -1.445514)
			(end -23.052786 -2.491486)
			(stroke
				(width 0.1)
				(type default)
			)
			(layer "B.SilkS")
		)
		(fp_line
			(start -21.957538 -2.652776)
			(end -22.909784 -3.56616)
			(stroke
				(width 0.1)
				(type default)
			)
			(layer "B.SilkS")
		)
		(fp_line
			(start -21.957538 -2.652776)
			(end -22.909784 -3.56616)
			(stroke
				(width 0.1)
				(type default)
			)
			(layer "B.SilkS")
		)
		(fp_line
			(start -21.942806 -1.484376)
			(end -23.220934 -2.710688)
			(stroke
				(width 0.1)
				(type default)
			)
			(layer "B.SilkS")
		)
		(fp_line
			(start -21.942806 -1.484376)
			(end -23.220934 -2.710688)
			(stroke
				(width 0.1)
				(type default)
			)
			(layer "B.SilkS")
		)
		(fp_line
			(start -21.93544 -2.573782)
			(end -23.00478 -3.599942)
			(stroke
				(width 0.1)
				(type default)
			)
			(layer "B.SilkS")
		)
		(fp_line
			(start -21.93544 -2.573782)
			(end -23.00478 -3.599942)
			(stroke
				(width 0.1)
				(type default)
			)
			(layer "B.SilkS")
		)
		(fp_line
			(start -21.924772 -1.525016)
			(end -24.205946 -3.712972)
			(stroke
				(width 0.1)
				(type default)
			)
			(layer "B.SilkS")
		)
		(fp_line
			(start -21.924772 -1.525016)
			(end -24.205946 -3.712972)
			(stroke
				(width 0.1)
				(type default)
			)
			(layer "B.SilkS")
		)
		(fp_line
			(start -21.913088 -2.494788)
			(end -23.10003 -3.63347)
			(stroke
				(width 0.1)
				(type default)
			)
			(layer "B.SilkS")
		)
		(fp_line
			(start -21.913088 -2.494788)
			(end -23.10003 -3.63347)
			(stroke
				(width 0.1)
				(type default)
			)
			(layer "B.SilkS")
		)
		(fp_line
			(start -21.909786 -1.568196)
			(end -24.154892 -3.721862)
			(stroke
				(width 0.1)
				(type default)
			)
			(layer "B.SilkS")
		)
		(fp_line
			(start -21.909786 -1.568196)
			(end -24.154892 -3.721862)
			(stroke
				(width 0.1)
				(type default)
			)
			(layer "B.SilkS")
		)
		(fp_line
			(start -21.894546 -1.611376)
			(end -24.101806 -3.728974)
			(stroke
				(width 0.1)
				(type default)
			)
			(layer "B.SilkS")
		)
		(fp_line
			(start -21.894546 -1.611376)
			(end -24.101806 -3.728974)
			(stroke
				(width 0.1)
				(type default)
			)
			(layer "B.SilkS")
		)
		(fp_line
			(start -21.89099 -2.416048)
			(end -23.187152 -3.659124)
			(stroke
				(width 0.1)
				(type default)
			)
			(layer "B.SilkS")
		)
		(fp_line
			(start -21.89099 -2.416048)
			(end -23.187152 -3.659124)
			(stroke
				(width 0.1)
				(type default)
			)
			(layer "B.SilkS")
		)
		(fp_line
			(start -21.88083 -1.655826)
			(end -24.04491 -3.731768)
			(stroke
				(width 0.1)
				(type default)
			)
			(layer "B.SilkS")
		)
		(fp_line
			(start -21.88083 -1.655826)
			(end -24.04491 -3.731768)
			(stroke
				(width 0.1)
				(type default)
			)
			(layer "B.SilkS")
		)
		(fp_line
			(start -21.870416 -1.703578)
			(end -23.98776 -3.734816)
			(stroke
				(width 0.1)
				(type default)
			)
			(layer "B.SilkS")
		)
		(fp_line
			(start -21.870416 -1.703578)
			(end -23.98776 -3.734816)
			(stroke
				(width 0.1)
				(type default)
			)
			(layer "B.SilkS")
		)
		(fp_line
			(start -21.869146 -2.337308)
			(end -23.26259 -3.673856)
			(stroke
				(width 0.1)
				(type default)
			)
			(layer "B.SilkS")
		)
		(fp_line
			(start -21.869146 -2.337308)
			(end -23.26259 -3.673856)
			(stroke
				(width 0.1)
				(type default)
			)
			(layer "B.SilkS")
		)
		(fp_line
			(start -21.86051 -1.75133)
			(end -23.930864 -3.737864)
			(stroke
				(width 0.1)
				(type default)
			)
			(layer "B.SilkS")
		)
		(fp_line
			(start -21.86051 -1.75133)
			(end -23.930864 -3.737864)
			(stroke
				(width 0.1)
				(type default)
			)
			(layer "B.SilkS")
		)
		(fp_line
			(start -21.85797 -2.268728)
			(end -23.338282 -3.688842)
			(stroke
				(width 0.1)
				(type default)
			)
			(layer "B.SilkS")
		)
		(fp_line
			(start -21.85797 -2.268728)
			(end -23.338282 -3.688842)
			(stroke
				(width 0.1)
				(type default)
			)
			(layer "B.SilkS")
		)
		(fp_line
			(start -21.850858 -1.799844)
			(end -23.874222 -3.740912)
			(stroke
				(width 0.1)
				(type default)
			)
			(layer "B.SilkS")
		)
		(fp_line
			(start -21.850858 -1.799844)
			(end -23.874222 -3.740912)
			(stroke
				(width 0.1)
				(type default)
			)
			(layer "B.SilkS")
		)
		(fp_line
			(start -21.849334 -2.202942)
			(end -23.414228 -3.703828)
			(stroke
				(width 0.1)
				(type default)
			)
			(layer "B.SilkS")
		)
		(fp_line
			(start -21.849334 -2.202942)
			(end -23.414228 -3.703828)
			(stroke
				(width 0.1)
				(type default)
			)
			(layer "B.SilkS")
		)
		(fp_line
			(start -21.846032 -1.853184)
			(end -23.811992 -3.739388)
			(stroke
				(width 0.1)
				(type default)
			)
			(layer "B.SilkS")
		)
		(fp_line
			(start -21.846032 -1.853184)
			(end -23.811992 -3.739388)
			(stroke
				(width 0.1)
				(type default)
			)
			(layer "B.SilkS")
		)
		(fp_line
			(start -21.841206 -2.137156)
			(end -23.489666 -3.71856)
			(stroke
				(width 0.1)
				(type default)
			)
			(layer "B.SilkS")
		)
		(fp_line
			(start -21.841206 -2.137156)
			(end -23.489666 -3.71856)
			(stroke
				(width 0.1)
				(type default)
			)
			(layer "B.SilkS")
		)
		(fp_line
			(start -21.841206 -1.90627)
			(end -23.747984 -3.735324)
			(stroke
				(width 0.1)
				(type default)
			)
			(layer "B.SilkS")
		)
		(fp_line
			(start -21.841206 -1.90627)
			(end -23.747984 -3.735324)
			(stroke
				(width 0.1)
				(type default)
			)
			(layer "B.SilkS")
		)
		(fp_line
			(start -21.839428 -2.07772)
			(end -23.55469 -3.723386)
			(stroke
				(width 0.1)
				(type default)
			)
			(layer "B.SilkS")
		)
		(fp_line
			(start -21.839428 -2.07772)
			(end -23.55469 -3.723386)
			(stroke
				(width 0.1)
				(type default)
			)
			(layer "B.SilkS")
		)
		(fp_line
			(start -21.838158 -2.018792)
			(end -23.619206 -3.727196)
			(stroke
				(width 0.1)
				(type default)
			)
			(layer "B.SilkS")
		)
		(fp_line
			(start -21.838158 -2.018792)
			(end -23.619206 -3.727196)
			(stroke
				(width 0.1)
				(type default)
			)
			(layer "B.SilkS")
		)
		(fp_line
			(start -21.798534 -5.171694)
			(end -21.755608 -5.171694)
			(stroke
				(width 0.1)
				(type default)
			)
			(layer "B.SilkS")
		)
		(fp_line
			(start -21.798534 -5.171694)
			(end -21.755608 -5.171694)
			(stroke
				(width 0.1)
				(type default)
			)
			(layer "B.SilkS")
		)
		(fp_line
			(start -21.794978 -5.151374)
			(end -21.798534 -5.171694)
			(stroke
				(width 0.1)
				(type default)
			)
			(layer "B.SilkS")
		)
		(fp_line
			(start -21.794978 -5.151374)
			(end -21.798534 -5.171694)
			(stroke
				(width 0.1)
				(type default)
			)
			(layer "B.SilkS")
		)
		(fp_line
			(start -21.794978 -5.151374)
			(end -20.70862 -4.109466)
			(stroke
				(width 0.1)
				(type default)
			)
			(layer "B.SilkS")
		)
		(fp_line
			(start -21.794978 -5.151374)
			(end -20.70862 -4.109466)
			(stroke
				(width 0.1)
				(type default)
			)
			(layer "B.SilkS")
		)
		(fp_line
			(start -21.78304 -5.082032)
			(end -21.794978 -5.151374)
			(stroke
				(width 0.1)
				(type default)
			)
			(layer "B.SilkS")
		)
		(fp_line
			(start -21.78304 -5.082032)
			(end -21.794978 -5.151374)
			(stroke
				(width 0.1)
				(type default)
			)
			(layer "B.SilkS")
		)
		(fp_line
			(start -21.78304 -5.082032)
			(end -20.768564 -4.109466)
			(stroke
				(width 0.1)
				(type default)
			)
			(layer "B.SilkS")
		)
		(fp_line
			(start -21.78304 -5.082032)
			(end -20.768564 -4.109466)
			(stroke
				(width 0.1)
				(type default)
			)
			(layer "B.SilkS")
		)
		(fp_line
			(start -21.770594 -5.012944)
			(end -21.78304 -5.082032)
			(stroke
				(width 0.1)
				(type default)
			)
			(layer "B.SilkS")
		)
		(fp_line
			(start -21.770594 -5.012944)
			(end -21.78304 -5.082032)
			(stroke
				(width 0.1)
				(type default)
			)
			(layer "B.SilkS")
		)
		(fp_line
			(start -21.770594 -5.012944)
			(end -20.829016 -4.109466)
			(stroke
				(width 0.1)
				(type default)
			)
			(layer "B.SilkS")
		)
		(fp_line
			(start -21.770594 -5.012944)
			(end -20.829016 -4.109466)
			(stroke
				(width 0.1)
				(type default)
			)
			(layer "B.SilkS")
		)
		(fp_line
			(start -21.758402 -4.943348)
			(end -21.770594 -5.012944)
			(stroke
				(width 0.1)
				(type default)
			)
			(layer "B.SilkS")
		)
		(fp_line
			(start -21.758402 -4.943348)
			(end -21.770594 -5.012944)
			(stroke
				(width 0.1)
				(type default)
			)
			(layer "B.SilkS")
		)
		(fp_line
			(start -21.758402 -4.943348)
			(end -20.889214 -4.109466)
			(stroke
				(width 0.1)
				(type default)
			)
			(layer "B.SilkS")
		)
		(fp_line
			(start -21.758402 -4.943348)
			(end -20.889214 -4.109466)
			(stroke
				(width 0.1)
				(type default)
			)
			(layer "B.SilkS")
		)
		(fp_line
			(start -21.755608 -5.171694)
			(end -21.69541 -5.171694)
			(stroke
				(width 0.1)
				(type default)
			)
			(layer "B.SilkS")
		)
		(fp_line
			(start -21.755608 -5.171694)
			(end -21.69541 -5.171694)
			(stroke
				(width 0.1)
				(type default)
			)
			(layer "B.SilkS")
		)
		(fp_line
			(start -21.755608 -5.171694)
			(end -20.648422 -4.109466)
			(stroke
				(width 0.1)
				(type default)
			)
			(layer "B.SilkS")
		)
		(fp_line
			(start -21.755608 -5.171694)
			(end -20.648422 -4.109466)
			(stroke
				(width 0.1)
				(type default)
			)
			(layer "B.SilkS")
		)
		(fp_line
			(start -21.746464 -4.874006)
			(end -21.758402 -4.943348)
			(stroke
				(width 0.1)
				(type default)
			)
			(layer "B.SilkS")
		)
		(fp_line
			(start -21.746464 -4.874006)
			(end -21.758402 -4.943348)
			(stroke
				(width 0.1)
				(type default)
			)
			(layer "B.SilkS")
		)
		(fp_line
			(start -21.746464 -4.874006)
			(end -20.949666 -4.109466)
			(stroke
				(width 0.1)
				(type default)
			)
			(layer "B.SilkS")
		)
		(fp_line
			(start -21.746464 -4.874006)
			(end -20.949666 -4.109466)
			(stroke
				(width 0.1)
				(type default)
			)
			(layer "B.SilkS")
		)
		(fp_line
			(start -21.734018 -4.804664)
			(end -21.746464 -4.874006)
			(stroke
				(width 0.1)
				(type default)
			)
			(layer "B.SilkS")
		)
		(fp_line
			(start -21.734018 -4.804664)
			(end -21.746464 -4.874006)
			(stroke
				(width 0.1)
				(type default)
			)
			(layer "B.SilkS")
		)
		(fp_line
			(start -21.734018 -4.804664)
			(end -21.00961 -4.109466)
			(stroke
				(width 0.1)
				(type default)
			)
			(layer "B.SilkS")
		)
		(fp_line
			(start -21.734018 -4.804664)
			(end -21.00961 -4.109466)
			(stroke
				(width 0.1)
				(type default)
			)
			(layer "B.SilkS")
		)
		(fp_line
			(start -21.721826 -4.735576)
			(end -21.734018 -4.804664)
			(stroke
				(width 0.1)
				(type default)
			)
			(layer "B.SilkS")
		)
		(fp_line
			(start -21.721826 -4.735576)
			(end -21.734018 -4.804664)
			(stroke
				(width 0.1)
				(type default)
			)
			(layer "B.SilkS")
		)
		(fp_line
			(start -21.721826 -4.735576)
			(end -21.069554 -4.109466)
			(stroke
				(width 0.1)
				(type default)
			)
			(layer "B.SilkS")
		)
		(fp_line
			(start -21.721826 -4.735576)
			(end -21.069554 -4.109466)
			(stroke
				(width 0.1)
				(type default)
			)
			(layer "B.SilkS")
		)
		(fp_line
			(start -21.709888 -4.66598)
			(end -21.721826 -4.735576)
			(stroke
				(width 0.1)
				(type default)
			)
			(layer "B.SilkS")
		)
		(fp_line
			(start -21.709888 -4.66598)
			(end -21.721826 -4.735576)
			(stroke
				(width 0.1)
				(type default)
			)
			(layer "B.SilkS")
		)
		(fp_line
			(start -21.709888 -4.66598)
			(end -21.129752 -4.109466)
			(stroke
				(width 0.1)
				(type default)
			)
			(layer "B.SilkS")
		)
		(fp_line
			(start -21.709888 -4.66598)
			(end -21.129752 -4.109466)
			(stroke
				(width 0.1)
				(type default)
			)
			(layer "B.SilkS")
		)
		(fp_line
			(start -21.69795 -4.596638)
			(end -21.709888 -4.66598)
			(stroke
				(width 0.1)
				(type default)
			)
			(layer "B.SilkS")
		)
		(fp_line
			(start -21.69795 -4.596638)
			(end -21.709888 -4.66598)
			(stroke
				(width 0.1)
				(type default)
			)
			(layer "B.SilkS")
		)
		(fp_line
			(start -21.69795 -4.596638)
			(end -21.18995 -4.109466)
			(stroke
				(width 0.1)
				(type default)
			)
			(layer "B.SilkS")
		)
		(fp_line
			(start -21.69795 -4.596638)
			(end -21.18995 -4.109466)
			(stroke
				(width 0.1)
				(type default)
			)
			(layer "B.SilkS")
		)
		(fp_line
			(start -21.69541 -5.171694)
			(end -21.635466 -5.171694)
			(stroke
				(width 0.1)
				(type default)
			)
			(layer "B.SilkS")
		)
		(fp_line
			(start -21.69541 -5.171694)
			(end -21.635466 -5.171694)
			(stroke
				(width 0.1)
				(type default)
			)
			(layer "B.SilkS")
		)
		(fp_line
			(start -21.69541 -5.171694)
			(end -20.588224 -4.109466)
			(stroke
				(width 0.1)
				(type default)
			)
			(layer "B.SilkS")
		)
		(fp_line
			(start -21.69541 -5.171694)
			(end -20.588224 -4.109466)
			(stroke
				(width 0.1)
				(type default)
			)
			(layer "B.SilkS")
		)
		(fp_line
			(start -21.685504 -4.527296)
			(end -21.69795 -4.596638)
			(stroke
				(width 0.1)
				(type default)
			)
			(layer "B.SilkS")
		)
		(fp_line
			(start -21.685504 -4.527296)
			(end -21.69795 -4.596638)
			(stroke
				(width 0.1)
				(type default)
			)
			(layer "B.SilkS")
		)
		(fp_line
			(start -21.685504 -4.527296)
			(end -21.250402 -4.109466)
			(stroke
				(width 0.1)
				(type default)
			)
			(layer "B.SilkS")
		)
		(fp_line
			(start -21.685504 -4.527296)
			(end -21.250402 -4.109466)
			(stroke
				(width 0.1)
				(type default)
			)
			(layer "B.SilkS")
		)
		(fp_line
			(start -21.673312 -4.457954)
			(end -21.685504 -4.527296)
			(stroke
				(width 0.1)
				(type default)
			)
			(layer "B.SilkS")
		)
		(fp_line
			(start -21.673312 -4.457954)
			(end -21.685504 -4.527296)
			(stroke
				(width 0.1)
				(type default)
			)
			(layer "B.SilkS")
		)
		(fp_line
			(start -21.673312 -4.457954)
			(end -21.310346 -4.109466)
			(stroke
				(width 0.1)
				(type default)
			)
			(layer "B.SilkS")
		)
		(fp_line
			(start -21.673312 -4.457954)
			(end -21.310346 -4.109466)
			(stroke
				(width 0.1)
				(type default)
			)
			(layer "B.SilkS")
		)
		(fp_line
			(start -21.661374 -4.388358)
			(end -21.673312 -4.457954)
			(stroke
				(width 0.1)
				(type default)
			)
			(layer "B.SilkS")
		)
		(fp_line
			(start -21.661374 -4.388358)
			(end -21.673312 -4.457954)
			(stroke
				(width 0.1)
				(type default)
			)
			(layer "B.SilkS")
		)
		(fp_line
			(start -21.661374 -4.388358)
			(end -21.370544 -4.109466)
			(stroke
				(width 0.1)
				(type default)
			)
			(layer "B.SilkS")
		)
		(fp_line
			(start -21.661374 -4.388358)
			(end -21.370544 -4.109466)
			(stroke
				(width 0.1)
				(type default)
			)
			(layer "B.SilkS")
		)
		(fp_line
			(start -21.649182 -4.319016)
			(end -21.661374 -4.388358)
			(stroke
				(width 0.1)
				(type default)
			)
			(layer "B.SilkS")
		)
		(fp_line
			(start -21.649182 -4.319016)
			(end -21.661374 -4.388358)
			(stroke
				(width 0.1)
				(type default)
			)
			(layer "B.SilkS")
		)
		(fp_line
			(start -21.649182 -4.319016)
			(end -21.430742 -4.109466)
			(stroke
				(width 0.1)
				(type default)
			)
			(layer "B.SilkS")
		)
		(fp_line
			(start -21.649182 -4.319016)
			(end -21.430742 -4.109466)
			(stroke
				(width 0.1)
				(type default)
			)
			(layer "B.SilkS")
		)
		(fp_line
			(start -21.636736 -4.249674)
			(end -21.649182 -4.319016)
			(stroke
				(width 0.1)
				(type default)
			)
			(layer "B.SilkS")
		)
		(fp_line
			(start -21.636736 -4.249674)
			(end -21.649182 -4.319016)
			(stroke
				(width 0.1)
				(type default)
			)
			(layer "B.SilkS")
		)
		(fp_line
			(start -21.636736 -4.249674)
			(end -21.490686 -4.109466)
			(stroke
				(width 0.1)
				(type default)
			)
			(layer "B.SilkS")
		)
		(fp_line
			(start -21.636736 -4.249674)
			(end -21.490686 -4.109466)
			(stroke
				(width 0.1)
				(type default)
			)
			(layer "B.SilkS")
		)
		(fp_line
			(start -21.635466 -5.171694)
			(end -21.575522 -5.171694)
			(stroke
				(width 0.1)
				(type default)
			)
			(layer "B.SilkS")
		)
		(fp_line
			(start -21.635466 -5.171694)
			(end -21.575522 -5.171694)
			(stroke
				(width 0.1)
				(type default)
			)
			(layer "B.SilkS")
		)
		(fp_line
			(start -21.624798 -4.180586)
			(end -21.636736 -4.249674)
			(stroke
				(width 0.1)
				(type default)
			)
			(layer "B.SilkS")
		)
		(fp_line
			(start -21.624798 -4.180586)
			(end -21.636736 -4.249674)
			(stroke
				(width 0.1)
				(type default)
			)
			(layer "B.SilkS")
		)
		(fp_line
			(start -21.624798 -4.180586)
			(end -21.55063 -4.109466)
			(stroke
				(width 0.1)
				(type default)
			)
			(layer "B.SilkS")
		)
		(fp_line
			(start -21.624798 -4.180586)
			(end -21.55063 -4.109466)
			(stroke
				(width 0.1)
				(type default)
			)
			(layer "B.SilkS")
		)
		(fp_line
			(start -21.61286 -4.11099)
			(end -21.624798 -4.180586)
			(stroke
				(width 0.1)
				(type default)
			)
			(layer "B.SilkS")
		)
		(fp_line
			(start -21.61286 -4.11099)
			(end -21.624798 -4.180586)
			(stroke
				(width 0.1)
				(type default)
			)
			(layer "B.SilkS")
		)
		(fp_line
			(start -21.61286 -4.11099)
			(end -21.612352 -4.109466)
			(stroke
				(width 0.1)
				(type default)
			)
			(layer "B.SilkS")
		)
		(fp_line
			(start -21.61286 -4.11099)
			(end -21.612352 -4.109466)
			(stroke
				(width 0.1)
				(type default)
			)
			(layer "B.SilkS")
		)
		(fp_line
			(start -21.61286 -4.11099)
			(end -21.611082 -4.109466)
			(stroke
				(width 0.1)
				(type default)
			)
			(layer "B.SilkS")
		)
		(fp_line
			(start -21.61286 -4.11099)
			(end -21.611082 -4.109466)
			(stroke
				(width 0.1)
				(type default)
			)
			(layer "B.SilkS")
		)
		(fp_line
			(start -21.612352 -4.109466)
			(end -21.611082 -4.109466)
			(stroke
				(width 0.1)
				(type default)
			)
			(layer "B.SilkS")
		)
		(fp_line
			(start -21.612352 -4.109466)
			(end -21.611082 -4.109466)
			(stroke
				(width 0.1)
				(type default)
			)
			(layer "B.SilkS")
		)
		(fp_line
			(start -21.575522 -5.171694)
			(end -21.515324 -5.171694)
			(stroke
				(width 0.1)
				(type default)
			)
			(layer "B.SilkS")
		)
		(fp_line
			(start -21.575522 -5.171694)
			(end -21.515324 -5.171694)
			(stroke
				(width 0.1)
				(type default)
			)
			(layer "B.SilkS")
		)
		(fp_line
			(start -21.575522 -5.171694)
			(end -19.250406 -2.941574)
			(stroke
				(width 0.1)
				(type default)
			)
			(layer "B.SilkS")
		)
		(fp_line
			(start -21.575522 -5.171694)
			(end -19.250406 -2.941574)
			(stroke
				(width 0.1)
				(type default)
			)
			(layer "B.SilkS")
		)
		(fp_line
			(start -21.55063 -4.109466)
			(end -21.611082 -4.109466)
			(stroke
				(width 0.1)
				(type default)
			)
			(layer "B.SilkS")
		)
		(fp_line
			(start -21.55063 -4.109466)
			(end -21.611082 -4.109466)
			(stroke
				(width 0.1)
				(type default)
			)
			(layer "B.SilkS")
		)
		(fp_line
			(start -21.515324 -5.171694)
			(end -21.454872 -5.171694)
			(stroke
				(width 0.1)
				(type default)
			)
			(layer "B.SilkS")
		)
		(fp_line
			(start -21.515324 -5.171694)
			(end -21.454872 -5.171694)
			(stroke
				(width 0.1)
				(type default)
			)
			(layer "B.SilkS")
		)
		(fp_line
			(start -21.515324 -5.171694)
			(end -19.262852 -3.01117)
			(stroke
				(width 0.1)
				(type default)
			)
			(layer "B.SilkS")
		)
		(fp_line
			(start -21.515324 -5.171694)
			(end -19.262852 -3.01117)
			(stroke
				(width 0.1)
				(type default)
			)
			(layer "B.SilkS")
		)
		(fp_line
			(start -21.490686 -4.109466)
			(end -21.55063 -4.109466)
			(stroke
				(width 0.1)
				(type default)
			)
			(layer "B.SilkS")
		)
		(fp_line
			(start -21.490686 -4.109466)
			(end -21.55063 -4.109466)
			(stroke
				(width 0.1)
				(type default)
			)
			(layer "B.SilkS")
		)
		(fp_line
			(start -21.454872 -5.171694)
			(end -21.394674 -5.171694)
			(stroke
				(width 0.1)
				(type default)
			)
			(layer "B.SilkS")
		)
		(fp_line
			(start -21.454872 -5.171694)
			(end -21.394674 -5.171694)
			(stroke
				(width 0.1)
				(type default)
			)
			(layer "B.SilkS")
		)
		(fp_line
			(start -21.454872 -5.171694)
			(end -19.27479 -3.080512)
			(stroke
				(width 0.1)
				(type default)
			)
			(layer "B.SilkS")
		)
		(fp_line
			(start -21.454872 -5.171694)
			(end -19.27479 -3.080512)
			(stroke
				(width 0.1)
				(type default)
			)
			(layer "B.SilkS")
		)
		(fp_line
			(start -21.430742 -4.109466)
			(end -21.490686 -4.109466)
			(stroke
				(width 0.1)
				(type default)
			)
			(layer "B.SilkS")
		)
		(fp_line
			(start -21.430742 -4.109466)
			(end -21.490686 -4.109466)
			(stroke
				(width 0.1)
				(type default)
			)
			(layer "B.SilkS")
		)
		(fp_line
			(start -21.394674 -5.171694)
			(end -21.33473 -5.171694)
			(stroke
				(width 0.1)
				(type default)
			)
			(layer "B.SilkS")
		)
		(fp_line
			(start -21.394674 -5.171694)
			(end -21.33473 -5.171694)
			(stroke
				(width 0.1)
				(type default)
			)
			(layer "B.SilkS")
		)
		(fp_line
			(start -21.394674 -5.171694)
			(end -19.286982 -3.149854)
			(stroke
				(width 0.1)
				(type default)
			)
			(layer "B.SilkS")
		)
		(fp_line
			(start -21.394674 -5.171694)
			(end -19.286982 -3.149854)
			(stroke
				(width 0.1)
				(type default)
			)
			(layer "B.SilkS")
		)
		(fp_line
			(start -21.370544 -4.109466)
			(end -21.430742 -4.109466)
			(stroke
				(width 0.1)
				(type default)
			)
			(layer "B.SilkS")
		)
		(fp_line
			(start -21.370544 -4.109466)
			(end -21.430742 -4.109466)
			(stroke
				(width 0.1)
				(type default)
			)
			(layer "B.SilkS")
		)
		(fp_line
			(start -21.33473 -5.171694)
			(end -21.274532 -5.171694)
			(stroke
				(width 0.1)
				(type default)
			)
			(layer "B.SilkS")
		)
		(fp_line
			(start -21.33473 -5.171694)
			(end -21.274532 -5.171694)
			(stroke
				(width 0.1)
				(type default)
			)
			(layer "B.SilkS")
		)
		(fp_line
			(start -21.33473 -5.171694)
			(end -19.299428 -3.218942)
			(stroke
				(width 0.1)
				(type default)
			)
			(layer "B.SilkS")
		)
		(fp_line
			(start -21.33473 -5.171694)
			(end -19.299428 -3.218942)
			(stroke
				(width 0.1)
				(type default)
			)
			(layer "B.SilkS")
		)
		(fp_line
			(start -21.310346 -4.109466)
			(end -21.370544 -4.109466)
			(stroke
				(width 0.1)
				(type default)
			)
			(layer "B.SilkS")
		)
		(fp_line
			(start -21.310346 -4.109466)
			(end -21.370544 -4.109466)
			(stroke
				(width 0.1)
				(type default)
			)
			(layer "B.SilkS")
		)
		(fp_line
			(start -21.299932 -2.195068)
			(end -21.273516 -2.11201)
			(stroke
				(width 0.1)
				(type default)
			)
			(layer "B.SilkS")
		)
		(fp_line
			(start -21.299932 -2.195068)
			(end -21.273516 -2.11201)
			(stroke
				(width 0.1)
				(type default)
			)
			(layer "B.SilkS")
		)
		(fp_line
			(start -21.274532 -5.171694)
			(end -21.21408 -5.171694)
			(stroke
				(width 0.1)
				(type default)
			)
			(layer "B.SilkS")
		)
		(fp_line
			(start -21.274532 -5.171694)
			(end -21.21408 -5.171694)
			(stroke
				(width 0.1)
				(type default)
			)
			(layer "B.SilkS")
		)
		(fp_line
			(start -21.274532 -5.171694)
			(end -19.311366 -3.288538)
			(stroke
				(width 0.1)
				(type default)
			)
			(layer "B.SilkS")
		)
		(fp_line
			(start -21.274532 -5.171694)
			(end -19.311366 -3.288538)
			(stroke
				(width 0.1)
				(type default)
			)
			(layer "B.SilkS")
		)
		(fp_line
			(start -21.273516 -2.11201)
			(end -21.2471 -2.028952)
			(stroke
				(width 0.1)
				(type default)
			)
			(layer "B.SilkS")
		)
		(fp_line
			(start -21.273516 -2.11201)
			(end -21.2471 -2.028952)
			(stroke
				(width 0.1)
				(type default)
			)
			(layer "B.SilkS")
		)
		(fp_line
			(start -21.250402 -4.109466)
			(end -21.310346 -4.109466)
			(stroke
				(width 0.1)
				(type default)
			)
			(layer "B.SilkS")
		)
		(fp_line
			(start -21.250402 -4.109466)
			(end -21.310346 -4.109466)
			(stroke
				(width 0.1)
				(type default)
			)
			(layer "B.SilkS")
		)
		(fp_line
			(start -21.2471 -2.028952)
			(end -21.220684 -1.946148)
			(stroke
				(width 0.1)
				(type default)
			)
			(layer "B.SilkS")
		)
		(fp_line
			(start -21.2471 -2.028952)
			(end -21.220684 -1.946148)
			(stroke
				(width 0.1)
				(type default)
			)
			(layer "B.SilkS")
		)
		(fp_line
			(start -21.220684 -1.946148)
			(end -21.194268 -1.862836)
			(stroke
				(width 0.1)
				(type default)
			)
			(layer "B.SilkS")
		)
		(fp_line
			(start -21.220684 -1.946148)
			(end -21.194268 -1.862836)
			(stroke
				(width 0.1)
				(type default)
			)
			(layer "B.SilkS")
		)
		(fp_line
			(start -21.21408 -5.171694)
			(end -21.154136 -5.171694)
			(stroke
				(width 0.1)
				(type default)
			)
			(layer "B.SilkS")
		)
		(fp_line
			(start -21.21408 -5.171694)
			(end -21.154136 -5.171694)
			(stroke
				(width 0.1)
				(type default)
			)
			(layer "B.SilkS")
		)
		(fp_line
			(start -21.21408 -5.171694)
			(end -19.323558 -3.358134)
			(stroke
				(width 0.1)
				(type default)
			)
			(layer "B.SilkS")
		)
		(fp_line
			(start -21.21408 -5.171694)
			(end -19.323558 -3.358134)
			(stroke
				(width 0.1)
				(type default)
			)
			(layer "B.SilkS")
		)
		(fp_line
			(start -21.194268 -1.862836)
			(end -21.167852 -1.779778)
			(stroke
				(width 0.1)
				(type default)
			)
			(layer "B.SilkS")
		)
		(fp_line
			(start -21.194268 -1.862836)
			(end -21.167852 -1.779778)
			(stroke
				(width 0.1)
				(type default)
			)
			(layer "B.SilkS")
		)
		(fp_line
			(start -21.18995 -4.109466)
			(end -21.250402 -4.109466)
			(stroke
				(width 0.1)
				(type default)
			)
			(layer "B.SilkS")
		)
		(fp_line
			(start -21.18995 -4.109466)
			(end -21.250402 -4.109466)
			(stroke
				(width 0.1)
				(type default)
			)
			(layer "B.SilkS")
		)
		(fp_line
			(start -21.167852 -1.779778)
			(end -21.141436 -1.69672)
			(stroke
				(width 0.1)
				(type default)
			)
			(layer "B.SilkS")
		)
		(fp_line
			(start -21.167852 -1.779778)
			(end -21.141436 -1.69672)
			(stroke
				(width 0.1)
				(type default)
			)
			(layer "B.SilkS")
		)
		(fp_line
			(start -21.154136 -5.171694)
			(end -21.093938 -5.171694)
			(stroke
				(width 0.1)
				(type default)
			)
			(layer "B.SilkS")
		)
		(fp_line
			(start -21.154136 -5.171694)
			(end -21.093938 -5.171694)
			(stroke
				(width 0.1)
				(type default)
			)
			(layer "B.SilkS")
		)
		(fp_line
			(start -21.154136 -5.171694)
			(end -19.33575 -3.427476)
			(stroke
				(width 0.1)
				(type default)
			)
			(layer "B.SilkS")
		)
		(fp_line
			(start -21.154136 -5.171694)
			(end -19.33575 -3.427476)
			(stroke
				(width 0.1)
				(type default)
			)
			(layer "B.SilkS")
		)
		(fp_line
			(start -21.141436 -1.69672)
			(end -21.115274 -1.613916)
			(stroke
				(width 0.1)
				(type default)
			)
			(layer "B.SilkS")
		)
		(fp_line
			(start -21.141436 -1.69672)
			(end -21.115274 -1.613916)
			(stroke
				(width 0.1)
				(type default)
			)
			(layer "B.SilkS")
		)
		(fp_line
			(start -21.129752 -4.109466)
			(end -21.18995 -4.109466)
			(stroke
				(width 0.1)
				(type default)
			)
			(layer "B.SilkS")
		)
		(fp_line
			(start -21.129752 -4.109466)
			(end -21.18995 -4.109466)
			(stroke
				(width 0.1)
				(type default)
			)
			(layer "B.SilkS")
		)
		(fp_line
			(start -21.115274 -1.613916)
			(end -21.088858 -1.530604)
			(stroke
				(width 0.1)
				(type default)
			)
			(layer "B.SilkS")
		)
		(fp_line
			(start -21.115274 -1.613916)
			(end -21.088858 -1.530604)
			(stroke
				(width 0.1)
				(type default)
			)
			(layer "B.SilkS")
		)
		(fp_line
			(start -21.093938 -5.171694)
			(end -21.033994 -5.171694)
			(stroke
				(width 0.1)
				(type default)
			)
			(layer "B.SilkS")
		)
		(fp_line
			(start -21.093938 -5.171694)
			(end -21.033994 -5.171694)
			(stroke
				(width 0.1)
				(type default)
			)
			(layer "B.SilkS")
		)
		(fp_line
			(start -21.093938 -5.171694)
			(end -19.347942 -3.496564)
			(stroke
				(width 0.1)
				(type default)
			)
			(layer "B.SilkS")
		)
		(fp_line
			(start -21.093938 -5.171694)
			(end -19.347942 -3.496564)
			(stroke
				(width 0.1)
				(type default)
			)
			(layer "B.SilkS")
		)
		(fp_line
			(start -21.088858 -1.530604)
			(end -21.062188 -1.447546)
			(stroke
				(width 0.1)
				(type default)
			)
			(layer "B.SilkS")
		)
		(fp_line
			(start -21.088858 -1.530604)
			(end -21.062188 -1.447546)
			(stroke
				(width 0.1)
				(type default)
			)
			(layer "B.SilkS")
		)
		(fp_line
			(start -21.069554 -4.109466)
			(end -21.129752 -4.109466)
			(stroke
				(width 0.1)
				(type default)
			)
			(layer "B.SilkS")
		)
		(fp_line
			(start -21.069554 -4.109466)
			(end -21.129752 -4.109466)
			(stroke
				(width 0.1)
				(type default)
			)
			(layer "B.SilkS")
		)
		(fp_line
			(start -21.062188 -1.447546)
			(end -21.035772 -1.364742)
			(stroke
				(width 0.1)
				(type default)
			)
			(layer "B.SilkS")
		)
		(fp_line
			(start -21.062188 -1.447546)
			(end -21.035772 -1.364742)
			(stroke
				(width 0.1)
				(type default)
			)
			(layer "B.SilkS")
		)
		(fp_line
			(start -21.061934 -6.838188)
			(end -20.993354 -6.806438)
			(stroke
				(width 0.1)
				(type default)
			)
			(layer "B.SilkS")
		)
		(fp_line
			(start -21.061934 -6.838188)
			(end -20.993354 -6.806438)
			(stroke
				(width 0.1)
				(type default)
			)
			(layer "B.SilkS")
		)
		(fp_line
			(start -21.057108 -6.80974)
			(end -21.061934 -6.838188)
			(stroke
				(width 0.1)
				(type default)
			)
			(layer "B.SilkS")
		)
		(fp_line
			(start -21.057108 -6.80974)
			(end -21.061934 -6.838188)
			(stroke
				(width 0.1)
				(type default)
			)
			(layer "B.SilkS")
		)
		(fp_line
			(start -21.057108 -6.80974)
			(end -19.700748 -5.508752)
			(stroke
				(width 0.1)
				(type default)
			)
			(layer "B.SilkS")
		)
		(fp_line
			(start -21.057108 -6.80974)
			(end -19.700748 -5.508752)
			(stroke
				(width 0.1)
				(type default)
			)
			(layer "B.SilkS")
		)
		(fp_line
			(start -21.044662 -6.740144)
			(end -21.057108 -6.80974)
			(stroke
				(width 0.1)
				(type default)
			)
			(layer "B.SilkS")
		)
		(fp_line
			(start -21.044662 -6.740144)
			(end -21.057108 -6.80974)
			(stroke
				(width 0.1)
				(type default)
			)
			(layer "B.SilkS")
		)
		(fp_line
			(start -21.044662 -6.740144)
			(end -19.688302 -5.439156)
			(stroke
				(width 0.1)
				(type default)
			)
			(layer "B.SilkS")
		)
		(fp_line
			(start -21.044662 -6.740144)
			(end -19.688302 -5.439156)
			(stroke
				(width 0.1)
				(type default)
			)
			(layer "B.SilkS")
		)
		(fp_line
			(start -21.035772 -1.364742)
			(end -21.00961 -1.281684)
			(stroke
				(width 0.1)
				(type default)
			)
			(layer "B.SilkS")
		)
		(fp_line
			(start -21.035772 -1.364742)
			(end -21.00961 -1.281684)
			(stroke
				(width 0.1)
				(type default)
			)
			(layer "B.SilkS")
		)
		(fp_line
			(start -21.033994 -5.171694)
			(end -20.973542 -5.171694)
			(stroke
				(width 0.1)
				(type default)
			)
			(layer "B.SilkS")
		)
		(fp_line
			(start -21.033994 -5.171694)
			(end -20.973542 -5.171694)
			(stroke
				(width 0.1)
				(type default)
			)
			(layer "B.SilkS")
		)
		(fp_line
			(start -21.033994 -5.171694)
			(end -19.35988 -3.56616)
			(stroke
				(width 0.1)
				(type default)
			)
			(layer "B.SilkS")
		)
		(fp_line
			(start -21.033994 -5.171694)
			(end -19.35988 -3.56616)
			(stroke
				(width 0.1)
				(type default)
			)
			(layer "B.SilkS")
		)
		(fp_line
			(start -21.03247 -6.671056)
			(end -21.044662 -6.740144)
			(stroke
				(width 0.1)
				(type default)
			)
			(layer "B.SilkS")
		)
		(fp_line
			(start -21.03247 -6.671056)
			(end -21.044662 -6.740144)
			(stroke
				(width 0.1)
				(type default)
			)
			(layer "B.SilkS")
		)
		(fp_line
			(start -21.03247 -6.671056)
			(end -19.676364 -5.370068)
			(stroke
				(width 0.1)
				(type default)
			)
			(layer "B.SilkS")
		)
		(fp_line
			(start -21.03247 -6.671056)
			(end -19.676364 -5.370068)
			(stroke
				(width 0.1)
				(type default)
			)
			(layer "B.SilkS")
		)
		(fp_line
			(start -21.020278 -6.60146)
			(end -21.03247 -6.671056)
			(stroke
				(width 0.1)
				(type default)
			)
			(layer "B.SilkS")
		)
		(fp_line
			(start -21.020278 -6.60146)
			(end -21.03247 -6.671056)
			(stroke
				(width 0.1)
				(type default)
			)
			(layer "B.SilkS")
		)
		(fp_line
			(start -21.020278 -6.60146)
			(end -19.664172 -5.300472)
			(stroke
				(width 0.1)
				(type default)
			)
			(layer "B.SilkS")
		)
		(fp_line
			(start -21.020278 -6.60146)
			(end -19.664172 -5.300472)
			(stroke
				(width 0.1)
				(type default)
			)
			(layer "B.SilkS")
		)
		(fp_line
			(start -21.00961 -4.109466)
			(end -21.069554 -4.109466)
			(stroke
				(width 0.1)
				(type default)
			)
			(layer "B.SilkS")
		)
		(fp_line
			(start -21.00961 -4.109466)
			(end -21.069554 -4.109466)
			(stroke
				(width 0.1)
				(type default)
			)
			(layer "B.SilkS")
		)
		(fp_line
			(start -21.00961 -4.109466)
			(end -20.949666 -4.109466)
			(stroke
				(width 0.1)
				(type default)
			)
			(layer "B.SilkS")
		)
		(fp_line
			(start -21.00961 -4.109466)
			(end -20.949666 -4.109466)
			(stroke
				(width 0.1)
				(type default)
			)
			(layer "B.SilkS")
		)
		(fp_line
			(start -21.00961 -1.281684)
			(end -20.98294 -1.198626)
			(stroke
				(width 0.1)
				(type default)
			)
			(layer "B.SilkS")
		)
		(fp_line
			(start -21.00961 -1.281684)
			(end -20.98294 -1.198626)
			(stroke
				(width 0.1)
				(type default)
			)
			(layer "B.SilkS")
		)
		(fp_line
			(start -21.008086 -6.532118)
			(end -21.020278 -6.60146)
			(stroke
				(width 0.1)
				(type default)
			)
			(layer "B.SilkS")
		)
		(fp_line
			(start -21.008086 -6.532118)
			(end -21.020278 -6.60146)
			(stroke
				(width 0.1)
				(type default)
			)
			(layer "B.SilkS")
		)
		(fp_line
			(start -21.008086 -6.532118)
			(end -19.651726 -5.23113)
			(stroke
				(width 0.1)
				(type default)
			)
			(layer "B.SilkS")
		)
		(fp_line
			(start -21.008086 -6.532118)
			(end -19.651726 -5.23113)
			(stroke
				(width 0.1)
				(type default)
			)
			(layer "B.SilkS")
		)
		(fp_line
			(start -20.996148 -6.462522)
			(end -21.008086 -6.532118)
			(stroke
				(width 0.1)
				(type default)
			)
			(layer "B.SilkS")
		)
		(fp_line
			(start -20.996148 -6.462522)
			(end -21.008086 -6.532118)
			(stroke
				(width 0.1)
				(type default)
			)
			(layer "B.SilkS")
		)
		(fp_line
			(start -20.996148 -6.462522)
			(end -18.775934 -4.33324)
			(stroke
				(width 0.1)
				(type default)
			)
			(layer "B.SilkS")
		)
		(fp_line
			(start -20.996148 -6.462522)
			(end -18.775934 -4.33324)
			(stroke
				(width 0.1)
				(type default)
			)
			(layer "B.SilkS")
		)
		(fp_line
			(start -20.993354 -6.806438)
			(end -20.877784 -6.753606)
			(stroke
				(width 0.1)
				(type default)
			)
			(layer "B.SilkS")
		)
		(fp_line
			(start -20.993354 -6.806438)
			(end -20.877784 -6.753606)
			(stroke
				(width 0.1)
				(type default)
			)
			(layer "B.SilkS")
		)
		(fp_line
			(start -20.993354 -6.806438)
			(end -19.712686 -5.578094)
			(stroke
				(width 0.1)
				(type default)
			)
			(layer "B.SilkS")
		)
		(fp_line
			(start -20.993354 -6.806438)
			(end -19.712686 -5.578094)
			(stroke
				(width 0.1)
				(type default)
			)
			(layer "B.SilkS")
		)
		(fp_line
			(start -20.983702 -6.393434)
			(end -20.996148 -6.462522)
			(stroke
				(width 0.1)
				(type default)
			)
			(layer "B.SilkS")
		)
		(fp_line
			(start -20.983702 -6.393434)
			(end -20.996148 -6.462522)
			(stroke
				(width 0.1)
				(type default)
			)
			(layer "B.SilkS")
		)
		(fp_line
			(start -20.983702 -6.393434)
			(end -18.763996 -4.263898)
			(stroke
				(width 0.1)
				(type default)
			)
			(layer "B.SilkS")
		)
		(fp_line
			(start -20.983702 -6.393434)
			(end -18.763996 -4.263898)
			(stroke
				(width 0.1)
				(type default)
			)
			(layer "B.SilkS")
		)
		(fp_line
			(start -20.98294 -1.198626)
			(end -20.956524 -1.115314)
			(stroke
				(width 0.1)
				(type default)
			)
			(layer "B.SilkS")
		)
		(fp_line
			(start -20.98294 -1.198626)
			(end -20.956524 -1.115314)
			(stroke
				(width 0.1)
				(type default)
			)
			(layer "B.SilkS")
		)
		(fp_line
			(start -20.973542 -5.171694)
			(end -20.913344 -5.171694)
			(stroke
				(width 0.1)
				(type default)
			)
			(layer "B.SilkS")
		)
		(fp_line
			(start -20.973542 -5.171694)
			(end -20.913344 -5.171694)
			(stroke
				(width 0.1)
				(type default)
			)
			(layer "B.SilkS")
		)
		(fp_line
			(start -20.973542 -5.171694)
			(end -19.372326 -3.635502)
			(stroke
				(width 0.1)
				(type default)
			)
			(layer "B.SilkS")
		)
		(fp_line
			(start -20.973542 -5.171694)
			(end -19.372326 -3.635502)
			(stroke
				(width 0.1)
				(type default)
			)
			(layer "B.SilkS")
		)
		(fp_line
			(start -20.97151 -6.324092)
			(end -20.983702 -6.393434)
			(stroke
				(width 0.1)
				(type default)
			)
			(layer "B.SilkS")
		)
		(fp_line
			(start -20.97151 -6.324092)
			(end -20.983702 -6.393434)
			(stroke
				(width 0.1)
				(type default)
			)
			(layer "B.SilkS")
		)
		(fp_line
			(start -20.97151 -6.324092)
			(end -18.75155 -4.194556)
			(stroke
				(width 0.1)
				(type default)
			)
			(layer "B.SilkS")
		)
		(fp_line
			(start -20.97151 -6.324092)
			(end -18.75155 -4.194556)
			(stroke
				(width 0.1)
				(type default)
			)
			(layer "B.SilkS")
		)
		(fp_line
			(start -20.959318 -6.254496)
			(end -20.97151 -6.324092)
			(stroke
				(width 0.1)
				(type default)
			)
			(layer "B.SilkS")
		)
		(fp_line
			(start -20.959318 -6.254496)
			(end -20.97151 -6.324092)
			(stroke
				(width 0.1)
				(type default)
			)
			(layer "B.SilkS")
		)
		(fp_line
			(start -20.949666 -4.109466)
			(end -20.889214 -4.109466)
			(stroke
				(width 0.1)
				(type default)
			)
			(layer "B.SilkS")
		)
		(fp_line
			(start -20.949666 -4.109466)
			(end -20.889214 -4.109466)
			(stroke
				(width 0.1)
				(type default)
			)
			(layer "B.SilkS")
		)
		(fp_line
			(start -20.947126 -6.1849)
			(end -20.959318 -6.254496)
			(stroke
				(width 0.1)
				(type default)
			)
			(layer "B.SilkS")
		)
		(fp_line
			(start -20.947126 -6.1849)
			(end -20.959318 -6.254496)
			(stroke
				(width 0.1)
				(type default)
			)
			(layer "B.SilkS")
		)
		(fp_line
			(start -20.93468 -6.115558)
			(end -20.947126 -6.1849)
			(stroke
				(width 0.1)
				(type default)
			)
			(layer "B.SilkS")
		)
		(fp_line
			(start -20.93468 -6.115558)
			(end -20.947126 -6.1849)
			(stroke
				(width 0.1)
				(type default)
			)
			(layer "B.SilkS")
		)
		(fp_line
			(start -20.922742 -6.04647)
			(end -20.93468 -6.115558)
			(stroke
				(width 0.1)
				(type default)
			)
			(layer "B.SilkS")
		)
		(fp_line
			(start -20.922742 -6.04647)
			(end -20.93468 -6.115558)
			(stroke
				(width 0.1)
				(type default)
			)
			(layer "B.SilkS")
		)
		(fp_line
			(start -20.913344 -5.171694)
			(end -20.8534 -5.171694)
			(stroke
				(width 0.1)
				(type default)
			)
			(layer "B.SilkS")
		)
		(fp_line
			(start -20.913344 -5.171694)
			(end -20.8534 -5.171694)
			(stroke
				(width 0.1)
				(type default)
			)
			(layer "B.SilkS")
		)
		(fp_line
			(start -20.913344 -5.171694)
			(end -19.384518 -3.704844)
			(stroke
				(width 0.1)
				(type default)
			)
			(layer "B.SilkS")
		)
		(fp_line
			(start -20.913344 -5.171694)
			(end -19.384518 -3.704844)
			(stroke
				(width 0.1)
				(type default)
			)
			(layer "B.SilkS")
		)
		(fp_line
			(start -20.91055 -5.976874)
			(end -20.922742 -6.04647)
			(stroke
				(width 0.1)
				(type default)
			)
			(layer "B.SilkS")
		)
		(fp_line
			(start -20.91055 -5.976874)
			(end -20.922742 -6.04647)
			(stroke
				(width 0.1)
				(type default)
			)
			(layer "B.SilkS")
		)
		(fp_line
			(start -20.898104 -5.907278)
			(end -20.91055 -5.976874)
			(stroke
				(width 0.1)
				(type default)
			)
			(layer "B.SilkS")
		)
		(fp_line
			(start -20.898104 -5.907278)
			(end -20.91055 -5.976874)
			(stroke
				(width 0.1)
				(type default)
			)
			(layer "B.SilkS")
		)
		(fp_line
			(start -20.889214 -4.109466)
			(end -20.829016 -4.109466)
			(stroke
				(width 0.1)
				(type default)
			)
			(layer "B.SilkS")
		)
		(fp_line
			(start -20.889214 -4.109466)
			(end -20.829016 -4.109466)
			(stroke
				(width 0.1)
				(type default)
			)
			(layer "B.SilkS")
		)
		(fp_line
			(start -20.886166 -5.837936)
			(end -20.898104 -5.907278)
			(stroke
				(width 0.1)
				(type default)
			)
			(layer "B.SilkS")
		)
		(fp_line
			(start -20.886166 -5.837936)
			(end -20.898104 -5.907278)
			(stroke
				(width 0.1)
				(type default)
			)
			(layer "B.SilkS")
		)
		(fp_line
			(start -20.877784 -6.753606)
			(end -20.762722 -6.70052)
			(stroke
				(width 0.1)
				(type default)
			)
			(layer "B.SilkS")
		)
		(fp_line
			(start -20.877784 -6.753606)
			(end -20.762722 -6.70052)
			(stroke
				(width 0.1)
				(type default)
			)
			(layer "B.SilkS")
		)
		(fp_line
			(start -20.877784 -6.753606)
			(end -19.725132 -5.647436)
			(stroke
				(width 0.1)
				(type default)
			)
			(layer "B.SilkS")
		)
		(fp_line
			(start -20.877784 -6.753606)
			(end -19.725132 -5.647436)
			(stroke
				(width 0.1)
				(type default)
			)
			(layer "B.SilkS")
		)
		(fp_line
			(start -20.874228 -5.768594)
			(end -20.886166 -5.837936)
			(stroke
				(width 0.1)
				(type default)
			)
			(layer "B.SilkS")
		)
		(fp_line
			(start -20.874228 -5.768594)
			(end -20.886166 -5.837936)
			(stroke
				(width 0.1)
				(type default)
			)
			(layer "B.SilkS")
		)
		(fp_line
			(start -20.861782 -5.699252)
			(end -20.874228 -5.768594)
			(stroke
				(width 0.1)
				(type default)
			)
			(layer "B.SilkS")
		)
		(fp_line
			(start -20.861782 -5.699252)
			(end -20.874228 -5.768594)
			(stroke
				(width 0.1)
				(type default)
			)
			(layer "B.SilkS")
		)
		(fp_line
			(start -20.8534 -5.171694)
			(end -20.793202 -5.171694)
			(stroke
				(width 0.1)
				(type default)
			)
			(layer "B.SilkS")
		)
		(fp_line
			(start -20.8534 -5.171694)
			(end -20.793202 -5.171694)
			(stroke
				(width 0.1)
				(type default)
			)
			(layer "B.SilkS")
		)
		(fp_line
			(start -20.8534 -5.171694)
			(end -19.396456 -3.774186)
			(stroke
				(width 0.1)
				(type default)
			)
			(layer "B.SilkS")
		)
		(fp_line
			(start -20.8534 -5.171694)
			(end -19.396456 -3.774186)
			(stroke
				(width 0.1)
				(type default)
			)
			(layer "B.SilkS")
		)
		(fp_line
			(start -20.84959 -5.629656)
			(end -20.861782 -5.699252)
			(stroke
				(width 0.1)
				(type default)
			)
			(layer "B.SilkS")
		)
		(fp_line
			(start -20.84959 -5.629656)
			(end -20.861782 -5.699252)
			(stroke
				(width 0.1)
				(type default)
			)
			(layer "B.SilkS")
		)
		(fp_line
			(start -20.837144 -5.560314)
			(end -20.84959 -5.629656)
			(stroke
				(width 0.1)
				(type default)
			)
			(layer "B.SilkS")
		)
		(fp_line
			(start -20.837144 -5.560314)
			(end -20.84959 -5.629656)
			(stroke
				(width 0.1)
				(type default)
			)
			(layer "B.SilkS")
		)
		(fp_line
			(start -20.831302 -0.995426)
			(end -20.956524 -1.115314)
			(stroke
				(width 0.1)
				(type default)
			)
			(layer "B.SilkS")
		)
		(fp_line
			(start -20.831302 -0.995426)
			(end -20.956524 -1.115314)
			(stroke
				(width 0.1)
				(type default)
			)
			(layer "B.SilkS")
		)
		(fp_line
			(start -20.829016 -4.109466)
			(end -20.768564 -4.109466)
			(stroke
				(width 0.1)
				(type default)
			)
			(layer "B.SilkS")
		)
		(fp_line
			(start -20.829016 -4.109466)
			(end -20.768564 -4.109466)
			(stroke
				(width 0.1)
				(type default)
			)
			(layer "B.SilkS")
		)
		(fp_line
			(start -20.825206 -5.490972)
			(end -20.837144 -5.560314)
			(stroke
				(width 0.1)
				(type default)
			)
			(layer "B.SilkS")
		)
		(fp_line
			(start -20.825206 -5.490972)
			(end -20.837144 -5.560314)
			(stroke
				(width 0.1)
				(type default)
			)
			(layer "B.SilkS")
		)
		(fp_line
			(start -20.81276 -5.421376)
			(end -20.825206 -5.490972)
			(stroke
				(width 0.1)
				(type default)
			)
			(layer "B.SilkS")
		)
		(fp_line
			(start -20.81276 -5.421376)
			(end -20.825206 -5.490972)
			(stroke
				(width 0.1)
				(type default)
			)
			(layer "B.SilkS")
		)
		(fp_line
			(start -20.800822 -5.352034)
			(end -20.81276 -5.421376)
			(stroke
				(width 0.1)
				(type default)
			)
			(layer "B.SilkS")
		)
		(fp_line
			(start -20.800822 -5.352034)
			(end -20.81276 -5.421376)
			(stroke
				(width 0.1)
				(type default)
			)
			(layer "B.SilkS")
		)
		(fp_line
			(start -20.800822 -5.352034)
			(end -19.445478 -4.051554)
			(stroke
				(width 0.1)
				(type default)
			)
			(layer "B.SilkS")
		)
		(fp_line
			(start -20.800822 -5.352034)
			(end -19.445478 -4.051554)
			(stroke
				(width 0.1)
				(type default)
			)
			(layer "B.SilkS")
		)
		(fp_line
			(start -20.793202 -5.171694)
			(end -19.408902 -3.843528)
			(stroke
				(width 0.1)
				(type default)
			)
			(layer "B.SilkS")
		)
		(fp_line
			(start -20.793202 -5.171694)
			(end -19.408902 -3.843528)
			(stroke
				(width 0.1)
				(type default)
			)
			(layer "B.SilkS")
		)
		(fp_line
			(start -20.78863 -5.282692)
			(end -20.800822 -5.352034)
			(stroke
				(width 0.1)
				(type default)
			)
			(layer "B.SilkS")
		)
		(fp_line
			(start -20.78863 -5.282692)
			(end -20.800822 -5.352034)
			(stroke
				(width 0.1)
				(type default)
			)
			(layer "B.SilkS")
		)
		(fp_line
			(start -20.78863 -5.282692)
			(end -19.433032 -3.982466)
			(stroke
				(width 0.1)
				(type default)
			)
			(layer "B.SilkS")
		)
		(fp_line
			(start -20.78863 -5.282692)
			(end -19.433032 -3.982466)
			(stroke
				(width 0.1)
				(type default)
			)
			(layer "B.SilkS")
		)
		(fp_line
			(start -20.776184 -5.21335)
			(end -20.78863 -5.282692)
			(stroke
				(width 0.1)
				(type default)
			)
			(layer "B.SilkS")
		)
		(fp_line
			(start -20.776184 -5.21335)
			(end -20.78863 -5.282692)
			(stroke
				(width 0.1)
				(type default)
			)
			(layer "B.SilkS")
		)
		(fp_line
			(start -20.776184 -5.21335)
			(end -20.769072 -5.171694)
			(stroke
				(width 0.1)
				(type default)
			)
			(layer "B.SilkS")
		)
		(fp_line
			(start -20.776184 -5.21335)
			(end -20.769072 -5.171694)
			(stroke
				(width 0.1)
				(type default)
			)
			(layer "B.SilkS")
		)
		(fp_line
			(start -20.769072 -5.171694)
			(end -20.793202 -5.171694)
			(stroke
				(width 0.1)
				(type default)
			)
			(layer "B.SilkS")
		)
		(fp_line
			(start -20.769072 -5.171694)
			(end -20.793202 -5.171694)
			(stroke
				(width 0.1)
				(type default)
			)
			(layer "B.SilkS")
		)
		(fp_line
			(start -20.768564 -4.109466)
			(end -20.70862 -4.109466)
			(stroke
				(width 0.1)
				(type default)
			)
			(layer "B.SilkS")
		)
		(fp_line
			(start -20.768564 -4.109466)
			(end -20.70862 -4.109466)
			(stroke
				(width 0.1)
				(type default)
			)
			(layer "B.SilkS")
		)
		(fp_line
			(start -20.762722 -6.70052)
			(end -20.647152 -6.647434)
			(stroke
				(width 0.1)
				(type default)
			)
			(layer "B.SilkS")
		)
		(fp_line
			(start -20.762722 -6.70052)
			(end -20.647152 -6.647434)
			(stroke
				(width 0.1)
				(type default)
			)
			(layer "B.SilkS")
		)
		(fp_line
			(start -20.762722 -6.70052)
			(end -19.737324 -5.716778)
			(stroke
				(width 0.1)
				(type default)
			)
			(layer "B.SilkS")
		)
		(fp_line
			(start -20.762722 -6.70052)
			(end -19.737324 -5.716778)
			(stroke
				(width 0.1)
				(type default)
			)
			(layer "B.SilkS")
		)
		(fp_line
			(start -20.70862 -4.109466)
			(end -20.648422 -4.109466)
			(stroke
				(width 0.1)
				(type default)
			)
			(layer "B.SilkS")
		)
		(fp_line
			(start -20.70862 -4.109466)
			(end -20.648422 -4.109466)
			(stroke
				(width 0.1)
				(type default)
			)
			(layer "B.SilkS")
		)
		(fp_line
			(start -20.708366 -0.934974)
			(end -20.98294 -1.198626)
			(stroke
				(width 0.1)
				(type default)
			)
			(layer "B.SilkS")
		)
		(fp_line
			(start -20.708366 -0.934974)
			(end -20.98294 -1.198626)
			(stroke
				(width 0.1)
				(type default)
			)
			(layer "B.SilkS")
		)
		(fp_line
			(start -20.648422 -4.109466)
			(end -20.588224 -4.109466)
			(stroke
				(width 0.1)
				(type default)
			)
			(layer "B.SilkS")
		)
		(fp_line
			(start -20.648422 -4.109466)
			(end -20.588224 -4.109466)
			(stroke
				(width 0.1)
				(type default)
			)
			(layer "B.SilkS")
		)
		(fp_line
			(start -20.647152 -6.647434)
			(end -20.531328 -6.594348)
			(stroke
				(width 0.1)
				(type default)
			)
			(layer "B.SilkS")
		)
		(fp_line
			(start -20.647152 -6.647434)
			(end -20.531328 -6.594348)
			(stroke
				(width 0.1)
				(type default)
			)
			(layer "B.SilkS")
		)
		(fp_line
			(start -20.647152 -6.647434)
			(end -19.749262 -5.786374)
			(stroke
				(width 0.1)
				(type default)
			)
			(layer "B.SilkS")
		)
		(fp_line
			(start -20.647152 -6.647434)
			(end -19.749262 -5.786374)
			(stroke
				(width 0.1)
				(type default)
			)
			(layer "B.SilkS")
		)
		(fp_line
			(start -20.610322 -0.898652)
			(end -21.00961 -1.281684)
			(stroke
				(width 0.1)
				(type default)
			)
			(layer "B.SilkS")
		)
		(fp_line
			(start -20.610322 -0.898652)
			(end -21.00961 -1.281684)
			(stroke
				(width 0.1)
				(type default)
			)
			(layer "B.SilkS")
		)
		(fp_line
			(start -20.583398 -4.109466)
			(end -20.588224 -4.109466)
			(stroke
				(width 0.1)
				(type default)
			)
			(layer "B.SilkS")
		)
		(fp_line
			(start -20.583398 -4.109466)
			(end -20.588224 -4.109466)
			(stroke
				(width 0.1)
				(type default)
			)
			(layer "B.SilkS")
		)
		(fp_line
			(start -20.582382 -4.103878)
			(end -20.588224 -4.109466)
			(stroke
				(width 0.1)
				(type default)
			)
			(layer "B.SilkS")
		)
		(fp_line
			(start -20.582382 -4.103878)
			(end -20.588224 -4.109466)
			(stroke
				(width 0.1)
				(type default)
			)
			(layer "B.SilkS")
		)
		(fp_line
			(start -20.582382 -4.103878)
			(end -20.583398 -4.109466)
			(stroke
				(width 0.1)
				(type default)
			)
			(layer "B.SilkS")
		)
		(fp_line
			(start -20.582382 -4.103878)
			(end -20.583398 -4.109466)
			(stroke
				(width 0.1)
				(type default)
			)
			(layer "B.SilkS")
		)
		(fp_line
			(start -20.57019 -4.034282)
			(end -20.582382 -4.103878)
			(stroke
				(width 0.1)
				(type default)
			)
			(layer "B.SilkS")
		)
		(fp_line
			(start -20.57019 -4.034282)
			(end -20.582382 -4.103878)
			(stroke
				(width 0.1)
				(type default)
			)
			(layer "B.SilkS")
		)
		(fp_line
			(start -20.557744 -3.96494)
			(end -20.57019 -4.034282)
			(stroke
				(width 0.1)
				(type default)
			)
			(layer "B.SilkS")
		)
		(fp_line
			(start -20.557744 -3.96494)
			(end -20.57019 -4.034282)
			(stroke
				(width 0.1)
				(type default)
			)
			(layer "B.SilkS")
		)
		(fp_line
			(start -20.545806 -3.895344)
			(end -20.557744 -3.96494)
			(stroke
				(width 0.1)
				(type default)
			)
			(layer "B.SilkS")
		)
		(fp_line
			(start -20.545806 -3.895344)
			(end -20.557744 -3.96494)
			(stroke
				(width 0.1)
				(type default)
			)
			(layer "B.SilkS")
		)
		(fp_line
			(start -20.533614 -3.826256)
			(end -20.545806 -3.895344)
			(stroke
				(width 0.1)
				(type default)
			)
			(layer "B.SilkS")
		)
		(fp_line
			(start -20.533614 -3.826256)
			(end -20.545806 -3.895344)
			(stroke
				(width 0.1)
				(type default)
			)
			(layer "B.SilkS")
		)
		(fp_line
			(start -20.531328 -6.594348)
			(end -20.416012 -6.541262)
			(stroke
				(width 0.1)
				(type default)
			)
			(layer "B.SilkS")
		)
		(fp_line
			(start -20.531328 -6.594348)
			(end -20.416012 -6.541262)
			(stroke
				(width 0.1)
				(type default)
			)
			(layer "B.SilkS")
		)
		(fp_line
			(start -20.531328 -6.594348)
			(end -19.761708 -5.85597)
			(stroke
				(width 0.1)
				(type default)
			)
			(layer "B.SilkS")
		)
		(fp_line
			(start -20.531328 -6.594348)
			(end -19.761708 -5.85597)
			(stroke
				(width 0.1)
				(type default)
			)
			(layer "B.SilkS")
		)
		(fp_line
			(start -20.521422 -3.75666)
			(end -20.533614 -3.826256)
			(stroke
				(width 0.1)
				(type default)
			)
			(layer "B.SilkS")
		)
		(fp_line
			(start -20.521422 -3.75666)
			(end -20.533614 -3.826256)
			(stroke
				(width 0.1)
				(type default)
			)
			(layer "B.SilkS")
		)
		(fp_line
			(start -20.515834 -0.865632)
			(end -21.035772 -1.364742)
			(stroke
				(width 0.1)
				(type default)
			)
			(layer "B.SilkS")
		)
		(fp_line
			(start -20.515834 -0.865632)
			(end -21.035772 -1.364742)
			(stroke
				(width 0.1)
				(type default)
			)
			(layer "B.SilkS")
		)
		(fp_line
			(start -20.50923 -3.687064)
			(end -20.521422 -3.75666)
			(stroke
				(width 0.1)
				(type default)
			)
			(layer "B.SilkS")
		)
		(fp_line
			(start -20.50923 -3.687064)
			(end -20.521422 -3.75666)
			(stroke
				(width 0.1)
				(type default)
			)
			(layer "B.SilkS")
		)
		(fp_line
			(start -20.496784 -3.617976)
			(end -20.50923 -3.687064)
			(stroke
				(width 0.1)
				(type default)
			)
			(layer "B.SilkS")
		)
		(fp_line
			(start -20.496784 -3.617976)
			(end -20.50923 -3.687064)
			(stroke
				(width 0.1)
				(type default)
			)
			(layer "B.SilkS")
		)
		(fp_line
			(start -20.496784 -3.617976)
			(end -20.484846 -3.548634)
			(stroke
				(width 0.1)
				(type default)
			)
			(layer "B.SilkS")
		)
		(fp_line
			(start -20.496784 -3.617976)
			(end -20.484846 -3.548634)
			(stroke
				(width 0.1)
				(type default)
			)
			(layer "B.SilkS")
		)
		(fp_line
			(start -20.496784 -3.617976)
			(end -19.141186 -2.317242)
			(stroke
				(width 0.1)
				(type default)
			)
			(layer "B.SilkS")
		)
		(fp_line
			(start -20.496784 -3.617976)
			(end -19.141186 -2.317242)
			(stroke
				(width 0.1)
				(type default)
			)
			(layer "B.SilkS")
		)
		(fp_line
			(start -20.484846 -3.548634)
			(end -20.4724 -3.479038)
			(stroke
				(width 0.1)
				(type default)
			)
			(layer "B.SilkS")
		)
		(fp_line
			(start -20.484846 -3.548634)
			(end -20.4724 -3.479038)
			(stroke
				(width 0.1)
				(type default)
			)
			(layer "B.SilkS")
		)
		(fp_line
			(start -20.460462 -3.409442)
			(end -20.4724 -3.479038)
			(stroke
				(width 0.1)
				(type default)
			)
			(layer "B.SilkS")
		)
		(fp_line
			(start -20.460462 -3.409442)
			(end -20.4724 -3.479038)
			(stroke
				(width 0.1)
				(type default)
			)
			(layer "B.SilkS")
		)
		(fp_line
			(start -20.44827 -3.340354)
			(end -20.460462 -3.409442)
			(stroke
				(width 0.1)
				(type default)
			)
			(layer "B.SilkS")
		)
		(fp_line
			(start -20.44827 -3.340354)
			(end -20.460462 -3.409442)
			(stroke
				(width 0.1)
				(type default)
			)
			(layer "B.SilkS")
		)
		(fp_line
			(start -20.437602 -0.848106)
			(end -21.062188 -1.447546)
			(stroke
				(width 0.1)
				(type default)
			)
			(layer "B.SilkS")
		)
		(fp_line
			(start -20.437602 -0.848106)
			(end -21.062188 -1.447546)
			(stroke
				(width 0.1)
				(type default)
			)
			(layer "B.SilkS")
		)
		(fp_line
			(start -20.435824 -3.270758)
			(end -20.44827 -3.340354)
			(stroke
				(width 0.1)
				(type default)
			)
			(layer "B.SilkS")
		)
		(fp_line
			(start -20.435824 -3.270758)
			(end -20.44827 -3.340354)
			(stroke
				(width 0.1)
				(type default)
			)
			(layer "B.SilkS")
		)
		(fp_line
			(start -20.423886 -3.201416)
			(end -20.435824 -3.270758)
			(stroke
				(width 0.1)
				(type default)
			)
			(layer "B.SilkS")
		)
		(fp_line
			(start -20.423886 -3.201416)
			(end -20.435824 -3.270758)
			(stroke
				(width 0.1)
				(type default)
			)
			(layer "B.SilkS")
		)
		(fp_line
			(start -20.416012 -6.541262)
			(end -20.30095 -6.488176)
			(stroke
				(width 0.1)
				(type default)
			)
			(layer "B.SilkS")
		)
		(fp_line
			(start -20.416012 -6.541262)
			(end -20.30095 -6.488176)
			(stroke
				(width 0.1)
				(type default)
			)
			(layer "B.SilkS")
		)
		(fp_line
			(start -20.416012 -6.541262)
			(end -19.773646 -5.925058)
			(stroke
				(width 0.1)
				(type default)
			)
			(layer "B.SilkS")
		)
		(fp_line
			(start -20.416012 -6.541262)
			(end -19.773646 -5.925058)
			(stroke
				(width 0.1)
				(type default)
			)
			(layer "B.SilkS")
		)
		(fp_line
			(start -20.41144 -3.13182)
			(end -20.423886 -3.201416)
			(stroke
				(width 0.1)
				(type default)
			)
			(layer "B.SilkS")
		)
		(fp_line
			(start -20.41144 -3.13182)
			(end -20.423886 -3.201416)
			(stroke
				(width 0.1)
				(type default)
			)
			(layer "B.SilkS")
		)
		(fp_line
			(start -20.399248 -3.062478)
			(end -20.41144 -3.13182)
			(stroke
				(width 0.1)
				(type default)
			)
			(layer "B.SilkS")
		)
		(fp_line
			(start -20.399248 -3.062478)
			(end -20.41144 -3.13182)
			(stroke
				(width 0.1)
				(type default)
			)
			(layer "B.SilkS")
		)
		(fp_line
			(start -20.38731 -2.99339)
			(end -20.399248 -3.062478)
			(stroke
				(width 0.1)
				(type default)
			)
			(layer "B.SilkS")
		)
		(fp_line
			(start -20.38731 -2.99339)
			(end -20.399248 -3.062478)
			(stroke
				(width 0.1)
				(type default)
			)
			(layer "B.SilkS")
		)
		(fp_line
			(start -20.374864 -2.923794)
			(end -20.38731 -2.99339)
			(stroke
				(width 0.1)
				(type default)
			)
			(layer "B.SilkS")
		)
		(fp_line
			(start -20.374864 -2.923794)
			(end -20.38731 -2.99339)
			(stroke
				(width 0.1)
				(type default)
			)
			(layer "B.SilkS")
		)
		(fp_line
			(start -20.362926 -2.854198)
			(end -20.374864 -2.923794)
			(stroke
				(width 0.1)
				(type default)
			)
			(layer "B.SilkS")
		)
		(fp_line
			(start -20.362926 -2.854198)
			(end -20.374864 -2.923794)
			(stroke
				(width 0.1)
				(type default)
			)
			(layer "B.SilkS")
		)
		(fp_line
			(start -20.359116 -0.830834)
			(end -21.088858 -1.530604)
			(stroke
				(width 0.1)
				(type default)
			)
			(layer "B.SilkS")
		)
		(fp_line
			(start -20.359116 -0.830834)
			(end -21.088858 -1.530604)
			(stroke
				(width 0.1)
				(type default)
			)
			(layer "B.SilkS")
		)
		(fp_line
			(start -20.35048 -2.784856)
			(end -20.362926 -2.854198)
			(stroke
				(width 0.1)
				(type default)
			)
			(layer "B.SilkS")
		)
		(fp_line
			(start -20.35048 -2.784856)
			(end -20.362926 -2.854198)
			(stroke
				(width 0.1)
				(type default)
			)
			(layer "B.SilkS")
		)
		(fp_line
			(start -20.338288 -2.715768)
			(end -20.35048 -2.784856)
			(stroke
				(width 0.1)
				(type default)
			)
			(layer "B.SilkS")
		)
		(fp_line
			(start -20.338288 -2.715768)
			(end -20.35048 -2.784856)
			(stroke
				(width 0.1)
				(type default)
			)
			(layer "B.SilkS")
		)
		(fp_line
			(start -20.32635 -2.646172)
			(end -20.338288 -2.715768)
			(stroke
				(width 0.1)
				(type default)
			)
			(layer "B.SilkS")
		)
		(fp_line
			(start -20.32635 -2.646172)
			(end -20.338288 -2.715768)
			(stroke
				(width 0.1)
				(type default)
			)
			(layer "B.SilkS")
		)
		(fp_line
			(start -20.32635 -2.646172)
			(end -20.313904 -2.576576)
			(stroke
				(width 0.1)
				(type default)
			)
			(layer "B.SilkS")
		)
		(fp_line
			(start -20.32635 -2.646172)
			(end -20.313904 -2.576576)
			(stroke
				(width 0.1)
				(type default)
			)
			(layer "B.SilkS")
		)
		(fp_line
			(start -20.313904 -2.576576)
			(end -20.301966 -2.507234)
			(stroke
				(width 0.1)
				(type default)
			)
			(layer "B.SilkS")
		)
		(fp_line
			(start -20.313904 -2.576576)
			(end -20.301966 -2.507234)
			(stroke
				(width 0.1)
				(type default)
			)
			(layer "B.SilkS")
		)
		(fp_line
			(start -20.301966 -2.507234)
			(end -20.28952 -2.437892)
			(stroke
				(width 0.1)
				(type default)
			)
			(layer "B.SilkS")
		)
		(fp_line
			(start -20.301966 -2.507234)
			(end -20.28952 -2.437892)
			(stroke
				(width 0.1)
				(type default)
			)
			(layer "B.SilkS")
		)
		(fp_line
			(start -20.30095 -6.488176)
			(end -20.185126 -6.43509)
			(stroke
				(width 0.1)
				(type default)
			)
			(layer "B.SilkS")
		)
		(fp_line
			(start -20.30095 -6.488176)
			(end -20.185126 -6.43509)
			(stroke
				(width 0.1)
				(type default)
			)
			(layer "B.SilkS")
		)
		(fp_line
			(start -20.30095 -6.488176)
			(end -19.785838 -5.9944)
			(stroke
				(width 0.1)
				(type default)
			)
			(layer "B.SilkS")
		)
		(fp_line
			(start -20.30095 -6.488176)
			(end -19.785838 -5.9944)
			(stroke
				(width 0.1)
				(type default)
			)
			(layer "B.SilkS")
		)
		(fp_line
			(start -20.280884 -0.813562)
			(end -21.115274 -1.613916)
			(stroke
				(width 0.1)
				(type default)
			)
			(layer "B.SilkS")
		)
		(fp_line
			(start -20.280884 -0.813562)
			(end -21.115274 -1.613916)
			(stroke
				(width 0.1)
				(type default)
			)
			(layer "B.SilkS")
		)
		(fp_line
			(start -20.215352 -0.808228)
			(end -21.141436 -1.69672)
			(stroke
				(width 0.1)
				(type default)
			)
			(layer "B.SilkS")
		)
		(fp_line
			(start -20.215352 -0.808228)
			(end -21.141436 -1.69672)
			(stroke
				(width 0.1)
				(type default)
			)
			(layer "B.SilkS")
		)
		(fp_line
			(start -20.185126 -6.43509)
			(end -20.069302 -6.382004)
			(stroke
				(width 0.1)
				(type default)
			)
			(layer "B.SilkS")
		)
		(fp_line
			(start -20.185126 -6.43509)
			(end -20.069302 -6.382004)
			(stroke
				(width 0.1)
				(type default)
			)
			(layer "B.SilkS")
		)
		(fp_line
			(start -20.185126 -6.43509)
			(end -19.798284 -6.063996)
			(stroke
				(width 0.1)
				(type default)
			)
			(layer "B.SilkS")
		)
		(fp_line
			(start -20.185126 -6.43509)
			(end -19.798284 -6.063996)
			(stroke
				(width 0.1)
				(type default)
			)
			(layer "B.SilkS")
		)
		(fp_line
			(start -20.14982 -0.803402)
			(end -21.167852 -1.779778)
			(stroke
				(width 0.1)
				(type default)
			)
			(layer "B.SilkS")
		)
		(fp_line
			(start -20.14982 -0.803402)
			(end -21.167852 -1.779778)
			(stroke
				(width 0.1)
				(type default)
			)
			(layer "B.SilkS")
		)
		(fp_line
			(start -20.084542 -0.798576)
			(end -21.194268 -1.862836)
			(stroke
				(width 0.1)
				(type default)
			)
			(layer "B.SilkS")
		)
		(fp_line
			(start -20.084542 -0.798576)
			(end -21.194268 -1.862836)
			(stroke
				(width 0.1)
				(type default)
			)
			(layer "B.SilkS")
		)
		(fp_line
			(start -20.069302 -6.382004)
			(end -19.95424 -6.329172)
			(stroke
				(width 0.1)
				(type default)
			)
			(layer "B.SilkS")
		)
		(fp_line
			(start -20.069302 -6.382004)
			(end -19.95424 -6.329172)
			(stroke
				(width 0.1)
				(type default)
			)
			(layer "B.SilkS")
		)
		(fp_line
			(start -20.069302 -6.382004)
			(end -19.810222 -6.133338)
			(stroke
				(width 0.1)
				(type default)
			)
			(layer "B.SilkS")
		)
		(fp_line
			(start -20.069302 -6.382004)
			(end -19.810222 -6.133338)
			(stroke
				(width 0.1)
				(type default)
			)
			(layer "B.SilkS")
		)
		(fp_line
			(start -20.01901 -0.792988)
			(end -21.220684 -1.946148)
			(stroke
				(width 0.1)
				(type default)
			)
			(layer "B.SilkS")
		)
		(fp_line
			(start -20.01901 -0.792988)
			(end -21.220684 -1.946148)
			(stroke
				(width 0.1)
				(type default)
			)
			(layer "B.SilkS")
		)
		(fp_line
			(start -19.964654 -0.798576)
			(end -21.2471 -2.028952)
			(stroke
				(width 0.1)
				(type default)
			)
			(layer "B.SilkS")
		)
		(fp_line
			(start -19.964654 -0.798576)
			(end -21.2471 -2.028952)
			(stroke
				(width 0.1)
				(type default)
			)
			(layer "B.SilkS")
		)
		(fp_line
			(start -19.95424 -6.329172)
			(end -19.838924 -6.276086)
			(stroke
				(width 0.1)
				(type default)
			)
			(layer "B.SilkS")
		)
		(fp_line
			(start -19.95424 -6.329172)
			(end -19.838924 -6.276086)
			(stroke
				(width 0.1)
				(type default)
			)
			(layer "B.SilkS")
		)
		(fp_line
			(start -19.95424 -6.329172)
			(end -19.822668 -6.20268)
			(stroke
				(width 0.1)
				(type default)
			)
			(layer "B.SilkS")
		)
		(fp_line
			(start -19.95424 -6.329172)
			(end -19.822668 -6.20268)
			(stroke
				(width 0.1)
				(type default)
			)
			(layer "B.SilkS")
		)
		(fp_line
			(start -19.910044 -0.80391)
			(end -21.273516 -2.11201)
			(stroke
				(width 0.1)
				(type default)
			)
			(layer "B.SilkS")
		)
		(fp_line
			(start -19.910044 -0.80391)
			(end -21.273516 -2.11201)
			(stroke
				(width 0.1)
				(type default)
			)
			(layer "B.SilkS")
		)
		(fp_line
			(start -19.855434 -0.809498)
			(end -21.299932 -2.195068)
			(stroke
				(width 0.1)
				(type default)
			)
			(layer "B.SilkS")
		)
		(fp_line
			(start -19.855434 -0.809498)
			(end -21.299932 -2.195068)
			(stroke
				(width 0.1)
				(type default)
			)
			(layer "B.SilkS")
		)
		(fp_line
			(start -19.838924 -6.276086)
			(end -19.835114 -6.274308)
			(stroke
				(width 0.1)
				(type default)
			)
			(layer "B.SilkS")
		)
		(fp_line
			(start -19.838924 -6.276086)
			(end -19.835114 -6.274308)
			(stroke
				(width 0.1)
				(type default)
			)
			(layer "B.SilkS")
		)
		(fp_line
			(start -19.838924 -6.276086)
			(end -19.834606 -6.272022)
			(stroke
				(width 0.1)
				(type default)
			)
			(layer "B.SilkS")
		)
		(fp_line
			(start -19.838924 -6.276086)
			(end -19.834606 -6.272022)
			(stroke
				(width 0.1)
				(type default)
			)
			(layer "B.SilkS")
		)
		(fp_line
			(start -19.835114 -6.274308)
			(end -19.834606 -6.272022)
			(stroke
				(width 0.1)
				(type default)
			)
			(layer "B.SilkS")
		)
		(fp_line
			(start -19.835114 -6.274308)
			(end -19.834606 -6.272022)
			(stroke
				(width 0.1)
				(type default)
			)
			(layer "B.SilkS")
		)
		(fp_line
			(start -19.822668 -6.20268)
			(end -19.834606 -6.272022)
			(stroke
				(width 0.1)
				(type default)
			)
			(layer "B.SilkS")
		)
		(fp_line
			(start -19.822668 -6.20268)
			(end -19.834606 -6.272022)
			(stroke
				(width 0.1)
				(type default)
			)
			(layer "B.SilkS")
		)
		(fp_line
			(start -19.810222 -6.133338)
			(end -19.822668 -6.20268)
			(stroke
				(width 0.1)
				(type default)
			)
			(layer "B.SilkS")
		)
		(fp_line
			(start -19.810222 -6.133338)
			(end -19.822668 -6.20268)
			(stroke
				(width 0.1)
				(type default)
			)
			(layer "B.SilkS")
		)
		(fp_line
			(start -19.801078 -0.815086)
			(end -21.08327 -2.044954)
			(stroke
				(width 0.1)
				(type default)
			)
			(layer "B.SilkS")
		)
		(fp_line
			(start -19.801078 -0.815086)
			(end -21.08327 -2.044954)
			(stroke
				(width 0.1)
				(type default)
			)
			(layer "B.SilkS")
		)
		(fp_line
			(start -19.798284 -6.063996)
			(end -19.810222 -6.133338)
			(stroke
				(width 0.1)
				(type default)
			)
			(layer "B.SilkS")
		)
		(fp_line
			(start -19.798284 -6.063996)
			(end -19.810222 -6.133338)
			(stroke
				(width 0.1)
				(type default)
			)
			(layer "B.SilkS")
		)
		(fp_line
			(start -19.798284 -6.063996)
			(end -19.785838 -5.9944)
			(stroke
				(width 0.1)
				(type default)
			)
			(layer "B.SilkS")
		)
		(fp_line
			(start -19.798284 -6.063996)
			(end -19.785838 -5.9944)
			(stroke
				(width 0.1)
				(type default)
			)
			(layer "B.SilkS")
		)
		(fp_line
			(start -19.785838 -5.9944)
			(end -19.773646 -5.925058)
			(stroke
				(width 0.1)
				(type default)
			)
			(layer "B.SilkS")
		)
		(fp_line
			(start -19.785838 -5.9944)
			(end -19.773646 -5.925058)
			(stroke
				(width 0.1)
				(type default)
			)
			(layer "B.SilkS")
		)
		(fp_line
			(start -19.773646 -5.925058)
			(end -19.761708 -5.85597)
			(stroke
				(width 0.1)
				(type default)
			)
			(layer "B.SilkS")
		)
		(fp_line
			(start -19.773646 -5.925058)
			(end -19.761708 -5.85597)
			(stroke
				(width 0.1)
				(type default)
			)
			(layer "B.SilkS")
		)
		(fp_line
			(start -19.761708 -5.85597)
			(end -19.749262 -5.786374)
			(stroke
				(width 0.1)
				(type default)
			)
			(layer "B.SilkS")
		)
		(fp_line
			(start -19.761708 -5.85597)
			(end -19.749262 -5.786374)
			(stroke
				(width 0.1)
				(type default)
			)
			(layer "B.SilkS")
		)
		(fp_line
			(start -19.751802 -0.825246)
			(end -20.932902 -1.95834)
			(stroke
				(width 0.1)
				(type default)
			)
			(layer "B.SilkS")
		)
		(fp_line
			(start -19.751802 -0.825246)
			(end -20.932902 -1.95834)
			(stroke
				(width 0.1)
				(type default)
			)
			(layer "B.SilkS")
		)
		(fp_line
			(start -19.749262 -5.786374)
			(end -19.737324 -5.716778)
			(stroke
				(width 0.1)
				(type default)
			)
			(layer "B.SilkS")
		)
		(fp_line
			(start -19.749262 -5.786374)
			(end -19.737324 -5.716778)
			(stroke
				(width 0.1)
				(type default)
			)
			(layer "B.SilkS")
		)
		(fp_line
			(start -19.737324 -5.716778)
			(end -19.725132 -5.647436)
			(stroke
				(width 0.1)
				(type default)
			)
			(layer "B.SilkS")
		)
		(fp_line
			(start -19.737324 -5.716778)
			(end -19.725132 -5.647436)
			(stroke
				(width 0.1)
				(type default)
			)
			(layer "B.SilkS")
		)
		(fp_line
			(start -19.725132 -5.647436)
			(end -19.712686 -5.578094)
			(stroke
				(width 0.1)
				(type default)
			)
			(layer "B.SilkS")
		)
		(fp_line
			(start -19.725132 -5.647436)
			(end -19.712686 -5.578094)
			(stroke
				(width 0.1)
				(type default)
			)
			(layer "B.SilkS")
		)
		(fp_line
			(start -19.712686 -5.578094)
			(end -19.700748 -5.508752)
			(stroke
				(width 0.1)
				(type default)
			)
			(layer "B.SilkS")
		)
		(fp_line
			(start -19.712686 -5.578094)
			(end -19.700748 -5.508752)
			(stroke
				(width 0.1)
				(type default)
			)
			(layer "B.SilkS")
		)
		(fp_line
			(start -19.707352 -0.840486)
			(end -20.828 -1.915414)
			(stroke
				(width 0.1)
				(type default)
			)
			(layer "B.SilkS")
		)
		(fp_line
			(start -19.707352 -0.840486)
			(end -20.828 -1.915414)
			(stroke
				(width 0.1)
				(type default)
			)
			(layer "B.SilkS")
		)
		(fp_line
			(start -19.700748 -5.508752)
			(end -19.688302 -5.439156)
			(stroke
				(width 0.1)
				(type default)
			)
			(layer "B.SilkS")
		)
		(fp_line
			(start -19.700748 -5.508752)
			(end -19.688302 -5.439156)
			(stroke
				(width 0.1)
				(type default)
			)
			(layer "B.SilkS")
		)
		(fp_line
			(start -19.688302 -5.439156)
			(end -19.676364 -5.370068)
			(stroke
				(width 0.1)
				(type default)
			)
			(layer "B.SilkS")
		)
		(fp_line
			(start -19.688302 -5.439156)
			(end -19.676364 -5.370068)
			(stroke
				(width 0.1)
				(type default)
			)
			(layer "B.SilkS")
		)
		(fp_line
			(start -19.676364 -5.370068)
			(end -19.664172 -5.300472)
			(stroke
				(width 0.1)
				(type default)
			)
			(layer "B.SilkS")
		)
		(fp_line
			(start -19.676364 -5.370068)
			(end -19.664172 -5.300472)
			(stroke
				(width 0.1)
				(type default)
			)
			(layer "B.SilkS")
		)
		(fp_line
			(start -19.664172 -5.300472)
			(end -19.651726 -5.23113)
			(stroke
				(width 0.1)
				(type default)
			)
			(layer "B.SilkS")
		)
		(fp_line
			(start -19.664172 -5.300472)
			(end -19.651726 -5.23113)
			(stroke
				(width 0.1)
				(type default)
			)
			(layer "B.SilkS")
		)
		(fp_line
			(start -19.662902 -0.855218)
			(end -20.738084 -1.886966)
			(stroke
				(width 0.1)
				(type default)
			)
			(layer "B.SilkS")
		)
		(fp_line
			(start -19.662902 -0.855218)
			(end -20.738084 -1.886966)
			(stroke
				(width 0.1)
				(type default)
			)
			(layer "B.SilkS")
		)
		(fp_line
			(start -19.641566 -5.171694)
			(end -19.651726 -5.23113)
			(stroke
				(width 0.1)
				(type default)
			)
			(layer "B.SilkS")
		)
		(fp_line
			(start -19.641566 -5.171694)
			(end -19.651726 -5.23113)
			(stroke
				(width 0.1)
				(type default)
			)
			(layer "B.SilkS")
		)
		(fp_line
			(start -19.617944 -0.870458)
			(end -20.669504 -1.878838)
			(stroke
				(width 0.1)
				(type default)
			)
			(layer "B.SilkS")
		)
		(fp_line
			(start -19.617944 -0.870458)
			(end -20.669504 -1.878838)
			(stroke
				(width 0.1)
				(type default)
			)
			(layer "B.SilkS")
		)
		(fp_line
			(start -19.58975 -5.171694)
			(end -19.641566 -5.171694)
			(stroke
				(width 0.1)
				(type default)
			)
			(layer "B.SilkS")
		)
		(fp_line
			(start -19.58975 -5.171694)
			(end -19.641566 -5.171694)
			(stroke
				(width 0.1)
				(type default)
			)
			(layer "B.SilkS")
		)
		(fp_line
			(start -19.58975 -5.171694)
			(end -19.529806 -5.171694)
			(stroke
				(width 0.1)
				(type default)
			)
			(layer "B.SilkS")
		)
		(fp_line
			(start -19.58975 -5.171694)
			(end -19.529806 -5.171694)
			(stroke
				(width 0.1)
				(type default)
			)
			(layer "B.SilkS")
		)
		(fp_line
			(start -19.574002 -0.88519)
			(end -20.60194 -1.871726)
			(stroke
				(width 0.1)
				(type default)
			)
			(layer "B.SilkS")
		)
		(fp_line
			(start -19.574002 -0.88519)
			(end -20.60194 -1.871726)
			(stroke
				(width 0.1)
				(type default)
			)
			(layer "B.SilkS")
		)
		(fp_line
			(start -19.536156 -0.906526)
			(end -20.545044 -1.874774)
			(stroke
				(width 0.1)
				(type default)
			)
			(layer "B.SilkS")
		)
		(fp_line
			(start -19.536156 -0.906526)
			(end -20.545044 -1.874774)
			(stroke
				(width 0.1)
				(type default)
			)
			(layer "B.SilkS")
		)
		(fp_line
			(start -19.529806 -5.171694)
			(end -19.469608 -5.171694)
			(stroke
				(width 0.1)
				(type default)
			)
			(layer "B.SilkS")
		)
		(fp_line
			(start -19.529806 -5.171694)
			(end -19.469608 -5.171694)
			(stroke
				(width 0.1)
				(type default)
			)
			(layer "B.SilkS")
		)
		(fp_line
			(start -19.500088 -0.930148)
			(end -20.491704 -1.881378)
			(stroke
				(width 0.1)
				(type default)
			)
			(layer "B.SilkS")
		)
		(fp_line
			(start -19.500088 -0.930148)
			(end -20.491704 -1.881378)
			(stroke
				(width 0.1)
				(type default)
			)
			(layer "B.SilkS")
		)
		(fp_line
			(start -19.469608 -5.171694)
			(end -19.409664 -5.171694)
			(stroke
				(width 0.1)
				(type default)
			)
			(layer "B.SilkS")
		)
		(fp_line
			(start -19.469608 -5.171694)
			(end -19.409664 -5.171694)
			(stroke
				(width 0.1)
				(type default)
			)
			(layer "B.SilkS")
		)
		(fp_line
			(start -19.46402 -0.953516)
			(end -20.442428 -1.892046)
			(stroke
				(width 0.1)
				(type default)
			)
			(layer "B.SilkS")
		)
		(fp_line
			(start -19.46402 -0.953516)
			(end -20.442428 -1.892046)
			(stroke
				(width 0.1)
				(type default)
			)
			(layer "B.SilkS")
		)
		(fp_line
			(start -19.455384 -4.109466)
			(end -19.445478 -4.051554)
			(stroke
				(width 0.1)
				(type default)
			)
			(layer "B.SilkS")
		)
		(fp_line
			(start -19.455384 -4.109466)
			(end -19.445478 -4.051554)
			(stroke
				(width 0.1)
				(type default)
			)
			(layer "B.SilkS")
		)
		(fp_line
			(start -19.445478 -4.109466)
			(end -20.81276 -5.421376)
			(stroke
				(width 0.1)
				(type default)
			)
			(layer "B.SilkS")
		)
		(fp_line
			(start -19.445478 -4.109466)
			(end -20.81276 -5.421376)
			(stroke
				(width 0.1)
				(type default)
			)
			(layer "B.SilkS")
		)
		(fp_line
			(start -19.445478 -4.109466)
			(end -19.455384 -4.109466)
			(stroke
				(width 0.1)
				(type default)
			)
			(layer "B.SilkS")
		)
		(fp_line
			(start -19.445478 -4.109466)
			(end -19.455384 -4.109466)
			(stroke
				(width 0.1)
				(type default)
			)
			(layer "B.SilkS")
		)
		(fp_line
			(start -19.445478 -4.051554)
			(end -19.433032 -3.982466)
			(stroke
				(width 0.1)
				(type default)
			)
			(layer "B.SilkS")
		)
		(fp_line
			(start -19.445478 -4.051554)
			(end -19.433032 -3.982466)
			(stroke
				(width 0.1)
				(type default)
			)
			(layer "B.SilkS")
		)
		(fp_line
			(start -19.433032 -3.982466)
			(end -19.42084 -3.913124)
			(stroke
				(width 0.1)
				(type default)
			)
			(layer "B.SilkS")
		)
		(fp_line
			(start -19.433032 -3.982466)
			(end -19.42084 -3.913124)
			(stroke
				(width 0.1)
				(type default)
			)
			(layer "B.SilkS")
		)
		(fp_line
			(start -19.42846 -0.976884)
			(end -20.400772 -1.909572)
			(stroke
				(width 0.1)
				(type default)
			)
			(layer "B.SilkS")
		)
		(fp_line
			(start -19.42846 -0.976884)
			(end -20.400772 -1.909572)
			(stroke
				(width 0.1)
				(type default)
			)
			(layer "B.SilkS")
		)
		(fp_line
			(start -19.42084 -3.913124)
			(end -20.776184 -5.21335)
			(stroke
				(width 0.1)
				(type default)
			)
			(layer "B.SilkS")
		)
		(fp_line
			(start -19.42084 -3.913124)
			(end -20.776184 -5.21335)
			(stroke
				(width 0.1)
				(type default)
			)
			(layer "B.SilkS")
		)
		(fp_line
			(start -19.42084 -3.913124)
			(end -19.408902 -3.843528)
			(stroke
				(width 0.1)
				(type default)
			)
			(layer "B.SilkS")
		)
		(fp_line
			(start -19.42084 -3.913124)
			(end -19.408902 -3.843528)
			(stroke
				(width 0.1)
				(type default)
			)
			(layer "B.SilkS")
		)
		(fp_line
			(start -19.409664 -5.171694)
			(end -19.349212 -5.171694)
			(stroke
				(width 0.1)
				(type default)
			)
			(layer "B.SilkS")
		)
		(fp_line
			(start -19.409664 -5.171694)
			(end -19.349212 -5.171694)
			(stroke
				(width 0.1)
				(type default)
			)
			(layer "B.SilkS")
		)
		(fp_line
			(start -19.408902 -3.843528)
			(end -19.396456 -3.774186)
			(stroke
				(width 0.1)
				(type default)
			)
			(layer "B.SilkS")
		)
		(fp_line
			(start -19.408902 -3.843528)
			(end -19.396456 -3.774186)
			(stroke
				(width 0.1)
				(type default)
			)
			(layer "B.SilkS")
		)
		(fp_line
			(start -19.396456 -3.774186)
			(end -19.384518 -3.704844)
			(stroke
				(width 0.1)
				(type default)
			)
			(layer "B.SilkS")
		)
		(fp_line
			(start -19.396456 -3.774186)
			(end -19.384518 -3.704844)
			(stroke
				(width 0.1)
				(type default)
			)
			(layer "B.SilkS")
		)
		(fp_line
			(start -19.392646 -1.000252)
			(end -20.362164 -1.9304)
			(stroke
				(width 0.1)
				(type default)
			)
			(layer "B.SilkS")
		)
		(fp_line
			(start -19.392646 -1.000252)
			(end -20.362164 -1.9304)
			(stroke
				(width 0.1)
				(type default)
			)
			(layer "B.SilkS")
		)
		(fp_line
			(start -19.385026 -4.109466)
			(end -20.825206 -5.490972)
			(stroke
				(width 0.1)
				(type default)
			)
			(layer "B.SilkS")
		)
		(fp_line
			(start -19.385026 -4.109466)
			(end -20.825206 -5.490972)
			(stroke
				(width 0.1)
				(type default)
			)
			(layer "B.SilkS")
		)
		(fp_line
			(start -19.385026 -4.109466)
			(end -19.445478 -4.109466)
			(stroke
				(width 0.1)
				(type default)
			)
			(layer "B.SilkS")
		)
		(fp_line
			(start -19.385026 -4.109466)
			(end -19.445478 -4.109466)
			(stroke
				(width 0.1)
				(type default)
			)
			(layer "B.SilkS")
		)
		(fp_line
			(start -19.384518 -3.704844)
			(end -19.372326 -3.635502)
			(stroke
				(width 0.1)
				(type default)
			)
			(layer "B.SilkS")
		)
		(fp_line
			(start -19.384518 -3.704844)
			(end -19.372326 -3.635502)
			(stroke
				(width 0.1)
				(type default)
			)
			(layer "B.SilkS")
		)
		(fp_line
			(start -19.372326 -3.635502)
			(end -19.35988 -3.56616)
			(stroke
				(width 0.1)
				(type default)
			)
			(layer "B.SilkS")
		)
		(fp_line
			(start -19.372326 -3.635502)
			(end -19.35988 -3.56616)
			(stroke
				(width 0.1)
				(type default)
			)
			(layer "B.SilkS")
		)
		(fp_line
			(start -19.363436 -1.030224)
			(end -20.332446 -1.959356)
			(stroke
				(width 0.1)
				(type default)
			)
			(layer "B.SilkS")
		)
		(fp_line
			(start -19.363436 -1.030224)
			(end -20.332446 -1.959356)
			(stroke
				(width 0.1)
				(type default)
			)
			(layer "B.SilkS")
		)
		(fp_line
			(start -19.35988 -3.56616)
			(end -19.347942 -3.496564)
			(stroke
				(width 0.1)
				(type default)
			)
			(layer "B.SilkS")
		)
		(fp_line
			(start -19.35988 -3.56616)
			(end -19.347942 -3.496564)
			(stroke
				(width 0.1)
				(type default)
			)
			(layer "B.SilkS")
		)
		(fp_line
			(start -19.349212 -5.171694)
			(end -19.289014 -5.171694)
			(stroke
				(width 0.1)
				(type default)
			)
			(layer "B.SilkS")
		)
		(fp_line
			(start -19.349212 -5.171694)
			(end -19.289014 -5.171694)
			(stroke
				(width 0.1)
				(type default)
			)
			(layer "B.SilkS")
		)
		(fp_line
			(start -19.347942 -3.496564)
			(end -19.33575 -3.427476)
			(stroke
				(width 0.1)
				(type default)
			)
			(layer "B.SilkS")
		)
		(fp_line
			(start -19.347942 -3.496564)
			(end -19.33575 -3.427476)
			(stroke
				(width 0.1)
				(type default)
			)
			(layer "B.SilkS")
		)
		(fp_line
			(start -19.33575 -3.427476)
			(end -19.323558 -3.358134)
			(stroke
				(width 0.1)
				(type default)
			)
			(layer "B.SilkS")
		)
		(fp_line
			(start -19.33575 -3.427476)
			(end -19.323558 -3.358134)
			(stroke
				(width 0.1)
				(type default)
			)
			(layer "B.SilkS")
		)
		(fp_line
			(start -19.335496 -1.061212)
			(end -20.307046 -1.992884)
			(stroke
				(width 0.1)
				(type default)
			)
			(layer "B.SilkS")
		)
		(fp_line
			(start -19.335496 -1.061212)
			(end -20.307046 -1.992884)
			(stroke
				(width 0.1)
				(type default)
			)
			(layer "B.SilkS")
		)
		(fp_line
			(start -19.324828 -4.109466)
			(end -20.837144 -5.560314)
			(stroke
				(width 0.1)
				(type default)
			)
			(layer "B.SilkS")
		)
		(fp_line
			(start -19.324828 -4.109466)
			(end -20.837144 -5.560314)
			(stroke
				(width 0.1)
				(type default)
			)
			(layer "B.SilkS")
		)
		(fp_line
			(start -19.324828 -4.109466)
			(end -19.385026 -4.109466)
			(stroke
				(width 0.1)
				(type default)
			)
			(layer "B.SilkS")
		)
		(fp_line
			(start -19.324828 -4.109466)
			(end -19.385026 -4.109466)
			(stroke
				(width 0.1)
				(type default)
			)
			(layer "B.SilkS")
		)
		(fp_line
			(start -19.323558 -3.358134)
			(end -19.311366 -3.288538)
			(stroke
				(width 0.1)
				(type default)
			)
			(layer "B.SilkS")
		)
		(fp_line
			(start -19.323558 -3.358134)
			(end -19.311366 -3.288538)
			(stroke
				(width 0.1)
				(type default)
			)
			(layer "B.SilkS")
		)
		(fp_line
			(start -19.311366 -3.288538)
			(end -19.299428 -3.218942)
			(stroke
				(width 0.1)
				(type default)
			)
			(layer "B.SilkS")
		)
		(fp_line
			(start -19.311366 -3.288538)
			(end -19.299428 -3.218942)
			(stroke
				(width 0.1)
				(type default)
			)
			(layer "B.SilkS")
		)
		(fp_line
			(start -19.307556 -1.091946)
			(end -20.287488 -2.031746)
			(stroke
				(width 0.1)
				(type default)
			)
			(layer "B.SilkS")
		)
		(fp_line
			(start -19.307556 -1.091946)
			(end -20.287488 -2.031746)
			(stroke
				(width 0.1)
				(type default)
			)
			(layer "B.SilkS")
		)
		(fp_line
			(start -19.299428 -3.218942)
			(end -19.286982 -3.149854)
			(stroke
				(width 0.1)
				(type default)
			)
			(layer "B.SilkS")
		)
		(fp_line
			(start -19.299428 -3.218942)
			(end -19.286982 -3.149854)
			(stroke
				(width 0.1)
				(type default)
			)
			(layer "B.SilkS")
		)
		(fp_line
			(start -19.289014 -5.171694)
			(end -19.22907 -5.171694)
			(stroke
				(width 0.1)
				(type default)
			)
			(layer "B.SilkS")
		)
		(fp_line
			(start -19.289014 -5.171694)
			(end -19.22907 -5.171694)
			(stroke
				(width 0.1)
				(type default)
			)
			(layer "B.SilkS")
		)
		(fp_line
			(start -19.286982 -3.149854)
			(end -19.27479 -3.080512)
			(stroke
				(width 0.1)
				(type default)
			)
			(layer "B.SilkS")
		)
		(fp_line
			(start -19.286982 -3.149854)
			(end -19.27479 -3.080512)
			(stroke
				(width 0.1)
				(type default)
			)
			(layer "B.SilkS")
		)
		(fp_line
			(start -19.279616 -1.122934)
			(end -20.274534 -2.077212)
			(stroke
				(width 0.1)
				(type default)
			)
			(layer "B.SilkS")
		)
		(fp_line
			(start -19.279616 -1.122934)
			(end -20.274534 -2.077212)
			(stroke
				(width 0.1)
				(type default)
			)
			(layer "B.SilkS")
		)
		(fp_line
			(start -19.27479 -3.080512)
			(end -19.262852 -3.01117)
			(stroke
				(width 0.1)
				(type default)
			)
			(layer "B.SilkS")
		)
		(fp_line
			(start -19.27479 -3.080512)
			(end -19.262852 -3.01117)
			(stroke
				(width 0.1)
				(type default)
			)
			(layer "B.SilkS")
		)
		(fp_line
			(start -19.264884 -4.109466)
			(end -20.84959 -5.629656)
			(stroke
				(width 0.1)
				(type default)
			)
			(layer "B.SilkS")
		)
		(fp_line
			(start -19.264884 -4.109466)
			(end -20.84959 -5.629656)
			(stroke
				(width 0.1)
				(type default)
			)
			(layer "B.SilkS")
		)
		(fp_line
			(start -19.264884 -4.109466)
			(end -19.324828 -4.109466)
			(stroke
				(width 0.1)
				(type default)
			)
			(layer "B.SilkS")
		)
		(fp_line
			(start -19.264884 -4.109466)
			(end -19.324828 -4.109466)
			(stroke
				(width 0.1)
				(type default)
			)
			(layer "B.SilkS")
		)
		(fp_line
			(start -19.262852 -3.01117)
			(end -19.250406 -2.941574)
			(stroke
				(width 0.1)
				(type default)
			)
			(layer "B.SilkS")
		)
		(fp_line
			(start -19.262852 -3.01117)
			(end -19.250406 -2.941574)
			(stroke
				(width 0.1)
				(type default)
			)
			(layer "B.SilkS")
		)
		(fp_line
			(start -19.25193 -1.153922)
			(end -20.265136 -2.125726)
			(stroke
				(width 0.1)
				(type default)
			)
			(layer "B.SilkS")
		)
		(fp_line
			(start -19.25193 -1.153922)
			(end -20.265136 -2.125726)
			(stroke
				(width 0.1)
				(type default)
			)
			(layer "B.SilkS")
		)
		(fp_line
			(start -19.250406 -2.941574)
			(end -19.238468 -2.872232)
			(stroke
				(width 0.1)
				(type default)
			)
			(layer "B.SilkS")
		)
		(fp_line
			(start -19.250406 -2.941574)
			(end -19.238468 -2.872232)
			(stroke
				(width 0.1)
				(type default)
			)
			(layer "B.SilkS")
		)
		(fp_line
			(start -19.238468 -2.872232)
			(end -21.635466 -5.171694)
			(stroke
				(width 0.1)
				(type default)
			)
			(layer "B.SilkS")
		)
		(fp_line
			(start -19.238468 -2.872232)
			(end -21.635466 -5.171694)
			(stroke
				(width 0.1)
				(type default)
			)
			(layer "B.SilkS")
		)
		(fp_line
			(start -19.238468 -2.872232)
			(end -19.226276 -2.80289)
			(stroke
				(width 0.1)
				(type default)
			)
			(layer "B.SilkS")
		)
		(fp_line
			(start -19.238468 -2.872232)
			(end -19.226276 -2.80289)
			(stroke
				(width 0.1)
				(type default)
			)
			(layer "B.SilkS")
		)
		(fp_line
			(start -19.230848 -1.191514)
			(end -20.263358 -2.181606)
			(stroke
				(width 0.1)
				(type default)
			)
			(layer "B.SilkS")
		)
		(fp_line
			(start -19.230848 -1.191514)
			(end -20.263358 -2.181606)
			(stroke
				(width 0.1)
				(type default)
			)
			(layer "B.SilkS")
		)
		(fp_line
			(start -19.22907 -5.171694)
			(end -19.168872 -5.171694)
			(stroke
				(width 0.1)
				(type default)
			)
			(layer "B.SilkS")
		)
		(fp_line
			(start -19.22907 -5.171694)
			(end -19.168872 -5.171694)
			(stroke
				(width 0.1)
				(type default)
			)
			(layer "B.SilkS")
		)
		(fp_line
			(start -19.226276 -2.80289)
			(end -20.582382 -4.103878)
			(stroke
				(width 0.1)
				(type default)
			)
			(layer "B.SilkS")
		)
		(fp_line
			(start -19.226276 -2.80289)
			(end -20.582382 -4.103878)
			(stroke
				(width 0.1)
				(type default)
			)
			(layer "B.SilkS")
		)
		(fp_line
			(start -19.226276 -2.80289)
			(end -19.21383 -2.733548)
			(stroke
				(width 0.1)
				(type default)
			)
			(layer "B.SilkS")
		)
		(fp_line
			(start -19.226276 -2.80289)
			(end -19.21383 -2.733548)
			(stroke
				(width 0.1)
				(type default)
			)
			(layer "B.SilkS")
		)
		(fp_line
			(start -19.21383 -2.733548)
			(end -20.57019 -4.034282)
			(stroke
				(width 0.1)
				(type default)
			)
			(layer "B.SilkS")
		)
		(fp_line
			(start -19.21383 -2.733548)
			(end -20.57019 -4.034282)
			(stroke
				(width 0.1)
				(type default)
			)
			(layer "B.SilkS")
		)
		(fp_line
			(start -19.21383 -2.733548)
			(end -19.201892 -2.663952)
			(stroke
				(width 0.1)
				(type default)
			)
			(layer "B.SilkS")
		)
		(fp_line
			(start -19.21383 -2.733548)
			(end -19.201892 -2.663952)
			(stroke
				(width 0.1)
				(type default)
			)
			(layer "B.SilkS")
		)
		(fp_line
			(start -19.210782 -1.229868)
			(end -20.26285 -2.239264)
			(stroke
				(width 0.1)
				(type default)
			)
			(layer "B.SilkS")
		)
		(fp_line
			(start -19.210782 -1.229868)
			(end -20.26285 -2.239264)
			(stroke
				(width 0.1)
				(type default)
			)
			(layer "B.SilkS")
		)
		(fp_line
			(start -19.204686 -4.109466)
			(end -20.861782 -5.699252)
			(stroke
				(width 0.1)
				(type default)
			)
			(layer "B.SilkS")
		)
		(fp_line
			(start -19.204686 -4.109466)
			(end -20.861782 -5.699252)
			(stroke
				(width 0.1)
				(type default)
			)
			(layer "B.SilkS")
		)
		(fp_line
			(start -19.204686 -4.109466)
			(end -19.264884 -4.109466)
			(stroke
				(width 0.1)
				(type default)
			)
			(layer "B.SilkS")
		)
		(fp_line
			(start -19.204686 -4.109466)
			(end -19.264884 -4.109466)
			(stroke
				(width 0.1)
				(type default)
			)
			(layer "B.SilkS")
		)
		(fp_line
			(start -19.201892 -2.663952)
			(end -20.557744 -3.96494)
			(stroke
				(width 0.1)
				(type default)
			)
			(layer "B.SilkS")
		)
		(fp_line
			(start -19.201892 -2.663952)
			(end -20.557744 -3.96494)
			(stroke
				(width 0.1)
				(type default)
			)
			(layer "B.SilkS")
		)
		(fp_line
			(start -19.201892 -2.663952)
			(end -19.1897 -2.594864)
			(stroke
				(width 0.1)
				(type default)
			)
			(layer "B.SilkS")
		)
		(fp_line
			(start -19.201892 -2.663952)
			(end -19.1897 -2.594864)
			(stroke
				(width 0.1)
				(type default)
			)
			(layer "B.SilkS")
		)
		(fp_line
			(start -19.190462 -1.267968)
			(end -20.270216 -2.303526)
			(stroke
				(width 0.1)
				(type default)
			)
			(layer "B.SilkS")
		)
		(fp_line
			(start -19.190462 -1.267968)
			(end -20.270216 -2.303526)
			(stroke
				(width 0.1)
				(type default)
			)
			(layer "B.SilkS")
		)
		(fp_line
			(start -19.1897 -2.594864)
			(end -20.545806 -3.895344)
			(stroke
				(width 0.1)
				(type default)
			)
			(layer "B.SilkS")
		)
		(fp_line
			(start -19.1897 -2.594864)
			(end -20.545806 -3.895344)
			(stroke
				(width 0.1)
				(type default)
			)
			(layer "B.SilkS")
		)
		(fp_line
			(start -19.1897 -2.594864)
			(end -19.177762 -2.525522)
			(stroke
				(width 0.1)
				(type default)
			)
			(layer "B.SilkS")
		)
		(fp_line
			(start -19.1897 -2.594864)
			(end -19.177762 -2.525522)
			(stroke
				(width 0.1)
				(type default)
			)
			(layer "B.SilkS")
		)
		(fp_line
			(start -19.177762 -2.525522)
			(end -20.533614 -3.826256)
			(stroke
				(width 0.1)
				(type default)
			)
			(layer "B.SilkS")
		)
		(fp_line
			(start -19.177762 -2.525522)
			(end -20.533614 -3.826256)
			(stroke
				(width 0.1)
				(type default)
			)
			(layer "B.SilkS")
		)
		(fp_line
			(start -19.177762 -2.525522)
			(end -19.165316 -2.455926)
			(stroke
				(width 0.1)
				(type default)
			)
			(layer "B.SilkS")
		)
		(fp_line
			(start -19.177762 -2.525522)
			(end -19.165316 -2.455926)
			(stroke
				(width 0.1)
				(type default)
			)
			(layer "B.SilkS")
		)
		(fp_line
			(start -19.170142 -1.306322)
			(end -20.278344 -2.369312)
			(stroke
				(width 0.1)
				(type default)
			)
			(layer "B.SilkS")
		)
		(fp_line
			(start -19.170142 -1.306322)
			(end -20.278344 -2.369312)
			(stroke
				(width 0.1)
				(type default)
			)
			(layer "B.SilkS")
		)
		(fp_line
			(start -19.165316 -2.455926)
			(end -20.521422 -3.75666)
			(stroke
				(width 0.1)
				(type default)
			)
			(layer "B.SilkS")
		)
		(fp_line
			(start -19.165316 -2.455926)
			(end -20.521422 -3.75666)
			(stroke
				(width 0.1)
				(type default)
			)
			(layer "B.SilkS")
		)
		(fp_line
			(start -19.165316 -2.455926)
			(end -19.153378 -2.386584)
			(stroke
				(width 0.1)
				(type default)
			)
			(layer "B.SilkS")
		)
		(fp_line
			(start -19.165316 -2.455926)
			(end -19.153378 -2.386584)
			(stroke
				(width 0.1)
				(type default)
			)
			(layer "B.SilkS")
		)
		(fp_line
			(start -19.153378 -2.386584)
			(end -20.50923 -3.687064)
			(stroke
				(width 0.1)
				(type default)
			)
			(layer "B.SilkS")
		)
		(fp_line
			(start -19.153378 -2.386584)
			(end -20.50923 -3.687064)
			(stroke
				(width 0.1)
				(type default)
			)
			(layer "B.SilkS")
		)
		(fp_line
			(start -19.153378 -2.386584)
			(end -19.141186 -2.317242)
			(stroke
				(width 0.1)
				(type default)
			)
			(layer "B.SilkS")
		)
		(fp_line
			(start -19.153378 -2.386584)
			(end -19.141186 -2.317242)
			(stroke
				(width 0.1)
				(type default)
			)
			(layer "B.SilkS")
		)
		(fp_line
			(start -19.149822 -1.344676)
			(end -20.28952 -2.437892)
			(stroke
				(width 0.1)
				(type default)
			)
			(layer "B.SilkS")
		)
		(fp_line
			(start -19.149822 -1.344676)
			(end -20.28952 -2.437892)
			(stroke
				(width 0.1)
				(type default)
			)
			(layer "B.SilkS")
		)
		(fp_line
			(start -19.144234 -4.109466)
			(end -20.874228 -5.768594)
			(stroke
				(width 0.1)
				(type default)
			)
			(layer "B.SilkS")
		)
		(fp_line
			(start -19.144234 -4.109466)
			(end -20.874228 -5.768594)
			(stroke
				(width 0.1)
				(type default)
			)
			(layer "B.SilkS")
		)
		(fp_line
			(start -19.144234 -4.109466)
			(end -19.204686 -4.109466)
			(stroke
				(width 0.1)
				(type default)
			)
			(layer "B.SilkS")
		)
		(fp_line
			(start -19.144234 -4.109466)
			(end -19.204686 -4.109466)
			(stroke
				(width 0.1)
				(type default)
			)
			(layer "B.SilkS")
		)
		(fp_line
			(start -19.137376 -1.390396)
			(end -20.301966 -2.507234)
			(stroke
				(width 0.1)
				(type default)
			)
			(layer "B.SilkS")
		)
		(fp_line
			(start -19.137376 -1.390396)
			(end -20.301966 -2.507234)
			(stroke
				(width 0.1)
				(type default)
			)
			(layer "B.SilkS")
		)
		(fp_line
			(start -19.12874 -2.2479)
			(end -20.484846 -3.548634)
			(stroke
				(width 0.1)
				(type default)
			)
			(layer "B.SilkS")
		)
		(fp_line
			(start -19.12874 -2.2479)
			(end -20.484846 -3.548634)
			(stroke
				(width 0.1)
				(type default)
			)
			(layer "B.SilkS")
		)
		(fp_line
			(start -19.12874 -2.2479)
			(end -19.141186 -2.317242)
			(stroke
				(width 0.1)
				(type default)
			)
			(layer "B.SilkS")
		)
		(fp_line
			(start -19.12874 -2.2479)
			(end -19.141186 -2.317242)
			(stroke
				(width 0.1)
				(type default)
			)
			(layer "B.SilkS")
		)
		(fp_line
			(start -19.12874 -2.2479)
			(end -19.116802 -2.178304)
			(stroke
				(width 0.1)
				(type default)
			)
			(layer "B.SilkS")
		)
		(fp_line
			(start -19.12874 -2.2479)
			(end -19.116802 -2.178304)
			(stroke
				(width 0.1)
				(type default)
			)
			(layer "B.SilkS")
		)
		(fp_line
			(start -19.12493 -1.436116)
			(end -20.313904 -2.576576)
			(stroke
				(width 0.1)
				(type default)
			)
			(layer "B.SilkS")
		)
		(fp_line
			(start -19.12493 -1.436116)
			(end -20.313904 -2.576576)
			(stroke
				(width 0.1)
				(type default)
			)
			(layer "B.SilkS")
		)
		(fp_line
			(start -19.116802 -2.178304)
			(end -20.4724 -3.479038)
			(stroke
				(width 0.1)
				(type default)
			)
			(layer "B.SilkS")
		)
		(fp_line
			(start -19.116802 -2.178304)
			(end -20.4724 -3.479038)
			(stroke
				(width 0.1)
				(type default)
			)
			(layer "B.SilkS")
		)
		(fp_line
			(start -19.116802 -2.178304)
			(end -19.10461 -2.108962)
			(stroke
				(width 0.1)
				(type default)
			)
			(layer "B.SilkS")
		)
		(fp_line
			(start -19.116802 -2.178304)
			(end -19.10461 -2.108962)
			(stroke
				(width 0.1)
				(type default)
			)
			(layer "B.SilkS")
		)
		(fp_line
			(start -19.112738 -1.48209)
			(end -20.32635 -2.646172)
			(stroke
				(width 0.1)
				(type default)
			)
			(layer "B.SilkS")
		)
		(fp_line
			(start -19.112738 -1.48209)
			(end -20.32635 -2.646172)
			(stroke
				(width 0.1)
				(type default)
			)
			(layer "B.SilkS")
		)
		(fp_line
			(start -19.10842 -5.171694)
			(end -19.168872 -5.171694)
			(stroke
				(width 0.1)
				(type default)
			)
			(layer "B.SilkS")
		)
		(fp_line
			(start -19.10842 -5.171694)
			(end -19.168872 -5.171694)
			(stroke
				(width 0.1)
				(type default)
			)
			(layer "B.SilkS")
		)
		(fp_line
			(start -19.10842 -5.171694)
			(end -18.885916 -4.95808)
			(stroke
				(width 0.1)
				(type default)
			)
			(layer "B.SilkS")
		)
		(fp_line
			(start -19.10842 -5.171694)
			(end -18.885916 -4.95808)
			(stroke
				(width 0.1)
				(type default)
			)
			(layer "B.SilkS")
		)
		(fp_line
			(start -19.10461 -2.108962)
			(end -20.460462 -3.409442)
			(stroke
				(width 0.1)
				(type default)
			)
			(layer "B.SilkS")
		)
		(fp_line
			(start -19.10461 -2.108962)
			(end -20.460462 -3.409442)
			(stroke
				(width 0.1)
				(type default)
			)
			(layer "B.SilkS")
		)
		(fp_line
			(start -19.100292 -1.528064)
			(end -20.338288 -2.715768)
			(stroke
				(width 0.1)
				(type default)
			)
			(layer "B.SilkS")
		)
		(fp_line
			(start -19.100292 -1.528064)
			(end -20.338288 -2.715768)
			(stroke
				(width 0.1)
				(type default)
			)
			(layer "B.SilkS")
		)
		(fp_line
			(start -19.095974 -2.043176)
			(end -20.44827 -3.340354)
			(stroke
				(width 0.1)
				(type default)
			)
			(layer "B.SilkS")
		)
		(fp_line
			(start -19.095974 -2.043176)
			(end -20.44827 -3.340354)
			(stroke
				(width 0.1)
				(type default)
			)
			(layer "B.SilkS")
		)
		(fp_line
			(start -19.089878 -1.979676)
			(end -20.435824 -3.270758)
			(stroke
				(width 0.1)
				(type default)
			)
			(layer "B.SilkS")
		)
		(fp_line
			(start -19.089878 -1.979676)
			(end -20.435824 -3.270758)
			(stroke
				(width 0.1)
				(type default)
			)
			(layer "B.SilkS")
		)
		(fp_line
			(start -19.089624 -1.575308)
			(end -20.35048 -2.784856)
			(stroke
				(width 0.1)
				(type default)
			)
			(layer "B.SilkS")
		)
		(fp_line
			(start -19.089624 -1.575308)
			(end -20.35048 -2.784856)
			(stroke
				(width 0.1)
				(type default)
			)
			(layer "B.SilkS")
		)
		(fp_line
			(start -19.086068 -1.62941)
			(end -20.362926 -2.854198)
			(stroke
				(width 0.1)
				(type default)
			)
			(layer "B.SilkS")
		)
		(fp_line
			(start -19.086068 -1.62941)
			(end -20.362926 -2.854198)
			(stroke
				(width 0.1)
				(type default)
			)
			(layer "B.SilkS")
		)
		(fp_line
			(start -19.08429 -4.109466)
			(end -20.886166 -5.837936)
			(stroke
				(width 0.1)
				(type default)
			)
			(layer "B.SilkS")
		)
		(fp_line
			(start -19.08429 -4.109466)
			(end -20.886166 -5.837936)
			(stroke
				(width 0.1)
				(type default)
			)
			(layer "B.SilkS")
		)
		(fp_line
			(start -19.08429 -4.109466)
			(end -19.144234 -4.109466)
			(stroke
				(width 0.1)
				(type default)
			)
			(layer "B.SilkS")
		)
		(fp_line
			(start -19.08429 -4.109466)
			(end -19.144234 -4.109466)
			(stroke
				(width 0.1)
				(type default)
			)
			(layer "B.SilkS")
		)
		(fp_line
			(start -19.083274 -1.915668)
			(end -20.423886 -3.201416)
			(stroke
				(width 0.1)
				(type default)
			)
			(layer "B.SilkS")
		)
		(fp_line
			(start -19.083274 -1.915668)
			(end -20.423886 -3.201416)
			(stroke
				(width 0.1)
				(type default)
			)
			(layer "B.SilkS")
		)
		(fp_line
			(start -19.082258 -1.683512)
			(end -20.374864 -2.923794)
			(stroke
				(width 0.1)
				(type default)
			)
			(layer "B.SilkS")
		)
		(fp_line
			(start -19.082258 -1.683512)
			(end -20.374864 -2.923794)
			(stroke
				(width 0.1)
				(type default)
			)
			(layer "B.SilkS")
		)
		(fp_line
			(start -19.078448 -1.737868)
			(end -20.38731 -2.99339)
			(stroke
				(width 0.1)
				(type default)
			)
			(layer "B.SilkS")
		)
		(fp_line
			(start -19.078448 -1.737868)
			(end -20.38731 -2.99339)
			(stroke
				(width 0.1)
				(type default)
			)
			(layer "B.SilkS")
		)
		(fp_line
			(start -19.077178 -1.851914)
			(end -20.41144 -3.13182)
			(stroke
				(width 0.1)
				(type default)
			)
			(layer "B.SilkS")
		)
		(fp_line
			(start -19.077178 -1.851914)
			(end -20.41144 -3.13182)
			(stroke
				(width 0.1)
				(type default)
			)
			(layer "B.SilkS")
		)
		(fp_line
			(start -19.074638 -1.79197)
			(end -20.399248 -3.062478)
			(stroke
				(width 0.1)
				(type default)
			)
			(layer "B.SilkS")
		)
		(fp_line
			(start -19.074638 -1.79197)
			(end -20.399248 -3.062478)
			(stroke
				(width 0.1)
				(type default)
			)
			(layer "B.SilkS")
		)
		(fp_line
			(start -19.048476 -5.171694)
			(end -19.10842 -5.171694)
			(stroke
				(width 0.1)
				(type default)
			)
			(layer "B.SilkS")
		)
		(fp_line
			(start -19.048476 -5.171694)
			(end -19.10842 -5.171694)
			(stroke
				(width 0.1)
				(type default)
			)
			(layer "B.SilkS")
		)
		(fp_line
			(start -19.048476 -5.171694)
			(end -18.988278 -5.171694)
			(stroke
				(width 0.1)
				(type default)
			)
			(layer "B.SilkS")
		)
		(fp_line
			(start -19.048476 -5.171694)
			(end -18.988278 -5.171694)
			(stroke
				(width 0.1)
				(type default)
			)
			(layer "B.SilkS")
		)
		(fp_line
			(start -19.024092 -4.109466)
			(end -20.898104 -5.907278)
			(stroke
				(width 0.1)
				(type default)
			)
			(layer "B.SilkS")
		)
		(fp_line
			(start -19.024092 -4.109466)
			(end -20.898104 -5.907278)
			(stroke
				(width 0.1)
				(type default)
			)
			(layer "B.SilkS")
		)
		(fp_line
			(start -19.024092 -4.109466)
			(end -19.08429 -4.109466)
			(stroke
				(width 0.1)
				(type default)
			)
			(layer "B.SilkS")
		)
		(fp_line
			(start -19.024092 -4.109466)
			(end -19.08429 -4.109466)
			(stroke
				(width 0.1)
				(type default)
			)
			(layer "B.SilkS")
		)
		(fp_line
			(start -18.988278 -5.171694)
			(end -18.928334 -5.171694)
			(stroke
				(width 0.1)
				(type default)
			)
			(layer "B.SilkS")
		)
		(fp_line
			(start -18.988278 -5.171694)
			(end -18.928334 -5.171694)
			(stroke
				(width 0.1)
				(type default)
			)
			(layer "B.SilkS")
		)
		(fp_line
			(start -18.964148 -4.109466)
			(end -20.91055 -5.976874)
			(stroke
				(width 0.1)
				(type default)
			)
			(layer "B.SilkS")
		)
		(fp_line
			(start -18.964148 -4.109466)
			(end -20.91055 -5.976874)
			(stroke
				(width 0.1)
				(type default)
			)
			(layer "B.SilkS")
		)
		(fp_line
			(start -18.964148 -4.109466)
			(end -19.024092 -4.109466)
			(stroke
				(width 0.1)
				(type default)
			)
			(layer "B.SilkS")
		)
		(fp_line
			(start -18.964148 -4.109466)
			(end -19.024092 -4.109466)
			(stroke
				(width 0.1)
				(type default)
			)
			(layer "B.SilkS")
		)
		(fp_line
			(start -18.923508 -5.171694)
			(end -18.928334 -5.171694)
			(stroke
				(width 0.1)
				(type default)
			)
			(layer "B.SilkS")
		)
		(fp_line
			(start -18.923508 -5.171694)
			(end -18.928334 -5.171694)
			(stroke
				(width 0.1)
				(type default)
			)
			(layer "B.SilkS")
		)
		(fp_line
			(start -18.922492 -5.166106)
			(end -18.928334 -5.171694)
			(stroke
				(width 0.1)
				(type default)
			)
			(layer "B.SilkS")
		)
		(fp_line
			(start -18.922492 -5.166106)
			(end -18.928334 -5.171694)
			(stroke
				(width 0.1)
				(type default)
			)
			(layer "B.SilkS")
		)
		(fp_line
			(start -18.922492 -5.166106)
			(end -18.923508 -5.171694)
			(stroke
				(width 0.1)
				(type default)
			)
			(layer "B.SilkS")
		)
		(fp_line
			(start -18.922492 -5.166106)
			(end -18.923508 -5.171694)
			(stroke
				(width 0.1)
				(type default)
			)
			(layer "B.SilkS")
		)
		(fp_line
			(start -18.9103 -5.097018)
			(end -18.988278 -5.171694)
			(stroke
				(width 0.1)
				(type default)
			)
			(layer "B.SilkS")
		)
		(fp_line
			(start -18.9103 -5.097018)
			(end -18.988278 -5.171694)
			(stroke
				(width 0.1)
				(type default)
			)
			(layer "B.SilkS")
		)
		(fp_line
			(start -18.9103 -5.097018)
			(end -18.922492 -5.166106)
			(stroke
				(width 0.1)
				(type default)
			)
			(layer "B.SilkS")
		)
		(fp_line
			(start -18.9103 -5.097018)
			(end -18.922492 -5.166106)
			(stroke
				(width 0.1)
				(type default)
			)
			(layer "B.SilkS")
		)
		(fp_line
			(start -18.90395 -4.109466)
			(end -20.922742 -6.04647)
			(stroke
				(width 0.1)
				(type default)
			)
			(layer "B.SilkS")
		)
		(fp_line
			(start -18.90395 -4.109466)
			(end -20.922742 -6.04647)
			(stroke
				(width 0.1)
				(type default)
			)
			(layer "B.SilkS")
		)
		(fp_line
			(start -18.90395 -4.109466)
			(end -18.964148 -4.109466)
			(stroke
				(width 0.1)
				(type default)
			)
			(layer "B.SilkS")
		)
		(fp_line
			(start -18.90395 -4.109466)
			(end -18.964148 -4.109466)
			(stroke
				(width 0.1)
				(type default)
			)
			(layer "B.SilkS")
		)
		(fp_line
			(start -18.898108 -5.027422)
			(end -19.048476 -5.171694)
			(stroke
				(width 0.1)
				(type default)
			)
			(layer "B.SilkS")
		)
		(fp_line
			(start -18.898108 -5.027422)
			(end -19.048476 -5.171694)
			(stroke
				(width 0.1)
				(type default)
			)
			(layer "B.SilkS")
		)
		(fp_line
			(start -18.898108 -5.027422)
			(end -18.9103 -5.097018)
			(stroke
				(width 0.1)
				(type default)
			)
			(layer "B.SilkS")
		)
		(fp_line
			(start -18.898108 -5.027422)
			(end -18.9103 -5.097018)
			(stroke
				(width 0.1)
				(type default)
			)
			(layer "B.SilkS")
		)
		(fp_line
			(start -18.898108 -5.027422)
			(end -18.885916 -4.95808)
			(stroke
				(width 0.1)
				(type default)
			)
			(layer "B.SilkS")
		)
		(fp_line
			(start -18.898108 -5.027422)
			(end -18.885916 -4.95808)
			(stroke
				(width 0.1)
				(type default)
			)
			(layer "B.SilkS")
		)
		(fp_line
			(start -18.885916 -4.95808)
			(end -18.873978 -4.888484)
			(stroke
				(width 0.1)
				(type default)
			)
			(layer "B.SilkS")
		)
		(fp_line
			(start -18.885916 -4.95808)
			(end -18.873978 -4.888484)
			(stroke
				(width 0.1)
				(type default)
			)
			(layer "B.SilkS")
		)
		(fp_line
			(start -18.873978 -4.888484)
			(end -19.168872 -5.171694)
			(stroke
				(width 0.1)
				(type default)
			)
			(layer "B.SilkS")
		)
		(fp_line
			(start -18.873978 -4.888484)
			(end -19.168872 -5.171694)
			(stroke
				(width 0.1)
				(type default)
			)
			(layer "B.SilkS")
		)
		(fp_line
			(start -18.861532 -4.819142)
			(end -19.22907 -5.171694)
			(stroke
				(width 0.1)
				(type default)
			)
			(layer "B.SilkS")
		)
		(fp_line
			(start -18.861532 -4.819142)
			(end -19.22907 -5.171694)
			(stroke
				(width 0.1)
				(type default)
			)
			(layer "B.SilkS")
		)
		(fp_line
			(start -18.861532 -4.819142)
			(end -18.873978 -4.888484)
			(stroke
				(width 0.1)
				(type default)
			)
			(layer "B.SilkS")
		)
		(fp_line
			(start -18.861532 -4.819142)
			(end -18.873978 -4.888484)
			(stroke
				(width 0.1)
				(type default)
			)
			(layer "B.SilkS")
		)
		(fp_line
			(start -18.84934 -4.7498)
			(end -19.289014 -5.171694)
			(stroke
				(width 0.1)
				(type default)
			)
			(layer "B.SilkS")
		)
		(fp_line
			(start -18.84934 -4.7498)
			(end -19.289014 -5.171694)
			(stroke
				(width 0.1)
				(type default)
			)
			(layer "B.SilkS")
		)
		(fp_line
			(start -18.84934 -4.7498)
			(end -18.861532 -4.819142)
			(stroke
				(width 0.1)
				(type default)
			)
			(layer "B.SilkS")
		)
		(fp_line
			(start -18.84934 -4.7498)
			(end -18.861532 -4.819142)
			(stroke
				(width 0.1)
				(type default)
			)
			(layer "B.SilkS")
		)
		(fp_line
			(start -18.843498 -4.109466)
			(end -20.93468 -6.115558)
			(stroke
				(width 0.1)
				(type default)
			)
			(layer "B.SilkS")
		)
		(fp_line
			(start -18.843498 -4.109466)
			(end -20.93468 -6.115558)
			(stroke
				(width 0.1)
				(type default)
			)
			(layer "B.SilkS")
		)
		(fp_line
			(start -18.843498 -4.109466)
			(end -18.90395 -4.109466)
			(stroke
				(width 0.1)
				(type default)
			)
			(layer "B.SilkS")
		)
		(fp_line
			(start -18.843498 -4.109466)
			(end -18.90395 -4.109466)
			(stroke
				(width 0.1)
				(type default)
			)
			(layer "B.SilkS")
		)
		(fp_line
			(start -18.836894 -4.680458)
			(end -19.349212 -5.171694)
			(stroke
				(width 0.1)
				(type default)
			)
			(layer "B.SilkS")
		)
		(fp_line
			(start -18.836894 -4.680458)
			(end -19.349212 -5.171694)
			(stroke
				(width 0.1)
				(type default)
			)
			(layer "B.SilkS")
		)
		(fp_line
			(start -18.836894 -4.680458)
			(end -18.84934 -4.7498)
			(stroke
				(width 0.1)
				(type default)
			)
			(layer "B.SilkS")
		)
		(fp_line
			(start -18.836894 -4.680458)
			(end -18.84934 -4.7498)
			(stroke
				(width 0.1)
				(type default)
			)
			(layer "B.SilkS")
		)
		(fp_line
			(start -18.824956 -4.610862)
			(end -19.409664 -5.171694)
			(stroke
				(width 0.1)
				(type default)
			)
			(layer "B.SilkS")
		)
		(fp_line
			(start -18.824956 -4.610862)
			(end -19.409664 -5.171694)
			(stroke
				(width 0.1)
				(type default)
			)
			(layer "B.SilkS")
		)
		(fp_line
			(start -18.824956 -4.610862)
			(end -18.836894 -4.680458)
			(stroke
				(width 0.1)
				(type default)
			)
			(layer "B.SilkS")
		)
		(fp_line
			(start -18.824956 -4.610862)
			(end -18.836894 -4.680458)
			(stroke
				(width 0.1)
				(type default)
			)
			(layer "B.SilkS")
		)
		(fp_line
			(start -18.81251 -4.54152)
			(end -19.469608 -5.171694)
			(stroke
				(width 0.1)
				(type default)
			)
			(layer "B.SilkS")
		)
		(fp_line
			(start -18.81251 -4.54152)
			(end -19.469608 -5.171694)
			(stroke
				(width 0.1)
				(type default)
			)
			(layer "B.SilkS")
		)
		(fp_line
			(start -18.81251 -4.54152)
			(end -18.824956 -4.610862)
			(stroke
				(width 0.1)
				(type default)
			)
			(layer "B.SilkS")
		)
		(fp_line
			(start -18.81251 -4.54152)
			(end -18.824956 -4.610862)
			(stroke
				(width 0.1)
				(type default)
			)
			(layer "B.SilkS")
		)
		(fp_line
			(start -18.800572 -4.472178)
			(end -19.529806 -5.171694)
			(stroke
				(width 0.1)
				(type default)
			)
			(layer "B.SilkS")
		)
		(fp_line
			(start -18.800572 -4.472178)
			(end -19.529806 -5.171694)
			(stroke
				(width 0.1)
				(type default)
			)
			(layer "B.SilkS")
		)
		(fp_line
			(start -18.800572 -4.472178)
			(end -18.81251 -4.54152)
			(stroke
				(width 0.1)
				(type default)
			)
			(layer "B.SilkS")
		)
		(fp_line
			(start -18.800572 -4.472178)
			(end -18.81251 -4.54152)
			(stroke
				(width 0.1)
				(type default)
			)
			(layer "B.SilkS")
		)
		(fp_line
			(start -18.78838 -4.402836)
			(end -19.58975 -5.171694)
			(stroke
				(width 0.1)
				(type default)
			)
			(layer "B.SilkS")
		)
		(fp_line
			(start -18.78838 -4.402836)
			(end -19.58975 -5.171694)
			(stroke
				(width 0.1)
				(type default)
			)
			(layer "B.SilkS")
		)
		(fp_line
			(start -18.78838 -4.402836)
			(end -18.800572 -4.472178)
			(stroke
				(width 0.1)
				(type default)
			)
			(layer "B.SilkS")
		)
		(fp_line
			(start -18.78838 -4.402836)
			(end -18.800572 -4.472178)
			(stroke
				(width 0.1)
				(type default)
			)
			(layer "B.SilkS")
		)
		(fp_line
			(start -18.783554 -4.109466)
			(end -20.947126 -6.1849)
			(stroke
				(width 0.1)
				(type default)
			)
			(layer "B.SilkS")
		)
		(fp_line
			(start -18.783554 -4.109466)
			(end -20.947126 -6.1849)
			(stroke
				(width 0.1)
				(type default)
			)
			(layer "B.SilkS")
		)
		(fp_line
			(start -18.783554 -4.109466)
			(end -18.843498 -4.109466)
			(stroke
				(width 0.1)
				(type default)
			)
			(layer "B.SilkS")
		)
		(fp_line
			(start -18.783554 -4.109466)
			(end -18.843498 -4.109466)
			(stroke
				(width 0.1)
				(type default)
			)
			(layer "B.SilkS")
		)
		(fp_line
			(start -18.775934 -4.33324)
			(end -18.78838 -4.402836)
			(stroke
				(width 0.1)
				(type default)
			)
			(layer "B.SilkS")
		)
		(fp_line
			(start -18.775934 -4.33324)
			(end -18.78838 -4.402836)
			(stroke
				(width 0.1)
				(type default)
			)
			(layer "B.SilkS")
		)
		(fp_line
			(start -18.775934 -4.33324)
			(end -18.763996 -4.263898)
			(stroke
				(width 0.1)
				(type default)
			)
			(layer "B.SilkS")
		)
		(fp_line
			(start -18.775934 -4.33324)
			(end -18.763996 -4.263898)
			(stroke
				(width 0.1)
				(type default)
			)
			(layer "B.SilkS")
		)
		(fp_line
			(start -18.763996 -4.263898)
			(end -18.75155 -4.194556)
			(stroke
				(width 0.1)
				(type default)
			)
			(layer "B.SilkS")
		)
		(fp_line
			(start -18.763996 -4.263898)
			(end -18.75155 -4.194556)
			(stroke
				(width 0.1)
				(type default)
			)
			(layer "B.SilkS")
		)
		(fp_line
			(start -18.75155 -4.194556)
			(end -18.739612 -4.12496)
			(stroke
				(width 0.1)
				(type default)
			)
			(layer "B.SilkS")
		)
		(fp_line
			(start -18.75155 -4.194556)
			(end -18.739612 -4.12496)
			(stroke
				(width 0.1)
				(type default)
			)
			(layer "B.SilkS")
		)
		(fp_line
			(start -18.739612 -4.12496)
			(end -20.959318 -6.254496)
			(stroke
				(width 0.1)
				(type default)
			)
			(layer "B.SilkS")
		)
		(fp_line
			(start -18.739612 -4.12496)
			(end -20.959318 -6.254496)
			(stroke
				(width 0.1)
				(type default)
			)
			(layer "B.SilkS")
		)
		(fp_line
			(start -18.739612 -4.12496)
			(end -18.736818 -4.109466)
			(stroke
				(width 0.1)
				(type default)
			)
			(layer "B.SilkS")
		)
		(fp_line
			(start -18.739612 -4.12496)
			(end -18.736818 -4.109466)
			(stroke
				(width 0.1)
				(type default)
			)
			(layer "B.SilkS")
		)
		(fp_line
			(start -18.736818 -4.109466)
			(end -18.783554 -4.109466)
			(stroke
				(width 0.1)
				(type default)
			)
			(layer "B.SilkS")
		)
		(fp_line
			(start -18.736818 -4.109466)
			(end -18.783554 -4.109466)
			(stroke
				(width 0.1)
				(type default)
			)
			(layer "B.SilkS")
		)
		(fp_line
			(start -18.137632 -3.836416)
			(end -16.83258 -2.58445)
			(stroke
				(width 0.1)
				(type default)
			)
			(layer "B.SilkS")
		)
		(fp_line
			(start -18.137632 -3.836416)
			(end -16.83258 -2.58445)
			(stroke
				(width 0.1)
				(type default)
			)
			(layer "B.SilkS")
		)
		(fp_line
			(start -18.107914 -4.26974)
			(end -16.930624 -3.139694)
			(stroke
				(width 0.1)
				(type default)
			)
			(layer "B.SilkS")
		)
		(fp_line
			(start -18.107914 -4.26974)
			(end -16.930624 -3.139694)
			(stroke
				(width 0.1)
				(type default)
			)
			(layer "B.SilkS")
		)
		(fp_line
			(start -18.099532 -4.318762)
			(end -16.942308 -3.208782)
			(stroke
				(width 0.1)
				(type default)
			)
			(layer "B.SilkS")
		)
		(fp_line
			(start -18.099532 -4.318762)
			(end -16.942308 -3.208782)
			(stroke
				(width 0.1)
				(type default)
			)
			(layer "B.SilkS")
		)
		(fp_line
			(start -18.090388 -4.368038)
			(end -16.950436 -3.274568)
			(stroke
				(width 0.1)
				(type default)
			)
			(layer "B.SilkS")
		)
		(fp_line
			(start -18.090388 -4.368038)
			(end -16.950436 -3.274568)
			(stroke
				(width 0.1)
				(type default)
			)
			(layer "B.SilkS")
		)
		(fp_line
			(start -18.081752 -4.417314)
			(end -16.959326 -3.340608)
			(stroke
				(width 0.1)
				(type default)
			)
			(layer "B.SilkS")
		)
		(fp_line
			(start -18.081752 -4.417314)
			(end -16.959326 -3.340608)
			(stroke
				(width 0.1)
				(type default)
			)
			(layer "B.SilkS")
		)
		(fp_line
			(start -18.079212 -3.260598)
			(end -18.066766 -3.191002)
			(stroke
				(width 0.1)
				(type default)
			)
			(layer "B.SilkS")
		)
		(fp_line
			(start -18.079212 -3.260598)
			(end -18.066766 -3.191002)
			(stroke
				(width 0.1)
				(type default)
			)
			(layer "B.SilkS")
		)
		(fp_line
			(start -18.070068 -4.464304)
			(end -16.967708 -3.406648)
			(stroke
				(width 0.1)
				(type default)
			)
			(layer "B.SilkS")
		)
		(fp_line
			(start -18.070068 -4.464304)
			(end -16.967708 -3.406648)
			(stroke
				(width 0.1)
				(type default)
			)
			(layer "B.SilkS")
		)
		(fp_line
			(start -18.066766 -3.191002)
			(end -18.054574 -3.121914)
			(stroke
				(width 0.1)
				(type default)
			)
			(layer "B.SilkS")
		)
		(fp_line
			(start -18.066766 -3.191002)
			(end -18.054574 -3.121914)
			(stroke
				(width 0.1)
				(type default)
			)
			(layer "B.SilkS")
		)
		(fp_line
			(start -18.054574 -3.121914)
			(end -18.042636 -3.052572)
			(stroke
				(width 0.1)
				(type default)
			)
			(layer "B.SilkS")
		)
		(fp_line
			(start -18.054574 -3.121914)
			(end -18.042636 -3.052572)
			(stroke
				(width 0.1)
				(type default)
			)
			(layer "B.SilkS")
		)
		(fp_line
			(start -18.052796 -4.505198)
			(end -16.975582 -3.471672)
			(stroke
				(width 0.1)
				(type default)
			)
			(layer "B.SilkS")
		)
		(fp_line
			(start -18.052796 -4.505198)
			(end -16.975582 -3.471672)
			(stroke
				(width 0.1)
				(type default)
			)
			(layer "B.SilkS")
		)
		(fp_line
			(start -18.042636 -3.052572)
			(end -18.03019 -2.982976)
			(stroke
				(width 0.1)
				(type default)
			)
			(layer "B.SilkS")
		)
		(fp_line
			(start -18.042636 -3.052572)
			(end -18.03019 -2.982976)
			(stroke
				(width 0.1)
				(type default)
			)
			(layer "B.SilkS")
		)
		(fp_line
			(start -18.035778 -4.546346)
			(end -16.97609 -3.529838)
			(stroke
				(width 0.1)
				(type default)
			)
			(layer "B.SilkS")
		)
		(fp_line
			(start -18.035778 -4.546346)
			(end -16.97609 -3.529838)
			(stroke
				(width 0.1)
				(type default)
			)
			(layer "B.SilkS")
		)
		(fp_line
			(start -18.03019 -2.982976)
			(end -18.017998 -2.913634)
			(stroke
				(width 0.1)
				(type default)
			)
			(layer "B.SilkS")
		)
		(fp_line
			(start -18.03019 -2.982976)
			(end -18.017998 -2.913634)
			(stroke
				(width 0.1)
				(type default)
			)
			(layer "B.SilkS")
		)
		(fp_line
			(start -18.017998 -4.58724)
			(end -16.976598 -3.588258)
			(stroke
				(width 0.1)
				(type default)
			)
			(layer "B.SilkS")
		)
		(fp_line
			(start -18.017998 -4.58724)
			(end -16.976598 -3.588258)
			(stroke
				(width 0.1)
				(type default)
			)
			(layer "B.SilkS")
		)
		(fp_line
			(start -18.017998 -2.913634)
			(end -18.00606 -2.844292)
			(stroke
				(width 0.1)
				(type default)
			)
			(layer "B.SilkS")
		)
		(fp_line
			(start -18.017998 -2.913634)
			(end -18.00606 -2.844292)
			(stroke
				(width 0.1)
				(type default)
			)
			(layer "B.SilkS")
		)
		(fp_line
			(start -18.00606 -2.844292)
			(end -17.993614 -2.77495)
			(stroke
				(width 0.1)
				(type default)
			)
			(layer "B.SilkS")
		)
		(fp_line
			(start -18.00606 -2.844292)
			(end -17.993614 -2.77495)
			(stroke
				(width 0.1)
				(type default)
			)
			(layer "B.SilkS")
		)
		(fp_line
			(start -18.000472 -4.628388)
			(end -16.97736 -3.646424)
			(stroke
				(width 0.1)
				(type default)
			)
			(layer "B.SilkS")
		)
		(fp_line
			(start -18.000472 -4.628388)
			(end -16.97736 -3.646424)
			(stroke
				(width 0.1)
				(type default)
			)
			(layer "B.SilkS")
		)
		(fp_line
			(start -17.993614 -2.77495)
			(end -17.981676 -2.705608)
			(stroke
				(width 0.1)
				(type default)
			)
			(layer "B.SilkS")
		)
		(fp_line
			(start -17.993614 -2.77495)
			(end -17.981676 -2.705608)
			(stroke
				(width 0.1)
				(type default)
			)
			(layer "B.SilkS")
		)
		(fp_line
			(start -17.9832 -4.669282)
			(end -16.974566 -3.701542)
			(stroke
				(width 0.1)
				(type default)
			)
			(layer "B.SilkS")
		)
		(fp_line
			(start -17.9832 -4.669282)
			(end -16.974566 -3.701542)
			(stroke
				(width 0.1)
				(type default)
			)
			(layer "B.SilkS")
		)
		(fp_line
			(start -17.981676 -2.705608)
			(end -17.969484 -2.636012)
			(stroke
				(width 0.1)
				(type default)
			)
			(layer "B.SilkS")
		)
		(fp_line
			(start -17.981676 -2.705608)
			(end -17.969484 -2.636012)
			(stroke
				(width 0.1)
				(type default)
			)
			(layer "B.SilkS")
		)
		(fp_line
			(start -17.969484 -2.636012)
			(end -17.957038 -2.56667)
			(stroke
				(width 0.1)
				(type default)
			)
			(layer "B.SilkS")
		)
		(fp_line
			(start -17.969484 -2.636012)
			(end -17.957038 -2.56667)
			(stroke
				(width 0.1)
				(type default)
			)
			(layer "B.SilkS")
		)
		(fp_line
			(start -17.966182 -4.710176)
			(end -16.966438 -3.751326)
			(stroke
				(width 0.1)
				(type default)
			)
			(layer "B.SilkS")
		)
		(fp_line
			(start -17.966182 -4.710176)
			(end -16.966438 -3.751326)
			(stroke
				(width 0.1)
				(type default)
			)
			(layer "B.SilkS")
		)
		(fp_line
			(start -17.957038 -2.56667)
			(end -17.9451 -2.497328)
			(stroke
				(width 0.1)
				(type default)
			)
			(layer "B.SilkS")
		)
		(fp_line
			(start -17.957038 -2.56667)
			(end -17.9451 -2.497328)
			(stroke
				(width 0.1)
				(type default)
			)
			(layer "B.SilkS")
		)
		(fp_line
			(start -17.9451 -2.497328)
			(end -17.932908 -2.427732)
			(stroke
				(width 0.1)
				(type default)
			)
			(layer "B.SilkS")
		)
		(fp_line
			(start -17.9451 -2.497328)
			(end -17.932908 -2.427732)
			(stroke
				(width 0.1)
				(type default)
			)
			(layer "B.SilkS")
		)
		(fp_line
			(start -17.944846 -4.748022)
			(end -16.958056 -3.80111)
			(stroke
				(width 0.1)
				(type default)
			)
			(layer "B.SilkS")
		)
		(fp_line
			(start -17.944846 -4.748022)
			(end -16.958056 -3.80111)
			(stroke
				(width 0.1)
				(type default)
			)
			(layer "B.SilkS")
		)
		(fp_line
			(start -17.932908 -2.427732)
			(end -17.920716 -2.35839)
			(stroke
				(width 0.1)
				(type default)
			)
			(layer "B.SilkS")
		)
		(fp_line
			(start -17.932908 -2.427732)
			(end -17.920716 -2.35839)
			(stroke
				(width 0.1)
				(type default)
			)
			(layer "B.SilkS")
		)
		(fp_line
			(start -17.920716 -2.35839)
			(end -17.908524 -2.289048)
			(stroke
				(width 0.1)
				(type default)
			)
			(layer "B.SilkS")
		)
		(fp_line
			(start -17.920716 -2.35839)
			(end -17.908524 -2.289048)
			(stroke
				(width 0.1)
				(type default)
			)
			(layer "B.SilkS")
		)
		(fp_line
			(start -17.91843 -4.780534)
			(end -16.949674 -3.850894)
			(stroke
				(width 0.1)
				(type default)
			)
			(layer "B.SilkS")
		)
		(fp_line
			(start -17.91843 -4.780534)
			(end -16.949674 -3.850894)
			(stroke
				(width 0.1)
				(type default)
			)
			(layer "B.SilkS")
		)
		(fp_line
			(start -17.908524 -2.289048)
			(end -17.896586 -2.21996)
			(stroke
				(width 0.1)
				(type default)
			)
			(layer "B.SilkS")
		)
		(fp_line
			(start -17.908524 -2.289048)
			(end -17.896586 -2.21996)
			(stroke
				(width 0.1)
				(type default)
			)
			(layer "B.SilkS")
		)
		(fp_line
			(start -17.896586 -2.21996)
			(end -17.88414 -2.150364)
			(stroke
				(width 0.1)
				(type default)
			)
			(layer "B.SilkS")
		)
		(fp_line
			(start -17.896586 -2.21996)
			(end -17.88414 -2.150364)
			(stroke
				(width 0.1)
				(type default)
			)
			(layer "B.SilkS")
		)
		(fp_line
			(start -17.892268 -4.813046)
			(end -16.93291 -3.89255)
			(stroke
				(width 0.1)
				(type default)
			)
			(layer "B.SilkS")
		)
		(fp_line
			(start -17.892268 -4.813046)
			(end -16.93291 -3.89255)
			(stroke
				(width 0.1)
				(type default)
			)
			(layer "B.SilkS")
		)
		(fp_line
			(start -17.88414 -2.150364)
			(end -17.871948 -2.081022)
			(stroke
				(width 0.1)
				(type default)
			)
			(layer "B.SilkS")
		)
		(fp_line
			(start -17.88414 -2.150364)
			(end -17.871948 -2.081022)
			(stroke
				(width 0.1)
				(type default)
			)
			(layer "B.SilkS")
		)
		(fp_line
			(start -17.871948 -2.081022)
			(end -17.86001 -2.011426)
			(stroke
				(width 0.1)
				(type default)
			)
			(layer "B.SilkS")
		)
		(fp_line
			(start -17.871948 -2.081022)
			(end -17.86001 -2.011426)
			(stroke
				(width 0.1)
				(type default)
			)
			(layer "B.SilkS")
		)
		(fp_line
			(start -17.866106 -4.845558)
			(end -16.915384 -3.93319)
			(stroke
				(width 0.1)
				(type default)
			)
			(layer "B.SilkS")
		)
		(fp_line
			(start -17.866106 -4.845558)
			(end -16.915384 -3.93319)
			(stroke
				(width 0.1)
				(type default)
			)
			(layer "B.SilkS")
		)
		(fp_line
			(start -17.86001 -2.011426)
			(end -17.847564 -1.942338)
			(stroke
				(width 0.1)
				(type default)
			)
			(layer "B.SilkS")
		)
		(fp_line
			(start -17.86001 -2.011426)
			(end -17.847564 -1.942338)
			(stroke
				(width 0.1)
				(type default)
			)
			(layer "B.SilkS")
		)
		(fp_line
			(start -17.847564 -1.942338)
			(end -17.835626 -1.872742)
			(stroke
				(width 0.1)
				(type default)
			)
			(layer "B.SilkS")
		)
		(fp_line
			(start -17.847564 -1.942338)
			(end -17.835626 -1.872742)
			(stroke
				(width 0.1)
				(type default)
			)
			(layer "B.SilkS")
		)
		(fp_line
			(start -17.839944 -4.878324)
			(end -16.89735 -3.97383)
			(stroke
				(width 0.1)
				(type default)
			)
			(layer "B.SilkS")
		)
		(fp_line
			(start -17.839944 -4.878324)
			(end -16.89735 -3.97383)
			(stroke
				(width 0.1)
				(type default)
			)
			(layer "B.SilkS")
		)
		(fp_line
			(start -17.835626 -1.872742)
			(end -17.823434 -1.8034)
			(stroke
				(width 0.1)
				(type default)
			)
			(layer "B.SilkS")
		)
		(fp_line
			(start -17.835626 -1.872742)
			(end -17.823434 -1.8034)
			(stroke
				(width 0.1)
				(type default)
			)
			(layer "B.SilkS")
		)
		(fp_line
			(start -17.823434 -1.8034)
			(end -17.810988 -1.734058)
			(stroke
				(width 0.1)
				(type default)
			)
			(layer "B.SilkS")
		)
		(fp_line
			(start -17.823434 -1.8034)
			(end -17.810988 -1.734058)
			(stroke
				(width 0.1)
				(type default)
			)
			(layer "B.SilkS")
		)
		(fp_line
			(start -17.813782 -4.910836)
			(end -16.87322 -4.008882)
			(stroke
				(width 0.1)
				(type default)
			)
			(layer "B.SilkS")
		)
		(fp_line
			(start -17.813782 -4.910836)
			(end -16.87322 -4.008882)
			(stroke
				(width 0.1)
				(type default)
			)
			(layer "B.SilkS")
		)
		(fp_line
			(start -17.810988 -1.734058)
			(end -17.79905 -1.664716)
			(stroke
				(width 0.1)
				(type default)
			)
			(layer "B.SilkS")
		)
		(fp_line
			(start -17.810988 -1.734058)
			(end -17.79905 -1.664716)
			(stroke
				(width 0.1)
				(type default)
			)
			(layer "B.SilkS")
		)
		(fp_line
			(start -17.79905 -1.664716)
			(end -17.786858 -1.595374)
			(stroke
				(width 0.1)
				(type default)
			)
			(layer "B.SilkS")
		)
		(fp_line
			(start -17.79905 -1.664716)
			(end -17.786858 -1.595374)
			(stroke
				(width 0.1)
				(type default)
			)
			(layer "B.SilkS")
		)
		(fp_line
			(start -17.78762 -4.943348)
			(end -16.845788 -4.03987)
			(stroke
				(width 0.1)
				(type default)
			)
			(layer "B.SilkS")
		)
		(fp_line
			(start -17.78762 -4.943348)
			(end -16.845788 -4.03987)
			(stroke
				(width 0.1)
				(type default)
			)
			(layer "B.SilkS")
		)
		(fp_line
			(start -17.786858 -1.595374)
			(end -17.774666 -1.525778)
			(stroke
				(width 0.1)
				(type default)
			)
			(layer "B.SilkS")
		)
		(fp_line
			(start -17.786858 -1.595374)
			(end -17.774666 -1.525778)
			(stroke
				(width 0.1)
				(type default)
			)
			(layer "B.SilkS")
		)
		(fp_line
			(start -17.774666 -1.525778)
			(end -17.762474 -1.456436)
			(stroke
				(width 0.1)
				(type default)
			)
			(layer "B.SilkS")
		)
		(fp_line
			(start -17.774666 -1.525778)
			(end -17.762474 -1.456436)
			(stroke
				(width 0.1)
				(type default)
			)
			(layer "B.SilkS")
		)
		(fp_line
			(start -17.762474 -1.456436)
			(end -17.750536 -1.387348)
			(stroke
				(width 0.1)
				(type default)
			)
			(layer "B.SilkS")
		)
		(fp_line
			(start -17.762474 -1.456436)
			(end -17.750536 -1.387348)
			(stroke
				(width 0.1)
				(type default)
			)
			(layer "B.SilkS")
		)
		(fp_line
			(start -17.757394 -4.971796)
			(end -16.818102 -4.071112)
			(stroke
				(width 0.1)
				(type default)
			)
			(layer "B.SilkS")
		)
		(fp_line
			(start -17.757394 -4.971796)
			(end -16.818102 -4.071112)
			(stroke
				(width 0.1)
				(type default)
			)
			(layer "B.SilkS")
		)
		(fp_line
			(start -17.750536 -1.387348)
			(end -17.73809 -1.317752)
			(stroke
				(width 0.1)
				(type default)
			)
			(layer "B.SilkS")
		)
		(fp_line
			(start -17.750536 -1.387348)
			(end -17.73809 -1.317752)
			(stroke
				(width 0.1)
				(type default)
			)
			(layer "B.SilkS")
		)
		(fp_line
			(start -17.73809 -1.317752)
			(end -17.725898 -1.248156)
			(stroke
				(width 0.1)
				(type default)
			)
			(layer "B.SilkS")
		)
		(fp_line
			(start -17.73809 -1.317752)
			(end -17.725898 -1.248156)
			(stroke
				(width 0.1)
				(type default)
			)
			(layer "B.SilkS")
		)
		(fp_line
			(start -17.725898 -1.248156)
			(end -17.71396 -1.178814)
			(stroke
				(width 0.1)
				(type default)
			)
			(layer "B.SilkS")
		)
		(fp_line
			(start -17.725898 -1.248156)
			(end -17.71396 -1.178814)
			(stroke
				(width 0.1)
				(type default)
			)
			(layer "B.SilkS")
		)
		(fp_line
			(start -17.721834 -4.995672)
			(end -16.785844 -4.097782)
			(stroke
				(width 0.1)
				(type default)
			)
			(layer "B.SilkS")
		)
		(fp_line
			(start -17.721834 -4.995672)
			(end -16.785844 -4.097782)
			(stroke
				(width 0.1)
				(type default)
			)
			(layer "B.SilkS")
		)
		(fp_line
			(start -17.71396 -1.178814)
			(end -17.701514 -1.109472)
			(stroke
				(width 0.1)
				(type default)
			)
			(layer "B.SilkS")
		)
		(fp_line
			(start -17.71396 -1.178814)
			(end -17.701514 -1.109472)
			(stroke
				(width 0.1)
				(type default)
			)
			(layer "B.SilkS")
		)
		(fp_line
			(start -17.701514 -1.109472)
			(end -17.689576 -1.04013)
			(stroke
				(width 0.1)
				(type default)
			)
			(layer "B.SilkS")
		)
		(fp_line
			(start -17.701514 -1.109472)
			(end -17.689576 -1.04013)
			(stroke
				(width 0.1)
				(type default)
			)
			(layer "B.SilkS")
		)
		(fp_line
			(start -17.689576 -1.04013)
			(end -17.677384 -0.970788)
			(stroke
				(width 0.1)
				(type default)
			)
			(layer "B.SilkS")
		)
		(fp_line
			(start -17.689576 -1.04013)
			(end -17.677384 -0.970788)
			(stroke
				(width 0.1)
				(type default)
			)
			(layer "B.SilkS")
		)
		(fp_line
			(start -17.686274 -5.019294)
			(end -16.747998 -4.119118)
			(stroke
				(width 0.1)
				(type default)
			)
			(layer "B.SilkS")
		)
		(fp_line
			(start -17.686274 -5.019294)
			(end -16.747998 -4.119118)
			(stroke
				(width 0.1)
				(type default)
			)
			(layer "B.SilkS")
		)
		(fp_line
			(start -17.677384 -0.970788)
			(end -17.664938 -0.901192)
			(stroke
				(width 0.1)
				(type default)
			)
			(layer "B.SilkS")
		)
		(fp_line
			(start -17.677384 -0.970788)
			(end -17.664938 -0.901192)
			(stroke
				(width 0.1)
				(type default)
			)
			(layer "B.SilkS")
		)
		(fp_line
			(start -17.66189 -0.882904)
			(end -17.664938 -0.901192)
			(stroke
				(width 0.1)
				(type default)
			)
			(layer "B.SilkS")
		)
		(fp_line
			(start -17.66189 -0.882904)
			(end -17.664938 -0.901192)
			(stroke
				(width 0.1)
				(type default)
			)
			(layer "B.SilkS")
		)
		(fp_line
			(start -17.651222 -5.043424)
			(end -16.71066 -4.140962)
			(stroke
				(width 0.1)
				(type default)
			)
			(layer "B.SilkS")
		)
		(fp_line
			(start -17.651222 -5.043424)
			(end -16.71066 -4.140962)
			(stroke
				(width 0.1)
				(type default)
			)
			(layer "B.SilkS")
		)
		(fp_line
			(start -17.645634 -0.882904)
			(end -17.664938 -0.901192)
			(stroke
				(width 0.1)
				(type default)
			)
			(layer "B.SilkS")
		)
		(fp_line
			(start -17.645634 -0.882904)
			(end -17.664938 -0.901192)
			(stroke
				(width 0.1)
				(type default)
			)
			(layer "B.SilkS")
		)
		(fp_line
			(start -17.645634 -0.882904)
			(end -17.66189 -0.882904)
			(stroke
				(width 0.1)
				(type default)
			)
			(layer "B.SilkS")
		)
		(fp_line
			(start -17.645634 -0.882904)
			(end -17.66189 -0.882904)
			(stroke
				(width 0.1)
				(type default)
			)
			(layer "B.SilkS")
		)
		(fp_line
			(start -17.61617 -5.067046)
			(end -16.668242 -4.15798)
			(stroke
				(width 0.1)
				(type default)
			)
			(layer "B.SilkS")
		)
		(fp_line
			(start -17.61617 -5.067046)
			(end -16.668242 -4.15798)
			(stroke
				(width 0.1)
				(type default)
			)
			(layer "B.SilkS")
		)
		(fp_line
			(start -17.58569 -0.882904)
			(end -17.677384 -0.970788)
			(stroke
				(width 0.1)
				(type default)
			)
			(layer "B.SilkS")
		)
		(fp_line
			(start -17.58569 -0.882904)
			(end -17.677384 -0.970788)
			(stroke
				(width 0.1)
				(type default)
			)
			(layer "B.SilkS")
		)
		(fp_line
			(start -17.58569 -0.882904)
			(end -17.645634 -0.882904)
			(stroke
				(width 0.1)
				(type default)
			)
			(layer "B.SilkS")
		)
		(fp_line
			(start -17.58569 -0.882904)
			(end -17.645634 -0.882904)
			(stroke
				(width 0.1)
				(type default)
			)
			(layer "B.SilkS")
		)
		(fp_line
			(start -17.580864 -5.091176)
			(end -16.621252 -4.170426)
			(stroke
				(width 0.1)
				(type default)
			)
			(layer "B.SilkS")
		)
		(fp_line
			(start -17.580864 -5.091176)
			(end -16.621252 -4.170426)
			(stroke
				(width 0.1)
				(type default)
			)
			(layer "B.SilkS")
		)
		(fp_line
			(start -17.545558 -5.115052)
			(end -16.5735 -4.182872)
			(stroke
				(width 0.1)
				(type default)
			)
			(layer "B.SilkS")
		)
		(fp_line
			(start -17.545558 -5.115052)
			(end -16.5735 -4.182872)
			(stroke
				(width 0.1)
				(type default)
			)
			(layer "B.SilkS")
		)
		(fp_line
			(start -17.525746 -0.882904)
			(end -17.689576 -1.04013)
			(stroke
				(width 0.1)
				(type default)
			)
			(layer "B.SilkS")
		)
		(fp_line
			(start -17.525746 -0.882904)
			(end -17.689576 -1.04013)
			(stroke
				(width 0.1)
				(type default)
			)
			(layer "B.SilkS")
		)
		(fp_line
			(start -17.525746 -0.882904)
			(end -17.58569 -0.882904)
			(stroke
				(width 0.1)
				(type default)
			)
			(layer "B.SilkS")
		)
		(fp_line
			(start -17.525746 -0.882904)
			(end -17.58569 -0.882904)
			(stroke
				(width 0.1)
				(type default)
			)
			(layer "B.SilkS")
		)
		(fp_line
			(start -17.50441 -5.13334)
			(end -16.521938 -4.190746)
			(stroke
				(width 0.1)
				(type default)
			)
			(layer "B.SilkS")
		)
		(fp_line
			(start -17.50441 -5.13334)
			(end -16.521938 -4.190746)
			(stroke
				(width 0.1)
				(type default)
			)
			(layer "B.SilkS")
		)
		(fp_line
			(start -17.465294 -0.882904)
			(end -17.701514 -1.109472)
			(stroke
				(width 0.1)
				(type default)
			)
			(layer "B.SilkS")
		)
		(fp_line
			(start -17.465294 -0.882904)
			(end -17.701514 -1.109472)
			(stroke
				(width 0.1)
				(type default)
			)
			(layer "B.SilkS")
		)
		(fp_line
			(start -17.465294 -0.882904)
			(end -17.525746 -0.882904)
			(stroke
				(width 0.1)
				(type default)
			)
			(layer "B.SilkS")
		)
		(fp_line
			(start -17.465294 -0.882904)
			(end -17.525746 -0.882904)
			(stroke
				(width 0.1)
				(type default)
			)
			(layer "B.SilkS")
		)
		(fp_line
			(start -17.45996 -5.148326)
			(end -16.465804 -4.194556)
			(stroke
				(width 0.1)
				(type default)
			)
			(layer "B.SilkS")
		)
		(fp_line
			(start -17.45996 -5.148326)
			(end -16.465804 -4.194556)
			(stroke
				(width 0.1)
				(type default)
			)
			(layer "B.SilkS")
		)
		(fp_line
			(start -17.415002 -5.163058)
			(end -16.40967 -4.198366)
			(stroke
				(width 0.1)
				(type default)
			)
			(layer "B.SilkS")
		)
		(fp_line
			(start -17.415002 -5.163058)
			(end -16.40967 -4.198366)
			(stroke
				(width 0.1)
				(type default)
			)
			(layer "B.SilkS")
		)
		(fp_line
			(start -17.40535 -0.882904)
			(end -17.71396 -1.178814)
			(stroke
				(width 0.1)
				(type default)
			)
			(layer "B.SilkS")
		)
		(fp_line
			(start -17.40535 -0.882904)
			(end -17.71396 -1.178814)
			(stroke
				(width 0.1)
				(type default)
			)
			(layer "B.SilkS")
		)
		(fp_line
			(start -17.40535 -0.882904)
			(end -17.465294 -0.882904)
			(stroke
				(width 0.1)
				(type default)
			)
			(layer "B.SilkS")
		)
		(fp_line
			(start -17.40535 -0.882904)
			(end -17.465294 -0.882904)
			(stroke
				(width 0.1)
				(type default)
			)
			(layer "B.SilkS")
		)
		(fp_line
			(start -17.370044 -5.17779)
			(end -16.347948 -4.197096)
			(stroke
				(width 0.1)
				(type default)
			)
			(layer "B.SilkS")
		)
		(fp_line
			(start -17.370044 -5.17779)
			(end -16.347948 -4.197096)
			(stroke
				(width 0.1)
				(type default)
			)
			(layer "B.SilkS")
		)
		(fp_line
			(start -17.345406 -0.882904)
			(end -17.725898 -1.248156)
			(stroke
				(width 0.1)
				(type default)
			)
			(layer "B.SilkS")
		)
		(fp_line
			(start -17.345406 -0.882904)
			(end -17.725898 -1.248156)
			(stroke
				(width 0.1)
				(type default)
			)
			(layer "B.SilkS")
		)
		(fp_line
			(start -17.345406 -0.882904)
			(end -17.40535 -0.882904)
			(stroke
				(width 0.1)
				(type default)
			)
			(layer "B.SilkS")
		)
		(fp_line
			(start -17.345406 -0.882904)
			(end -17.40535 -0.882904)
			(stroke
				(width 0.1)
				(type default)
			)
			(layer "B.SilkS")
		)
		(fp_line
			(start -17.32534 -5.192522)
			(end -16.283178 -4.192524)
			(stroke
				(width 0.1)
				(type default)
			)
			(layer "B.SilkS")
		)
		(fp_line
			(start -17.32534 -5.192522)
			(end -16.283178 -4.192524)
			(stroke
				(width 0.1)
				(type default)
			)
			(layer "B.SilkS")
		)
		(fp_line
			(start -17.284954 -0.882904)
			(end -17.73809 -1.317752)
			(stroke
				(width 0.1)
				(type default)
			)
			(layer "B.SilkS")
		)
		(fp_line
			(start -17.284954 -0.882904)
			(end -17.73809 -1.317752)
			(stroke
				(width 0.1)
				(type default)
			)
			(layer "B.SilkS")
		)
		(fp_line
			(start -17.284954 -0.882904)
			(end -17.345406 -0.882904)
			(stroke
				(width 0.1)
				(type default)
			)
			(layer "B.SilkS")
		)
		(fp_line
			(start -17.284954 -0.882904)
			(end -17.345406 -0.882904)
			(stroke
				(width 0.1)
				(type default)
			)
			(layer "B.SilkS")
		)
		(fp_line
			(start -17.280636 -5.207254)
			(end -16.218154 -4.187698)
			(stroke
				(width 0.1)
				(type default)
			)
			(layer "B.SilkS")
		)
		(fp_line
			(start -17.280636 -5.207254)
			(end -16.218154 -4.187698)
			(stroke
				(width 0.1)
				(type default)
			)
			(layer "B.SilkS")
		)
		(fp_line
			(start -17.235678 -5.221986)
			(end -16.13789 -4.168648)
			(stroke
				(width 0.1)
				(type default)
			)
			(layer "B.SilkS")
		)
		(fp_line
			(start -17.235678 -5.221986)
			(end -16.13789 -4.168648)
			(stroke
				(width 0.1)
				(type default)
			)
			(layer "B.SilkS")
		)
		(fp_line
			(start -17.224756 -0.882904)
			(end -17.750536 -1.387348)
			(stroke
				(width 0.1)
				(type default)
			)
			(layer "B.SilkS")
		)
		(fp_line
			(start -17.224756 -0.882904)
			(end -17.750536 -1.387348)
			(stroke
				(width 0.1)
				(type default)
			)
			(layer "B.SilkS")
		)
		(fp_line
			(start -17.224756 -0.882904)
			(end -17.284954 -0.882904)
			(stroke
				(width 0.1)
				(type default)
			)
			(layer "B.SilkS")
		)
		(fp_line
			(start -17.224756 -0.882904)
			(end -17.284954 -0.882904)
			(stroke
				(width 0.1)
				(type default)
			)
			(layer "B.SilkS")
		)
		(fp_line
			(start -17.184116 -5.230114)
			(end -16.052292 -4.144264)
			(stroke
				(width 0.1)
				(type default)
			)
			(layer "B.SilkS")
		)
		(fp_line
			(start -17.184116 -5.230114)
			(end -16.052292 -4.144264)
			(stroke
				(width 0.1)
				(type default)
			)
			(layer "B.SilkS")
		)
		(fp_line
			(start -17.164812 -0.882904)
			(end -17.762474 -1.456436)
			(stroke
				(width 0.1)
				(type default)
			)
			(layer "B.SilkS")
		)
		(fp_line
			(start -17.164812 -0.882904)
			(end -17.762474 -1.456436)
			(stroke
				(width 0.1)
				(type default)
			)
			(layer "B.SilkS")
		)
		(fp_line
			(start -17.164812 -0.882904)
			(end -17.224756 -0.882904)
			(stroke
				(width 0.1)
				(type default)
			)
			(layer "B.SilkS")
		)
		(fp_line
			(start -17.164812 -0.882904)
			(end -17.224756 -0.882904)
			(stroke
				(width 0.1)
				(type default)
			)
			(layer "B.SilkS")
		)
		(fp_line
			(start -17.129252 -5.235194)
			(end -15.934944 -4.0894)
			(stroke
				(width 0.1)
				(type default)
			)
			(layer "B.SilkS")
		)
		(fp_line
			(start -17.129252 -5.235194)
			(end -15.934944 -4.0894)
			(stroke
				(width 0.1)
				(type default)
			)
			(layer "B.SilkS")
		)
		(fp_line
			(start -17.10436 -0.882904)
			(end -17.774666 -1.525778)
			(stroke
				(width 0.1)
				(type default)
			)
			(layer "B.SilkS")
		)
		(fp_line
			(start -17.10436 -0.882904)
			(end -17.774666 -1.525778)
			(stroke
				(width 0.1)
				(type default)
			)
			(layer "B.SilkS")
		)
		(fp_line
			(start -17.10436 -0.882904)
			(end -17.164812 -0.882904)
			(stroke
				(width 0.1)
				(type default)
			)
			(layer "B.SilkS")
		)
		(fp_line
			(start -17.10436 -0.882904)
			(end -17.164812 -0.882904)
			(stroke
				(width 0.1)
				(type default)
			)
			(layer "B.SilkS")
		)
		(fp_line
			(start -17.074388 -5.240274)
			(end -14.230858 -2.512314)
			(stroke
				(width 0.1)
				(type default)
			)
			(layer "B.SilkS")
		)
		(fp_line
			(start -17.074388 -5.240274)
			(end -14.230858 -2.512314)
			(stroke
				(width 0.1)
				(type default)
			)
			(layer "B.SilkS")
		)
		(fp_line
			(start -17.044162 -0.882904)
			(end -17.786858 -1.595374)
			(stroke
				(width 0.1)
				(type default)
			)
			(layer "B.SilkS")
		)
		(fp_line
			(start -17.044162 -0.882904)
			(end -17.786858 -1.595374)
			(stroke
				(width 0.1)
				(type default)
			)
			(layer "B.SilkS")
		)
		(fp_line
			(start -17.044162 -0.882904)
			(end -17.10436 -0.882904)
			(stroke
				(width 0.1)
				(type default)
			)
			(layer "B.SilkS")
		)
		(fp_line
			(start -17.044162 -0.882904)
			(end -17.10436 -0.882904)
			(stroke
				(width 0.1)
				(type default)
			)
			(layer "B.SilkS")
		)
		(fp_line
			(start -17.01927 -5.245354)
			(end -14.243304 -2.58191)
			(stroke
				(width 0.1)
				(type default)
			)
			(layer "B.SilkS")
		)
		(fp_line
			(start -17.01927 -5.245354)
			(end -14.243304 -2.58191)
			(stroke
				(width 0.1)
				(type default)
			)
			(layer "B.SilkS")
		)
		(fp_line
			(start -16.984218 -0.882904)
			(end -17.79905 -1.664716)
			(stroke
				(width 0.1)
				(type default)
			)
			(layer "B.SilkS")
		)
		(fp_line
			(start -16.984218 -0.882904)
			(end -17.79905 -1.664716)
			(stroke
				(width 0.1)
				(type default)
			)
			(layer "B.SilkS")
		)
		(fp_line
			(start -16.984218 -0.882904)
			(end -17.044162 -0.882904)
			(stroke
				(width 0.1)
				(type default)
			)
			(layer "B.SilkS")
		)
		(fp_line
			(start -16.984218 -0.882904)
			(end -17.044162 -0.882904)
			(stroke
				(width 0.1)
				(type default)
			)
			(layer "B.SilkS")
		)
		(fp_line
			(start -16.96466 -5.25018)
			(end -14.255496 -2.651506)
			(stroke
				(width 0.1)
				(type default)
			)
			(layer "B.SilkS")
		)
		(fp_line
			(start -16.96466 -5.25018)
			(end -14.255496 -2.651506)
			(stroke
				(width 0.1)
				(type default)
			)
			(layer "B.SilkS")
		)
		(fp_line
			(start -16.930624 -3.139694)
			(end -16.918178 -3.070352)
			(stroke
				(width 0.1)
				(type default)
			)
			(layer "B.SilkS")
		)
		(fp_line
			(start -16.930624 -3.139694)
			(end -16.918178 -3.070352)
			(stroke
				(width 0.1)
				(type default)
			)
			(layer "B.SilkS")
		)
		(fp_line
			(start -16.92402 -0.882904)
			(end -17.810988 -1.734058)
			(stroke
				(width 0.1)
				(type default)
			)
			(layer "B.SilkS")
		)
		(fp_line
			(start -16.92402 -0.882904)
			(end -17.810988 -1.734058)
			(stroke
				(width 0.1)
				(type default)
			)
			(layer "B.SilkS")
		)
		(fp_line
			(start -16.92402 -0.882904)
			(end -16.984218 -0.882904)
			(stroke
				(width 0.1)
				(type default)
			)
			(layer "B.SilkS")
		)
		(fp_line
			(start -16.92402 -0.882904)
			(end -16.984218 -0.882904)
			(stroke
				(width 0.1)
				(type default)
			)
			(layer "B.SilkS")
		)
		(fp_line
			(start -16.918178 -3.070352)
			(end -18.117058 -4.220464)
			(stroke
				(width 0.1)
				(type default)
			)
			(layer "B.SilkS")
		)
		(fp_line
			(start -16.918178 -3.070352)
			(end -18.117058 -4.220464)
			(stroke
				(width 0.1)
				(type default)
			)
			(layer "B.SilkS")
		)
		(fp_line
			(start -16.918178 -3.070352)
			(end -16.905732 -3.000756)
			(stroke
				(width 0.1)
				(type default)
			)
			(layer "B.SilkS")
		)
		(fp_line
			(start -16.918178 -3.070352)
			(end -16.905732 -3.000756)
			(stroke
				(width 0.1)
				(type default)
			)
			(layer "B.SilkS")
		)
		(fp_line
			(start -16.909796 -5.255514)
			(end -14.267434 -2.720594)
			(stroke
				(width 0.1)
				(type default)
			)
			(layer "B.SilkS")
		)
		(fp_line
			(start -16.909796 -5.255514)
			(end -14.267434 -2.720594)
			(stroke
				(width 0.1)
				(type default)
			)
			(layer "B.SilkS")
		)
		(fp_line
			(start -16.905732 -3.000756)
			(end -18.125948 -4.171188)
			(stroke
				(width 0.1)
				(type default)
			)
			(layer "B.SilkS")
		)
		(fp_line
			(start -16.905732 -3.000756)
			(end -18.125948 -4.171188)
			(stroke
				(width 0.1)
				(type default)
			)
			(layer "B.SilkS")
		)
		(fp_line
			(start -16.905732 -3.000756)
			(end -16.89354 -2.931414)
			(stroke
				(width 0.1)
				(type default)
			)
			(layer "B.SilkS")
		)
		(fp_line
			(start -16.905732 -3.000756)
			(end -16.89354 -2.931414)
			(stroke
				(width 0.1)
				(type default)
			)
			(layer "B.SilkS")
		)
		(fp_line
			(start -16.89354 -2.931414)
			(end -18.134838 -4.121912)
			(stroke
				(width 0.1)
				(type default)
			)
			(layer "B.SilkS")
		)
		(fp_line
			(start -16.89354 -2.931414)
			(end -18.134838 -4.121912)
			(stroke
				(width 0.1)
				(type default)
			)
			(layer "B.SilkS")
		)
		(fp_line
			(start -16.89354 -2.931414)
			(end -16.881602 -2.862072)
			(stroke
				(width 0.1)
				(type default)
			)
			(layer "B.SilkS")
		)
		(fp_line
			(start -16.89354 -2.931414)
			(end -16.881602 -2.862072)
			(stroke
				(width 0.1)
				(type default)
			)
			(layer "B.SilkS")
		)
		(fp_line
			(start -16.881602 -2.862072)
			(end -18.136362 -4.065524)
			(stroke
				(width 0.1)
				(type default)
			)
			(layer "B.SilkS")
		)
		(fp_line
			(start -16.881602 -2.862072)
			(end -18.136362 -4.065524)
			(stroke
				(width 0.1)
				(type default)
			)
			(layer "B.SilkS")
		)
		(fp_line
			(start -16.881602 -2.862072)
			(end -16.869156 -2.79273)
			(stroke
				(width 0.1)
				(type default)
			)
			(layer "B.SilkS")
		)
		(fp_line
			(start -16.881602 -2.862072)
			(end -16.869156 -2.79273)
			(stroke
				(width 0.1)
				(type default)
			)
			(layer "B.SilkS")
		)
		(fp_line
			(start -16.869156 -2.79273)
			(end -18.136362 -4.008374)
			(stroke
				(width 0.1)
				(type default)
			)
			(layer "B.SilkS")
		)
		(fp_line
			(start -16.869156 -2.79273)
			(end -18.136362 -4.008374)
			(stroke
				(width 0.1)
				(type default)
			)
			(layer "B.SilkS")
		)
		(fp_line
			(start -16.869156 -2.79273)
			(end -16.857218 -2.723134)
			(stroke
				(width 0.1)
				(type default)
			)
			(layer "B.SilkS")
		)
		(fp_line
			(start -16.869156 -2.79273)
			(end -16.857218 -2.723134)
			(stroke
				(width 0.1)
				(type default)
			)
			(layer "B.SilkS")
		)
		(fp_line
			(start -16.863568 -0.882904)
			(end -17.823434 -1.8034)
			(stroke
				(width 0.1)
				(type default)
			)
			(layer "B.SilkS")
		)
		(fp_line
			(start -16.863568 -0.882904)
			(end -17.823434 -1.8034)
			(stroke
				(width 0.1)
				(type default)
			)
			(layer "B.SilkS")
		)
		(fp_line
			(start -16.863568 -0.882904)
			(end -16.92402 -0.882904)
			(stroke
				(width 0.1)
				(type default)
			)
			(layer "B.SilkS")
		)
		(fp_line
			(start -16.863568 -0.882904)
			(end -16.92402 -0.882904)
			(stroke
				(width 0.1)
				(type default)
			)
			(layer "B.SilkS")
		)
		(fp_line
			(start -16.857218 -2.723134)
			(end -18.13687 -3.95097)
			(stroke
				(width 0.1)
				(type default)
			)
			(layer "B.SilkS")
		)
		(fp_line
			(start -16.857218 -2.723134)
			(end -18.13687 -3.95097)
			(stroke
				(width 0.1)
				(type default)
			)
			(layer "B.SilkS")
		)
		(fp_line
			(start -16.857218 -2.723134)
			(end -16.845026 -2.653792)
			(stroke
				(width 0.1)
				(type default)
			)
			(layer "B.SilkS")
		)
		(fp_line
			(start -16.857218 -2.723134)
			(end -16.845026 -2.653792)
			(stroke
				(width 0.1)
				(type default)
			)
			(layer "B.SilkS")
		)
		(fp_line
			(start -16.854678 -5.26034)
			(end -14.27988 -2.79019)
			(stroke
				(width 0.1)
				(type default)
			)
			(layer "B.SilkS")
		)
		(fp_line
			(start -16.854678 -5.26034)
			(end -14.27988 -2.79019)
			(stroke
				(width 0.1)
				(type default)
			)
			(layer "B.SilkS")
		)
		(fp_line
			(start -16.845026 -2.653792)
			(end -18.137378 -3.89382)
			(stroke
				(width 0.1)
				(type default)
			)
			(layer "B.SilkS")
		)
		(fp_line
			(start -16.845026 -2.653792)
			(end -18.137378 -3.89382)
			(stroke
				(width 0.1)
				(type default)
			)
			(layer "B.SilkS")
		)
		(fp_line
			(start -16.845026 -2.653792)
			(end -16.83258 -2.58445)
			(stroke
				(width 0.1)
				(type default)
			)
			(layer "B.SilkS")
		)
		(fp_line
			(start -16.845026 -2.653792)
			(end -16.83258 -2.58445)
			(stroke
				(width 0.1)
				(type default)
			)
			(layer "B.SilkS")
		)
		(fp_line
			(start -16.820134 -2.515108)
			(end -18.138394 -3.779266)
			(stroke
				(width 0.1)
				(type default)
			)
			(layer "B.SilkS")
		)
		(fp_line
			(start -16.820134 -2.515108)
			(end -18.138394 -3.779266)
			(stroke
				(width 0.1)
				(type default)
			)
			(layer "B.SilkS")
		)
		(fp_line
			(start -16.820134 -2.515108)
			(end -16.83258 -2.58445)
			(stroke
				(width 0.1)
				(type default)
			)
			(layer "B.SilkS")
		)
		(fp_line
			(start -16.820134 -2.515108)
			(end -16.83258 -2.58445)
			(stroke
				(width 0.1)
				(type default)
			)
			(layer "B.SilkS")
		)
		(fp_line
			(start -16.820134 -2.515108)
			(end -16.808196 -2.445512)
			(stroke
				(width 0.1)
				(type default)
			)
			(layer "B.SilkS")
		)
		(fp_line
			(start -16.820134 -2.515108)
			(end -16.808196 -2.445512)
			(stroke
				(width 0.1)
				(type default)
			)
			(layer "B.SilkS")
		)
		(fp_line
			(start -16.808196 -2.445512)
			(end -18.13687 -3.720338)
			(stroke
				(width 0.1)
				(type default)
			)
			(layer "B.SilkS")
		)
		(fp_line
			(start -16.808196 -2.445512)
			(end -18.13687 -3.720338)
			(stroke
				(width 0.1)
				(type default)
			)
			(layer "B.SilkS")
		)
		(fp_line
			(start -16.808196 -2.445512)
			(end -16.796258 -2.37617)
			(stroke
				(width 0.1)
				(type default)
			)
			(layer "B.SilkS")
		)
		(fp_line
			(start -16.808196 -2.445512)
			(end -16.796258 -2.37617)
			(stroke
				(width 0.1)
				(type default)
			)
			(layer "B.SilkS")
		)
		(fp_line
			(start -16.803624 -0.882904)
			(end -17.835626 -1.872742)
			(stroke
				(width 0.1)
				(type default)
			)
			(layer "B.SilkS")
		)
		(fp_line
			(start -16.803624 -0.882904)
			(end -17.835626 -1.872742)
			(stroke
				(width 0.1)
				(type default)
			)
			(layer "B.SilkS")
		)
		(fp_line
			(start -16.803624 -0.882904)
			(end -16.863568 -0.882904)
			(stroke
				(width 0.1)
				(type default)
			)
			(layer "B.SilkS")
		)
		(fp_line
			(start -16.803624 -0.882904)
			(end -16.863568 -0.882904)
			(stroke
				(width 0.1)
				(type default)
			)
			(layer "B.SilkS")
		)
		(fp_line
			(start -16.796258 -2.37617)
			(end -18.129504 -3.65506)
			(stroke
				(width 0.1)
				(type default)
			)
			(layer "B.SilkS")
		)
		(fp_line
			(start -16.796258 -2.37617)
			(end -18.129504 -3.65506)
			(stroke
				(width 0.1)
				(type default)
			)
			(layer "B.SilkS")
		)
		(fp_line
			(start -16.796258 -2.37617)
			(end -16.783812 -2.306828)
			(stroke
				(width 0.1)
				(type default)
			)
			(layer "B.SilkS")
		)
		(fp_line
			(start -16.796258 -2.37617)
			(end -16.783812 -2.306828)
			(stroke
				(width 0.1)
				(type default)
			)
			(layer "B.SilkS")
		)
		(fp_line
			(start -16.790162 -5.256022)
			(end -14.291818 -2.859532)
			(stroke
				(width 0.1)
				(type default)
			)
			(layer "B.SilkS")
		)
		(fp_line
			(start -16.790162 -5.256022)
			(end -14.291818 -2.859532)
			(stroke
				(width 0.1)
				(type default)
			)
			(layer "B.SilkS")
		)
		(fp_line
			(start -16.783812 -2.306828)
			(end -18.121122 -3.589782)
			(stroke
				(width 0.1)
				(type default)
			)
			(layer "B.SilkS")
		)
		(fp_line
			(start -16.783812 -2.306828)
			(end -18.121122 -3.589782)
			(stroke
				(width 0.1)
				(type default)
			)
			(layer "B.SilkS")
		)
		(fp_line
			(start -16.783812 -2.306828)
			(end -16.77162 -2.237232)
			(stroke
				(width 0.1)
				(type default)
			)
			(layer "B.SilkS")
		)
		(fp_line
			(start -16.783812 -2.306828)
			(end -16.77162 -2.237232)
			(stroke
				(width 0.1)
				(type default)
			)
			(layer "B.SilkS")
		)
		(fp_line
			(start -16.77162 -2.237232)
			(end -18.113248 -3.52425)
			(stroke
				(width 0.1)
				(type default)
			)
			(layer "B.SilkS")
		)
		(fp_line
			(start -16.77162 -2.237232)
			(end -18.113248 -3.52425)
			(stroke
				(width 0.1)
				(type default)
			)
			(layer "B.SilkS")
		)
		(fp_line
			(start -16.77162 -2.237232)
			(end -16.759682 -2.16789)
			(stroke
				(width 0.1)
				(type default)
			)
			(layer "B.SilkS")
		)
		(fp_line
			(start -16.77162 -2.237232)
			(end -16.759682 -2.16789)
			(stroke
				(width 0.1)
				(type default)
			)
			(layer "B.SilkS")
		)
		(fp_line
			(start -16.759682 -2.16789)
			(end -18.105374 -3.458718)
			(stroke
				(width 0.1)
				(type default)
			)
			(layer "B.SilkS")
		)
		(fp_line
			(start -16.759682 -2.16789)
			(end -18.105374 -3.458718)
			(stroke
				(width 0.1)
				(type default)
			)
			(layer "B.SilkS")
		)
		(fp_line
			(start -16.759682 -2.16789)
			(end -16.747236 -2.098548)
			(stroke
				(width 0.1)
				(type default)
			)
			(layer "B.SilkS")
		)
		(fp_line
			(start -16.759682 -2.16789)
			(end -16.747236 -2.098548)
			(stroke
				(width 0.1)
				(type default)
			)
			(layer "B.SilkS")
		)
		(fp_line
			(start -16.747236 -2.098548)
			(end -18.097246 -3.393694)
			(stroke
				(width 0.1)
				(type default)
			)
			(layer "B.SilkS")
		)
		(fp_line
			(start -16.747236 -2.098548)
			(end -18.097246 -3.393694)
			(stroke
				(width 0.1)
				(type default)
			)
			(layer "B.SilkS")
		)
		(fp_line
			(start -16.747236 -2.098548)
			(end -16.735044 -2.028952)
			(stroke
				(width 0.1)
				(type default)
			)
			(layer "B.SilkS")
		)
		(fp_line
			(start -16.747236 -2.098548)
			(end -16.735044 -2.028952)
			(stroke
				(width 0.1)
				(type default)
			)
			(layer "B.SilkS")
		)
		(fp_line
			(start -16.743426 -0.882904)
			(end -17.847564 -1.942338)
			(stroke
				(width 0.1)
				(type default)
			)
			(layer "B.SilkS")
		)
		(fp_line
			(start -16.743426 -0.882904)
			(end -17.847564 -1.942338)
			(stroke
				(width 0.1)
				(type default)
			)
			(layer "B.SilkS")
		)
		(fp_line
			(start -16.743426 -0.882904)
			(end -16.803624 -0.882904)
			(stroke
				(width 0.1)
				(type default)
			)
			(layer "B.SilkS")
		)
		(fp_line
			(start -16.743426 -0.882904)
			(end -16.803624 -0.882904)
			(stroke
				(width 0.1)
				(type default)
			)
			(layer "B.SilkS")
		)
		(fp_line
			(start -16.735044 -2.028952)
			(end -18.089372 -3.328416)
			(stroke
				(width 0.1)
				(type default)
			)
			(layer "B.SilkS")
		)
		(fp_line
			(start -16.735044 -2.028952)
			(end -18.089372 -3.328416)
			(stroke
				(width 0.1)
				(type default)
			)
			(layer "B.SilkS")
		)
		(fp_line
			(start -16.735044 -2.028952)
			(end -16.723106 -1.95961)
			(stroke
				(width 0.1)
				(type default)
			)
			(layer "B.SilkS")
		)
		(fp_line
			(start -16.735044 -2.028952)
			(end -16.723106 -1.95961)
			(stroke
				(width 0.1)
				(type default)
			)
			(layer "B.SilkS")
		)
		(fp_line
			(start -16.723868 -5.25018)
			(end -14.30401 -2.928874)
			(stroke
				(width 0.1)
				(type default)
			)
			(layer "B.SilkS")
		)
		(fp_line
			(start -16.723868 -5.25018)
			(end -14.30401 -2.928874)
			(stroke
				(width 0.1)
				(type default)
			)
			(layer "B.SilkS")
		)
		(fp_line
			(start -16.723106 -1.95961)
			(end -18.079212 -3.260598)
			(stroke
				(width 0.1)
				(type default)
			)
			(layer "B.SilkS")
		)
		(fp_line
			(start -16.723106 -1.95961)
			(end -18.079212 -3.260598)
			(stroke
				(width 0.1)
				(type default)
			)
			(layer "B.SilkS")
		)
		(fp_line
			(start -16.723106 -1.95961)
			(end -16.71066 -1.890268)
			(stroke
				(width 0.1)
				(type default)
			)
			(layer "B.SilkS")
		)
		(fp_line
			(start -16.723106 -1.95961)
			(end -16.71066 -1.890268)
			(stroke
				(width 0.1)
				(type default)
			)
			(layer "B.SilkS")
		)
		(fp_line
			(start -16.71066 -1.890268)
			(end -18.066766 -3.191002)
			(stroke
				(width 0.1)
				(type default)
			)
			(layer "B.SilkS")
		)
		(fp_line
			(start -16.71066 -1.890268)
			(end -18.066766 -3.191002)
			(stroke
				(width 0.1)
				(type default)
			)
			(layer "B.SilkS")
		)
		(fp_line
			(start -16.71066 -1.890268)
			(end -16.698214 -1.820926)
			(stroke
				(width 0.1)
				(type default)
			)
			(layer "B.SilkS")
		)
		(fp_line
			(start -16.71066 -1.890268)
			(end -16.698214 -1.820926)
			(stroke
				(width 0.1)
				(type default)
			)
			(layer "B.SilkS")
		)
		(fp_line
			(start -16.698214 -1.820926)
			(end -18.054574 -3.121914)
			(stroke
				(width 0.1)
				(type default)
			)
			(layer "B.SilkS")
		)
		(fp_line
			(start -16.698214 -1.820926)
			(end -18.054574 -3.121914)
			(stroke
				(width 0.1)
				(type default)
			)
			(layer "B.SilkS")
		)
		(fp_line
			(start -16.698214 -1.820926)
			(end -16.686276 -1.751584)
			(stroke
				(width 0.1)
				(type default)
			)
			(layer "B.SilkS")
		)
		(fp_line
			(start -16.698214 -1.820926)
			(end -16.686276 -1.751584)
			(stroke
				(width 0.1)
				(type default)
			)
			(layer "B.SilkS")
		)
		(fp_line
			(start -16.686276 -1.751584)
			(end -18.042636 -3.052572)
			(stroke
				(width 0.1)
				(type default)
			)
			(layer "B.SilkS")
		)
		(fp_line
			(start -16.686276 -1.751584)
			(end -18.042636 -3.052572)
			(stroke
				(width 0.1)
				(type default)
			)
			(layer "B.SilkS")
		)
		(fp_line
			(start -16.686276 -1.751584)
			(end -16.674084 -1.681988)
			(stroke
				(width 0.1)
				(type default)
			)
			(layer "B.SilkS")
		)
		(fp_line
			(start -16.686276 -1.751584)
			(end -16.674084 -1.681988)
			(stroke
				(width 0.1)
				(type default)
			)
			(layer "B.SilkS")
		)
		(fp_line
			(start -16.683228 -0.882904)
			(end -17.86001 -2.011426)
			(stroke
				(width 0.1)
				(type default)
			)
			(layer "B.SilkS")
		)
		(fp_line
			(start -16.683228 -0.882904)
			(end -17.86001 -2.011426)
			(stroke
				(width 0.1)
				(type default)
			)
			(layer "B.SilkS")
		)
		(fp_line
			(start -16.683228 -0.882904)
			(end -16.743426 -0.882904)
			(stroke
				(width 0.1)
				(type default)
			)
			(layer "B.SilkS")
		)
		(fp_line
			(start -16.683228 -0.882904)
			(end -16.743426 -0.882904)
			(stroke
				(width 0.1)
				(type default)
			)
			(layer "B.SilkS")
		)
		(fp_line
			(start -16.674084 -1.681988)
			(end -18.03019 -2.982976)
			(stroke
				(width 0.1)
				(type default)
			)
			(layer "B.SilkS")
		)
		(fp_line
			(start -16.674084 -1.681988)
			(end -18.03019 -2.982976)
			(stroke
				(width 0.1)
				(type default)
			)
			(layer "B.SilkS")
		)
		(fp_line
			(start -16.674084 -1.681988)
			(end -16.661892 -1.612646)
			(stroke
				(width 0.1)
				(type default)
			)
			(layer "B.SilkS")
		)
		(fp_line
			(start -16.674084 -1.681988)
			(end -16.661892 -1.612646)
			(stroke
				(width 0.1)
				(type default)
			)
			(layer "B.SilkS")
		)
		(fp_line
			(start -16.661892 -1.612646)
			(end -18.017998 -2.913634)
			(stroke
				(width 0.1)
				(type default)
			)
			(layer "B.SilkS")
		)
		(fp_line
			(start -16.661892 -1.612646)
			(end -18.017998 -2.913634)
			(stroke
				(width 0.1)
				(type default)
			)
			(layer "B.SilkS")
		)
		(fp_line
			(start -16.661892 -1.612646)
			(end -16.6497 -1.54305)
			(stroke
				(width 0.1)
				(type default)
			)
			(layer "B.SilkS")
		)
		(fp_line
			(start -16.661892 -1.612646)
			(end -16.6497 -1.54305)
			(stroke
				(width 0.1)
				(type default)
			)
			(layer "B.SilkS")
		)
		(fp_line
			(start -16.657066 -5.24383)
			(end -14.316456 -2.998216)
			(stroke
				(width 0.1)
				(type default)
			)
			(layer "B.SilkS")
		)
		(fp_line
			(start -16.657066 -5.24383)
			(end -14.316456 -2.998216)
			(stroke
				(width 0.1)
				(type default)
			)
			(layer "B.SilkS")
		)
		(fp_line
			(start -16.6497 -1.54305)
			(end -18.00606 -2.844292)
			(stroke
				(width 0.1)
				(type default)
			)
			(layer "B.SilkS")
		)
		(fp_line
			(start -16.6497 -1.54305)
			(end -18.00606 -2.844292)
			(stroke
				(width 0.1)
				(type default)
			)
			(layer "B.SilkS")
		)
		(fp_line
			(start -16.6497 -1.54305)
			(end -16.637762 -1.473962)
			(stroke
				(width 0.1)
				(type default)
			)
			(layer "B.SilkS")
		)
		(fp_line
			(start -16.6497 -1.54305)
			(end -16.637762 -1.473962)
			(stroke
				(width 0.1)
				(type default)
			)
			(layer "B.SilkS")
		)
		(fp_line
			(start -16.637762 -1.473962)
			(end -17.993614 -2.77495)
			(stroke
				(width 0.1)
				(type default)
			)
			(layer "B.SilkS")
		)
		(fp_line
			(start -16.637762 -1.473962)
			(end -17.993614 -2.77495)
			(stroke
				(width 0.1)
				(type default)
			)
			(layer "B.SilkS")
		)
		(fp_line
			(start -16.637762 -1.473962)
			(end -16.625316 -1.404366)
			(stroke
				(width 0.1)
				(type default)
			)
			(layer "B.SilkS")
		)
		(fp_line
			(start -16.637762 -1.473962)
			(end -16.625316 -1.404366)
			(stroke
				(width 0.1)
				(type default)
			)
			(layer "B.SilkS")
		)
		(fp_line
			(start -16.625316 -1.404366)
			(end -17.981676 -2.705608)
			(stroke
				(width 0.1)
				(type default)
			)
			(layer "B.SilkS")
		)
		(fp_line
			(start -16.625316 -1.404366)
			(end -17.981676 -2.705608)
			(stroke
				(width 0.1)
				(type default)
			)
			(layer "B.SilkS")
		)
		(fp_line
			(start -16.625316 -1.404366)
			(end -16.61287 -1.33477)
			(stroke
				(width 0.1)
				(type default)
			)
			(layer "B.SilkS")
		)
		(fp_line
			(start -16.625316 -1.404366)
			(end -16.61287 -1.33477)
			(stroke
				(width 0.1)
				(type default)
			)
			(layer "B.SilkS")
		)
		(fp_line
			(start -16.623284 -0.882904)
			(end -17.871948 -2.081022)
			(stroke
				(width 0.1)
				(type default)
			)
			(layer "B.SilkS")
		)
		(fp_line
			(start -16.623284 -0.882904)
			(end -17.871948 -2.081022)
			(stroke
				(width 0.1)
				(type default)
			)
			(layer "B.SilkS")
		)
		(fp_line
			(start -16.623284 -0.882904)
			(end -16.683228 -0.882904)
			(stroke
				(width 0.1)
				(type default)
			)
			(layer "B.SilkS")
		)
		(fp_line
			(start -16.623284 -0.882904)
			(end -16.683228 -0.882904)
			(stroke
				(width 0.1)
				(type default)
			)
			(layer "B.SilkS")
		)
		(fp_line
			(start -16.61287 -1.33477)
			(end -17.969484 -2.636012)
			(stroke
				(width 0.1)
				(type default)
			)
			(layer "B.SilkS")
		)
		(fp_line
			(start -16.61287 -1.33477)
			(end -17.969484 -2.636012)
			(stroke
				(width 0.1)
				(type default)
			)
			(layer "B.SilkS")
		)
		(fp_line
			(start -16.61287 -1.33477)
			(end -16.600932 -1.265428)
			(stroke
				(width 0.1)
				(type default)
			)
			(layer "B.SilkS")
		)
		(fp_line
			(start -16.61287 -1.33477)
			(end -16.600932 -1.265428)
			(stroke
				(width 0.1)
				(type default)
			)
			(layer "B.SilkS")
		)
		(fp_line
			(start -16.600932 -1.265428)
			(end -17.957038 -2.56667)
			(stroke
				(width 0.1)
				(type default)
			)
			(layer "B.SilkS")
		)
		(fp_line
			(start -16.600932 -1.265428)
			(end -17.957038 -2.56667)
			(stroke
				(width 0.1)
				(type default)
			)
			(layer "B.SilkS")
		)
		(fp_line
			(start -16.600932 -1.265428)
			(end -16.58874 -1.196086)
			(stroke
				(width 0.1)
				(type default)
			)
			(layer "B.SilkS")
		)
		(fp_line
			(start -16.600932 -1.265428)
			(end -16.58874 -1.196086)
			(stroke
				(width 0.1)
				(type default)
			)
			(layer "B.SilkS")
		)
		(fp_line
			(start -16.590772 -5.237734)
			(end -14.328394 -3.067558)
			(stroke
				(width 0.1)
				(type default)
			)
			(layer "B.SilkS")
		)
		(fp_line
			(start -16.590772 -5.237734)
			(end -14.328394 -3.067558)
			(stroke
				(width 0.1)
				(type default)
			)
			(layer "B.SilkS")
		)
		(fp_line
			(start -16.58874 -1.196086)
			(end -17.9451 -2.497328)
			(stroke
				(width 0.1)
				(type default)
			)
			(layer "B.SilkS")
		)
		(fp_line
			(start -16.58874 -1.196086)
			(end -17.9451 -2.497328)
			(stroke
				(width 0.1)
				(type default)
			)
			(layer "B.SilkS")
		)
		(fp_line
			(start -16.58874 -1.196086)
			(end -16.576294 -1.126744)
			(stroke
				(width 0.1)
				(type default)
			)
			(layer "B.SilkS")
		)
		(fp_line
			(start -16.58874 -1.196086)
			(end -16.576294 -1.126744)
			(stroke
				(width 0.1)
				(type default)
			)
			(layer "B.SilkS")
		)
		(fp_line
			(start -16.576294 -1.126744)
			(end -17.932908 -2.427732)
			(stroke
				(width 0.1)
				(type default)
			)
			(layer "B.SilkS")
		)
		(fp_line
			(start -16.576294 -1.126744)
			(end -17.932908 -2.427732)
			(stroke
				(width 0.1)
				(type default)
			)
			(layer "B.SilkS")
		)
		(fp_line
			(start -16.576294 -1.126744)
			(end -16.564356 -1.057148)
			(stroke
				(width 0.1)
				(type default)
			)
			(layer "B.SilkS")
		)
		(fp_line
			(start -16.576294 -1.126744)
			(end -16.564356 -1.057148)
			(stroke
				(width 0.1)
				(type default)
			)
			(layer "B.SilkS")
		)
		(fp_line
			(start -16.564356 -1.057148)
			(end -17.920716 -2.35839)
			(stroke
				(width 0.1)
				(type default)
			)
			(layer "B.SilkS")
		)
		(fp_line
			(start -16.564356 -1.057148)
			(end -17.920716 -2.35839)
			(stroke
				(width 0.1)
				(type default)
			)
			(layer "B.SilkS")
		)
		(fp_line
			(start -16.564356 -1.057148)
			(end -16.552164 -0.987806)
			(stroke
				(width 0.1)
				(type default)
			)
			(layer "B.SilkS")
		)
		(fp_line
			(start -16.564356 -1.057148)
			(end -16.552164 -0.987806)
			(stroke
				(width 0.1)
				(type default)
			)
			(layer "B.SilkS")
		)
		(fp_line
			(start -16.562832 -0.882904)
			(end -17.88414 -2.150364)
			(stroke
				(width 0.1)
				(type default)
			)
			(layer "B.SilkS")
		)
		(fp_line
			(start -16.562832 -0.882904)
			(end -17.88414 -2.150364)
			(stroke
				(width 0.1)
				(type default)
			)
			(layer "B.SilkS")
		)
		(fp_line
			(start -16.562832 -0.882904)
			(end -16.623284 -0.882904)
			(stroke
				(width 0.1)
				(type default)
			)
			(layer "B.SilkS")
		)
		(fp_line
			(start -16.562832 -0.882904)
			(end -16.623284 -0.882904)
			(stroke
				(width 0.1)
				(type default)
			)
			(layer "B.SilkS")
		)
		(fp_line
			(start -16.552164 -0.987806)
			(end -17.908524 -2.289048)
			(stroke
				(width 0.1)
				(type default)
			)
			(layer "B.SilkS")
		)
		(fp_line
			(start -16.552164 -0.987806)
			(end -17.908524 -2.289048)
			(stroke
				(width 0.1)
				(type default)
			)
			(layer "B.SilkS")
		)
		(fp_line
			(start -16.552164 -0.987806)
			(end -16.539718 -0.918464)
			(stroke
				(width 0.1)
				(type default)
			)
			(layer "B.SilkS")
		)
		(fp_line
			(start -16.552164 -0.987806)
			(end -16.539718 -0.918464)
			(stroke
				(width 0.1)
				(type default)
			)
			(layer "B.SilkS")
		)
		(fp_line
			(start -16.539718 -0.918464)
			(end -17.896586 -2.21996)
			(stroke
				(width 0.1)
				(type default)
			)
			(layer "B.SilkS")
		)
		(fp_line
			(start -16.539718 -0.918464)
			(end -17.896586 -2.21996)
			(stroke
				(width 0.1)
				(type default)
			)
			(layer "B.SilkS")
		)
		(fp_line
			(start -16.539718 -0.918464)
			(end -16.533622 -0.882904)
			(stroke
				(width 0.1)
				(type default)
			)
			(layer "B.SilkS")
		)
		(fp_line
			(start -16.539718 -0.918464)
			(end -16.533622 -0.882904)
			(stroke
				(width 0.1)
				(type default)
			)
			(layer "B.SilkS")
		)
		(fp_line
			(start -16.533622 -0.882904)
			(end -16.562832 -0.882904)
			(stroke
				(width 0.1)
				(type default)
			)
			(layer "B.SilkS")
		)
		(fp_line
			(start -16.533622 -0.882904)
			(end -16.562832 -0.882904)
			(stroke
				(width 0.1)
				(type default)
			)
			(layer "B.SilkS")
		)
		(fp_line
			(start -16.52397 -5.231638)
			(end -14.340586 -3.137154)
			(stroke
				(width 0.1)
				(type default)
			)
			(layer "B.SilkS")
		)
		(fp_line
			(start -16.52397 -5.231638)
			(end -14.340586 -3.137154)
			(stroke
				(width 0.1)
				(type default)
			)
			(layer "B.SilkS")
		)
		(fp_line
			(start -16.439896 -5.208778)
			(end -14.352778 -3.206496)
			(stroke
				(width 0.1)
				(type default)
			)
			(layer "B.SilkS")
		)
		(fp_line
			(start -16.439896 -5.208778)
			(end -14.352778 -3.206496)
			(stroke
				(width 0.1)
				(type default)
			)
			(layer "B.SilkS")
		)
		(fp_line
			(start -16.355568 -5.18541)
			(end -14.36497 -3.275838)
			(stroke
				(width 0.1)
				(type default)
			)
			(layer "B.SilkS")
		)
		(fp_line
			(start -16.355568 -5.18541)
			(end -14.36497 -3.275838)
			(stroke
				(width 0.1)
				(type default)
			)
			(layer "B.SilkS")
		)
		(fp_line
			(start -16.270986 -5.161788)
			(end -14.376908 -3.34518)
			(stroke
				(width 0.1)
				(type default)
			)
			(layer "B.SilkS")
		)
		(fp_line
			(start -16.270986 -5.161788)
			(end -14.376908 -3.34518)
			(stroke
				(width 0.1)
				(type default)
			)
			(layer "B.SilkS")
		)
		(fp_line
			(start -16.169132 -5.12191)
			(end -14.389354 -3.414776)
			(stroke
				(width 0.1)
				(type default)
			)
			(layer "B.SilkS")
		)
		(fp_line
			(start -16.169132 -5.12191)
			(end -14.389354 -3.414776)
			(stroke
				(width 0.1)
				(type default)
			)
			(layer "B.SilkS")
		)
		(fp_line
			(start -16.049498 -5.065268)
			(end -14.401546 -3.484118)
			(stroke
				(width 0.1)
				(type default)
			)
			(layer "B.SilkS")
		)
		(fp_line
			(start -16.049498 -5.065268)
			(end -14.401546 -3.484118)
			(stroke
				(width 0.1)
				(type default)
			)
			(layer "B.SilkS")
		)
		(fp_line
			(start -15.884652 -4.96443)
			(end -14.413484 -3.55346)
			(stroke
				(width 0.1)
				(type default)
			)
			(layer "B.SilkS")
		)
		(fp_line
			(start -15.884652 -4.96443)
			(end -14.413484 -3.55346)
			(stroke
				(width 0.1)
				(type default)
			)
			(layer "B.SilkS")
		)
		(fp_line
			(start -15.824962 -5.171694)
			(end -15.799816 -5.171694)
			(stroke
				(width 0.1)
				(type default)
			)
			(layer "B.SilkS")
		)
		(fp_line
			(start -15.824962 -5.171694)
			(end -15.799816 -5.171694)
			(stroke
				(width 0.1)
				(type default)
			)
			(layer "B.SilkS")
		)
		(fp_line
			(start -15.81785 -5.131308)
			(end -15.824962 -5.171694)
			(stroke
				(width 0.1)
				(type default)
			)
			(layer "B.SilkS")
		)
		(fp_line
			(start -15.81785 -5.131308)
			(end -15.824962 -5.171694)
			(stroke
				(width 0.1)
				(type default)
			)
			(layer "B.SilkS")
		)
		(fp_line
			(start -15.81785 -5.131308)
			(end -14.462506 -3.831082)
			(stroke
				(width 0.1)
				(type default)
			)
			(layer "B.SilkS")
		)
		(fp_line
			(start -15.81785 -5.131308)
			(end -14.462506 -3.831082)
			(stroke
				(width 0.1)
				(type default)
			)
			(layer "B.SilkS")
		)
		(fp_line
			(start -15.805658 -5.061966)
			(end -15.81785 -5.131308)
			(stroke
				(width 0.1)
				(type default)
			)
			(layer "B.SilkS")
		)
		(fp_line
			(start -15.805658 -5.061966)
			(end -15.81785 -5.131308)
			(stroke
				(width 0.1)
				(type default)
			)
			(layer "B.SilkS")
		)
		(fp_line
			(start -15.805658 -5.061966)
			(end -14.45006 -3.76174)
			(stroke
				(width 0.1)
				(type default)
			)
			(layer "B.SilkS")
		)
		(fp_line
			(start -15.805658 -5.061966)
			(end -14.45006 -3.76174)
			(stroke
				(width 0.1)
				(type default)
			)
			(layer "B.SilkS")
		)
		(fp_line
			(start -15.799816 -5.171694)
			(end -15.739618 -5.171694)
			(stroke
				(width 0.1)
				(type default)
			)
			(layer "B.SilkS")
		)
		(fp_line
			(start -15.799816 -5.171694)
			(end -15.739618 -5.171694)
			(stroke
				(width 0.1)
				(type default)
			)
			(layer "B.SilkS")
		)
		(fp_line
			(start -15.799816 -5.171694)
			(end -14.474952 -3.900424)
			(stroke
				(width 0.1)
				(type default)
			)
			(layer "B.SilkS")
		)
		(fp_line
			(start -15.799816 -5.171694)
			(end -14.474952 -3.900424)
			(stroke
				(width 0.1)
				(type default)
			)
			(layer "B.SilkS")
		)
		(fp_line
			(start -15.79372 -4.992624)
			(end -15.805658 -5.061966)
			(stroke
				(width 0.1)
				(type default)
			)
			(layer "B.SilkS")
		)
		(fp_line
			(start -15.79372 -4.992624)
			(end -15.805658 -5.061966)
			(stroke
				(width 0.1)
				(type default)
			)
			(layer "B.SilkS")
		)
		(fp_line
			(start -15.79372 -4.992624)
			(end -14.438376 -3.692398)
			(stroke
				(width 0.1)
				(type default)
			)
			(layer "B.SilkS")
		)
		(fp_line
			(start -15.79372 -4.992624)
			(end -14.438376 -3.692398)
			(stroke
				(width 0.1)
				(type default)
			)
			(layer "B.SilkS")
		)
		(fp_line
			(start -15.781274 -4.923028)
			(end -15.79372 -4.992624)
			(stroke
				(width 0.1)
				(type default)
			)
			(layer "B.SilkS")
		)
		(fp_line
			(start -15.781274 -4.923028)
			(end -15.79372 -4.992624)
			(stroke
				(width 0.1)
				(type default)
			)
			(layer "B.SilkS")
		)
		(fp_line
			(start -15.781274 -4.923028)
			(end -14.42593 -3.622802)
			(stroke
				(width 0.1)
				(type default)
			)
			(layer "B.SilkS")
		)
		(fp_line
			(start -15.781274 -4.923028)
			(end -14.42593 -3.622802)
			(stroke
				(width 0.1)
				(type default)
			)
			(layer "B.SilkS")
		)
		(fp_line
			(start -15.739618 -5.171694)
			(end -15.679166 -5.171694)
			(stroke
				(width 0.1)
				(type default)
			)
			(layer "B.SilkS")
		)
		(fp_line
			(start -15.739618 -5.171694)
			(end -15.679166 -5.171694)
			(stroke
				(width 0.1)
				(type default)
			)
			(layer "B.SilkS")
		)
		(fp_line
			(start -15.739618 -5.171694)
			(end -14.486636 -3.969766)
			(stroke
				(width 0.1)
				(type default)
			)
			(layer "B.SilkS")
		)
		(fp_line
			(start -15.739618 -5.171694)
			(end -14.486636 -3.969766)
			(stroke
				(width 0.1)
				(type default)
			)
			(layer "B.SilkS")
		)
		(fp_line
			(start -15.729458 -3.892296)
			(end -14.21892 -2.443226)
			(stroke
				(width 0.1)
				(type default)
			)
			(layer "B.SilkS")
		)
		(fp_line
			(start -15.729458 -3.892296)
			(end -14.21892 -2.443226)
			(stroke
				(width 0.1)
				(type default)
			)
			(layer "B.SilkS")
		)
		(fp_line
			(start -15.679166 -5.171694)
			(end -15.619222 -5.171694)
			(stroke
				(width 0.1)
				(type default)
			)
			(layer "B.SilkS")
		)
		(fp_line
			(start -15.679166 -5.171694)
			(end -15.619222 -5.171694)
			(stroke
				(width 0.1)
				(type default)
			)
			(layer "B.SilkS")
		)
		(fp_line
			(start -15.679166 -5.171694)
			(end -14.498828 -4.039362)
			(stroke
				(width 0.1)
				(type default)
			)
			(layer "B.SilkS")
		)
		(fp_line
			(start -15.679166 -5.171694)
			(end -14.498828 -4.039362)
			(stroke
				(width 0.1)
				(type default)
			)
			(layer "B.SilkS")
		)
		(fp_line
			(start -15.649702 -3.75793)
			(end -14.206728 -2.373884)
			(stroke
				(width 0.1)
				(type default)
			)
			(layer "B.SilkS")
		)
		(fp_line
			(start -15.649702 -3.75793)
			(end -14.206728 -2.373884)
			(stroke
				(width 0.1)
				(type default)
			)
			(layer "B.SilkS")
		)
		(fp_line
			(start -15.619222 -5.171694)
			(end -15.559278 -5.171694)
			(stroke
				(width 0.1)
				(type default)
			)
			(layer "B.SilkS")
		)
		(fp_line
			(start -15.619222 -5.171694)
			(end -15.559278 -5.171694)
			(stroke
				(width 0.1)
				(type default)
			)
			(layer "B.SilkS")
		)
		(fp_line
			(start -15.619222 -5.171694)
			(end -14.511274 -4.108704)
			(stroke
				(width 0.1)
				(type default)
			)
			(layer "B.SilkS")
		)
		(fp_line
			(start -15.619222 -5.171694)
			(end -14.511274 -4.108704)
			(stroke
				(width 0.1)
				(type default)
			)
			(layer "B.SilkS")
		)
		(fp_line
			(start -15.601442 -3.654044)
			(end -14.194282 -2.304288)
			(stroke
				(width 0.1)
				(type default)
			)
			(layer "B.SilkS")
		)
		(fp_line
			(start -15.601442 -3.654044)
			(end -14.194282 -2.304288)
			(stroke
				(width 0.1)
				(type default)
			)
			(layer "B.SilkS")
		)
		(fp_line
			(start -15.570962 -3.566922)
			(end -14.182344 -2.234946)
			(stroke
				(width 0.1)
				(type default)
			)
			(layer "B.SilkS")
		)
		(fp_line
			(start -15.570962 -3.566922)
			(end -14.182344 -2.234946)
			(stroke
				(width 0.1)
				(type default)
			)
			(layer "B.SilkS")
		)
		(fp_line
			(start -15.559278 -5.171694)
			(end -15.49908 -5.171694)
			(stroke
				(width 0.1)
				(type default)
			)
			(layer "B.SilkS")
		)
		(fp_line
			(start -15.559278 -5.171694)
			(end -15.49908 -5.171694)
			(stroke
				(width 0.1)
				(type default)
			)
			(layer "B.SilkS")
		)
		(fp_line
			(start -15.559278 -5.171694)
			(end -14.523466 -4.178046)
			(stroke
				(width 0.1)
				(type default)
			)
			(layer "B.SilkS")
		)
		(fp_line
			(start -15.559278 -5.171694)
			(end -14.523466 -4.178046)
			(stroke
				(width 0.1)
				(type default)
			)
			(layer "B.SilkS")
		)
		(fp_line
			(start -15.54099 -3.480562)
			(end -14.170406 -2.165604)
			(stroke
				(width 0.1)
				(type default)
			)
			(layer "B.SilkS")
		)
		(fp_line
			(start -15.54099 -3.480562)
			(end -14.170406 -2.165604)
			(stroke
				(width 0.1)
				(type default)
			)
			(layer "B.SilkS")
		)
		(fp_line
			(start -15.524988 -3.40741)
			(end -14.15796 -2.096262)
			(stroke
				(width 0.1)
				(type default)
			)
			(layer "B.SilkS")
		)
		(fp_line
			(start -15.524988 -3.40741)
			(end -14.15796 -2.096262)
			(stroke
				(width 0.1)
				(type default)
			)
			(layer "B.SilkS")
		)
		(fp_line
			(start -15.508478 -3.334004)
			(end -14.145768 -2.02692)
			(stroke
				(width 0.1)
				(type default)
			)
			(layer "B.SilkS")
		)
		(fp_line
			(start -15.508478 -3.334004)
			(end -14.145768 -2.02692)
			(stroke
				(width 0.1)
				(type default)
			)
			(layer "B.SilkS")
		)
		(fp_line
			(start -15.49908 -5.171694)
			(end -15.438882 -5.171694)
			(stroke
				(width 0.1)
				(type default)
			)
			(layer "B.SilkS")
		)
		(fp_line
			(start -15.49908 -5.171694)
			(end -15.438882 -5.171694)
			(stroke
				(width 0.1)
				(type default)
			)
			(layer "B.SilkS")
		)
		(fp_line
			(start -15.49908 -5.171694)
			(end -14.535404 -4.247388)
			(stroke
				(width 0.1)
				(type default)
			)
			(layer "B.SilkS")
		)
		(fp_line
			(start -15.49908 -5.171694)
			(end -14.535404 -4.247388)
			(stroke
				(width 0.1)
				(type default)
			)
			(layer "B.SilkS")
		)
		(fp_line
			(start -15.491714 -3.260344)
			(end -14.13383 -1.957324)
			(stroke
				(width 0.1)
				(type default)
			)
			(layer "B.SilkS")
		)
		(fp_line
			(start -15.491714 -3.260344)
			(end -14.13383 -1.957324)
			(stroke
				(width 0.1)
				(type default)
			)
			(layer "B.SilkS")
		)
		(fp_line
			(start -15.477998 -3.189224)
			(end -15.465552 -3.119882)
			(stroke
				(width 0.1)
				(type default)
			)
			(layer "B.SilkS")
		)
		(fp_line
			(start -15.477998 -3.189224)
			(end -15.465552 -3.119882)
			(stroke
				(width 0.1)
				(type default)
			)
			(layer "B.SilkS")
		)
		(fp_line
			(start -15.477998 -3.189224)
			(end -14.121384 -1.887982)
			(stroke
				(width 0.1)
				(type default)
			)
			(layer "B.SilkS")
		)
		(fp_line
			(start -15.477998 -3.189224)
			(end -14.121384 -1.887982)
			(stroke
				(width 0.1)
				(type default)
			)
			(layer "B.SilkS")
		)
		(fp_line
			(start -15.465552 -3.119882)
			(end -15.45336 -3.050286)
			(stroke
				(width 0.1)
				(type default)
			)
			(layer "B.SilkS")
		)
		(fp_line
			(start -15.465552 -3.119882)
			(end -15.45336 -3.050286)
			(stroke
				(width 0.1)
				(type default)
			)
			(layer "B.SilkS")
		)
		(fp_line
			(start -15.465552 -3.119882)
			(end -14.109192 -1.81864)
			(stroke
				(width 0.1)
				(type default)
			)
			(layer "B.SilkS")
		)
		(fp_line
			(start -15.465552 -3.119882)
			(end -14.109192 -1.81864)
			(stroke
				(width 0.1)
				(type default)
			)
			(layer "B.SilkS")
		)
		(fp_line
			(start -15.45336 -3.050286)
			(end -15.441168 -2.980944)
			(stroke
				(width 0.1)
				(type default)
			)
			(layer "B.SilkS")
		)
		(fp_line
			(start -15.45336 -3.050286)
			(end -15.441168 -2.980944)
			(stroke
				(width 0.1)
				(type default)
			)
			(layer "B.SilkS")
		)
		(fp_line
			(start -15.45336 -3.050286)
			(end -14.097254 -1.749044)
			(stroke
				(width 0.1)
				(type default)
			)
			(layer "B.SilkS")
		)
		(fp_line
			(start -15.45336 -3.050286)
			(end -14.097254 -1.749044)
			(stroke
				(width 0.1)
				(type default)
			)
			(layer "B.SilkS")
		)
		(fp_line
			(start -15.441168 -2.980944)
			(end -15.42923 -2.911602)
			(stroke
				(width 0.1)
				(type default)
			)
			(layer "B.SilkS")
		)
		(fp_line
			(start -15.441168 -2.980944)
			(end -15.42923 -2.911602)
			(stroke
				(width 0.1)
				(type default)
			)
			(layer "B.SilkS")
		)
		(fp_line
			(start -15.441168 -2.980944)
			(end -14.084808 -1.679702)
			(stroke
				(width 0.1)
				(type default)
			)
			(layer "B.SilkS")
		)
		(fp_line
			(start -15.441168 -2.980944)
			(end -14.084808 -1.679702)
			(stroke
				(width 0.1)
				(type default)
			)
			(layer "B.SilkS")
		)
		(fp_line
			(start -15.438882 -5.171694)
			(end -15.378938 -5.171694)
			(stroke
				(width 0.1)
				(type default)
			)
			(layer "B.SilkS")
		)
		(fp_line
			(start -15.438882 -5.171694)
			(end -15.378938 -5.171694)
			(stroke
				(width 0.1)
				(type default)
			)
			(layer "B.SilkS")
		)
		(fp_line
			(start -15.438882 -5.171694)
			(end -14.54785 -4.316984)
			(stroke
				(width 0.1)
				(type default)
			)
			(layer "B.SilkS")
		)
		(fp_line
			(start -15.438882 -5.171694)
			(end -14.54785 -4.316984)
			(stroke
				(width 0.1)
				(type default)
			)
			(layer "B.SilkS")
		)
		(fp_line
			(start -15.42923 -2.911602)
			(end -15.416784 -2.84226)
			(stroke
				(width 0.1)
				(type default)
			)
			(layer "B.SilkS")
		)
		(fp_line
			(start -15.42923 -2.911602)
			(end -15.416784 -2.84226)
			(stroke
				(width 0.1)
				(type default)
			)
			(layer "B.SilkS")
		)
		(fp_line
			(start -15.404592 -2.772664)
			(end -15.416784 -2.84226)
			(stroke
				(width 0.1)
				(type default)
			)
			(layer "B.SilkS")
		)
		(fp_line
			(start -15.404592 -2.772664)
			(end -15.416784 -2.84226)
			(stroke
				(width 0.1)
				(type default)
			)
			(layer "B.SilkS")
		)
		(fp_line
			(start -15.392654 -2.703322)
			(end -15.404592 -2.772664)
			(stroke
				(width 0.1)
				(type default)
			)
			(layer "B.SilkS")
		)
		(fp_line
			(start -15.392654 -2.703322)
			(end -15.404592 -2.772664)
			(stroke
				(width 0.1)
				(type default)
			)
			(layer "B.SilkS")
		)
		(fp_line
			(start -15.380208 -2.633726)
			(end -15.392654 -2.703322)
			(stroke
				(width 0.1)
				(type default)
			)
			(layer "B.SilkS")
		)
		(fp_line
			(start -15.380208 -2.633726)
			(end -15.392654 -2.703322)
			(stroke
				(width 0.1)
				(type default)
			)
			(layer "B.SilkS")
		)
		(fp_line
			(start -15.378938 -5.171694)
			(end -15.318486 -5.171694)
			(stroke
				(width 0.1)
				(type default)
			)
			(layer "B.SilkS")
		)
		(fp_line
			(start -15.378938 -5.171694)
			(end -15.318486 -5.171694)
			(stroke
				(width 0.1)
				(type default)
			)
			(layer "B.SilkS")
		)
		(fp_line
			(start -15.378938 -5.171694)
			(end -14.560042 -4.386326)
			(stroke
				(width 0.1)
				(type default)
			)
			(layer "B.SilkS")
		)
		(fp_line
			(start -15.378938 -5.171694)
			(end -14.560042 -4.386326)
			(stroke
				(width 0.1)
				(type default)
			)
			(layer "B.SilkS")
		)
		(fp_line
			(start -15.367762 -2.564384)
			(end -15.380208 -2.633726)
			(stroke
				(width 0.1)
				(type default)
			)
			(layer "B.SilkS")
		)
		(fp_line
			(start -15.367762 -2.564384)
			(end -15.380208 -2.633726)
			(stroke
				(width 0.1)
				(type default)
			)
			(layer "B.SilkS")
		)
		(fp_line
			(start -15.355824 -2.495042)
			(end -15.367762 -2.564384)
			(stroke
				(width 0.1)
				(type default)
			)
			(layer "B.SilkS")
		)
		(fp_line
			(start -15.355824 -2.495042)
			(end -15.367762 -2.564384)
			(stroke
				(width 0.1)
				(type default)
			)
			(layer "B.SilkS")
		)
		(fp_line
			(start -15.343632 -2.425446)
			(end -15.355824 -2.495042)
			(stroke
				(width 0.1)
				(type default)
			)
			(layer "B.SilkS")
		)
		(fp_line
			(start -15.343632 -2.425446)
			(end -15.355824 -2.495042)
			(stroke
				(width 0.1)
				(type default)
			)
			(layer "B.SilkS")
		)
		(fp_line
			(start -15.331186 -2.356104)
			(end -15.343632 -2.425446)
			(stroke
				(width 0.1)
				(type default)
			)
			(layer "B.SilkS")
		)
		(fp_line
			(start -15.331186 -2.356104)
			(end -15.343632 -2.425446)
			(stroke
				(width 0.1)
				(type default)
			)
			(layer "B.SilkS")
		)
		(fp_line
			(start -15.319248 -2.286762)
			(end -15.331186 -2.356104)
			(stroke
				(width 0.1)
				(type default)
			)
			(layer "B.SilkS")
		)
		(fp_line
			(start -15.319248 -2.286762)
			(end -15.331186 -2.356104)
			(stroke
				(width 0.1)
				(type default)
			)
			(layer "B.SilkS")
		)
		(fp_line
			(start -15.318486 -5.171694)
			(end -15.258288 -5.171694)
			(stroke
				(width 0.1)
				(type default)
			)
			(layer "B.SilkS")
		)
		(fp_line
			(start -15.318486 -5.171694)
			(end -15.258288 -5.171694)
			(stroke
				(width 0.1)
				(type default)
			)
			(layer "B.SilkS")
		)
		(fp_line
			(start -15.318486 -5.171694)
			(end -14.57198 -4.455668)
			(stroke
				(width 0.1)
				(type default)
			)
			(layer "B.SilkS")
		)
		(fp_line
			(start -15.318486 -5.171694)
			(end -14.57198 -4.455668)
			(stroke
				(width 0.1)
				(type default)
			)
			(layer "B.SilkS")
		)
		(fp_line
			(start -15.307056 -2.21742)
			(end -15.319248 -2.286762)
			(stroke
				(width 0.1)
				(type default)
			)
			(layer "B.SilkS")
		)
		(fp_line
			(start -15.307056 -2.21742)
			(end -15.319248 -2.286762)
			(stroke
				(width 0.1)
				(type default)
			)
			(layer "B.SilkS")
		)
		(fp_line
			(start -15.294864 -2.147824)
			(end -15.307056 -2.21742)
			(stroke
				(width 0.1)
				(type default)
			)
			(layer "B.SilkS")
		)
		(fp_line
			(start -15.294864 -2.147824)
			(end -15.307056 -2.21742)
			(stroke
				(width 0.1)
				(type default)
			)
			(layer "B.SilkS")
		)
		(fp_line
			(start -15.282418 -2.078482)
			(end -15.294864 -2.147824)
			(stroke
				(width 0.1)
				(type default)
			)
			(layer "B.SilkS")
		)
		(fp_line
			(start -15.282418 -2.078482)
			(end -15.294864 -2.147824)
			(stroke
				(width 0.1)
				(type default)
			)
			(layer "B.SilkS")
		)
		(fp_line
			(start -15.270226 -2.00914)
			(end -15.282418 -2.078482)
			(stroke
				(width 0.1)
				(type default)
			)
			(layer "B.SilkS")
		)
		(fp_line
			(start -15.270226 -2.00914)
			(end -15.282418 -2.078482)
			(stroke
				(width 0.1)
				(type default)
			)
			(layer "B.SilkS")
		)
		(fp_line
			(start -15.258288 -5.171694)
			(end -15.198344 -5.171694)
			(stroke
				(width 0.1)
				(type default)
			)
			(layer "B.SilkS")
		)
		(fp_line
			(start -15.258288 -5.171694)
			(end -15.198344 -5.171694)
			(stroke
				(width 0.1)
				(type default)
			)
			(layer "B.SilkS")
		)
		(fp_line
			(start -15.258288 -5.171694)
			(end -14.584426 -4.52501)
			(stroke
				(width 0.1)
				(type default)
			)
			(layer "B.SilkS")
		)
		(fp_line
			(start -15.258288 -5.171694)
			(end -14.584426 -4.52501)
			(stroke
				(width 0.1)
				(type default)
			)
			(layer "B.SilkS")
		)
		(fp_line
			(start -15.258288 -1.939544)
			(end -15.270226 -2.00914)
			(stroke
				(width 0.1)
				(type default)
			)
			(layer "B.SilkS")
		)
		(fp_line
			(start -15.258288 -1.939544)
			(end -15.270226 -2.00914)
			(stroke
				(width 0.1)
				(type default)
			)
			(layer "B.SilkS")
		)
		(fp_line
			(start -15.245842 -1.869948)
			(end -15.258288 -1.939544)
			(stroke
				(width 0.1)
				(type default)
			)
			(layer "B.SilkS")
		)
		(fp_line
			(start -15.245842 -1.869948)
			(end -15.258288 -1.939544)
			(stroke
				(width 0.1)
				(type default)
			)
			(layer "B.SilkS")
		)
		(fp_line
			(start -15.233396 -1.800606)
			(end -15.245842 -1.869948)
			(stroke
				(width 0.1)
				(type default)
			)
			(layer "B.SilkS")
		)
		(fp_line
			(start -15.233396 -1.800606)
			(end -15.245842 -1.869948)
			(stroke
				(width 0.1)
				(type default)
			)
			(layer "B.SilkS")
		)
		(fp_line
			(start -15.221458 -1.731518)
			(end -15.233396 -1.800606)
			(stroke
				(width 0.1)
				(type default)
			)
			(layer "B.SilkS")
		)
		(fp_line
			(start -15.221458 -1.731518)
			(end -15.233396 -1.800606)
			(stroke
				(width 0.1)
				(type default)
			)
			(layer "B.SilkS")
		)
		(fp_line
			(start -15.209266 -1.661922)
			(end -15.221458 -1.731518)
			(stroke
				(width 0.1)
				(type default)
			)
			(layer "B.SilkS")
		)
		(fp_line
			(start -15.209266 -1.661922)
			(end -15.221458 -1.731518)
			(stroke
				(width 0.1)
				(type default)
			)
			(layer "B.SilkS")
		)
		(fp_line
			(start -15.198344 -5.171694)
			(end -15.137892 -5.171694)
			(stroke
				(width 0.1)
				(type default)
			)
			(layer "B.SilkS")
		)
		(fp_line
			(start -15.198344 -5.171694)
			(end -15.137892 -5.171694)
			(stroke
				(width 0.1)
				(type default)
			)
			(layer "B.SilkS")
		)
		(fp_line
			(start -15.198344 -5.171694)
			(end -14.596364 -4.594352)
			(stroke
				(width 0.1)
				(type default)
			)
			(layer "B.SilkS")
		)
		(fp_line
			(start -15.198344 -5.171694)
			(end -14.596364 -4.594352)
			(stroke
				(width 0.1)
				(type default)
			)
			(layer "B.SilkS")
		)
		(fp_line
			(start -15.19682 -1.592326)
			(end -15.209266 -1.661922)
			(stroke
				(width 0.1)
				(type default)
			)
			(layer "B.SilkS")
		)
		(fp_line
			(start -15.19682 -1.592326)
			(end -15.209266 -1.661922)
			(stroke
				(width 0.1)
				(type default)
			)
			(layer "B.SilkS")
		)
		(fp_line
			(start -15.184882 -1.522984)
			(end -15.19682 -1.592326)
			(stroke
				(width 0.1)
				(type default)
			)
			(layer "B.SilkS")
		)
		(fp_line
			(start -15.184882 -1.522984)
			(end -15.19682 -1.592326)
			(stroke
				(width 0.1)
				(type default)
			)
			(layer "B.SilkS")
		)
		(fp_line
			(start -15.184882 -1.522984)
			(end -15.17269 -1.453642)
			(stroke
				(width 0.1)
				(type default)
			)
			(layer "B.SilkS")
		)
		(fp_line
			(start -15.184882 -1.522984)
			(end -15.17269 -1.453642)
			(stroke
				(width 0.1)
				(type default)
			)
			(layer "B.SilkS")
		)
		(fp_line
			(start -15.17269 -1.453642)
			(end -15.160498 -1.384046)
			(stroke
				(width 0.1)
				(type default)
			)
			(layer "B.SilkS")
		)
		(fp_line
			(start -15.17269 -1.453642)
			(end -15.160498 -1.384046)
			(stroke
				(width 0.1)
				(type default)
			)
			(layer "B.SilkS")
		)
		(fp_line
			(start -15.160498 -1.384046)
			(end -15.148052 -1.314704)
			(stroke
				(width 0.1)
				(type default)
			)
			(layer "B.SilkS")
		)
		(fp_line
			(start -15.160498 -1.384046)
			(end -15.148052 -1.314704)
			(stroke
				(width 0.1)
				(type default)
			)
			(layer "B.SilkS")
		)
		(fp_line
			(start -15.148052 -1.314704)
			(end -15.13586 -1.245362)
			(stroke
				(width 0.1)
				(type default)
			)
			(layer "B.SilkS")
		)
		(fp_line
			(start -15.148052 -1.314704)
			(end -15.13586 -1.245362)
			(stroke
				(width 0.1)
				(type default)
			)
			(layer "B.SilkS")
		)
		(fp_line
			(start -15.137892 -5.171694)
			(end -15.077694 -5.171694)
			(stroke
				(width 0.1)
				(type default)
			)
			(layer "B.SilkS")
		)
		(fp_line
			(start -15.137892 -5.171694)
			(end -15.077694 -5.171694)
			(stroke
				(width 0.1)
				(type default)
			)
			(layer "B.SilkS")
		)
		(fp_line
			(start -15.137892 -5.171694)
			(end -14.608556 -4.663948)
			(stroke
				(width 0.1)
				(type default)
			)
			(layer "B.SilkS")
		)
		(fp_line
			(start -15.137892 -5.171694)
			(end -14.608556 -4.663948)
			(stroke
				(width 0.1)
				(type default)
			)
			(layer "B.SilkS")
		)
		(fp_line
			(start -15.13586 -1.245362)
			(end -15.123922 -1.17602)
			(stroke
				(width 0.1)
				(type default)
			)
			(layer "B.SilkS")
		)
		(fp_line
			(start -15.13586 -1.245362)
			(end -15.123922 -1.17602)
			(stroke
				(width 0.1)
				(type default)
			)
			(layer "B.SilkS")
		)
		(fp_line
			(start -15.123922 -1.17602)
			(end -15.111476 -1.106424)
			(stroke
				(width 0.1)
				(type default)
			)
			(layer "B.SilkS")
		)
		(fp_line
			(start -15.123922 -1.17602)
			(end -15.111476 -1.106424)
			(stroke
				(width 0.1)
				(type default)
			)
			(layer "B.SilkS")
		)
		(fp_line
			(start -15.111476 -1.106424)
			(end -15.09903 -1.036828)
			(stroke
				(width 0.1)
				(type default)
			)
			(layer "B.SilkS")
		)
		(fp_line
			(start -15.111476 -1.106424)
			(end -15.09903 -1.036828)
			(stroke
				(width 0.1)
				(type default)
			)
			(layer "B.SilkS")
		)
		(fp_line
			(start -15.09903 -1.036828)
			(end -15.087092 -0.96774)
			(stroke
				(width 0.1)
				(type default)
			)
			(layer "B.SilkS")
		)
		(fp_line
			(start -15.09903 -1.036828)
			(end -15.087092 -0.96774)
			(stroke
				(width 0.1)
				(type default)
			)
			(layer "B.SilkS")
		)
		(fp_line
			(start -15.087092 -0.96774)
			(end -15.0749 -0.898398)
			(stroke
				(width 0.1)
				(type default)
			)
			(layer "B.SilkS")
		)
		(fp_line
			(start -15.087092 -0.96774)
			(end -15.0749 -0.898398)
			(stroke
				(width 0.1)
				(type default)
			)
			(layer "B.SilkS")
		)
		(fp_line
			(start -15.077694 -5.171694)
			(end -15.01775 -5.171694)
			(stroke
				(width 0.1)
				(type default)
			)
			(layer "B.SilkS")
		)
		(fp_line
			(start -15.077694 -5.171694)
			(end -15.01775 -5.171694)
			(stroke
				(width 0.1)
				(type default)
			)
			(layer "B.SilkS")
		)
		(fp_line
			(start -15.077694 -5.171694)
			(end -14.621002 -4.733036)
			(stroke
				(width 0.1)
				(type default)
			)
			(layer "B.SilkS")
		)
		(fp_line
			(start -15.077694 -5.171694)
			(end -14.621002 -4.733036)
			(stroke
				(width 0.1)
				(type default)
			)
			(layer "B.SilkS")
		)
		(fp_line
			(start -15.072106 -0.882904)
			(end -15.0749 -0.898398)
			(stroke
				(width 0.1)
				(type default)
			)
			(layer "B.SilkS")
		)
		(fp_line
			(start -15.072106 -0.882904)
			(end -15.0749 -0.898398)
			(stroke
				(width 0.1)
				(type default)
			)
			(layer "B.SilkS")
		)
		(fp_line
			(start -15.059152 -0.882904)
			(end -15.0749 -0.898398)
			(stroke
				(width 0.1)
				(type default)
			)
			(layer "B.SilkS")
		)
		(fp_line
			(start -15.059152 -0.882904)
			(end -15.0749 -0.898398)
			(stroke
				(width 0.1)
				(type default)
			)
			(layer "B.SilkS")
		)
		(fp_line
			(start -15.059152 -0.882904)
			(end -15.072106 -0.882904)
			(stroke
				(width 0.1)
				(type default)
			)
			(layer "B.SilkS")
		)
		(fp_line
			(start -15.059152 -0.882904)
			(end -15.072106 -0.882904)
			(stroke
				(width 0.1)
				(type default)
			)
			(layer "B.SilkS")
		)
		(fp_line
			(start -15.01775 -5.171694)
			(end -14.957552 -5.171694)
			(stroke
				(width 0.1)
				(type default)
			)
			(layer "B.SilkS")
		)
		(fp_line
			(start -15.01775 -5.171694)
			(end -14.957552 -5.171694)
			(stroke
				(width 0.1)
				(type default)
			)
			(layer "B.SilkS")
		)
		(fp_line
			(start -15.01775 -5.171694)
			(end -14.63294 -4.802632)
			(stroke
				(width 0.1)
				(type default)
			)
			(layer "B.SilkS")
		)
		(fp_line
			(start -15.01775 -5.171694)
			(end -14.63294 -4.802632)
			(stroke
				(width 0.1)
				(type default)
			)
			(layer "B.SilkS")
		)
		(fp_line
			(start -14.998954 -0.882904)
			(end -15.087092 -0.96774)
			(stroke
				(width 0.1)
				(type default)
			)
			(layer "B.SilkS")
		)
		(fp_line
			(start -14.998954 -0.882904)
			(end -15.087092 -0.96774)
			(stroke
				(width 0.1)
				(type default)
			)
			(layer "B.SilkS")
		)
		(fp_line
			(start -14.998954 -0.882904)
			(end -15.059152 -0.882904)
			(stroke
				(width 0.1)
				(type default)
			)
			(layer "B.SilkS")
		)
		(fp_line
			(start -14.998954 -0.882904)
			(end -15.059152 -0.882904)
			(stroke
				(width 0.1)
				(type default)
			)
			(layer "B.SilkS")
		)
		(fp_line
			(start -14.957552 -5.171694)
			(end -14.8971 -5.171694)
			(stroke
				(width 0.1)
				(type default)
			)
			(layer "B.SilkS")
		)
		(fp_line
			(start -14.957552 -5.171694)
			(end -14.8971 -5.171694)
			(stroke
				(width 0.1)
				(type default)
			)
			(layer "B.SilkS")
		)
		(fp_line
			(start -14.957552 -5.171694)
			(end -14.645132 -4.872228)
			(stroke
				(width 0.1)
				(type default)
			)
			(layer "B.SilkS")
		)
		(fp_line
			(start -14.957552 -5.171694)
			(end -14.645132 -4.872228)
			(stroke
				(width 0.1)
				(type default)
			)
			(layer "B.SilkS")
		)
		(fp_line
			(start -14.938502 -0.882904)
			(end -15.09903 -1.036828)
			(stroke
				(width 0.1)
				(type default)
			)
			(layer "B.SilkS")
		)
		(fp_line
			(start -14.938502 -0.882904)
			(end -15.09903 -1.036828)
			(stroke
				(width 0.1)
				(type default)
			)
			(layer "B.SilkS")
		)
		(fp_line
			(start -14.938502 -0.882904)
			(end -14.998954 -0.882904)
			(stroke
				(width 0.1)
				(type default)
			)
			(layer "B.SilkS")
		)
		(fp_line
			(start -14.938502 -0.882904)
			(end -14.998954 -0.882904)
			(stroke
				(width 0.1)
				(type default)
			)
			(layer "B.SilkS")
		)
		(fp_line
			(start -14.8971 -5.171694)
			(end -14.837156 -5.171694)
			(stroke
				(width 0.1)
				(type default)
			)
			(layer "B.SilkS")
		)
		(fp_line
			(start -14.8971 -5.171694)
			(end -14.837156 -5.171694)
			(stroke
				(width 0.1)
				(type default)
			)
			(layer "B.SilkS")
		)
		(fp_line
			(start -14.8971 -5.171694)
			(end -14.657324 -4.941316)
			(stroke
				(width 0.1)
				(type default)
			)
			(layer "B.SilkS")
		)
		(fp_line
			(start -14.8971 -5.171694)
			(end -14.657324 -4.941316)
			(stroke
				(width 0.1)
				(type default)
			)
			(layer "B.SilkS")
		)
		(fp_line
			(start -14.878558 -0.882904)
			(end -15.111476 -1.106424)
			(stroke
				(width 0.1)
				(type default)
			)
			(layer "B.SilkS")
		)
		(fp_line
			(start -14.878558 -0.882904)
			(end -15.111476 -1.106424)
			(stroke
				(width 0.1)
				(type default)
			)
			(layer "B.SilkS")
		)
		(fp_line
			(start -14.878558 -0.882904)
			(end -14.938502 -0.882904)
			(stroke
				(width 0.1)
				(type default)
			)
			(layer "B.SilkS")
		)
		(fp_line
			(start -14.878558 -0.882904)
			(end -14.938502 -0.882904)
			(stroke
				(width 0.1)
				(type default)
			)
			(layer "B.SilkS")
		)
		(fp_line
			(start -14.837156 -5.171694)
			(end -14.776958 -5.171694)
			(stroke
				(width 0.1)
				(type default)
			)
			(layer "B.SilkS")
		)
		(fp_line
			(start -14.837156 -5.171694)
			(end -14.776958 -5.171694)
			(stroke
				(width 0.1)
				(type default)
			)
			(layer "B.SilkS")
		)
		(fp_line
			(start -14.837156 -5.171694)
			(end -14.669516 -5.010912)
			(stroke
				(width 0.1)
				(type default)
			)
			(layer "B.SilkS")
		)
		(fp_line
			(start -14.837156 -5.171694)
			(end -14.669516 -5.010912)
			(stroke
				(width 0.1)
				(type default)
			)
			(layer "B.SilkS")
		)
		(fp_line
			(start -14.81836 -0.882904)
			(end -15.123922 -1.17602)
			(stroke
				(width 0.1)
				(type default)
			)
			(layer "B.SilkS")
		)
		(fp_line
			(start -14.81836 -0.882904)
			(end -15.123922 -1.17602)
			(stroke
				(width 0.1)
				(type default)
			)
			(layer "B.SilkS")
		)
		(fp_line
			(start -14.81836 -0.882904)
			(end -14.878558 -0.882904)
			(stroke
				(width 0.1)
				(type default)
			)
			(layer "B.SilkS")
		)
		(fp_line
			(start -14.81836 -0.882904)
			(end -14.878558 -0.882904)
			(stroke
				(width 0.1)
				(type default)
			)
			(layer "B.SilkS")
		)
		(fp_line
			(start -14.776958 -5.171694)
			(end -14.71676 -5.171694)
			(stroke
				(width 0.1)
				(type default)
			)
			(layer "B.SilkS")
		)
		(fp_line
			(start -14.776958 -5.171694)
			(end -14.71676 -5.171694)
			(stroke
				(width 0.1)
				(type default)
			)
			(layer "B.SilkS")
		)
		(fp_line
			(start -14.776958 -5.171694)
			(end -14.681454 -5.080254)
			(stroke
				(width 0.1)
				(type default)
			)
			(layer "B.SilkS")
		)
		(fp_line
			(start -14.776958 -5.171694)
			(end -14.681454 -5.080254)
			(stroke
				(width 0.1)
				(type default)
			)
			(layer "B.SilkS")
		)
		(fp_line
			(start -14.757908 -0.882904)
			(end -15.13586 -1.245362)
			(stroke
				(width 0.1)
				(type default)
			)
			(layer "B.SilkS")
		)
		(fp_line
			(start -14.757908 -0.882904)
			(end -15.13586 -1.245362)
			(stroke
				(width 0.1)
				(type default)
			)
			(layer "B.SilkS")
		)
		(fp_line
			(start -14.757908 -0.882904)
			(end -14.81836 -0.882904)
			(stroke
				(width 0.1)
				(type default)
			)
			(layer "B.SilkS")
		)
		(fp_line
			(start -14.757908 -0.882904)
			(end -14.81836 -0.882904)
			(stroke
				(width 0.1)
				(type default)
			)
			(layer "B.SilkS")
		)
		(fp_line
			(start -14.71676 -5.171694)
			(end -14.69771 -5.171694)
			(stroke
				(width 0.1)
				(type default)
			)
			(layer "B.SilkS")
		)
		(fp_line
			(start -14.71676 -5.171694)
			(end -14.69771 -5.171694)
			(stroke
				(width 0.1)
				(type default)
			)
			(layer "B.SilkS")
		)
		(fp_line
			(start -14.71676 -5.171694)
			(end -14.6939 -5.149596)
			(stroke
				(width 0.1)
				(type default)
			)
			(layer "B.SilkS")
		)
		(fp_line
			(start -14.71676 -5.171694)
			(end -14.6939 -5.149596)
			(stroke
				(width 0.1)
				(type default)
			)
			(layer "B.SilkS")
		)
		(fp_line
			(start -14.697964 -0.882904)
			(end -15.148052 -1.314704)
			(stroke
				(width 0.1)
				(type default)
			)
			(layer "B.SilkS")
		)
		(fp_line
			(start -14.697964 -0.882904)
			(end -15.148052 -1.314704)
			(stroke
				(width 0.1)
				(type default)
			)
			(layer "B.SilkS")
		)
		(fp_line
			(start -14.697964 -0.882904)
			(end -14.757908 -0.882904)
			(stroke
				(width 0.1)
				(type default)
			)
			(layer "B.SilkS")
		)
		(fp_line
			(start -14.697964 -0.882904)
			(end -14.757908 -0.882904)
			(stroke
				(width 0.1)
				(type default)
			)
			(layer "B.SilkS")
		)
		(fp_line
			(start -14.69771 -5.171694)
			(end -14.6939 -5.149596)
			(stroke
				(width 0.1)
				(type default)
			)
			(layer "B.SilkS")
		)
		(fp_line
			(start -14.69771 -5.171694)
			(end -14.6939 -5.149596)
			(stroke
				(width 0.1)
				(type default)
			)
			(layer "B.SilkS")
		)
		(fp_line
			(start -14.681454 -5.080254)
			(end -14.6939 -5.149596)
			(stroke
				(width 0.1)
				(type default)
			)
			(layer "B.SilkS")
		)
		(fp_line
			(start -14.681454 -5.080254)
			(end -14.6939 -5.149596)
			(stroke
				(width 0.1)
				(type default)
			)
			(layer "B.SilkS")
		)
		(fp_line
			(start -14.669516 -5.010912)
			(end -14.681454 -5.080254)
			(stroke
				(width 0.1)
				(type default)
			)
			(layer "B.SilkS")
		)
		(fp_line
			(start -14.669516 -5.010912)
			(end -14.681454 -5.080254)
			(stroke
				(width 0.1)
				(type default)
			)
			(layer "B.SilkS")
		)
		(fp_line
			(start -14.657324 -4.941316)
			(end -14.669516 -5.010912)
			(stroke
				(width 0.1)
				(type default)
			)
			(layer "B.SilkS")
		)
		(fp_line
			(start -14.657324 -4.941316)
			(end -14.669516 -5.010912)
			(stroke
				(width 0.1)
				(type default)
			)
			(layer "B.SilkS")
		)
		(fp_line
			(start -14.645132 -4.872228)
			(end -14.657324 -4.941316)
			(stroke
				(width 0.1)
				(type default)
			)
			(layer "B.SilkS")
		)
		(fp_line
			(start -14.645132 -4.872228)
			(end -14.657324 -4.941316)
			(stroke
				(width 0.1)
				(type default)
			)
			(layer "B.SilkS")
		)
		(fp_line
			(start -14.637766 -0.882904)
			(end -15.160498 -1.384046)
			(stroke
				(width 0.1)
				(type default)
			)
			(layer "B.SilkS")
		)
		(fp_line
			(start -14.637766 -0.882904)
			(end -15.160498 -1.384046)
			(stroke
				(width 0.1)
				(type default)
			)
			(layer "B.SilkS")
		)
		(fp_line
			(start -14.637766 -0.882904)
			(end -14.697964 -0.882904)
			(stroke
				(width 0.1)
				(type default)
			)
			(layer "B.SilkS")
		)
		(fp_line
			(start -14.637766 -0.882904)
			(end -14.697964 -0.882904)
			(stroke
				(width 0.1)
				(type default)
			)
			(layer "B.SilkS")
		)
		(fp_line
			(start -14.63294 -4.802632)
			(end -14.645132 -4.872228)
			(stroke
				(width 0.1)
				(type default)
			)
			(layer "B.SilkS")
		)
		(fp_line
			(start -14.63294 -4.802632)
			(end -14.645132 -4.872228)
			(stroke
				(width 0.1)
				(type default)
			)
			(layer "B.SilkS")
		)
		(fp_line
			(start -14.621002 -4.733036)
			(end -14.63294 -4.802632)
			(stroke
				(width 0.1)
				(type default)
			)
			(layer "B.SilkS")
		)
		(fp_line
			(start -14.621002 -4.733036)
			(end -14.63294 -4.802632)
			(stroke
				(width 0.1)
				(type default)
			)
			(layer "B.SilkS")
		)
		(fp_line
			(start -14.608556 -4.663948)
			(end -14.621002 -4.733036)
			(stroke
				(width 0.1)
				(type default)
			)
			(layer "B.SilkS")
		)
		(fp_line
			(start -14.608556 -4.663948)
			(end -14.621002 -4.733036)
			(stroke
				(width 0.1)
				(type default)
			)
			(layer "B.SilkS")
		)
		(fp_line
			(start -14.596364 -4.594352)
			(end -14.608556 -4.663948)
			(stroke
				(width 0.1)
				(type default)
			)
			(layer "B.SilkS")
		)
		(fp_line
			(start -14.596364 -4.594352)
			(end -14.608556 -4.663948)
			(stroke
				(width 0.1)
				(type default)
			)
			(layer "B.SilkS")
		)
		(fp_line
			(start -14.584426 -4.52501)
			(end -14.596364 -4.594352)
			(stroke
				(width 0.1)
				(type default)
			)
			(layer "B.SilkS")
		)
		(fp_line
			(start -14.584426 -4.52501)
			(end -14.596364 -4.594352)
			(stroke
				(width 0.1)
				(type default)
			)
			(layer "B.SilkS")
		)
		(fp_line
			(start -14.577568 -0.882904)
			(end -15.17269 -1.453642)
			(stroke
				(width 0.1)
				(type default)
			)
			(layer "B.SilkS")
		)
		(fp_line
			(start -14.577568 -0.882904)
			(end -15.17269 -1.453642)
			(stroke
				(width 0.1)
				(type default)
			)
			(layer "B.SilkS")
		)
		(fp_line
			(start -14.577568 -0.882904)
			(end -14.637766 -0.882904)
			(stroke
				(width 0.1)
				(type default)
			)
			(layer "B.SilkS")
		)
		(fp_line
			(start -14.577568 -0.882904)
			(end -14.637766 -0.882904)
			(stroke
				(width 0.1)
				(type default)
			)
			(layer "B.SilkS")
		)
		(fp_line
			(start -14.57198 -4.455668)
			(end -14.584426 -4.52501)
			(stroke
				(width 0.1)
				(type default)
			)
			(layer "B.SilkS")
		)
		(fp_line
			(start -14.57198 -4.455668)
			(end -14.584426 -4.52501)
			(stroke
				(width 0.1)
				(type default)
			)
			(layer "B.SilkS")
		)
		(fp_line
			(start -14.560042 -4.386326)
			(end -14.57198 -4.455668)
			(stroke
				(width 0.1)
				(type default)
			)
			(layer "B.SilkS")
		)
		(fp_line
			(start -14.560042 -4.386326)
			(end -14.57198 -4.455668)
			(stroke
				(width 0.1)
				(type default)
			)
			(layer "B.SilkS")
		)
		(fp_line
			(start -14.54785 -4.316984)
			(end -14.560042 -4.386326)
			(stroke
				(width 0.1)
				(type default)
			)
			(layer "B.SilkS")
		)
		(fp_line
			(start -14.54785 -4.316984)
			(end -14.560042 -4.386326)
			(stroke
				(width 0.1)
				(type default)
			)
			(layer "B.SilkS")
		)
		(fp_line
			(start -14.535404 -4.247388)
			(end -14.54785 -4.316984)
			(stroke
				(width 0.1)
				(type default)
			)
			(layer "B.SilkS")
		)
		(fp_line
			(start -14.535404 -4.247388)
			(end -14.54785 -4.316984)
			(stroke
				(width 0.1)
				(type default)
			)
			(layer "B.SilkS")
		)
		(fp_line
			(start -14.523466 -4.178046)
			(end -14.535404 -4.247388)
			(stroke
				(width 0.1)
				(type default)
			)
			(layer "B.SilkS")
		)
		(fp_line
			(start -14.523466 -4.178046)
			(end -14.535404 -4.247388)
			(stroke
				(width 0.1)
				(type default)
			)
			(layer "B.SilkS")
		)
		(fp_line
			(start -14.523466 -4.178046)
			(end -14.511274 -4.108704)
			(stroke
				(width 0.1)
				(type default)
			)
			(layer "B.SilkS")
		)
		(fp_line
			(start -14.523466 -4.178046)
			(end -14.511274 -4.108704)
			(stroke
				(width 0.1)
				(type default)
			)
			(layer "B.SilkS")
		)
		(fp_line
			(start -14.517624 -0.882904)
			(end -15.184882 -1.522984)
			(stroke
				(width 0.1)
				(type default)
			)
			(layer "B.SilkS")
		)
		(fp_line
			(start -14.517624 -0.882904)
			(end -15.184882 -1.522984)
			(stroke
				(width 0.1)
				(type default)
			)
			(layer "B.SilkS")
		)
		(fp_line
			(start -14.517624 -0.882904)
			(end -14.577568 -0.882904)
			(stroke
				(width 0.1)
				(type default)
			)
			(layer "B.SilkS")
		)
		(fp_line
			(start -14.517624 -0.882904)
			(end -14.577568 -0.882904)
			(stroke
				(width 0.1)
				(type default)
			)
			(layer "B.SilkS")
		)
		(fp_line
			(start -14.511274 -4.108704)
			(end -14.498828 -4.039362)
			(stroke
				(width 0.1)
				(type default)
			)
			(layer "B.SilkS")
		)
		(fp_line
			(start -14.511274 -4.108704)
			(end -14.498828 -4.039362)
			(stroke
				(width 0.1)
				(type default)
			)
			(layer "B.SilkS")
		)
		(fp_line
			(start -14.498828 -4.039362)
			(end -14.486636 -3.969766)
			(stroke
				(width 0.1)
				(type default)
			)
			(layer "B.SilkS")
		)
		(fp_line
			(start -14.498828 -4.039362)
			(end -14.486636 -3.969766)
			(stroke
				(width 0.1)
				(type default)
			)
			(layer "B.SilkS")
		)
		(fp_line
			(start -14.486636 -3.969766)
			(end -14.474952 -3.900424)
			(stroke
				(width 0.1)
				(type default)
			)
			(layer "B.SilkS")
		)
		(fp_line
			(start -14.486636 -3.969766)
			(end -14.474952 -3.900424)
			(stroke
				(width 0.1)
				(type default)
			)
			(layer "B.SilkS")
		)
		(fp_line
			(start -14.474952 -3.900424)
			(end -14.462506 -3.831082)
			(stroke
				(width 0.1)
				(type default)
			)
			(layer "B.SilkS")
		)
		(fp_line
			(start -14.474952 -3.900424)
			(end -14.462506 -3.831082)
			(stroke
				(width 0.1)
				(type default)
			)
			(layer "B.SilkS")
		)
		(fp_line
			(start -14.462506 -3.831082)
			(end -14.45006 -3.76174)
			(stroke
				(width 0.1)
				(type default)
			)
			(layer "B.SilkS")
		)
		(fp_line
			(start -14.462506 -3.831082)
			(end -14.45006 -3.76174)
			(stroke
				(width 0.1)
				(type default)
			)
			(layer "B.SilkS")
		)
		(fp_line
			(start -14.45768 -0.882904)
			(end -15.19682 -1.592326)
			(stroke
				(width 0.1)
				(type default)
			)
			(layer "B.SilkS")
		)
		(fp_line
			(start -14.45768 -0.882904)
			(end -15.19682 -1.592326)
			(stroke
				(width 0.1)
				(type default)
			)
			(layer "B.SilkS")
		)
		(fp_line
			(start -14.45768 -0.882904)
			(end -14.517624 -0.882904)
			(stroke
				(width 0.1)
				(type default)
			)
			(layer "B.SilkS")
		)
		(fp_line
			(start -14.45768 -0.882904)
			(end -14.517624 -0.882904)
			(stroke
				(width 0.1)
				(type default)
			)
			(layer "B.SilkS")
		)
		(fp_line
			(start -14.45006 -3.76174)
			(end -14.438376 -3.692398)
			(stroke
				(width 0.1)
				(type default)
			)
			(layer "B.SilkS")
		)
		(fp_line
			(start -14.45006 -3.76174)
			(end -14.438376 -3.692398)
			(stroke
				(width 0.1)
				(type default)
			)
			(layer "B.SilkS")
		)
		(fp_line
			(start -14.438376 -3.692398)
			(end -14.42593 -3.622802)
			(stroke
				(width 0.1)
				(type default)
			)
			(layer "B.SilkS")
		)
		(fp_line
			(start -14.438376 -3.692398)
			(end -14.42593 -3.622802)
			(stroke
				(width 0.1)
				(type default)
			)
			(layer "B.SilkS")
		)
		(fp_line
			(start -14.42593 -3.622802)
			(end -14.413484 -3.55346)
			(stroke
				(width 0.1)
				(type default)
			)
			(layer "B.SilkS")
		)
		(fp_line
			(start -14.42593 -3.622802)
			(end -14.413484 -3.55346)
			(stroke
				(width 0.1)
				(type default)
			)
			(layer "B.SilkS")
		)
		(fp_line
			(start -14.413484 -3.55346)
			(end -14.401546 -3.484118)
			(stroke
				(width 0.1)
				(type default)
			)
			(layer "B.SilkS")
		)
		(fp_line
			(start -14.413484 -3.55346)
			(end -14.401546 -3.484118)
			(stroke
				(width 0.1)
				(type default)
			)
			(layer "B.SilkS")
		)
		(fp_line
			(start -14.401546 -3.484118)
			(end -14.389354 -3.414776)
			(stroke
				(width 0.1)
				(type default)
			)
			(layer "B.SilkS")
		)
		(fp_line
			(start -14.401546 -3.484118)
			(end -14.389354 -3.414776)
			(stroke
				(width 0.1)
				(type default)
			)
			(layer "B.SilkS")
		)
		(fp_line
			(start -14.396974 -0.882904)
			(end -15.209266 -1.661922)
			(stroke
				(width 0.1)
				(type default)
			)
			(layer "B.SilkS")
		)
		(fp_line
			(start -14.396974 -0.882904)
			(end -15.209266 -1.661922)
			(stroke
				(width 0.1)
				(type default)
			)
			(layer "B.SilkS")
		)
		(fp_line
			(start -14.396974 -0.882904)
			(end -14.45768 -0.882904)
			(stroke
				(width 0.1)
				(type default)
			)
			(layer "B.SilkS")
		)
		(fp_line
			(start -14.396974 -0.882904)
			(end -14.45768 -0.882904)
			(stroke
				(width 0.1)
				(type default)
			)
			(layer "B.SilkS")
		)
		(fp_line
			(start -14.389354 -3.414776)
			(end -14.376908 -3.34518)
			(stroke
				(width 0.1)
				(type default)
			)
			(layer "B.SilkS")
		)
		(fp_line
			(start -14.389354 -3.414776)
			(end -14.376908 -3.34518)
			(stroke
				(width 0.1)
				(type default)
			)
			(layer "B.SilkS")
		)
		(fp_line
			(start -14.376908 -3.34518)
			(end -14.36497 -3.275838)
			(stroke
				(width 0.1)
				(type default)
			)
			(layer "B.SilkS")
		)
		(fp_line
			(start -14.376908 -3.34518)
			(end -14.36497 -3.275838)
			(stroke
				(width 0.1)
				(type default)
			)
			(layer "B.SilkS")
		)
		(fp_line
			(start -14.36497 -3.275838)
			(end -14.352778 -3.206496)
			(stroke
				(width 0.1)
				(type default)
			)
			(layer "B.SilkS")
		)
		(fp_line
			(start -14.36497 -3.275838)
			(end -14.352778 -3.206496)
			(stroke
				(width 0.1)
				(type default)
			)
			(layer "B.SilkS")
		)
		(fp_line
			(start -14.352778 -3.206496)
			(end -14.340586 -3.137154)
			(stroke
				(width 0.1)
				(type default)
			)
			(layer "B.SilkS")
		)
		(fp_line
			(start -14.352778 -3.206496)
			(end -14.340586 -3.137154)
			(stroke
				(width 0.1)
				(type default)
			)
			(layer "B.SilkS")
		)
		(fp_line
			(start -14.340586 -3.137154)
			(end -14.328394 -3.067558)
			(stroke
				(width 0.1)
				(type default)
			)
			(layer "B.SilkS")
		)
		(fp_line
			(start -14.340586 -3.137154)
			(end -14.328394 -3.067558)
			(stroke
				(width 0.1)
				(type default)
			)
			(layer "B.SilkS")
		)
		(fp_line
			(start -14.33703 -0.882904)
			(end -15.221458 -1.731518)
			(stroke
				(width 0.1)
				(type default)
			)
			(layer "B.SilkS")
		)
		(fp_line
			(start -14.33703 -0.882904)
			(end -15.221458 -1.731518)
			(stroke
				(width 0.1)
				(type default)
			)
			(layer "B.SilkS")
		)
		(fp_line
			(start -14.33703 -0.882904)
			(end -14.396974 -0.882904)
			(stroke
				(width 0.1)
				(type default)
			)
			(layer "B.SilkS")
		)
		(fp_line
			(start -14.33703 -0.882904)
			(end -14.396974 -0.882904)
			(stroke
				(width 0.1)
				(type default)
			)
			(layer "B.SilkS")
		)
		(fp_line
			(start -14.328394 -3.067558)
			(end -14.316456 -2.998216)
			(stroke
				(width 0.1)
				(type default)
			)
			(layer "B.SilkS")
		)
		(fp_line
			(start -14.328394 -3.067558)
			(end -14.316456 -2.998216)
			(stroke
				(width 0.1)
				(type default)
			)
			(layer "B.SilkS")
		)
		(fp_line
			(start -14.316456 -2.998216)
			(end -14.30401 -2.928874)
			(stroke
				(width 0.1)
				(type default)
			)
			(layer "B.SilkS")
		)
		(fp_line
			(start -14.316456 -2.998216)
			(end -14.30401 -2.928874)
			(stroke
				(width 0.1)
				(type default)
			)
			(layer "B.SilkS")
		)
		(fp_line
			(start -14.30401 -2.928874)
			(end -14.291818 -2.859532)
			(stroke
				(width 0.1)
				(type default)
			)
			(layer "B.SilkS")
		)
		(fp_line
			(start -14.30401 -2.928874)
			(end -14.291818 -2.859532)
			(stroke
				(width 0.1)
				(type default)
			)
			(layer "B.SilkS")
		)
		(fp_line
			(start -14.291818 -2.859532)
			(end -14.27988 -2.79019)
			(stroke
				(width 0.1)
				(type default)
			)
			(layer "B.SilkS")
		)
		(fp_line
			(start -14.291818 -2.859532)
			(end -14.27988 -2.79019)
			(stroke
				(width 0.1)
				(type default)
			)
			(layer "B.SilkS")
		)
		(fp_line
			(start -14.27988 -2.79019)
			(end -14.267434 -2.720594)
			(stroke
				(width 0.1)
				(type default)
			)
			(layer "B.SilkS")
		)
		(fp_line
			(start -14.27988 -2.79019)
			(end -14.267434 -2.720594)
			(stroke
				(width 0.1)
				(type default)
			)
			(layer "B.SilkS")
		)
		(fp_line
			(start -14.277086 -0.882904)
			(end -15.233396 -1.800606)
			(stroke
				(width 0.1)
				(type default)
			)
			(layer "B.SilkS")
		)
		(fp_line
			(start -14.277086 -0.882904)
			(end -15.233396 -1.800606)
			(stroke
				(width 0.1)
				(type default)
			)
			(layer "B.SilkS")
		)
		(fp_line
			(start -14.277086 -0.882904)
			(end -14.33703 -0.882904)
			(stroke
				(width 0.1)
				(type default)
			)
			(layer "B.SilkS")
		)
		(fp_line
			(start -14.277086 -0.882904)
			(end -14.33703 -0.882904)
			(stroke
				(width 0.1)
				(type default)
			)
			(layer "B.SilkS")
		)
		(fp_line
			(start -14.267434 -2.720594)
			(end -14.255496 -2.651506)
			(stroke
				(width 0.1)
				(type default)
			)
			(layer "B.SilkS")
		)
		(fp_line
			(start -14.267434 -2.720594)
			(end -14.255496 -2.651506)
			(stroke
				(width 0.1)
				(type default)
			)
			(layer "B.SilkS")
		)
		(fp_line
			(start -14.255496 -2.651506)
			(end -14.243304 -2.58191)
			(stroke
				(width 0.1)
				(type default)
			)
			(layer "B.SilkS")
		)
		(fp_line
			(start -14.255496 -2.651506)
			(end -14.243304 -2.58191)
			(stroke
				(width 0.1)
				(type default)
			)
			(layer "B.SilkS")
		)
		(fp_line
			(start -14.243304 -2.58191)
			(end -14.230858 -2.512314)
			(stroke
				(width 0.1)
				(type default)
			)
			(layer "B.SilkS")
		)
		(fp_line
			(start -14.243304 -2.58191)
			(end -14.230858 -2.512314)
			(stroke
				(width 0.1)
				(type default)
			)
			(layer "B.SilkS")
		)
		(fp_line
			(start -14.230858 -2.512314)
			(end -14.21892 -2.443226)
			(stroke
				(width 0.1)
				(type default)
			)
			(layer "B.SilkS")
		)
		(fp_line
			(start -14.230858 -2.512314)
			(end -14.21892 -2.443226)
			(stroke
				(width 0.1)
				(type default)
			)
			(layer "B.SilkS")
		)
		(fp_line
			(start -14.21892 -2.443226)
			(end -14.206728 -2.373884)
			(stroke
				(width 0.1)
				(type default)
			)
			(layer "B.SilkS")
		)
		(fp_line
			(start -14.21892 -2.443226)
			(end -14.206728 -2.373884)
			(stroke
				(width 0.1)
				(type default)
			)
			(layer "B.SilkS")
		)
		(fp_line
			(start -14.216888 -0.882904)
			(end -15.245842 -1.869948)
			(stroke
				(width 0.1)
				(type default)
			)
			(layer "B.SilkS")
		)
		(fp_line
			(start -14.216888 -0.882904)
			(end -15.245842 -1.869948)
			(stroke
				(width 0.1)
				(type default)
			)
			(layer "B.SilkS")
		)
		(fp_line
			(start -14.216888 -0.882904)
			(end -14.277086 -0.882904)
			(stroke
				(width 0.1)
				(type default)
			)
			(layer "B.SilkS")
		)
		(fp_line
			(start -14.216888 -0.882904)
			(end -14.277086 -0.882904)
			(stroke
				(width 0.1)
				(type default)
			)
			(layer "B.SilkS")
		)
		(fp_line
			(start -14.206728 -2.373884)
			(end -14.194282 -2.304288)
			(stroke
				(width 0.1)
				(type default)
			)
			(layer "B.SilkS")
		)
		(fp_line
			(start -14.206728 -2.373884)
			(end -14.194282 -2.304288)
			(stroke
				(width 0.1)
				(type default)
			)
			(layer "B.SilkS")
		)
		(fp_line
			(start -14.194282 -2.304288)
			(end -14.182344 -2.234946)
			(stroke
				(width 0.1)
				(type default)
			)
			(layer "B.SilkS")
		)
		(fp_line
			(start -14.194282 -2.304288)
			(end -14.182344 -2.234946)
			(stroke
				(width 0.1)
				(type default)
			)
			(layer "B.SilkS")
		)
		(fp_line
			(start -14.182344 -2.234946)
			(end -14.170406 -2.165604)
			(stroke
				(width 0.1)
				(type default)
			)
			(layer "B.SilkS")
		)
		(fp_line
			(start -14.182344 -2.234946)
			(end -14.170406 -2.165604)
			(stroke
				(width 0.1)
				(type default)
			)
			(layer "B.SilkS")
		)
		(fp_line
			(start -14.170406 -2.165604)
			(end -14.15796 -2.096262)
			(stroke
				(width 0.1)
				(type default)
			)
			(layer "B.SilkS")
		)
		(fp_line
			(start -14.170406 -2.165604)
			(end -14.15796 -2.096262)
			(stroke
				(width 0.1)
				(type default)
			)
			(layer "B.SilkS")
		)
		(fp_line
			(start -14.15796 -2.096262)
			(end -14.145768 -2.02692)
			(stroke
				(width 0.1)
				(type default)
			)
			(layer "B.SilkS")
		)
		(fp_line
			(start -14.15796 -2.096262)
			(end -14.145768 -2.02692)
			(stroke
				(width 0.1)
				(type default)
			)
			(layer "B.SilkS")
		)
		(fp_line
			(start -14.156436 -0.882904)
			(end -15.258288 -1.939544)
			(stroke
				(width 0.1)
				(type default)
			)
			(layer "B.SilkS")
		)
		(fp_line
			(start -14.156436 -0.882904)
			(end -15.258288 -1.939544)
			(stroke
				(width 0.1)
				(type default)
			)
			(layer "B.SilkS")
		)
		(fp_line
			(start -14.156436 -0.882904)
			(end -14.216888 -0.882904)
			(stroke
				(width 0.1)
				(type default)
			)
			(layer "B.SilkS")
		)
		(fp_line
			(start -14.156436 -0.882904)
			(end -14.216888 -0.882904)
			(stroke
				(width 0.1)
				(type default)
			)
			(layer "B.SilkS")
		)
		(fp_line
			(start -14.145768 -2.02692)
			(end -14.13383 -1.957324)
			(stroke
				(width 0.1)
				(type default)
			)
			(layer "B.SilkS")
		)
		(fp_line
			(start -14.145768 -2.02692)
			(end -14.13383 -1.957324)
			(stroke
				(width 0.1)
				(type default)
			)
			(layer "B.SilkS")
		)
		(fp_line
			(start -14.13383 -1.957324)
			(end -14.121384 -1.887982)
			(stroke
				(width 0.1)
				(type default)
			)
			(layer "B.SilkS")
		)
		(fp_line
			(start -14.13383 -1.957324)
			(end -14.121384 -1.887982)
			(stroke
				(width 0.1)
				(type default)
			)
			(layer "B.SilkS")
		)
		(fp_line
			(start -14.121384 -1.887982)
			(end -14.109192 -1.81864)
			(stroke
				(width 0.1)
				(type default)
			)
			(layer "B.SilkS")
		)
		(fp_line
			(start -14.121384 -1.887982)
			(end -14.109192 -1.81864)
			(stroke
				(width 0.1)
				(type default)
			)
			(layer "B.SilkS")
		)
		(fp_line
			(start -14.109192 -1.81864)
			(end -14.097254 -1.749044)
			(stroke
				(width 0.1)
				(type default)
			)
			(layer "B.SilkS")
		)
		(fp_line
			(start -14.109192 -1.81864)
			(end -14.097254 -1.749044)
			(stroke
				(width 0.1)
				(type default)
			)
			(layer "B.SilkS")
		)
		(fp_line
			(start -14.096238 -0.882904)
			(end -15.270226 -2.00914)
			(stroke
				(width 0.1)
				(type default)
			)
			(layer "B.SilkS")
		)
		(fp_line
			(start -14.096238 -0.882904)
			(end -15.270226 -2.00914)
			(stroke
				(width 0.1)
				(type default)
			)
			(layer "B.SilkS")
		)
		(fp_line
			(start -14.096238 -0.882904)
			(end -14.156436 -0.882904)
			(stroke
				(width 0.1)
				(type default)
			)
			(layer "B.SilkS")
		)
		(fp_line
			(start -14.096238 -0.882904)
			(end -14.156436 -0.882904)
			(stroke
				(width 0.1)
				(type default)
			)
			(layer "B.SilkS")
		)
		(fp_line
			(start -14.084808 -1.679702)
			(end -14.097254 -1.749044)
			(stroke
				(width 0.1)
				(type default)
			)
			(layer "B.SilkS")
		)
		(fp_line
			(start -14.084808 -1.679702)
			(end -14.097254 -1.749044)
			(stroke
				(width 0.1)
				(type default)
			)
			(layer "B.SilkS")
		)
		(fp_line
			(start -14.084808 -1.679702)
			(end -14.072362 -1.61036)
			(stroke
				(width 0.1)
				(type default)
			)
			(layer "B.SilkS")
		)
		(fp_line
			(start -14.084808 -1.679702)
			(end -14.072362 -1.61036)
			(stroke
				(width 0.1)
				(type default)
			)
			(layer "B.SilkS")
		)
		(fp_line
			(start -14.072362 -1.61036)
			(end -15.42923 -2.911602)
			(stroke
				(width 0.1)
				(type default)
			)
			(layer "B.SilkS")
		)
		(fp_line
			(start -14.072362 -1.61036)
			(end -15.42923 -2.911602)
			(stroke
				(width 0.1)
				(type default)
			)
			(layer "B.SilkS")
		)
		(fp_line
			(start -14.072362 -1.61036)
			(end -14.060678 -1.541018)
			(stroke
				(width 0.1)
				(type default)
			)
			(layer "B.SilkS")
		)
		(fp_line
			(start -14.072362 -1.61036)
			(end -14.060678 -1.541018)
			(stroke
				(width 0.1)
				(type default)
			)
			(layer "B.SilkS")
		)
		(fp_line
			(start -14.060678 -1.541018)
			(end -15.416784 -2.84226)
			(stroke
				(width 0.1)
				(type default)
			)
			(layer "B.SilkS")
		)
		(fp_line
			(start -14.060678 -1.541018)
			(end -15.416784 -2.84226)
			(stroke
				(width 0.1)
				(type default)
			)
			(layer "B.SilkS")
		)
		(fp_line
			(start -14.060678 -1.541018)
			(end -14.048232 -1.471676)
			(stroke
				(width 0.1)
				(type default)
			)
			(layer "B.SilkS")
		)
		(fp_line
			(start -14.060678 -1.541018)
			(end -14.048232 -1.471676)
			(stroke
				(width 0.1)
				(type default)
			)
			(layer "B.SilkS")
		)
		(fp_line
			(start -14.048232 -1.471676)
			(end -15.404592 -2.772664)
			(stroke
				(width 0.1)
				(type default)
			)
			(layer "B.SilkS")
		)
		(fp_line
			(start -14.048232 -1.471676)
			(end -15.404592 -2.772664)
			(stroke
				(width 0.1)
				(type default)
			)
			(layer "B.SilkS")
		)
		(fp_line
			(start -14.048232 -1.471676)
			(end -14.03604 -1.40208)
			(stroke
				(width 0.1)
				(type default)
			)
			(layer "B.SilkS")
		)
		(fp_line
			(start -14.048232 -1.471676)
			(end -14.03604 -1.40208)
			(stroke
				(width 0.1)
				(type default)
			)
			(layer "B.SilkS")
		)
		(fp_line
			(start -14.036294 -0.882904)
			(end -15.282418 -2.078482)
			(stroke
				(width 0.1)
				(type default)
			)
			(layer "B.SilkS")
		)
		(fp_line
			(start -14.036294 -0.882904)
			(end -15.282418 -2.078482)
			(stroke
				(width 0.1)
				(type default)
			)
			(layer "B.SilkS")
		)
		(fp_line
			(start -14.036294 -0.882904)
			(end -14.096238 -0.882904)
			(stroke
				(width 0.1)
				(type default)
			)
			(layer "B.SilkS")
		)
		(fp_line
			(start -14.036294 -0.882904)
			(end -14.096238 -0.882904)
			(stroke
				(width 0.1)
				(type default)
			)
			(layer "B.SilkS")
		)
		(fp_line
			(start -14.03604 -1.40208)
			(end -15.392654 -2.703322)
			(stroke
				(width 0.1)
				(type default)
			)
			(layer "B.SilkS")
		)
		(fp_line
			(start -14.03604 -1.40208)
			(end -15.392654 -2.703322)
			(stroke
				(width 0.1)
				(type default)
			)
			(layer "B.SilkS")
		)
		(fp_line
			(start -14.03604 -1.40208)
			(end -14.023848 -1.332738)
			(stroke
				(width 0.1)
				(type default)
			)
			(layer "B.SilkS")
		)
		(fp_line
			(start -14.03604 -1.40208)
			(end -14.023848 -1.332738)
			(stroke
				(width 0.1)
				(type default)
			)
			(layer "B.SilkS")
		)
		(fp_line
			(start -14.023848 -1.332738)
			(end -15.380208 -2.633726)
			(stroke
				(width 0.1)
				(type default)
			)
			(layer "B.SilkS")
		)
		(fp_line
			(start -14.023848 -1.332738)
			(end -15.380208 -2.633726)
			(stroke
				(width 0.1)
				(type default)
			)
			(layer "B.SilkS")
		)
		(fp_line
			(start -14.023848 -1.332738)
			(end -14.01191 -1.26365)
			(stroke
				(width 0.1)
				(type default)
			)
			(layer "B.SilkS")
		)
		(fp_line
			(start -14.023848 -1.332738)
			(end -14.01191 -1.26365)
			(stroke
				(width 0.1)
				(type default)
			)
			(layer "B.SilkS")
		)
		(fp_line
			(start -14.01191 -1.26365)
			(end -15.367762 -2.564384)
			(stroke
				(width 0.1)
				(type default)
			)
			(layer "B.SilkS")
		)
		(fp_line
			(start -14.01191 -1.26365)
			(end -15.367762 -2.564384)
			(stroke
				(width 0.1)
				(type default)
			)
			(layer "B.SilkS")
		)
		(fp_line
			(start -14.01191 -1.26365)
			(end -13.999464 -1.194054)
			(stroke
				(width 0.1)
				(type default)
			)
			(layer "B.SilkS")
		)
		(fp_line
			(start -14.01191 -1.26365)
			(end -13.999464 -1.194054)
			(stroke
				(width 0.1)
				(type default)
			)
			(layer "B.SilkS")
		)
		(fp_line
			(start -13.999464 -1.194054)
			(end -15.355824 -2.495042)
			(stroke
				(width 0.1)
				(type default)
			)
			(layer "B.SilkS")
		)
		(fp_line
			(start -13.999464 -1.194054)
			(end -15.355824 -2.495042)
			(stroke
				(width 0.1)
				(type default)
			)
			(layer "B.SilkS")
		)
		(fp_line
			(start -13.999464 -1.194054)
			(end -13.987272 -1.124458)
			(stroke
				(width 0.1)
				(type default)
			)
			(layer "B.SilkS")
		)
		(fp_line
			(start -13.999464 -1.194054)
			(end -13.987272 -1.124458)
			(stroke
				(width 0.1)
				(type default)
			)
			(layer "B.SilkS")
		)
		(fp_line
			(start -13.987272 -1.124458)
			(end -15.343632 -2.425446)
			(stroke
				(width 0.1)
				(type default)
			)
			(layer "B.SilkS")
		)
		(fp_line
			(start -13.987272 -1.124458)
			(end -15.343632 -2.425446)
			(stroke
				(width 0.1)
				(type default)
			)
			(layer "B.SilkS")
		)
		(fp_line
			(start -13.987272 -1.124458)
			(end -13.975334 -1.055116)
			(stroke
				(width 0.1)
				(type default)
			)
			(layer "B.SilkS")
		)
		(fp_line
			(start -13.987272 -1.124458)
			(end -13.975334 -1.055116)
			(stroke
				(width 0.1)
				(type default)
			)
			(layer "B.SilkS")
		)
		(fp_line
			(start -13.976096 -0.882904)
			(end -15.294864 -2.147824)
			(stroke
				(width 0.1)
				(type default)
			)
			(layer "B.SilkS")
		)
		(fp_line
			(start -13.976096 -0.882904)
			(end -15.294864 -2.147824)
			(stroke
				(width 0.1)
				(type default)
			)
			(layer "B.SilkS")
		)
		(fp_line
			(start -13.976096 -0.882904)
			(end -14.036294 -0.882904)
			(stroke
				(width 0.1)
				(type default)
			)
			(layer "B.SilkS")
		)
		(fp_line
			(start -13.976096 -0.882904)
			(end -14.036294 -0.882904)
			(stroke
				(width 0.1)
				(type default)
			)
			(layer "B.SilkS")
		)
		(fp_line
			(start -13.975334 -1.055116)
			(end -15.331186 -2.356104)
			(stroke
				(width 0.1)
				(type default)
			)
			(layer "B.SilkS")
		)
		(fp_line
			(start -13.975334 -1.055116)
			(end -15.331186 -2.356104)
			(stroke
				(width 0.1)
				(type default)
			)
			(layer "B.SilkS")
		)
		(fp_line
			(start -13.975334 -1.055116)
			(end -13.962888 -0.985774)
			(stroke
				(width 0.1)
				(type default)
			)
			(layer "B.SilkS")
		)
		(fp_line
			(start -13.975334 -1.055116)
			(end -13.962888 -0.985774)
			(stroke
				(width 0.1)
				(type default)
			)
			(layer "B.SilkS")
		)
		(fp_line
			(start -13.962888 -0.985774)
			(end -15.319248 -2.286762)
			(stroke
				(width 0.1)
				(type default)
			)
			(layer "B.SilkS")
		)
		(fp_line
			(start -13.962888 -0.985774)
			(end -15.319248 -2.286762)
			(stroke
				(width 0.1)
				(type default)
			)
			(layer "B.SilkS")
		)
		(fp_line
			(start -13.962888 -0.985774)
			(end -13.95095 -0.916178)
			(stroke
				(width 0.1)
				(type default)
			)
			(layer "B.SilkS")
		)
		(fp_line
			(start -13.962888 -0.985774)
			(end -13.95095 -0.916178)
			(stroke
				(width 0.1)
				(type default)
			)
			(layer "B.SilkS")
		)
		(fp_line
			(start -13.95095 -0.916178)
			(end -15.307056 -2.21742)
			(stroke
				(width 0.1)
				(type default)
			)
			(layer "B.SilkS")
		)
		(fp_line
			(start -13.95095 -0.916178)
			(end -15.307056 -2.21742)
			(stroke
				(width 0.1)
				(type default)
			)
			(layer "B.SilkS")
		)
		(fp_line
			(start -13.95095 -0.916178)
			(end -13.944854 -0.882904)
			(stroke
				(width 0.1)
				(type default)
			)
			(layer "B.SilkS")
		)
		(fp_line
			(start -13.95095 -0.916178)
			(end -13.944854 -0.882904)
			(stroke
				(width 0.1)
				(type default)
			)
			(layer "B.SilkS")
		)
		(fp_line
			(start -13.944854 -0.882904)
			(end -13.976096 -0.882904)
			(stroke
				(width 0.1)
				(type default)
			)
			(layer "B.SilkS")
		)
		(fp_line
			(start -13.944854 -0.882904)
			(end -13.976096 -0.882904)
			(stroke
				(width 0.1)
				(type default)
			)
			(layer "B.SilkS")
		)
		(fp_line
			(start -13.751814 -4.072636)
			(end -12.344654 -2.722626)
			(stroke
				(width 0.1)
				(type default)
			)
			(layer "B.SilkS")
		)
		(fp_line
			(start -13.751814 -4.072636)
			(end -12.344654 -2.722626)
			(stroke
				(width 0.1)
				(type default)
			)
			(layer "B.SilkS")
		)
		(fp_line
			(start -13.750036 -4.12877)
			(end -12.306046 -2.743454)
			(stroke
				(width 0.1)
				(type default)
			)
			(layer "B.SilkS")
		)
		(fp_line
			(start -13.750036 -4.12877)
			(end -12.306046 -2.743454)
			(stroke
				(width 0.1)
				(type default)
			)
			(layer "B.SilkS")
		)
		(fp_line
			(start -13.74648 -4.010152)
			(end -12.380214 -2.699512)
			(stroke
				(width 0.1)
				(type default)
			)
			(layer "B.SilkS")
		)
		(fp_line
			(start -13.74648 -4.010152)
			(end -12.380214 -2.699512)
			(stroke
				(width 0.1)
				(type default)
			)
			(layer "B.SilkS")
		)
		(fp_line
			(start -13.743178 -4.179824)
			(end -12.266422 -2.76352)
			(stroke
				(width 0.1)
				(type default)
			)
			(layer "B.SilkS")
		)
		(fp_line
			(start -13.743178 -4.179824)
			(end -12.266422 -2.76352)
			(stroke
				(width 0.1)
				(type default)
			)
			(layer "B.SilkS")
		)
		(fp_line
			(start -13.741654 -3.947668)
			(end -12.408154 -2.668524)
			(stroke
				(width 0.1)
				(type default)
			)
			(layer "B.SilkS")
		)
		(fp_line
			(start -13.741654 -3.947668)
			(end -12.408154 -2.668524)
			(stroke
				(width 0.1)
				(type default)
			)
			(layer "B.SilkS")
		)
		(fp_line
			(start -13.736574 -3.88493)
			(end -12.395962 -2.598928)
			(stroke
				(width 0.1)
				(type default)
			)
			(layer "B.SilkS")
		)
		(fp_line
			(start -13.736574 -3.88493)
			(end -12.395962 -2.598928)
			(stroke
				(width 0.1)
				(type default)
			)
			(layer "B.SilkS")
		)
		(fp_line
			(start -13.73632 -4.230878)
			(end -12.224766 -2.781046)
			(stroke
				(width 0.1)
				(type default)
			)
			(layer "B.SilkS")
		)
		(fp_line
			(start -13.73632 -4.230878)
			(end -12.224766 -2.781046)
			(stroke
				(width 0.1)
				(type default)
			)
			(layer "B.SilkS")
		)
		(fp_line
			(start -13.731494 -3.822446)
			(end -12.38377 -2.529586)
			(stroke
				(width 0.1)
				(type default)
			)
			(layer "B.SilkS")
		)
		(fp_line
			(start -13.731494 -3.822446)
			(end -12.38377 -2.529586)
			(stroke
				(width 0.1)
				(type default)
			)
			(layer "B.SilkS")
		)
		(fp_line
			(start -13.729208 -4.281932)
			(end -12.181078 -2.796794)
			(stroke
				(width 0.1)
				(type default)
			)
			(layer "B.SilkS")
		)
		(fp_line
			(start -13.729208 -4.281932)
			(end -12.181078 -2.796794)
			(stroke
				(width 0.1)
				(type default)
			)
			(layer "B.SilkS")
		)
		(fp_line
			(start -13.72616 -3.759962)
			(end -12.371578 -2.460244)
			(stroke
				(width 0.1)
				(type default)
			)
			(layer "B.SilkS")
		)
		(fp_line
			(start -13.72616 -3.759962)
			(end -12.371578 -2.460244)
			(stroke
				(width 0.1)
				(type default)
			)
			(layer "B.SilkS")
		)
		(fp_line
			(start -13.722096 -4.332732)
			(end -12.135612 -2.810764)
			(stroke
				(width 0.1)
				(type default)
			)
			(layer "B.SilkS")
		)
		(fp_line
			(start -13.722096 -4.332732)
			(end -12.135612 -2.810764)
			(stroke
				(width 0.1)
				(type default)
			)
			(layer "B.SilkS")
		)
		(fp_line
			(start -13.715238 -4.383786)
			(end -12.087352 -2.822448)
			(stroke
				(width 0.1)
				(type default)
			)
			(layer "B.SilkS")
		)
		(fp_line
			(start -13.715238 -4.383786)
			(end -12.087352 -2.822448)
			(stroke
				(width 0.1)
				(type default)
			)
			(layer "B.SilkS")
		)
		(fp_line
			(start -13.714222 -3.690366)
			(end -13.70203 -3.621024)
			(stroke
				(width 0.1)
				(type default)
			)
			(layer "B.SilkS")
		)
		(fp_line
			(start -13.714222 -3.690366)
			(end -13.70203 -3.621024)
			(stroke
				(width 0.1)
				(type default)
			)
			(layer "B.SilkS")
		)
		(fp_line
			(start -13.714222 -3.690366)
			(end -12.359386 -2.390902)
			(stroke
				(width 0.1)
				(type default)
			)
			(layer "B.SilkS")
		)
		(fp_line
			(start -13.714222 -3.690366)
			(end -12.359386 -2.390902)
			(stroke
				(width 0.1)
				(type default)
			)
			(layer "B.SilkS")
		)
		(fp_line
			(start -13.70203 -3.621024)
			(end -13.690092 -3.551682)
			(stroke
				(width 0.1)
				(type default)
			)
			(layer "B.SilkS")
		)
		(fp_line
			(start -13.70203 -3.621024)
			(end -13.690092 -3.551682)
			(stroke
				(width 0.1)
				(type default)
			)
			(layer "B.SilkS")
		)
		(fp_line
			(start -13.70203 -3.621024)
			(end -12.347194 -2.321306)
			(stroke
				(width 0.1)
				(type default)
			)
			(layer "B.SilkS")
		)
		(fp_line
			(start -13.70203 -3.621024)
			(end -12.347194 -2.321306)
			(stroke
				(width 0.1)
				(type default)
			)
			(layer "B.SilkS")
		)
		(fp_line
			(start -13.701014 -4.42849)
			(end -12.037822 -2.832862)
			(stroke
				(width 0.1)
				(type default)
			)
			(layer "B.SilkS")
		)
		(fp_line
			(start -13.701014 -4.42849)
			(end -12.037822 -2.832862)
			(stroke
				(width 0.1)
				(type default)
			)
			(layer "B.SilkS")
		)
		(fp_line
			(start -13.690092 -3.551682)
			(end -13.677646 -3.48234)
			(stroke
				(width 0.1)
				(type default)
			)
			(layer "B.SilkS")
		)
		(fp_line
			(start -13.690092 -3.551682)
			(end -13.677646 -3.48234)
			(stroke
				(width 0.1)
				(type default)
			)
			(layer "B.SilkS")
		)
		(fp_line
			(start -13.690092 -3.551682)
			(end -12.335002 -2.251964)
			(stroke
				(width 0.1)
				(type default)
			)
			(layer "B.SilkS")
		)
		(fp_line
			(start -13.690092 -3.551682)
			(end -12.335002 -2.251964)
			(stroke
				(width 0.1)
				(type default)
			)
			(layer "B.SilkS")
		)
		(fp_line
			(start -13.684504 -4.469638)
			(end -11.986006 -2.840482)
			(stroke
				(width 0.1)
				(type default)
			)
			(layer "B.SilkS")
		)
		(fp_line
			(start -13.684504 -4.469638)
			(end -11.986006 -2.840482)
			(stroke
				(width 0.1)
				(type default)
			)
			(layer "B.SilkS")
		)
		(fp_line
			(start -13.677646 -3.48234)
			(end -13.665708 -3.412998)
			(stroke
				(width 0.1)
				(type default)
			)
			(layer "B.SilkS")
		)
		(fp_line
			(start -13.677646 -3.48234)
			(end -13.665708 -3.412998)
			(stroke
				(width 0.1)
				(type default)
			)
			(layer "B.SilkS")
		)
		(fp_line
			(start -13.677646 -3.48234)
			(end -12.323064 -2.182622)
			(stroke
				(width 0.1)
				(type default)
			)
			(layer "B.SilkS")
		)
		(fp_line
			(start -13.677646 -3.48234)
			(end -12.323064 -2.182622)
			(stroke
				(width 0.1)
				(type default)
			)
			(layer "B.SilkS")
		)
		(fp_line
			(start -13.667232 -4.51104)
			(end -11.93292 -2.84734)
			(stroke
				(width 0.1)
				(type default)
			)
			(layer "B.SilkS")
		)
		(fp_line
			(start -13.667232 -4.51104)
			(end -11.93292 -2.84734)
			(stroke
				(width 0.1)
				(type default)
			)
			(layer "B.SilkS")
		)
		(fp_line
			(start -13.665708 -3.412998)
			(end -13.653516 -3.343402)
			(stroke
				(width 0.1)
				(type default)
			)
			(layer "B.SilkS")
		)
		(fp_line
			(start -13.665708 -3.412998)
			(end -13.653516 -3.343402)
			(stroke
				(width 0.1)
				(type default)
			)
			(layer "B.SilkS")
		)
		(fp_line
			(start -13.665708 -3.412998)
			(end -10.943336 -0.801624)
			(stroke
				(width 0.1)
				(type default)
			)
			(layer "B.SilkS")
		)
		(fp_line
			(start -13.665708 -3.412998)
			(end -10.943336 -0.801624)
			(stroke
				(width 0.1)
				(type default)
			)
			(layer "B.SilkS")
		)
		(fp_line
			(start -13.653516 -3.343402)
			(end -13.64107 -3.27406)
			(stroke
				(width 0.1)
				(type default)
			)
			(layer "B.SilkS")
		)
		(fp_line
			(start -13.653516 -3.343402)
			(end -13.64107 -3.27406)
			(stroke
				(width 0.1)
				(type default)
			)
			(layer "B.SilkS")
		)
		(fp_line
			(start -13.64996 -4.552442)
			(end -11.877548 -2.851912)
			(stroke
				(width 0.1)
				(type default)
			)
			(layer "B.SilkS")
		)
		(fp_line
			(start -13.64996 -4.552442)
			(end -11.877548 -2.851912)
			(stroke
				(width 0.1)
				(type default)
			)
			(layer "B.SilkS")
		)
		(fp_line
			(start -13.633196 -4.593844)
			(end -11.82116 -2.855722)
			(stroke
				(width 0.1)
				(type default)
			)
			(layer "B.SilkS")
		)
		(fp_line
			(start -13.633196 -4.593844)
			(end -11.82116 -2.855722)
			(stroke
				(width 0.1)
				(type default)
			)
			(layer "B.SilkS")
		)
		(fp_line
			(start -13.629132 -3.204972)
			(end -13.64107 -3.27406)
			(stroke
				(width 0.1)
				(type default)
			)
			(layer "B.SilkS")
		)
		(fp_line
			(start -13.629132 -3.204972)
			(end -13.64107 -3.27406)
			(stroke
				(width 0.1)
				(type default)
			)
			(layer "B.SilkS")
		)
		(fp_line
			(start -13.61694 -3.135376)
			(end -13.629132 -3.204972)
			(stroke
				(width 0.1)
				(type default)
			)
			(layer "B.SilkS")
		)
		(fp_line
			(start -13.61694 -3.135376)
			(end -13.629132 -3.204972)
			(stroke
				(width 0.1)
				(type default)
			)
			(layer "B.SilkS")
		)
		(fp_line
			(start -13.616432 -4.635246)
			(end -12.57808 -3.639312)
			(stroke
				(width 0.1)
				(type default)
			)
			(layer "B.SilkS")
		)
		(fp_line
			(start -13.616432 -4.635246)
			(end -12.57808 -3.639312)
			(stroke
				(width 0.1)
				(type default)
			)
			(layer "B.SilkS")
		)
		(fp_line
			(start -13.604494 -3.06578)
			(end -13.61694 -3.135376)
			(stroke
				(width 0.1)
				(type default)
			)
			(layer "B.SilkS")
		)
		(fp_line
			(start -13.604494 -3.06578)
			(end -13.61694 -3.135376)
			(stroke
				(width 0.1)
				(type default)
			)
			(layer "B.SilkS")
		)
		(fp_line
			(start -13.59535 -4.672838)
			(end -12.590018 -3.708654)
			(stroke
				(width 0.1)
				(type default)
			)
			(layer "B.SilkS")
		)
		(fp_line
			(start -13.59535 -4.672838)
			(end -12.590018 -3.708654)
			(stroke
				(width 0.1)
				(type default)
			)
			(layer "B.SilkS")
		)
		(fp_line
			(start -13.592556 -2.996692)
			(end -13.604494 -3.06578)
			(stroke
				(width 0.1)
				(type default)
			)
			(layer "B.SilkS")
		)
		(fp_line
			(start -13.592556 -2.996692)
			(end -13.604494 -3.06578)
			(stroke
				(width 0.1)
				(type default)
			)
			(layer "B.SilkS")
		)
		(fp_line
			(start -13.580364 -2.927096)
			(end -13.592556 -2.996692)
			(stroke
				(width 0.1)
				(type default)
			)
			(layer "B.SilkS")
		)
		(fp_line
			(start -13.580364 -2.927096)
			(end -13.592556 -2.996692)
			(stroke
				(width 0.1)
				(type default)
			)
			(layer "B.SilkS")
		)
		(fp_line
			(start -13.569442 -4.705858)
			(end -12.601956 -3.777996)
			(stroke
				(width 0.1)
				(type default)
			)
			(layer "B.SilkS")
		)
		(fp_line
			(start -13.569442 -4.705858)
			(end -12.601956 -3.777996)
			(stroke
				(width 0.1)
				(type default)
			)
			(layer "B.SilkS")
		)
		(fp_line
			(start -13.568172 -2.857754)
			(end -13.580364 -2.927096)
			(stroke
				(width 0.1)
				(type default)
			)
			(layer "B.SilkS")
		)
		(fp_line
			(start -13.568172 -2.857754)
			(end -13.580364 -2.927096)
			(stroke
				(width 0.1)
				(type default)
			)
			(layer "B.SilkS")
		)
		(fp_line
			(start -13.55598 -2.788412)
			(end -13.568172 -2.857754)
			(stroke
				(width 0.1)
				(type default)
			)
			(layer "B.SilkS")
		)
		(fp_line
			(start -13.55598 -2.788412)
			(end -13.568172 -2.857754)
			(stroke
				(width 0.1)
				(type default)
			)
			(layer "B.SilkS")
		)
		(fp_line
			(start -13.544042 -4.738878)
			(end -12.60856 -3.84175)
			(stroke
				(width 0.1)
				(type default)
			)
			(layer "B.SilkS")
		)
		(fp_line
			(start -13.544042 -4.738878)
			(end -12.60856 -3.84175)
			(stroke
				(width 0.1)
				(type default)
			)
			(layer "B.SilkS")
		)
		(fp_line
			(start -13.544042 -2.71907)
			(end -13.55598 -2.788412)
			(stroke
				(width 0.1)
				(type default)
			)
			(layer "B.SilkS")
		)
		(fp_line
			(start -13.544042 -2.71907)
			(end -13.55598 -2.788412)
			(stroke
				(width 0.1)
				(type default)
			)
			(layer "B.SilkS")
		)
		(fp_line
			(start -13.531596 -2.649728)
			(end -13.544042 -2.71907)
			(stroke
				(width 0.1)
				(type default)
			)
			(layer "B.SilkS")
		)
		(fp_line
			(start -13.531596 -2.649728)
			(end -13.544042 -2.71907)
			(stroke
				(width 0.1)
				(type default)
			)
			(layer "B.SilkS")
		)
		(fp_line
			(start -13.519404 -2.580386)
			(end -13.531596 -2.649728)
			(stroke
				(width 0.1)
				(type default)
			)
			(layer "B.SilkS")
		)
		(fp_line
			(start -13.519404 -2.580386)
			(end -13.531596 -2.649728)
			(stroke
				(width 0.1)
				(type default)
			)
			(layer "B.SilkS")
		)
		(fp_line
			(start -13.518134 -4.771898)
			(end -12.612116 -3.902964)
			(stroke
				(width 0.1)
				(type default)
			)
			(layer "B.SilkS")
		)
		(fp_line
			(start -13.518134 -4.771898)
			(end -12.612116 -3.902964)
			(stroke
				(width 0.1)
				(type default)
			)
			(layer "B.SilkS")
		)
		(fp_line
			(start -13.507466 -2.51079)
			(end -13.519404 -2.580386)
			(stroke
				(width 0.1)
				(type default)
			)
			(layer "B.SilkS")
		)
		(fp_line
			(start -13.507466 -2.51079)
			(end -13.519404 -2.580386)
			(stroke
				(width 0.1)
				(type default)
			)
			(layer "B.SilkS")
		)
		(fp_line
			(start -13.49502 -2.441448)
			(end -13.507466 -2.51079)
			(stroke
				(width 0.1)
				(type default)
			)
			(layer "B.SilkS")
		)
		(fp_line
			(start -13.49502 -2.441448)
			(end -13.507466 -2.51079)
			(stroke
				(width 0.1)
				(type default)
			)
			(layer "B.SilkS")
		)
		(fp_line
			(start -13.492226 -4.804918)
			(end -12.606782 -3.955288)
			(stroke
				(width 0.1)
				(type default)
			)
			(layer "B.SilkS")
		)
		(fp_line
			(start -13.492226 -4.804918)
			(end -12.606782 -3.955288)
			(stroke
				(width 0.1)
				(type default)
			)
			(layer "B.SilkS")
		)
		(fp_line
			(start -13.483082 -2.372106)
			(end -13.49502 -2.441448)
			(stroke
				(width 0.1)
				(type default)
			)
			(layer "B.SilkS")
		)
		(fp_line
			(start -13.483082 -2.372106)
			(end -13.49502 -2.441448)
			(stroke
				(width 0.1)
				(type default)
			)
			(layer "B.SilkS")
		)
		(fp_line
			(start -13.47089 -2.302764)
			(end -13.483082 -2.372106)
			(stroke
				(width 0.1)
				(type default)
			)
			(layer "B.SilkS")
		)
		(fp_line
			(start -13.47089 -2.302764)
			(end -13.483082 -2.372106)
			(stroke
				(width 0.1)
				(type default)
			)
			(layer "B.SilkS")
		)
		(fp_line
			(start -13.466826 -4.837938)
			(end -12.599162 -4.005834)
			(stroke
				(width 0.1)
				(type default)
			)
			(layer "B.SilkS")
		)
		(fp_line
			(start -13.466826 -4.837938)
			(end -12.599162 -4.005834)
			(stroke
				(width 0.1)
				(type default)
			)
			(layer "B.SilkS")
		)
		(fp_line
			(start -13.458444 -2.233422)
			(end -13.47089 -2.302764)
			(stroke
				(width 0.1)
				(type default)
			)
			(layer "B.SilkS")
		)
		(fp_line
			(start -13.458444 -2.233422)
			(end -13.47089 -2.302764)
			(stroke
				(width 0.1)
				(type default)
			)
			(layer "B.SilkS")
		)
		(fp_line
			(start -13.446506 -2.163826)
			(end -13.458444 -2.233422)
			(stroke
				(width 0.1)
				(type default)
			)
			(layer "B.SilkS")
		)
		(fp_line
			(start -13.446506 -2.163826)
			(end -13.458444 -2.233422)
			(stroke
				(width 0.1)
				(type default)
			)
			(layer "B.SilkS")
		)
		(fp_line
			(start -13.440664 -4.871212)
			(end -12.58443 -4.049522)
			(stroke
				(width 0.1)
				(type default)
			)
			(layer "B.SilkS")
		)
		(fp_line
			(start -13.440664 -4.871212)
			(end -12.58443 -4.049522)
			(stroke
				(width 0.1)
				(type default)
			)
			(layer "B.SilkS")
		)
		(fp_line
			(start -13.434314 -2.094738)
			(end -13.446506 -2.163826)
			(stroke
				(width 0.1)
				(type default)
			)
			(layer "B.SilkS")
		)
		(fp_line
			(start -13.434314 -2.094738)
			(end -13.446506 -2.163826)
			(stroke
				(width 0.1)
				(type default)
			)
			(layer "B.SilkS")
		)
		(fp_line
			(start -13.422122 -2.025396)
			(end -13.434314 -2.094738)
			(stroke
				(width 0.1)
				(type default)
			)
			(layer "B.SilkS")
		)
		(fp_line
			(start -13.422122 -2.025396)
			(end -13.434314 -2.094738)
			(stroke
				(width 0.1)
				(type default)
			)
			(layer "B.SilkS")
		)
		(fp_line
			(start -13.40993 -1.9558)
			(end -13.422122 -2.025396)
			(stroke
				(width 0.1)
				(type default)
			)
			(layer "B.SilkS")
		)
		(fp_line
			(start -13.40993 -1.9558)
			(end -13.422122 -2.025396)
			(stroke
				(width 0.1)
				(type default)
			)
			(layer "B.SilkS")
		)
		(fp_line
			(start -13.407136 -4.896358)
			(end -12.568936 -4.092194)
			(stroke
				(width 0.1)
				(type default)
			)
			(layer "B.SilkS")
		)
		(fp_line
			(start -13.407136 -4.896358)
			(end -12.568936 -4.092194)
			(stroke
				(width 0.1)
				(type default)
			)
			(layer "B.SilkS")
		)
		(fp_line
			(start -13.397992 -1.886458)
			(end -13.40993 -1.9558)
			(stroke
				(width 0.1)
				(type default)
			)
			(layer "B.SilkS")
		)
		(fp_line
			(start -13.397992 -1.886458)
			(end -13.40993 -1.9558)
			(stroke
				(width 0.1)
				(type default)
			)
			(layer "B.SilkS")
		)
		(fp_line
			(start -13.385546 -1.817116)
			(end -13.397992 -1.886458)
			(stroke
				(width 0.1)
				(type default)
			)
			(layer "B.SilkS")
		)
		(fp_line
			(start -13.385546 -1.817116)
			(end -13.397992 -1.886458)
			(stroke
				(width 0.1)
				(type default)
			)
			(layer "B.SilkS")
		)
		(fp_line
			(start -13.373862 -4.922012)
			(end -12.545822 -4.127754)
			(stroke
				(width 0.1)
				(type default)
			)
			(layer "B.SilkS")
		)
		(fp_line
			(start -13.373862 -4.922012)
			(end -12.545822 -4.127754)
			(stroke
				(width 0.1)
				(type default)
			)
			(layer "B.SilkS")
		)
		(fp_line
			(start -13.373354 -1.74752)
			(end -13.385546 -1.817116)
			(stroke
				(width 0.1)
				(type default)
			)
			(layer "B.SilkS")
		)
		(fp_line
			(start -13.373354 -1.74752)
			(end -13.385546 -1.817116)
			(stroke
				(width 0.1)
				(type default)
			)
			(layer "B.SilkS")
		)
		(fp_line
			(start -13.361416 -1.678178)
			(end -13.373354 -1.74752)
			(stroke
				(width 0.1)
				(type default)
			)
			(layer "B.SilkS")
		)
		(fp_line
			(start -13.361416 -1.678178)
			(end -13.373354 -1.74752)
			(stroke
				(width 0.1)
				(type default)
			)
			(layer "B.SilkS")
		)
		(fp_line
			(start -13.34897 -1.608836)
			(end -13.361416 -1.678178)
			(stroke
				(width 0.1)
				(type default)
			)
			(layer "B.SilkS")
		)
		(fp_line
			(start -13.34897 -1.608836)
			(end -13.361416 -1.678178)
			(stroke
				(width 0.1)
				(type default)
			)
			(layer "B.SilkS")
		)
		(fp_line
			(start -13.34008 -4.947412)
			(end -12.522454 -4.16306)
			(stroke
				(width 0.1)
				(type default)
			)
			(layer "B.SilkS")
		)
		(fp_line
			(start -13.34008 -4.947412)
			(end -12.522454 -4.16306)
			(stroke
				(width 0.1)
				(type default)
			)
			(layer "B.SilkS")
		)
		(fp_line
			(start -13.337286 -1.539494)
			(end -13.34897 -1.608836)
			(stroke
				(width 0.1)
				(type default)
			)
			(layer "B.SilkS")
		)
		(fp_line
			(start -13.337286 -1.539494)
			(end -13.34897 -1.608836)
			(stroke
				(width 0.1)
				(type default)
			)
			(layer "B.SilkS")
		)
		(fp_line
			(start -13.32484 -1.470152)
			(end -13.337286 -1.539494)
			(stroke
				(width 0.1)
				(type default)
			)
			(layer "B.SilkS")
		)
		(fp_line
			(start -13.32484 -1.470152)
			(end -13.337286 -1.539494)
			(stroke
				(width 0.1)
				(type default)
			)
			(layer "B.SilkS")
		)
		(fp_line
			(start -13.312394 -1.400556)
			(end -13.32484 -1.470152)
			(stroke
				(width 0.1)
				(type default)
			)
			(layer "B.SilkS")
		)
		(fp_line
			(start -13.312394 -1.400556)
			(end -13.32484 -1.470152)
			(stroke
				(width 0.1)
				(type default)
			)
			(layer "B.SilkS")
		)
		(fp_line
			(start -13.306298 -4.972812)
			(end -12.49299 -4.192524)
			(stroke
				(width 0.1)
				(type default)
			)
			(layer "B.SilkS")
		)
		(fp_line
			(start -13.306298 -4.972812)
			(end -12.49299 -4.192524)
			(stroke
				(width 0.1)
				(type default)
			)
			(layer "B.SilkS")
		)
		(fp_line
			(start -13.30071 -1.331468)
			(end -13.312394 -1.400556)
			(stroke
				(width 0.1)
				(type default)
			)
			(layer "B.SilkS")
		)
		(fp_line
			(start -13.30071 -1.331468)
			(end -13.312394 -1.400556)
			(stroke
				(width 0.1)
				(type default)
			)
			(layer "B.SilkS")
		)
		(fp_line
			(start -13.288264 -1.262126)
			(end -13.30071 -1.331468)
			(stroke
				(width 0.1)
				(type default)
			)
			(layer "B.SilkS")
		)
		(fp_line
			(start -13.288264 -1.262126)
			(end -13.30071 -1.331468)
			(stroke
				(width 0.1)
				(type default)
			)
			(layer "B.SilkS")
		)
		(fp_line
			(start -13.275818 -1.19253)
			(end -13.288264 -1.262126)
			(stroke
				(width 0.1)
				(type default)
			)
			(layer "B.SilkS")
		)
		(fp_line
			(start -13.275818 -1.19253)
			(end -13.288264 -1.262126)
			(stroke
				(width 0.1)
				(type default)
			)
			(layer "B.SilkS")
		)
		(fp_line
			(start -13.272516 -4.998212)
			(end -12.461748 -4.22021)
			(stroke
				(width 0.1)
				(type default)
			)
			(layer "B.SilkS")
		)
		(fp_line
			(start -13.272516 -4.998212)
			(end -12.461748 -4.22021)
			(stroke
				(width 0.1)
				(type default)
			)
			(layer "B.SilkS")
		)
		(fp_line
			(start -13.264134 -1.123188)
			(end -13.275818 -1.19253)
			(stroke
				(width 0.1)
				(type default)
			)
			(layer "B.SilkS")
		)
		(fp_line
			(start -13.264134 -1.123188)
			(end -13.275818 -1.19253)
			(stroke
				(width 0.1)
				(type default)
			)
			(layer "B.SilkS")
		)
		(fp_line
			(start -13.251942 -1.053846)
			(end -13.264134 -1.123188)
			(stroke
				(width 0.1)
				(type default)
			)
			(layer "B.SilkS")
		)
		(fp_line
			(start -13.251942 -1.053846)
			(end -13.264134 -1.123188)
			(stroke
				(width 0.1)
				(type default)
			)
			(layer "B.SilkS")
		)
		(fp_line
			(start -13.23975 -0.984504)
			(end -13.251942 -1.053846)
			(stroke
				(width 0.1)
				(type default)
			)
			(layer "B.SilkS")
		)
		(fp_line
			(start -13.23975 -0.984504)
			(end -13.251942 -1.053846)
			(stroke
				(width 0.1)
				(type default)
			)
			(layer "B.SilkS")
		)
		(fp_line
			(start -13.238988 -5.023612)
			(end -12.427458 -4.245102)
			(stroke
				(width 0.1)
				(type default)
			)
			(layer "B.SilkS")
		)
		(fp_line
			(start -13.238988 -5.023612)
			(end -12.427458 -4.245102)
			(stroke
				(width 0.1)
				(type default)
			)
			(layer "B.SilkS")
		)
		(fp_line
			(start -13.227812 -0.914908)
			(end -13.23975 -0.984504)
			(stroke
				(width 0.1)
				(type default)
			)
			(layer "B.SilkS")
		)
		(fp_line
			(start -13.227812 -0.914908)
			(end -13.23975 -0.984504)
			(stroke
				(width 0.1)
				(type default)
			)
			(layer "B.SilkS")
		)
		(fp_line
			(start -13.22197 -0.882904)
			(end -13.227812 -0.914908)
			(stroke
				(width 0.1)
				(type default)
			)
			(layer "B.SilkS")
		)
		(fp_line
			(start -13.22197 -0.882904)
			(end -13.227812 -0.914908)
			(stroke
				(width 0.1)
				(type default)
			)
			(layer "B.SilkS")
		)
		(fp_line
			(start -13.20292 -5.046472)
			(end -12.388596 -4.265422)
			(stroke
				(width 0.1)
				(type default)
			)
			(layer "B.SilkS")
		)
		(fp_line
			(start -13.20292 -5.046472)
			(end -12.388596 -4.265422)
			(stroke
				(width 0.1)
				(type default)
			)
			(layer "B.SilkS")
		)
		(fp_line
			(start -13.19403 -0.882904)
			(end -13.227812 -0.914908)
			(stroke
				(width 0.1)
				(type default)
			)
			(layer "B.SilkS")
		)
		(fp_line
			(start -13.19403 -0.882904)
			(end -13.227812 -0.914908)
			(stroke
				(width 0.1)
				(type default)
			)
			(layer "B.SilkS")
		)
		(fp_line
			(start -13.19403 -0.882904)
			(end -13.22197 -0.882904)
			(stroke
				(width 0.1)
				(type default)
			)
			(layer "B.SilkS")
		)
		(fp_line
			(start -13.19403 -0.882904)
			(end -13.22197 -0.882904)
			(stroke
				(width 0.1)
				(type default)
			)
			(layer "B.SilkS")
		)
		(fp_line
			(start -13.161518 -5.06476)
			(end -12.34948 -4.285742)
			(stroke
				(width 0.1)
				(type default)
			)
			(layer "B.SilkS")
		)
		(fp_line
			(start -13.161518 -5.06476)
			(end -12.34948 -4.285742)
			(stroke
				(width 0.1)
				(type default)
			)
			(layer "B.SilkS")
		)
		(fp_line
			(start -13.133578 -0.882904)
			(end -13.23975 -0.984504)
			(stroke
				(width 0.1)
				(type default)
			)
			(layer "B.SilkS")
		)
		(fp_line
			(start -13.133578 -0.882904)
			(end -13.23975 -0.984504)
			(stroke
				(width 0.1)
				(type default)
			)
			(layer "B.SilkS")
		)
		(fp_line
			(start -13.133578 -0.882904)
			(end -13.19403 -0.882904)
			(stroke
				(width 0.1)
				(type default)
			)
			(layer "B.SilkS")
		)
		(fp_line
			(start -13.133578 -0.882904)
			(end -13.19403 -0.882904)
			(stroke
				(width 0.1)
				(type default)
			)
			(layer "B.SilkS")
		)
		(fp_line
			(start -13.120116 -5.083048)
			(end -12.302998 -4.29895)
			(stroke
				(width 0.1)
				(type default)
			)
			(layer "B.SilkS")
		)
		(fp_line
			(start -13.120116 -5.083048)
			(end -12.302998 -4.29895)
			(stroke
				(width 0.1)
				(type default)
			)
			(layer "B.SilkS")
		)
		(fp_line
			(start -13.079222 -5.101336)
			(end -12.256008 -4.311396)
			(stroke
				(width 0.1)
				(type default)
			)
			(layer "B.SilkS")
		)
		(fp_line
			(start -13.079222 -5.101336)
			(end -12.256008 -4.311396)
			(stroke
				(width 0.1)
				(type default)
			)
			(layer "B.SilkS")
		)
		(fp_line
			(start -13.073634 -0.882904)
			(end -13.251942 -1.053846)
			(stroke
				(width 0.1)
				(type default)
			)
			(layer "B.SilkS")
		)
		(fp_line
			(start -13.073634 -0.882904)
			(end -13.251942 -1.053846)
			(stroke
				(width 0.1)
				(type default)
			)
			(layer "B.SilkS")
		)
		(fp_line
			(start -13.073634 -0.882904)
			(end -13.133578 -0.882904)
			(stroke
				(width 0.1)
				(type default)
			)
			(layer "B.SilkS")
		)
		(fp_line
			(start -13.073634 -0.882904)
			(end -13.133578 -0.882904)
			(stroke
				(width 0.1)
				(type default)
			)
			(layer "B.SilkS")
		)
		(fp_line
			(start -13.038074 -5.11937)
			(end -12.205462 -4.320794)
			(stroke
				(width 0.1)
				(type default)
			)
			(layer "B.SilkS")
		)
		(fp_line
			(start -13.038074 -5.11937)
			(end -12.205462 -4.320794)
			(stroke
				(width 0.1)
				(type default)
			)
			(layer "B.SilkS")
		)
		(fp_line
			(start -13.01369 -0.882904)
			(end -13.264134 -1.123188)
			(stroke
				(width 0.1)
				(type default)
			)
			(layer "B.SilkS")
		)
		(fp_line
			(start -13.01369 -0.882904)
			(end -13.264134 -1.123188)
			(stroke
				(width 0.1)
				(type default)
			)
			(layer "B.SilkS")
		)
		(fp_line
			(start -13.01369 -0.882904)
			(end -13.073634 -0.882904)
			(stroke
				(width 0.1)
				(type default)
			)
			(layer "B.SilkS")
		)
		(fp_line
			(start -13.01369 -0.882904)
			(end -13.073634 -0.882904)
			(stroke
				(width 0.1)
				(type default)
			)
			(layer "B.SilkS")
		)
		(fp_line
			(start -12.996926 -5.137658)
			(end -12.149836 -4.325112)
			(stroke
				(width 0.1)
				(type default)
			)
			(layer "B.SilkS")
		)
		(fp_line
			(start -12.996926 -5.137658)
			(end -12.149836 -4.325112)
			(stroke
				(width 0.1)
				(type default)
			)
			(layer "B.SilkS")
		)
		(fp_line
			(start -12.955778 -5.155946)
			(end -12.09421 -4.32943)
			(stroke
				(width 0.1)
				(type default)
			)
			(layer "B.SilkS")
		)
		(fp_line
			(start -12.955778 -5.155946)
			(end -12.09421 -4.32943)
			(stroke
				(width 0.1)
				(type default)
			)
			(layer "B.SilkS")
		)
		(fp_line
			(start -12.953238 -0.882904)
			(end -13.275818 -1.19253)
			(stroke
				(width 0.1)
				(type default)
			)
			(layer "B.SilkS")
		)
		(fp_line
			(start -12.953238 -0.882904)
			(end -13.275818 -1.19253)
			(stroke
				(width 0.1)
				(type default)
			)
			(layer "B.SilkS")
		)
		(fp_line
			(start -12.953238 -0.882904)
			(end -13.01369 -0.882904)
			(stroke
				(width 0.1)
				(type default)
			)
			(layer "B.SilkS")
		)
		(fp_line
			(start -12.953238 -0.882904)
			(end -13.01369 -0.882904)
			(stroke
				(width 0.1)
				(type default)
			)
			(layer "B.SilkS")
		)
		(fp_line
			(start -12.909804 -5.169408)
			(end -12.033758 -4.328922)
			(stroke
				(width 0.1)
				(type default)
			)
			(layer "B.SilkS")
		)
		(fp_line
			(start -12.909804 -5.169408)
			(end -12.033758 -4.328922)
			(stroke
				(width 0.1)
				(type default)
			)
			(layer "B.SilkS")
		)
		(fp_line
			(start -12.89304 -0.882904)
			(end -13.288264 -1.262126)
			(stroke
				(width 0.1)
				(type default)
			)
			(layer "B.SilkS")
		)
		(fp_line
			(start -12.89304 -0.882904)
			(end -13.288264 -1.262126)
			(stroke
				(width 0.1)
				(type default)
			)
			(layer "B.SilkS")
		)
		(fp_line
			(start -12.89304 -0.882904)
			(end -12.953238 -0.882904)
			(stroke
				(width 0.1)
				(type default)
			)
			(layer "B.SilkS")
		)
		(fp_line
			(start -12.89304 -0.882904)
			(end -12.953238 -0.882904)
			(stroke
				(width 0.1)
				(type default)
			)
			(layer "B.SilkS")
		)
		(fp_line
			(start -12.861036 -5.180584)
			(end -11.972036 -4.327906)
			(stroke
				(width 0.1)
				(type default)
			)
			(layer "B.SilkS")
		)
		(fp_line
			(start -12.861036 -5.180584)
			(end -11.972036 -4.327906)
			(stroke
				(width 0.1)
				(type default)
			)
			(layer "B.SilkS")
		)
		(fp_line
			(start -12.832842 -0.882904)
			(end -13.30071 -1.331468)
			(stroke
				(width 0.1)
				(type default)
			)
			(layer "B.SilkS")
		)
		(fp_line
			(start -12.832842 -0.882904)
			(end -13.30071 -1.331468)
			(stroke
				(width 0.1)
				(type default)
			)
			(layer "B.SilkS")
		)
		(fp_line
			(start -12.832842 -0.882904)
			(end -12.89304 -0.882904)
			(stroke
				(width 0.1)
				(type default)
			)
			(layer "B.SilkS")
		)
		(fp_line
			(start -12.832842 -0.882904)
			(end -12.89304 -0.882904)
			(stroke
				(width 0.1)
				(type default)
			)
			(layer "B.SilkS")
		)
		(fp_line
			(start -12.812522 -5.19176)
			(end -11.910568 -4.326636)
			(stroke
				(width 0.1)
				(type default)
			)
			(layer "B.SilkS")
		)
		(fp_line
			(start -12.812522 -5.19176)
			(end -11.910568 -4.326636)
			(stroke
				(width 0.1)
				(type default)
			)
			(layer "B.SilkS")
		)
		(fp_line
			(start -12.772898 -0.882904)
			(end -13.312394 -1.400556)
			(stroke
				(width 0.1)
				(type default)
			)
			(layer "B.SilkS")
		)
		(fp_line
			(start -12.772898 -0.882904)
			(end -13.312394 -1.400556)
			(stroke
				(width 0.1)
				(type default)
			)
			(layer "B.SilkS")
		)
		(fp_line
			(start -12.772898 -0.882904)
			(end -12.832842 -0.882904)
			(stroke
				(width 0.1)
				(type default)
			)
			(layer "B.SilkS")
		)
		(fp_line
			(start -12.772898 -0.882904)
			(end -12.832842 -0.882904)
			(stroke
				(width 0.1)
				(type default)
			)
			(layer "B.SilkS")
		)
		(fp_line
			(start -12.764008 -5.202936)
			(end -11.846306 -4.322572)
			(stroke
				(width 0.1)
				(type default)
			)
			(layer "B.SilkS")
		)
		(fp_line
			(start -12.764008 -5.202936)
			(end -11.846306 -4.322572)
			(stroke
				(width 0.1)
				(type default)
			)
			(layer "B.SilkS")
		)
		(fp_line
			(start -12.715494 -5.214112)
			(end -11.78179 -4.318254)
			(stroke
				(width 0.1)
				(type default)
			)
			(layer "B.SilkS")
		)
		(fp_line
			(start -12.715494 -5.214112)
			(end -11.78179 -4.318254)
			(stroke
				(width 0.1)
				(type default)
			)
			(layer "B.SilkS")
		)
		(fp_line
			(start -12.7127 -0.882904)
			(end -13.32484 -1.470152)
			(stroke
				(width 0.1)
				(type default)
			)
			(layer "B.SilkS")
		)
		(fp_line
			(start -12.7127 -0.882904)
			(end -13.32484 -1.470152)
			(stroke
				(width 0.1)
				(type default)
			)
			(layer "B.SilkS")
		)
		(fp_line
			(start -12.7127 -0.882904)
			(end -12.772898 -0.882904)
			(stroke
				(width 0.1)
				(type default)
			)
			(layer "B.SilkS")
		)
		(fp_line
			(start -12.7127 -0.882904)
			(end -12.772898 -0.882904)
			(stroke
				(width 0.1)
				(type default)
			)
			(layer "B.SilkS")
		)
		(fp_line
			(start -12.666726 -5.225034)
			(end -11.715242 -4.312412)
			(stroke
				(width 0.1)
				(type default)
			)
			(layer "B.SilkS")
		)
		(fp_line
			(start -12.666726 -5.225034)
			(end -11.715242 -4.312412)
			(stroke
				(width 0.1)
				(type default)
			)
			(layer "B.SilkS")
		)
		(fp_line
			(start -12.652502 -0.882904)
			(end -13.337286 -1.539494)
			(stroke
				(width 0.1)
				(type default)
			)
			(layer "B.SilkS")
		)
		(fp_line
			(start -12.652502 -0.882904)
			(end -13.337286 -1.539494)
			(stroke
				(width 0.1)
				(type default)
			)
			(layer "B.SilkS")
		)
		(fp_line
			(start -12.652502 -0.882904)
			(end -12.7127 -0.882904)
			(stroke
				(width 0.1)
				(type default)
			)
			(layer "B.SilkS")
		)
		(fp_line
			(start -12.652502 -0.882904)
			(end -12.7127 -0.882904)
			(stroke
				(width 0.1)
				(type default)
			)
			(layer "B.SilkS")
		)
		(fp_line
			(start -12.618212 -5.23621)
			(end -11.6459 -4.303268)
			(stroke
				(width 0.1)
				(type default)
			)
			(layer "B.SilkS")
		)
		(fp_line
			(start -12.618212 -5.23621)
			(end -11.6459 -4.303268)
			(stroke
				(width 0.1)
				(type default)
			)
			(layer "B.SilkS")
		)
		(fp_line
			(start -12.601956 -3.777996)
			(end -12.590018 -3.708654)
			(stroke
				(width 0.1)
				(type default)
			)
			(layer "B.SilkS")
		)
		(fp_line
			(start -12.601956 -3.777996)
			(end -12.590018 -3.708654)
			(stroke
				(width 0.1)
				(type default)
			)
			(layer "B.SilkS")
		)
		(fp_line
			(start -12.592558 -0.882904)
			(end -13.34897 -1.608836)
			(stroke
				(width 0.1)
				(type default)
			)
			(layer "B.SilkS")
		)
		(fp_line
			(start -12.592558 -0.882904)
			(end -13.34897 -1.608836)
			(stroke
				(width 0.1)
				(type default)
			)
			(layer "B.SilkS")
		)
		(fp_line
			(start -12.592558 -0.882904)
			(end -12.652502 -0.882904)
			(stroke
				(width 0.1)
				(type default)
			)
			(layer "B.SilkS")
		)
		(fp_line
			(start -12.592558 -0.882904)
			(end -12.652502 -0.882904)
			(stroke
				(width 0.1)
				(type default)
			)
			(layer "B.SilkS")
		)
		(fp_line
			(start -12.590018 -3.708654)
			(end -12.57808 -3.639312)
			(stroke
				(width 0.1)
				(type default)
			)
			(layer "B.SilkS")
		)
		(fp_line
			(start -12.590018 -3.708654)
			(end -12.57808 -3.639312)
			(stroke
				(width 0.1)
				(type default)
			)
			(layer "B.SilkS")
		)
		(fp_line
			(start -12.562078 -5.24002)
			(end -11.575542 -4.293616)
			(stroke
				(width 0.1)
				(type default)
			)
			(layer "B.SilkS")
		)
		(fp_line
			(start -12.562078 -5.24002)
			(end -11.575542 -4.293616)
			(stroke
				(width 0.1)
				(type default)
			)
			(layer "B.SilkS")
		)
		(fp_line
			(start -12.53236 -0.882904)
			(end -13.361416 -1.678178)
			(stroke
				(width 0.1)
				(type default)
			)
			(layer "B.SilkS")
		)
		(fp_line
			(start -12.53236 -0.882904)
			(end -13.361416 -1.678178)
			(stroke
				(width 0.1)
				(type default)
			)
			(layer "B.SilkS")
		)
		(fp_line
			(start -12.53236 -0.882904)
			(end -12.592558 -0.882904)
			(stroke
				(width 0.1)
				(type default)
			)
			(layer "B.SilkS")
		)
		(fp_line
			(start -12.53236 -0.882904)
			(end -12.592558 -0.882904)
			(stroke
				(width 0.1)
				(type default)
			)
			(layer "B.SilkS")
		)
		(fp_line
			(start -12.52601 -3.589274)
			(end -11.763502 -2.858008)
			(stroke
				(width 0.1)
				(type default)
			)
			(layer "B.SilkS")
		)
		(fp_line
			(start -12.52601 -3.589274)
			(end -11.763502 -2.858008)
			(stroke
				(width 0.1)
				(type default)
			)
			(layer "B.SilkS")
		)
		(fp_line
			(start -12.506198 -5.24383)
			(end -11.499596 -4.278376)
			(stroke
				(width 0.1)
				(type default)
			)
			(layer "B.SilkS")
		)
		(fp_line
			(start -12.506198 -5.24383)
			(end -11.499596 -4.278376)
			(stroke
				(width 0.1)
				(type default)
			)
			(layer "B.SilkS")
		)
		(fp_line
			(start -12.485624 -3.608324)
			(end -11.704574 -2.859278)
			(stroke
				(width 0.1)
				(type default)
			)
			(layer "B.SilkS")
		)
		(fp_line
			(start -12.485624 -3.608324)
			(end -11.704574 -2.859278)
			(stroke
				(width 0.1)
				(type default)
			)
			(layer "B.SilkS")
		)
		(fp_line
			(start -12.471908 -0.882904)
			(end -13.373354 -1.74752)
			(stroke
				(width 0.1)
				(type default)
			)
			(layer "B.SilkS")
		)
		(fp_line
			(start -12.471908 -0.882904)
			(end -13.373354 -1.74752)
			(stroke
				(width 0.1)
				(type default)
			)
			(layer "B.SilkS")
		)
		(fp_line
			(start -12.471908 -0.882904)
			(end -12.53236 -0.882904)
			(stroke
				(width 0.1)
				(type default)
			)
			(layer "B.SilkS")
		)
		(fp_line
			(start -12.471908 -0.882904)
			(end -12.53236 -0.882904)
			(stroke
				(width 0.1)
				(type default)
			)
			(layer "B.SilkS")
		)
		(fp_line
			(start -12.44981 -5.24764)
			(end -11.421364 -4.261104)
			(stroke
				(width 0.1)
				(type default)
			)
			(layer "B.SilkS")
		)
		(fp_line
			(start -12.44981 -5.24764)
			(end -11.421364 -4.261104)
			(stroke
				(width 0.1)
				(type default)
			)
			(layer "B.SilkS")
		)
		(fp_line
			(start -12.445238 -3.62712)
			(end -11.643614 -2.858262)
			(stroke
				(width 0.1)
				(type default)
			)
			(layer "B.SilkS")
		)
		(fp_line
			(start -12.445238 -3.62712)
			(end -11.643614 -2.858262)
			(stroke
				(width 0.1)
				(type default)
			)
			(layer "B.SilkS")
		)
		(fp_line
			(start -12.41171 -0.882904)
			(end -13.385546 -1.817116)
			(stroke
				(width 0.1)
				(type default)
			)
			(layer "B.SilkS")
		)
		(fp_line
			(start -12.41171 -0.882904)
			(end -13.385546 -1.817116)
			(stroke
				(width 0.1)
				(type default)
			)
			(layer "B.SilkS")
		)
		(fp_line
			(start -12.41171 -0.882904)
			(end -12.471908 -0.882904)
			(stroke
				(width 0.1)
				(type default)
			)
			(layer "B.SilkS")
		)
		(fp_line
			(start -12.41171 -0.882904)
			(end -12.471908 -0.882904)
			(stroke
				(width 0.1)
				(type default)
			)
			(layer "B.SilkS")
		)
		(fp_line
			(start -12.408154 -2.668524)
			(end -12.395962 -2.598928)
			(stroke
				(width 0.1)
				(type default)
			)
			(layer "B.SilkS")
		)
		(fp_line
			(start -12.408154 -2.668524)
			(end -12.395962 -2.598928)
			(stroke
				(width 0.1)
				(type default)
			)
			(layer "B.SilkS")
		)
		(fp_line
			(start -12.401804 -3.64363)
			(end -11.574526 -2.849626)
			(stroke
				(width 0.1)
				(type default)
			)
			(layer "B.SilkS")
		)
		(fp_line
			(start -12.401804 -3.64363)
			(end -11.574526 -2.849626)
			(stroke
				(width 0.1)
				(type default)
			)
			(layer "B.SilkS")
		)
		(fp_line
			(start -12.395962 -2.598928)
			(end -12.38377 -2.529586)
			(stroke
				(width 0.1)
				(type default)
			)
			(layer "B.SilkS")
		)
		(fp_line
			(start -12.395962 -2.598928)
			(end -12.38377 -2.529586)
			(stroke
				(width 0.1)
				(type default)
			)
			(layer "B.SilkS")
		)
		(fp_line
			(start -12.393676 -5.251704)
			(end -11.336782 -4.237736)
			(stroke
				(width 0.1)
				(type default)
			)
			(layer "B.SilkS")
		)
		(fp_line
			(start -12.393676 -5.251704)
			(end -11.336782 -4.237736)
			(stroke
				(width 0.1)
				(type default)
			)
			(layer "B.SilkS")
		)
		(fp_line
			(start -12.38377 -2.529586)
			(end -12.371578 -2.460244)
			(stroke
				(width 0.1)
				(type default)
			)
			(layer "B.SilkS")
		)
		(fp_line
			(start -12.38377 -2.529586)
			(end -12.371578 -2.460244)
			(stroke
				(width 0.1)
				(type default)
			)
			(layer "B.SilkS")
		)
		(fp_line
			(start -12.371578 -2.460244)
			(end -12.359386 -2.390902)
			(stroke
				(width 0.1)
				(type default)
			)
			(layer "B.SilkS")
		)
		(fp_line
			(start -12.371578 -2.460244)
			(end -12.359386 -2.390902)
			(stroke
				(width 0.1)
				(type default)
			)
			(layer "B.SilkS")
		)
		(fp_line
			(start -12.359386 -2.390902)
			(end -12.347194 -2.321306)
			(stroke
				(width 0.1)
				(type default)
			)
			(layer "B.SilkS")
		)
		(fp_line
			(start -12.359386 -2.390902)
			(end -12.347194 -2.321306)
			(stroke
				(width 0.1)
				(type default)
			)
			(layer "B.SilkS")
		)
		(fp_line
			(start -12.351512 -0.882904)
			(end -13.397992 -1.886458)
			(stroke
				(width 0.1)
				(type default)
			)
			(layer "B.SilkS")
		)
		(fp_line
			(start -12.351512 -0.882904)
			(end -13.397992 -1.886458)
			(stroke
				(width 0.1)
				(type default)
			)
			(layer "B.SilkS")
		)
		(fp_line
			(start -12.351512 -0.882904)
			(end -12.41171 -0.882904)
			(stroke
				(width 0.1)
				(type default)
			)
			(layer "B.SilkS")
		)
		(fp_line
			(start -12.351512 -0.882904)
			(end -12.41171 -0.882904)
			(stroke
				(width 0.1)
				(type default)
			)
			(layer "B.SilkS")
		)
		(fp_line
			(start -12.347194 -2.321306)
			(end -12.335002 -2.251964)
			(stroke
				(width 0.1)
				(type default)
			)
			(layer "B.SilkS")
		)
		(fp_line
			(start -12.347194 -2.321306)
			(end -12.335002 -2.251964)
			(stroke
				(width 0.1)
				(type default)
			)
			(layer "B.SilkS")
		)
		(fp_line
			(start -12.337542 -5.255514)
			(end -11.246358 -4.208526)
			(stroke
				(width 0.1)
				(type default)
			)
			(layer "B.SilkS")
		)
		(fp_line
			(start -12.337542 -5.255514)
			(end -11.246358 -4.208526)
			(stroke
				(width 0.1)
				(type default)
			)
			(layer "B.SilkS")
		)
		(fp_line
			(start -12.335002 -2.251964)
			(end -12.323064 -2.182622)
			(stroke
				(width 0.1)
				(type default)
			)
			(layer "B.SilkS")
		)
		(fp_line
			(start -12.335002 -2.251964)
			(end -12.323064 -2.182622)
			(stroke
				(width 0.1)
				(type default)
			)
			(layer "B.SilkS")
		)
		(fp_line
			(start -12.291568 -0.882904)
			(end -13.40993 -1.9558)
			(stroke
				(width 0.1)
				(type default)
			)
			(layer "B.SilkS")
		)
		(fp_line
			(start -12.291568 -0.882904)
			(end -13.40993 -1.9558)
			(stroke
				(width 0.1)
				(type default)
			)
			(layer "B.SilkS")
		)
		(fp_line
			(start -12.291568 -0.882904)
			(end -12.351512 -0.882904)
			(stroke
				(width 0.1)
				(type default)
			)
			(layer "B.SilkS")
		)
		(fp_line
			(start -12.291568 -0.882904)
			(end -12.351512 -0.882904)
			(stroke
				(width 0.1)
				(type default)
			)
			(layer "B.SilkS")
		)
		(fp_line
			(start -12.281408 -5.25907)
			(end -11.150092 -4.173728)
			(stroke
				(width 0.1)
				(type default)
			)
			(layer "B.SilkS")
		)
		(fp_line
			(start -12.281408 -5.25907)
			(end -11.150092 -4.173728)
			(stroke
				(width 0.1)
				(type default)
			)
			(layer "B.SilkS")
		)
		(fp_line
			(start -12.23137 -0.882904)
			(end -13.422122 -2.025396)
			(stroke
				(width 0.1)
				(type default)
			)
			(layer "B.SilkS")
		)
		(fp_line
			(start -12.23137 -0.882904)
			(end -13.422122 -2.025396)
			(stroke
				(width 0.1)
				(type default)
			)
			(layer "B.SilkS")
		)
		(fp_line
			(start -12.23137 -0.882904)
			(end -12.291568 -0.882904)
			(stroke
				(width 0.1)
				(type default)
			)
			(layer "B.SilkS")
		)
		(fp_line
			(start -12.23137 -0.882904)
			(end -12.291568 -0.882904)
			(stroke
				(width 0.1)
				(type default)
			)
			(layer "B.SilkS")
		)
		(fp_line
			(start -12.22248 -5.260594)
			(end -11.042904 -4.12877)
			(stroke
				(width 0.1)
				(type default)
			)
			(layer "B.SilkS")
		)
		(fp_line
			(start -12.22248 -5.260594)
			(end -11.042904 -4.12877)
			(stroke
				(width 0.1)
				(type default)
			)
			(layer "B.SilkS")
		)
		(fp_line
			(start -12.171172 -0.882904)
			(end -13.434314 -2.094738)
			(stroke
				(width 0.1)
				(type default)
			)
			(layer "B.SilkS")
		)
		(fp_line
			(start -12.171172 -0.882904)
			(end -13.434314 -2.094738)
			(stroke
				(width 0.1)
				(type default)
			)
			(layer "B.SilkS")
		)
		(fp_line
			(start -12.171172 -0.882904)
			(end -12.23137 -0.882904)
			(stroke
				(width 0.1)
				(type default)
			)
			(layer "B.SilkS")
		)
		(fp_line
			(start -12.171172 -0.882904)
			(end -12.23137 -0.882904)
			(stroke
				(width 0.1)
				(type default)
			)
			(layer "B.SilkS")
		)
		(fp_line
			(start -12.160504 -5.258816)
			(end -10.92708 -4.07543)
			(stroke
				(width 0.1)
				(type default)
			)
			(layer "B.SilkS")
		)
		(fp_line
			(start -12.160504 -5.258816)
			(end -10.92708 -4.07543)
			(stroke
				(width 0.1)
				(type default)
			)
			(layer "B.SilkS")
		)
		(fp_line
			(start -12.139676 -1.140968)
			(end -13.49502 -2.441448)
			(stroke
				(width 0.1)
				(type default)
			)
			(layer "B.SilkS")
		)
		(fp_line
			(start -12.139676 -1.140968)
			(end -13.49502 -2.441448)
			(stroke
				(width 0.1)
				(type default)
			)
			(layer "B.SilkS")
		)
		(fp_line
			(start -12.139676 -1.140968)
			(end -12.12723 -1.071626)
			(stroke
				(width 0.1)
				(type default)
			)
			(layer "B.SilkS")
		)
		(fp_line
			(start -12.139676 -1.140968)
			(end -12.12723 -1.071626)
			(stroke
				(width 0.1)
				(type default)
			)
			(layer "B.SilkS")
		)
		(fp_line
			(start -12.12723 -1.071626)
			(end -13.483082 -2.372106)
			(stroke
				(width 0.1)
				(type default)
			)
			(layer "B.SilkS")
		)
		(fp_line
			(start -12.12723 -1.071626)
			(end -13.483082 -2.372106)
			(stroke
				(width 0.1)
				(type default)
			)
			(layer "B.SilkS")
		)
		(fp_line
			(start -12.12723 -1.071626)
			(end -12.115038 -1.00203)
			(stroke
				(width 0.1)
				(type default)
			)
			(layer "B.SilkS")
		)
		(fp_line
			(start -12.12723 -1.071626)
			(end -12.115038 -1.00203)
			(stroke
				(width 0.1)
				(type default)
			)
			(layer "B.SilkS")
		)
		(fp_line
			(start -12.115038 -1.00203)
			(end -13.47089 -2.302764)
			(stroke
				(width 0.1)
				(type default)
			)
			(layer "B.SilkS")
		)
		(fp_line
			(start -12.115038 -1.00203)
			(end -13.47089 -2.302764)
			(stroke
				(width 0.1)
				(type default)
			)
			(layer "B.SilkS")
		)
		(fp_line
			(start -12.115038 -1.00203)
			(end -12.102592 -0.932434)
			(stroke
				(width 0.1)
				(type default)
			)
			(layer "B.SilkS")
		)
		(fp_line
			(start -12.115038 -1.00203)
			(end -12.102592 -0.932434)
			(stroke
				(width 0.1)
				(type default)
			)
			(layer "B.SilkS")
		)
		(fp_line
			(start -12.111228 -0.882904)
			(end -13.446506 -2.163826)
			(stroke
				(width 0.1)
				(type default)
			)
			(layer "B.SilkS")
		)
		(fp_line
			(start -12.111228 -0.882904)
			(end -13.446506 -2.163826)
			(stroke
				(width 0.1)
				(type default)
			)
			(layer "B.SilkS")
		)
		(fp_line
			(start -12.111228 -0.882904)
			(end -12.171172 -0.882904)
			(stroke
				(width 0.1)
				(type default)
			)
			(layer "B.SilkS")
		)
		(fp_line
			(start -12.111228 -0.882904)
			(end -12.171172 -0.882904)
			(stroke
				(width 0.1)
				(type default)
			)
			(layer "B.SilkS")
		)
		(fp_line
			(start -12.102592 -0.932434)
			(end -13.458444 -2.233422)
			(stroke
				(width 0.1)
				(type default)
			)
			(layer "B.SilkS")
		)
		(fp_line
			(start -12.102592 -0.932434)
			(end -13.458444 -2.233422)
			(stroke
				(width 0.1)
				(type default)
			)
			(layer "B.SilkS")
		)
		(fp_line
			(start -12.102592 -0.932434)
			(end -12.093956 -0.882904)
			(stroke
				(width 0.1)
				(type default)
			)
			(layer "B.SilkS")
		)
		(fp_line
			(start -12.102592 -0.932434)
			(end -12.093956 -0.882904)
			(stroke
				(width 0.1)
				(type default)
			)
			(layer "B.SilkS")
		)
		(fp_line
			(start -12.098528 -5.257038)
			(end -10.85342 -4.062476)
			(stroke
				(width 0.1)
				(type default)
			)
			(layer "B.SilkS")
		)
		(fp_line
			(start -12.098528 -5.257038)
			(end -10.85342 -4.062476)
			(stroke
				(width 0.1)
				(type default)
			)
			(layer "B.SilkS")
		)
		(fp_line
			(start -12.093956 -0.882904)
			(end -12.111228 -0.882904)
			(stroke
				(width 0.1)
				(type default)
			)
			(layer "B.SilkS")
		)
		(fp_line
			(start -12.093956 -0.882904)
			(end -12.111228 -0.882904)
			(stroke
				(width 0.1)
				(type default)
			)
			(layer "B.SilkS")
		)
		(fp_line
			(start -12.036806 -5.255514)
			(end -10.837418 -4.104894)
			(stroke
				(width 0.1)
				(type default)
			)
			(layer "B.SilkS")
		)
		(fp_line
			(start -12.036806 -5.255514)
			(end -10.837418 -4.104894)
			(stroke
				(width 0.1)
				(type default)
			)
			(layer "B.SilkS")
		)
		(fp_line
			(start -12.000738 -1.06553)
			(end -13.507466 -2.51079)
			(stroke
				(width 0.1)
				(type default)
			)
			(layer "B.SilkS")
		)
		(fp_line
			(start -12.000738 -1.06553)
			(end -13.507466 -2.51079)
			(stroke
				(width 0.1)
				(type default)
			)
			(layer "B.SilkS")
		)
		(fp_line
			(start -11.972798 -5.251958)
			(end -10.821416 -4.147312)
			(stroke
				(width 0.1)
				(type default)
			)
			(layer "B.SilkS")
		)
		(fp_line
			(start -11.972798 -5.251958)
			(end -10.821416 -4.147312)
			(stroke
				(width 0.1)
				(type default)
			)
			(layer "B.SilkS")
		)
		(fp_line
			(start -11.906504 -5.245862)
			(end -10.805414 -4.18973)
			(stroke
				(width 0.1)
				(type default)
			)
			(layer "B.SilkS")
		)
		(fp_line
			(start -11.906504 -5.245862)
			(end -10.805414 -4.18973)
			(stroke
				(width 0.1)
				(type default)
			)
			(layer "B.SilkS")
		)
		(fp_line
			(start -11.8491 -0.9779)
			(end -13.519404 -2.580386)
			(stroke
				(width 0.1)
				(type default)
			)
			(layer "B.SilkS")
		)
		(fp_line
			(start -11.8491 -0.9779)
			(end -13.519404 -2.580386)
			(stroke
				(width 0.1)
				(type default)
			)
			(layer "B.SilkS")
		)
		(fp_line
			(start -11.84021 -5.24002)
			(end -10.789666 -4.232148)
			(stroke
				(width 0.1)
				(type default)
			)
			(layer "B.SilkS")
		)
		(fp_line
			(start -11.84021 -5.24002)
			(end -10.789666 -4.232148)
			(stroke
				(width 0.1)
				(type default)
			)
			(layer "B.SilkS")
		)
		(fp_line
			(start -11.77417 -5.234178)
			(end -10.773664 -4.274566)
			(stroke
				(width 0.1)
				(type default)
			)
			(layer "B.SilkS")
		)
		(fp_line
			(start -11.77417 -5.234178)
			(end -10.773664 -4.274566)
			(stroke
				(width 0.1)
				(type default)
			)
			(layer "B.SilkS")
		)
		(fp_line
			(start -11.728704 -0.919988)
			(end -13.531596 -2.649728)
			(stroke
				(width 0.1)
				(type default)
			)
			(layer "B.SilkS")
		)
		(fp_line
			(start -11.728704 -0.919988)
			(end -13.531596 -2.649728)
			(stroke
				(width 0.1)
				(type default)
			)
			(layer "B.SilkS")
		)
		(fp_line
			(start -11.702034 -5.223002)
			(end -10.757662 -4.316984)
			(stroke
				(width 0.1)
				(type default)
			)
			(layer "B.SilkS")
		)
		(fp_line
			(start -11.702034 -5.223002)
			(end -10.757662 -4.316984)
			(stroke
				(width 0.1)
				(type default)
			)
			(layer "B.SilkS")
		)
		(fp_line
			(start -11.63193 -0.884936)
			(end -13.544042 -2.71907)
			(stroke
				(width 0.1)
				(type default)
			)
			(layer "B.SilkS")
		)
		(fp_line
			(start -11.63193 -0.884936)
			(end -13.544042 -2.71907)
			(stroke
				(width 0.1)
				(type default)
			)
			(layer "B.SilkS")
		)
		(fp_line
			(start -11.629898 -5.211572)
			(end -10.74166 -4.359402)
			(stroke
				(width 0.1)
				(type default)
			)
			(layer "B.SilkS")
		)
		(fp_line
			(start -11.629898 -5.211572)
			(end -10.74166 -4.359402)
			(stroke
				(width 0.1)
				(type default)
			)
			(layer "B.SilkS")
		)
		(fp_line
			(start -11.557762 -5.199888)
			(end -10.725658 -4.40182)
			(stroke
				(width 0.1)
				(type default)
			)
			(layer "B.SilkS")
		)
		(fp_line
			(start -11.557762 -5.199888)
			(end -10.725658 -4.40182)
			(stroke
				(width 0.1)
				(type default)
			)
			(layer "B.SilkS")
		)
		(fp_line
			(start -11.546332 -0.860552)
			(end -13.55598 -2.788412)
			(stroke
				(width 0.1)
				(type default)
			)
			(layer "B.SilkS")
		)
		(fp_line
			(start -11.546332 -0.860552)
			(end -13.55598 -2.788412)
			(stroke
				(width 0.1)
				(type default)
			)
			(layer "B.SilkS")
		)
		(fp_line
			(start -11.505184 -2.84099)
			(end -12.356592 -3.657854)
			(stroke
				(width 0.1)
				(type default)
			)
			(layer "B.SilkS")
		)
		(fp_line
			(start -11.505184 -2.84099)
			(end -12.356592 -3.657854)
			(stroke
				(width 0.1)
				(type default)
			)
			(layer "B.SilkS")
		)
		(fp_line
			(start -11.478514 -5.1816)
			(end -10.709656 -4.443984)
			(stroke
				(width 0.1)
				(type default)
			)
			(layer "B.SilkS")
		)
		(fp_line
			(start -11.478514 -5.1816)
			(end -10.709656 -4.443984)
			(stroke
				(width 0.1)
				(type default)
			)
			(layer "B.SilkS")
		)
		(fp_line
			(start -11.460734 -0.836422)
			(end -13.568172 -2.857754)
			(stroke
				(width 0.1)
				(type default)
			)
			(layer "B.SilkS")
		)
		(fp_line
			(start -11.460734 -0.836422)
			(end -13.568172 -2.857754)
			(stroke
				(width 0.1)
				(type default)
			)
			(layer "B.SilkS")
		)
		(fp_line
			(start -11.436096 -2.832354)
			(end -12.31138 -3.672078)
			(stroke
				(width 0.1)
				(type default)
			)
			(layer "B.SilkS")
		)
		(fp_line
			(start -11.436096 -2.832354)
			(end -12.31138 -3.672078)
			(stroke
				(width 0.1)
				(type default)
			)
			(layer "B.SilkS")
		)
		(fp_line
			(start -11.398758 -5.163058)
			(end -10.693908 -4.486402)
			(stroke
				(width 0.1)
				(type default)
			)
			(layer "B.SilkS")
		)
		(fp_line
			(start -11.398758 -5.163058)
			(end -10.693908 -4.486402)
			(stroke
				(width 0.1)
				(type default)
			)
			(layer "B.SilkS")
		)
		(fp_line
			(start -11.382756 -0.81915)
			(end -13.580364 -2.927096)
			(stroke
				(width 0.1)
				(type default)
			)
			(layer "B.SilkS")
		)
		(fp_line
			(start -11.382756 -0.81915)
			(end -13.580364 -2.927096)
			(stroke
				(width 0.1)
				(type default)
			)
			(layer "B.SilkS")
		)
		(fp_line
			(start -11.364722 -2.821686)
			(end -12.265914 -3.686302)
			(stroke
				(width 0.1)
				(type default)
			)
			(layer "B.SilkS")
		)
		(fp_line
			(start -11.364722 -2.821686)
			(end -12.265914 -3.686302)
			(stroke
				(width 0.1)
				(type default)
			)
			(layer "B.SilkS")
		)
		(fp_line
			(start -11.315954 -0.813054)
			(end -13.592556 -2.996692)
			(stroke
				(width 0.1)
				(type default)
			)
			(layer "B.SilkS")
		)
		(fp_line
			(start -11.315954 -0.813054)
			(end -13.592556 -2.996692)
			(stroke
				(width 0.1)
				(type default)
			)
			(layer "B.SilkS")
		)
		(fp_line
			(start -11.315446 -5.140706)
			(end -10.677906 -4.529074)
			(stroke
				(width 0.1)
				(type default)
			)
			(layer "B.SilkS")
		)
		(fp_line
			(start -11.315446 -5.140706)
			(end -10.677906 -4.529074)
			(stroke
				(width 0.1)
				(type default)
			)
			(layer "B.SilkS")
		)
		(fp_line
			(start -11.248898 -0.805942)
			(end -13.604494 -3.06578)
			(stroke
				(width 0.1)
				(type default)
			)
			(layer "B.SilkS")
		)
		(fp_line
			(start -11.248898 -0.805942)
			(end -13.604494 -3.06578)
			(stroke
				(width 0.1)
				(type default)
			)
			(layer "B.SilkS")
		)
		(fp_line
			(start -11.246612 -2.76606)
			(end -12.216638 -3.696716)
			(stroke
				(width 0.1)
				(type default)
			)
			(layer "B.SilkS")
		)
		(fp_line
			(start -11.246612 -2.76606)
			(end -12.216638 -3.696716)
			(stroke
				(width 0.1)
				(type default)
			)
			(layer "B.SilkS")
		)
		(fp_line
			(start -11.226546 -5.11302)
			(end -10.661904 -4.571492)
			(stroke
				(width 0.1)
				(type default)
			)
			(layer "B.SilkS")
		)
		(fp_line
			(start -11.226546 -5.11302)
			(end -10.661904 -4.571492)
			(stroke
				(width 0.1)
				(type default)
			)
			(layer "B.SilkS")
		)
		(fp_line
			(start -11.182096 -0.799846)
			(end -13.61694 -3.135376)
			(stroke
				(width 0.1)
				(type default)
			)
			(layer "B.SilkS")
		)
		(fp_line
			(start -11.182096 -0.799846)
			(end -13.61694 -3.135376)
			(stroke
				(width 0.1)
				(type default)
			)
			(layer "B.SilkS")
		)
		(fp_line
			(start -11.13536 -5.083048)
			(end -10.645902 -4.613656)
			(stroke
				(width 0.1)
				(type default)
			)
			(layer "B.SilkS")
		)
		(fp_line
			(start -11.13536 -5.083048)
			(end -10.645902 -4.613656)
			(stroke
				(width 0.1)
				(type default)
			)
			(layer "B.SilkS")
		)
		(fp_line
			(start -11.11504 -0.792988)
			(end -13.629132 -3.204972)
			(stroke
				(width 0.1)
				(type default)
			)
			(layer "B.SilkS")
		)
		(fp_line
			(start -11.11504 -0.792988)
			(end -13.629132 -3.204972)
			(stroke
				(width 0.1)
				(type default)
			)
			(layer "B.SilkS")
		)
		(fp_line
			(start -11.057382 -0.795274)
			(end -13.64107 -3.27406)
			(stroke
				(width 0.1)
				(type default)
			)
			(layer "B.SilkS")
		)
		(fp_line
			(start -11.057382 -0.795274)
			(end -13.64107 -3.27406)
			(stroke
				(width 0.1)
				(type default)
			)
			(layer "B.SilkS")
		)
		(fp_line
			(start -11.03503 -5.044694)
			(end -10.6299 -4.656074)
			(stroke
				(width 0.1)
				(type default)
			)
			(layer "B.SilkS")
		)
		(fp_line
			(start -11.03503 -5.044694)
			(end -10.6299 -4.656074)
			(stroke
				(width 0.1)
				(type default)
			)
			(layer "B.SilkS")
		)
		(fp_line
			(start -10.99947 -0.797814)
			(end -13.653516 -3.343402)
			(stroke
				(width 0.1)
				(type default)
			)
			(layer "B.SilkS")
		)
		(fp_line
			(start -10.99947 -0.797814)
			(end -13.653516 -3.343402)
			(stroke
				(width 0.1)
				(type default)
			)
			(layer "B.SilkS")
		)
		(fp_line
			(start -10.931144 -5.002784)
			(end -10.613898 -4.698746)
			(stroke
				(width 0.1)
				(type default)
			)
			(layer "B.SilkS")
		)
		(fp_line
			(start -10.931144 -5.002784)
			(end -10.613898 -4.698746)
			(stroke
				(width 0.1)
				(type default)
			)
			(layer "B.SilkS")
		)
		(fp_line
			(start -10.889742 -0.808228)
			(end -12.047474 -1.918462)
			(stroke
				(width 0.1)
				(type default)
			)
			(layer "B.SilkS")
		)
		(fp_line
			(start -10.889742 -0.808228)
			(end -12.047474 -1.918462)
			(stroke
				(width 0.1)
				(type default)
			)
			(layer "B.SilkS")
		)
		(fp_line
			(start -10.837418 -4.104894)
			(end -10.85342 -4.062476)
			(stroke
				(width 0.1)
				(type default)
			)
			(layer "B.SilkS")
		)
		(fp_line
			(start -10.837418 -4.104894)
			(end -10.85342 -4.062476)
			(stroke
				(width 0.1)
				(type default)
			)
			(layer "B.SilkS")
		)
		(fp_line
			(start -10.836402 -0.814324)
			(end -11.91514 -1.84912)
			(stroke
				(width 0.1)
				(type default)
			)
			(layer "B.SilkS")
		)
		(fp_line
			(start -10.836402 -0.814324)
			(end -11.91514 -1.84912)
			(stroke
				(width 0.1)
				(type default)
			)
			(layer "B.SilkS")
		)
		(fp_line
			(start -10.821416 -4.147312)
			(end -10.837418 -4.104894)
			(stroke
				(width 0.1)
				(type default)
			)
			(layer "B.SilkS")
		)
		(fp_line
			(start -10.821416 -4.147312)
			(end -10.837418 -4.104894)
			(stroke
				(width 0.1)
				(type default)
			)
			(layer "B.SilkS")
		)
		(fp_line
			(start -10.818368 -4.952492)
			(end -10.59815 -4.74091)
			(stroke
				(width 0.1)
				(type default)
			)
			(layer "B.SilkS")
		)
		(fp_line
			(start -10.818368 -4.952492)
			(end -10.59815 -4.74091)
			(stroke
				(width 0.1)
				(type default)
			)
			(layer "B.SilkS")
		)
		(fp_line
			(start -10.805414 -4.18973)
			(end -10.821416 -4.147312)
			(stroke
				(width 0.1)
				(type default)
			)
			(layer "B.SilkS")
		)
		(fp_line
			(start -10.805414 -4.18973)
			(end -10.821416 -4.147312)
			(stroke
				(width 0.1)
				(type default)
			)
			(layer "B.SilkS")
		)
		(fp_line
			(start -10.789666 -4.232148)
			(end -10.805414 -4.18973)
			(stroke
				(width 0.1)
				(type default)
			)
			(layer "B.SilkS")
		)
		(fp_line
			(start -10.789666 -4.232148)
			(end -10.805414 -4.18973)
			(stroke
				(width 0.1)
				(type default)
			)
			(layer "B.SilkS")
		)
		(fp_line
			(start -10.785602 -0.823214)
			(end -11.818112 -1.813814)
			(stroke
				(width 0.1)
				(type default)
			)
			(layer "B.SilkS")
		)
		(fp_line
			(start -10.785602 -0.823214)
			(end -11.818112 -1.813814)
			(stroke
				(width 0.1)
				(type default)
			)
			(layer "B.SilkS")
		)
		(fp_line
			(start -10.773664 -4.274566)
			(end -10.789666 -4.232148)
			(stroke
				(width 0.1)
				(type default)
			)
			(layer "B.SilkS")
		)
		(fp_line
			(start -10.773664 -4.274566)
			(end -10.789666 -4.232148)
			(stroke
				(width 0.1)
				(type default)
			)
			(layer "B.SilkS")
		)
		(fp_line
			(start -10.757662 -4.316984)
			(end -10.773664 -4.274566)
			(stroke
				(width 0.1)
				(type default)
			)
			(layer "B.SilkS")
		)
		(fp_line
			(start -10.757662 -4.316984)
			(end -10.773664 -4.274566)
			(stroke
				(width 0.1)
				(type default)
			)
			(layer "B.SilkS")
		)
		(fp_line
			(start -10.74166 -4.359402)
			(end -10.757662 -4.316984)
			(stroke
				(width 0.1)
				(type default)
			)
			(layer "B.SilkS")
		)
		(fp_line
			(start -10.74166 -4.359402)
			(end -10.757662 -4.316984)
			(stroke
				(width 0.1)
				(type default)
			)
			(layer "B.SilkS")
		)
		(fp_line
			(start -10.736072 -0.833628)
			(end -11.723116 -1.78054)
			(stroke
				(width 0.1)
				(type default)
			)
			(layer "B.SilkS")
		)
		(fp_line
			(start -10.736072 -0.833628)
			(end -11.723116 -1.78054)
			(stroke
				(width 0.1)
				(type default)
			)
			(layer "B.SilkS")
		)
		(fp_line
			(start -10.725658 -4.40182)
			(end -10.74166 -4.359402)
			(stroke
				(width 0.1)
				(type default)
			)
			(layer "B.SilkS")
		)
		(fp_line
			(start -10.725658 -4.40182)
			(end -10.74166 -4.359402)
			(stroke
				(width 0.1)
				(type default)
			)
			(layer "B.SilkS")
		)
		(fp_line
			(start -10.709656 -4.443984)
			(end -10.725658 -4.40182)
			(stroke
				(width 0.1)
				(type default)
			)
			(layer "B.SilkS")
		)
		(fp_line
			(start -10.709656 -4.443984)
			(end -10.725658 -4.40182)
			(stroke
				(width 0.1)
				(type default)
			)
			(layer "B.SilkS")
		)
		(fp_line
			(start -10.698734 -4.895088)
			(end -10.582148 -4.783328)
			(stroke
				(width 0.1)
				(type default)
			)
			(layer "B.SilkS")
		)
		(fp_line
			(start -10.698734 -4.895088)
			(end -10.582148 -4.783328)
			(stroke
				(width 0.1)
				(type default)
			)
			(layer "B.SilkS")
		)
		(fp_line
			(start -10.693908 -4.486402)
			(end -10.709656 -4.443984)
			(stroke
				(width 0.1)
				(type default)
			)
			(layer "B.SilkS")
		)
		(fp_line
			(start -10.693908 -4.486402)
			(end -10.709656 -4.443984)
			(stroke
				(width 0.1)
				(type default)
			)
			(layer "B.SilkS")
		)
		(fp_line
			(start -10.686542 -0.843534)
			(end -11.654282 -1.772158)
			(stroke
				(width 0.1)
				(type default)
			)
			(layer "B.SilkS")
		)
		(fp_line
			(start -10.686542 -0.843534)
			(end -11.654282 -1.772158)
			(stroke
				(width 0.1)
				(type default)
			)
			(layer "B.SilkS")
		)
		(fp_line
			(start -10.677906 -4.529074)
			(end -10.693908 -4.486402)
			(stroke
				(width 0.1)
				(type default)
			)
			(layer "B.SilkS")
		)
		(fp_line
			(start -10.677906 -4.529074)
			(end -10.693908 -4.486402)
			(stroke
				(width 0.1)
				(type default)
			)
			(layer "B.SilkS")
		)
		(fp_line
			(start -10.661904 -4.571492)
			(end -10.677906 -4.529074)
			(stroke
				(width 0.1)
				(type default)
			)
			(layer "B.SilkS")
		)
		(fp_line
			(start -10.661904 -4.571492)
			(end -10.677906 -4.529074)
			(stroke
				(width 0.1)
				(type default)
			)
			(layer "B.SilkS")
		)
		(fp_line
			(start -10.645902 -4.613656)
			(end -10.661904 -4.571492)
			(stroke
				(width 0.1)
				(type default)
			)
			(layer "B.SilkS")
		)
		(fp_line
			(start -10.645902 -4.613656)
			(end -10.661904 -4.571492)
			(stroke
				(width 0.1)
				(type default)
			)
			(layer "B.SilkS")
		)
		(fp_line
			(start -10.64006 -0.856996)
			(end -11.585448 -1.763522)
			(stroke
				(width 0.1)
				(type default)
			)
			(layer "B.SilkS")
		)
		(fp_line
			(start -10.64006 -0.856996)
			(end -11.585448 -1.763522)
			(stroke
				(width 0.1)
				(type default)
			)
			(layer "B.SilkS")
		)
		(fp_line
			(start -10.6299 -4.656074)
			(end -10.645902 -4.613656)
			(stroke
				(width 0.1)
				(type default)
			)
			(layer "B.SilkS")
		)
		(fp_line
			(start -10.6299 -4.656074)
			(end -10.645902 -4.613656)
			(stroke
				(width 0.1)
				(type default)
			)
			(layer "B.SilkS")
		)
		(fp_line
			(start -10.613898 -4.698746)
			(end -10.6299 -4.656074)
			(stroke
				(width 0.1)
				(type default)
			)
			(layer "B.SilkS")
		)
		(fp_line
			(start -10.613898 -4.698746)
			(end -10.6299 -4.656074)
			(stroke
				(width 0.1)
				(type default)
			)
			(layer "B.SilkS")
		)
		(fp_line
			(start -10.613898 -4.698746)
			(end -10.59815 -4.74091)
			(stroke
				(width 0.1)
				(type default)
			)
			(layer "B.SilkS")
		)
		(fp_line
			(start -10.613898 -4.698746)
			(end -10.59815 -4.74091)
			(stroke
				(width 0.1)
				(type default)
			)
			(layer "B.SilkS")
		)
		(fp_line
			(start -10.59815 -4.74091)
			(end -10.582148 -4.783328)
			(stroke
				(width 0.1)
				(type default)
			)
			(layer "B.SilkS")
		)
		(fp_line
			(start -10.59815 -4.74091)
			(end -10.582148 -4.783328)
			(stroke
				(width 0.1)
				(type default)
			)
			(layer "B.SilkS")
		)
		(fp_line
			(start -10.59434 -0.870712)
			(end -11.516614 -1.75514)
			(stroke
				(width 0.1)
				(type default)
			)
			(layer "B.SilkS")
		)
		(fp_line
			(start -10.59434 -0.870712)
			(end -11.516614 -1.75514)
			(stroke
				(width 0.1)
				(type default)
			)
			(layer "B.SilkS")
		)
		(fp_line
			(start -10.582148 -4.783328)
			(end -10.566146 -4.825746)
			(stroke
				(width 0.1)
				(type default)
			)
			(layer "B.SilkS")
		)
		(fp_line
			(start -10.582148 -4.783328)
			(end -10.566146 -4.825746)
			(stroke
				(width 0.1)
				(type default)
			)
			(layer "B.SilkS")
		)
		(fp_line
			(start -10.572496 -4.831842)
			(end -10.566146 -4.825746)
			(stroke
				(width 0.1)
				(type default)
			)
			(layer "B.SilkS")
		)
		(fp_line
			(start -10.572496 -4.831842)
			(end -10.566146 -4.825746)
			(stroke
				(width 0.1)
				(type default)
			)
			(layer "B.SilkS")
		)
		(fp_line
			(start -10.548366 -0.884682)
			(end -11.45032 -1.749552)
			(stroke
				(width 0.1)
				(type default)
			)
			(layer "B.SilkS")
		)
		(fp_line
			(start -10.548366 -0.884682)
			(end -11.45032 -1.749552)
			(stroke
				(width 0.1)
				(type default)
			)
			(layer "B.SilkS")
		)
		(fp_line
			(start -10.505694 -0.901192)
			(end -11.39444 -1.753616)
			(stroke
				(width 0.1)
				(type default)
			)
			(layer "B.SilkS")
		)
		(fp_line
			(start -10.505694 -0.901192)
			(end -11.39444 -1.753616)
			(stroke
				(width 0.1)
				(type default)
			)
			(layer "B.SilkS")
		)
		(fp_line
			(start -10.46353 -0.918464)
			(end -11.33856 -1.75768)
			(stroke
				(width 0.1)
				(type default)
			)
			(layer "B.SilkS")
		)
		(fp_line
			(start -10.46353 -0.918464)
			(end -11.33856 -1.75768)
			(stroke
				(width 0.1)
				(type default)
			)
			(layer "B.SilkS")
		)
		(fp_line
			(start -10.421366 -0.935482)
			(end -11.28522 -1.76403)
			(stroke
				(width 0.1)
				(type default)
			)
			(layer "B.SilkS")
		)
		(fp_line
			(start -10.421366 -0.935482)
			(end -11.28522 -1.76403)
			(stroke
				(width 0.1)
				(type default)
			)
			(layer "B.SilkS")
		)
		(fp_line
			(start -10.381996 -0.955548)
			(end -11.237722 -1.776476)
			(stroke
				(width 0.1)
				(type default)
			)
			(layer "B.SilkS")
		)
		(fp_line
			(start -10.381996 -0.955548)
			(end -11.237722 -1.776476)
			(stroke
				(width 0.1)
				(type default)
			)
			(layer "B.SilkS")
		)
		(fp_line
			(start -10.343388 -0.976122)
			(end -11.190478 -1.788922)
			(stroke
				(width 0.1)
				(type default)
			)
			(layer "B.SilkS")
		)
		(fp_line
			(start -10.343388 -0.976122)
			(end -11.190478 -1.788922)
			(stroke
				(width 0.1)
				(type default)
			)
			(layer "B.SilkS")
		)
		(fp_line
			(start -10.30478 -0.99695)
			(end -11.147044 -1.804924)
			(stroke
				(width 0.1)
				(type default)
			)
			(layer "B.SilkS")
		)
		(fp_line
			(start -10.30478 -0.99695)
			(end -11.147044 -1.804924)
			(stroke
				(width 0.1)
				(type default)
			)
			(layer "B.SilkS")
		)
		(fp_line
			(start -10.268458 -1.01981)
			(end -11.108182 -1.825244)
			(stroke
				(width 0.1)
				(type default)
			)
			(layer "B.SilkS")
		)
		(fp_line
			(start -10.268458 -1.01981)
			(end -11.108182 -1.825244)
			(stroke
				(width 0.1)
				(type default)
			)
			(layer "B.SilkS")
		)
		(fp_line
			(start -10.233406 -1.043686)
			(end -11.06932 -1.845818)
			(stroke
				(width 0.1)
				(type default)
			)
			(layer "B.SilkS")
		)
		(fp_line
			(start -10.233406 -1.043686)
			(end -11.06932 -1.845818)
			(stroke
				(width 0.1)
				(type default)
			)
			(layer "B.SilkS")
		)
		(fp_line
			(start -10.198354 -1.067816)
			(end -11.037062 -1.872742)
			(stroke
				(width 0.1)
				(type default)
			)
			(layer "B.SilkS")
		)
		(fp_line
			(start -10.198354 -1.067816)
			(end -11.037062 -1.872742)
			(stroke
				(width 0.1)
				(type default)
			)
			(layer "B.SilkS")
		)
		(fp_line
			(start -10.16508 -1.093724)
			(end -11.006582 -1.90119)
			(stroke
				(width 0.1)
				(type default)
			)
			(layer "B.SilkS")
		)
		(fp_line
			(start -10.16508 -1.093724)
			(end -11.006582 -1.90119)
			(stroke
				(width 0.1)
				(type default)
			)
			(layer "B.SilkS")
		)
		(fp_line
			(start -10.133584 -1.121156)
			(end -10.978642 -1.931924)
			(stroke
				(width 0.1)
				(type default)
			)
			(layer "B.SilkS")
		)
		(fp_line
			(start -10.133584 -1.121156)
			(end -10.978642 -1.931924)
			(stroke
				(width 0.1)
				(type default)
			)
			(layer "B.SilkS")
		)
		(fp_line
			(start -10.102088 -1.148588)
			(end -10.956798 -1.9685)
			(stroke
				(width 0.1)
				(type default)
			)
			(layer "B.SilkS")
		)
		(fp_line
			(start -10.102088 -1.148588)
			(end -10.956798 -1.9685)
			(stroke
				(width 0.1)
				(type default)
			)
			(layer "B.SilkS")
		)
		(fp_line
			(start -10.071608 -1.17729)
			(end -10.9347 -2.00533)
			(stroke
				(width 0.1)
				(type default)
			)
			(layer "B.SilkS")
		)
		(fp_line
			(start -10.071608 -1.17729)
			(end -10.9347 -2.00533)
			(stroke
				(width 0.1)
				(type default)
			)
			(layer "B.SilkS")
		)
		(fp_line
			(start -10.043668 -1.208278)
			(end -10.921238 -2.04978)
			(stroke
				(width 0.1)
				(type default)
			)
			(layer "B.SilkS")
		)
		(fp_line
			(start -10.043668 -1.208278)
			(end -10.921238 -2.04978)
			(stroke
				(width 0.1)
				(type default)
			)
			(layer "B.SilkS")
		)
		(fp_line
			(start -10.015982 -1.239266)
			(end -10.90803 -2.094992)
			(stroke
				(width 0.1)
				(type default)
			)
			(layer "B.SilkS")
		)
		(fp_line
			(start -10.015982 -1.239266)
			(end -10.90803 -2.094992)
			(stroke
				(width 0.1)
				(type default)
			)
			(layer "B.SilkS")
		)
		(fp_line
			(start -10.005568 -2.902966)
			(end -10.557002 -3.431794)
			(stroke
				(width 0.1)
				(type default)
			)
			(layer "B.SilkS")
		)
		(fp_line
			(start -10.005568 -2.902966)
			(end -10.557002 -3.431794)
			(stroke
				(width 0.1)
				(type default)
			)
			(layer "B.SilkS")
		)
		(fp_line
			(start -9.98855 -1.270508)
			(end -10.902442 -2.147316)
			(stroke
				(width 0.1)
				(type default)
			)
			(layer "B.SilkS")
		)
		(fp_line
			(start -9.98855 -1.270508)
			(end -10.902442 -2.147316)
			(stroke
				(width 0.1)
				(type default)
			)
			(layer "B.SilkS")
		)
		(fp_line
			(start -9.964674 -1.30556)
			(end -10.898632 -2.201418)
			(stroke
				(width 0.1)
				(type default)
			)
			(layer "B.SilkS")
		)
		(fp_line
			(start -9.964674 -1.30556)
			(end -10.898632 -2.201418)
			(stroke
				(width 0.1)
				(type default)
			)
			(layer "B.SilkS")
		)
		(fp_line
			(start -9.945116 -2.787142)
			(end -10.69721 -3.508502)
			(stroke
				(width 0.1)
				(type default)
			)
			(layer "B.SilkS")
		)
		(fp_line
			(start -9.945116 -2.787142)
			(end -10.69721 -3.508502)
			(stroke
				(width 0.1)
				(type default)
			)
			(layer "B.SilkS")
		)
		(fp_line
			(start -9.940798 -1.340358)
			(end -10.903712 -2.263902)
			(stroke
				(width 0.1)
				(type default)
			)
			(layer "B.SilkS")
		)
		(fp_line
			(start -9.940798 -1.340358)
			(end -10.903712 -2.263902)
			(stroke
				(width 0.1)
				(type default)
			)
			(layer "B.SilkS")
		)
		(fp_line
			(start -9.916922 -1.375156)
			(end -10.912856 -2.33045)
			(stroke
				(width 0.1)
				(type default)
			)
			(layer "B.SilkS")
		)
		(fp_line
			(start -9.916922 -1.375156)
			(end -10.912856 -2.33045)
			(stroke
				(width 0.1)
				(type default)
			)
			(layer "B.SilkS")
		)
		(fp_line
			(start -9.896602 -1.413256)
			(end -10.944606 -2.418588)
			(stroke
				(width 0.1)
				(type default)
			)
			(layer "B.SilkS")
		)
		(fp_line
			(start -9.896602 -1.413256)
			(end -10.944606 -2.418588)
			(stroke
				(width 0.1)
				(type default)
			)
			(layer "B.SilkS")
		)
		(fp_line
			(start -9.884664 -2.671572)
			(end -10.811764 -3.560826)
			(stroke
				(width 0.1)
				(type default)
			)
			(layer "B.SilkS")
		)
		(fp_line
			(start -9.884664 -2.671572)
			(end -10.811764 -3.560826)
			(stroke
				(width 0.1)
				(type default)
			)
			(layer "B.SilkS")
		)
		(fp_line
			(start -9.87679 -1.452118)
			(end -10.97661 -2.50698)
			(stroke
				(width 0.1)
				(type default)
			)
			(layer "B.SilkS")
		)
		(fp_line
			(start -9.87679 -1.452118)
			(end -10.97661 -2.50698)
			(stroke
				(width 0.1)
				(type default)
			)
			(layer "B.SilkS")
		)
		(fp_line
			(start -9.857232 -1.49098)
			(end -12.165838 -3.705352)
			(stroke
				(width 0.1)
				(type default)
			)
			(layer "B.SilkS")
		)
		(fp_line
			(start -9.857232 -1.49098)
			(end -12.165838 -3.705352)
			(stroke
				(width 0.1)
				(type default)
			)
			(layer "B.SilkS")
		)
		(fp_line
			(start -9.856978 -2.587244)
			(end -10.90676 -3.594354)
			(stroke
				(width 0.1)
				(type default)
			)
			(layer "B.SilkS")
		)
		(fp_line
			(start -9.856978 -2.587244)
			(end -10.90676 -3.594354)
			(stroke
				(width 0.1)
				(type default)
			)
			(layer "B.SilkS")
		)
		(fp_line
			(start -9.840214 -1.532382)
			(end -12.115038 -3.714496)
			(stroke
				(width 0.1)
				(type default)
			)
			(layer "B.SilkS")
		)
		(fp_line
			(start -9.840214 -1.532382)
			(end -12.115038 -3.714496)
			(stroke
				(width 0.1)
				(type default)
			)
			(layer "B.SilkS")
		)
		(fp_line
			(start -9.834626 -2.507996)
			(end -11.00201 -3.627882)
			(stroke
				(width 0.1)
				(type default)
			)
			(layer "B.SilkS")
		)
		(fp_line
			(start -9.834626 -2.507996)
			(end -11.00201 -3.627882)
			(stroke
				(width 0.1)
				(type default)
			)
			(layer "B.SilkS")
		)
		(fp_line
			(start -9.825228 -1.575562)
			(end -12.063984 -3.723132)
			(stroke
				(width 0.1)
				(type default)
			)
			(layer "B.SilkS")
		)
		(fp_line
			(start -9.825228 -1.575562)
			(end -12.063984 -3.723132)
			(stroke
				(width 0.1)
				(type default)
			)
			(layer "B.SilkS")
		)
		(fp_line
			(start -9.812528 -2.429256)
			(end -11.09218 -3.656838)
			(stroke
				(width 0.1)
				(type default)
			)
			(layer "B.SilkS")
		)
		(fp_line
			(start -9.812528 -2.429256)
			(end -11.09218 -3.656838)
			(stroke
				(width 0.1)
				(type default)
			)
			(layer "B.SilkS")
		)
		(fp_line
			(start -9.809988 -1.618742)
			(end -12.010136 -3.729482)
			(stroke
				(width 0.1)
				(type default)
			)
			(layer "B.SilkS")
		)
		(fp_line
			(start -9.809988 -1.618742)
			(end -12.010136 -3.729482)
			(stroke
				(width 0.1)
				(type default)
			)
			(layer "B.SilkS")
		)
		(fp_line
			(start -9.797034 -1.663954)
			(end -11.952986 -3.732276)
			(stroke
				(width 0.1)
				(type default)
			)
			(layer "B.SilkS")
		)
		(fp_line
			(start -9.797034 -1.663954)
			(end -11.952986 -3.732276)
			(stroke
				(width 0.1)
				(type default)
			)
			(layer "B.SilkS")
		)
		(fp_line
			(start -9.79043 -2.350262)
			(end -11.167872 -3.67157)
			(stroke
				(width 0.1)
				(type default)
			)
			(layer "B.SilkS")
		)
		(fp_line
			(start -9.79043 -2.350262)
			(end -11.167872 -3.67157)
			(stroke
				(width 0.1)
				(type default)
			)
			(layer "B.SilkS")
		)
		(fp_line
			(start -9.78662 -1.711706)
			(end -11.89609 -3.735324)
			(stroke
				(width 0.1)
				(type default)
			)
			(layer "B.SilkS")
		)
		(fp_line
			(start -9.78662 -1.711706)
			(end -11.89609 -3.735324)
			(stroke
				(width 0.1)
				(type default)
			)
			(layer "B.SilkS")
		)
		(fp_line
			(start -9.777222 -2.279904)
			(end -11.24331 -3.686556)
			(stroke
				(width 0.1)
				(type default)
			)
			(layer "B.SilkS")
		)
		(fp_line
			(start -9.777222 -2.279904)
			(end -11.24331 -3.686556)
			(stroke
				(width 0.1)
				(type default)
			)
			(layer "B.SilkS")
		)
		(fp_line
			(start -9.77646 -1.759712)
			(end -11.83894 -3.738372)
			(stroke
				(width 0.1)
				(type default)
			)
			(layer "B.SilkS")
		)
		(fp_line
			(start -9.77646 -1.759712)
			(end -11.83894 -3.738372)
			(stroke
				(width 0.1)
				(type default)
			)
			(layer "B.SilkS")
		)
		(fp_line
			(start -9.768586 -2.214118)
			(end -11.319002 -3.701288)
			(stroke
				(width 0.1)
				(type default)
			)
			(layer "B.SilkS")
		)
		(fp_line
			(start -9.768586 -2.214118)
			(end -11.319002 -3.701288)
			(stroke
				(width 0.1)
				(type default)
			)
			(layer "B.SilkS")
		)
		(fp_line
			(start -9.76757 -1.808988)
			(end -11.782044 -3.74142)
			(stroke
				(width 0.1)
				(type default)
			)
			(layer "B.SilkS")
		)
		(fp_line
			(start -9.76757 -1.808988)
			(end -11.782044 -3.74142)
			(stroke
				(width 0.1)
				(type default)
			)
			(layer "B.SilkS")
		)
		(fp_line
			(start -9.762998 -1.862074)
			(end -11.719052 -3.738626)
			(stroke
				(width 0.1)
				(type default)
			)
			(layer "B.SilkS")
		)
		(fp_line
			(start -9.762998 -1.862074)
			(end -11.719052 -3.738626)
			(stroke
				(width 0.1)
				(type default)
			)
			(layer "B.SilkS")
		)
		(fp_line
			(start -9.760458 -2.148332)
			(end -11.394694 -3.71602)
			(stroke
				(width 0.1)
				(type default)
			)
			(layer "B.SilkS")
		)
		(fp_line
			(start -9.760458 -2.148332)
			(end -11.394694 -3.71602)
			(stroke
				(width 0.1)
				(type default)
			)
			(layer "B.SilkS")
		)
		(fp_line
			(start -9.758172 -1.915414)
			(end -11.65479 -3.734816)
			(stroke
				(width 0.1)
				(type default)
			)
			(layer "B.SilkS")
		)
		(fp_line
			(start -9.758172 -1.915414)
			(end -11.65479 -3.734816)
			(stroke
				(width 0.1)
				(type default)
			)
			(layer "B.SilkS")
		)
		(fp_line
			(start -9.75741 -2.08788)
			(end -11.46175 -3.722878)
			(stroke
				(width 0.1)
				(type default)
			)
			(layer "B.SilkS")
		)
		(fp_line
			(start -9.75741 -2.08788)
			(end -11.46175 -3.722878)
			(stroke
				(width 0.1)
				(type default)
			)
			(layer "B.SilkS")
		)
		(fp_line
			(start -9.75614 -2.028698)
			(end -11.526012 -3.726688)
			(stroke
				(width 0.1)
				(type default)
			)
			(layer "B.SilkS")
		)
		(fp_line
			(start -9.75614 -2.028698)
			(end -11.526012 -3.726688)
			(stroke
				(width 0.1)
				(type default)
			)
			(layer "B.SilkS")
		)
		(fp_line
			(start -9.754616 -1.96977)
			(end -11.590528 -3.730752)
			(stroke
				(width 0.1)
				(type default)
			)
			(layer "B.SilkS")
		)
		(fp_line
			(start -9.754616 -1.96977)
			(end -11.590528 -3.730752)
			(stroke
				(width 0.1)
				(type default)
			)
			(layer "B.SilkS")
		)
		(fp_line
			(start -9.701276 -5.171694)
			(end -9.663176 -5.171694)
			(stroke
				(width 0.1)
				(type default)
			)
			(layer "B.SilkS")
		)
		(fp_line
			(start -9.701276 -5.171694)
			(end -9.663176 -5.171694)
			(stroke
				(width 0.1)
				(type default)
			)
			(layer "B.SilkS")
		)
		(fp_line
			(start -9.696704 -5.14604)
			(end -9.701276 -5.171694)
			(stroke
				(width 0.1)
				(type default)
			)
			(layer "B.SilkS")
		)
		(fp_line
			(start -9.696704 -5.14604)
			(end -9.701276 -5.171694)
			(stroke
				(width 0.1)
				(type default)
			)
			(layer "B.SilkS")
		)
		(fp_line
			(start -9.696704 -5.14604)
			(end -8.340852 -3.845306)
			(stroke
				(width 0.1)
				(type default)
			)
			(layer "B.SilkS")
		)
		(fp_line
			(start -9.696704 -5.14604)
			(end -8.340852 -3.845306)
			(stroke
				(width 0.1)
				(type default)
			)
			(layer "B.SilkS")
		)
		(fp_line
			(start -9.684512 -5.076698)
			(end -9.696704 -5.14604)
			(stroke
				(width 0.1)
				(type default)
			)
			(layer "B.SilkS")
		)
		(fp_line
			(start -9.684512 -5.076698)
			(end -9.696704 -5.14604)
			(stroke
				(width 0.1)
				(type default)
			)
			(layer "B.SilkS")
		)
		(fp_line
			(start -9.684512 -5.076698)
			(end -8.32866 -3.77571)
			(stroke
				(width 0.1)
				(type default)
			)
			(layer "B.SilkS")
		)
		(fp_line
			(start -9.684512 -5.076698)
			(end -8.32866 -3.77571)
			(stroke
				(width 0.1)
				(type default)
			)
			(layer "B.SilkS")
		)
		(fp_line
			(start -9.67232 -5.007356)
			(end -9.684512 -5.076698)
			(stroke
				(width 0.1)
				(type default)
			)
			(layer "B.SilkS")
		)
		(fp_line
			(start -9.67232 -5.007356)
			(end -9.684512 -5.076698)
			(stroke
				(width 0.1)
				(type default)
			)
			(layer "B.SilkS")
		)
		(fp_line
			(start -9.67232 -5.007356)
			(end -8.316468 -3.706368)
			(stroke
				(width 0.1)
				(type default)
			)
			(layer "B.SilkS")
		)
		(fp_line
			(start -9.67232 -5.007356)
			(end -8.316468 -3.706368)
			(stroke
				(width 0.1)
				(type default)
			)
			(layer "B.SilkS")
		)
		(fp_line
			(start -9.663176 -5.171694)
			(end -9.603232 -5.171694)
			(stroke
				(width 0.1)
				(type default)
			)
			(layer "B.SilkS")
		)
		(fp_line
			(start -9.663176 -5.171694)
			(end -9.603232 -5.171694)
			(stroke
				(width 0.1)
				(type default)
			)
			(layer "B.SilkS")
		)
		(fp_line
			(start -9.663176 -5.171694)
			(end -8.35279 -3.914648)
			(stroke
				(width 0.1)
				(type default)
			)
			(layer "B.SilkS")
		)
		(fp_line
			(start -9.663176 -5.171694)
			(end -8.35279 -3.914648)
			(stroke
				(width 0.1)
				(type default)
			)
			(layer "B.SilkS")
		)
		(fp_line
			(start -9.660382 -4.938014)
			(end -9.67232 -5.007356)
			(stroke
				(width 0.1)
				(type default)
			)
			(layer "B.SilkS")
		)
		(fp_line
			(start -9.660382 -4.938014)
			(end -9.67232 -5.007356)
			(stroke
				(width 0.1)
				(type default)
			)
			(layer "B.SilkS")
		)
		(fp_line
			(start -9.660382 -4.938014)
			(end -8.304276 -3.63728)
			(stroke
				(width 0.1)
				(type default)
			)
			(layer "B.SilkS")
		)
		(fp_line
			(start -9.660382 -4.938014)
			(end -8.304276 -3.63728)
			(stroke
				(width 0.1)
				(type default)
			)
			(layer "B.SilkS")
		)
		(fp_line
			(start -9.64819 -4.868418)
			(end -9.660382 -4.938014)
			(stroke
				(width 0.1)
				(type default)
			)
			(layer "B.SilkS")
		)
		(fp_line
			(start -9.64819 -4.868418)
			(end -9.660382 -4.938014)
			(stroke
				(width 0.1)
				(type default)
			)
			(layer "B.SilkS")
		)
		(fp_line
			(start -9.64819 -4.868418)
			(end -8.292084 -3.567684)
			(stroke
				(width 0.1)
				(type default)
			)
			(layer "B.SilkS")
		)
		(fp_line
			(start -9.64819 -4.868418)
			(end -8.292084 -3.567684)
			(stroke
				(width 0.1)
				(type default)
			)
			(layer "B.SilkS")
		)
		(fp_line
			(start -9.635744 -4.798822)
			(end -9.64819 -4.868418)
			(stroke
				(width 0.1)
				(type default)
			)
			(layer "B.SilkS")
		)
		(fp_line
			(start -9.635744 -4.798822)
			(end -9.64819 -4.868418)
			(stroke
				(width 0.1)
				(type default)
			)
			(layer "B.SilkS")
		)
		(fp_line
			(start -9.635744 -4.798822)
			(end -8.279892 -3.498342)
			(stroke
				(width 0.1)
				(type default)
			)
			(layer "B.SilkS")
		)
		(fp_line
			(start -9.635744 -4.798822)
			(end -8.279892 -3.498342)
			(stroke
				(width 0.1)
				(type default)
			)
			(layer "B.SilkS")
		)
		(fp_line
			(start -9.623552 -4.729734)
			(end -9.635744 -4.798822)
			(stroke
				(width 0.1)
				(type default)
			)
			(layer "B.SilkS")
		)
		(fp_line
			(start -9.623552 -4.729734)
			(end -9.635744 -4.798822)
			(stroke
				(width 0.1)
				(type default)
			)
			(layer "B.SilkS")
		)
		(fp_line
			(start -9.623552 -4.729734)
			(end -8.2677 -3.429)
			(stroke
				(width 0.1)
				(type default)
			)
			(layer "B.SilkS")
		)
		(fp_line
			(start -9.623552 -4.729734)
			(end -8.2677 -3.429)
			(stroke
				(width 0.1)
				(type default)
			)
			(layer "B.SilkS")
		)
		(fp_line
			(start -9.61136 -4.660138)
			(end -9.623552 -4.729734)
			(stroke
				(width 0.1)
				(type default)
			)
			(layer "B.SilkS")
		)
		(fp_line
			(start -9.61136 -4.660138)
			(end -9.623552 -4.729734)
			(stroke
				(width 0.1)
				(type default)
			)
			(layer "B.SilkS")
		)
		(fp_line
			(start -9.61136 -4.660138)
			(end -8.255762 -3.359658)
			(stroke
				(width 0.1)
				(type default)
			)
			(layer "B.SilkS")
		)
		(fp_line
			(start -9.61136 -4.660138)
			(end -8.255762 -3.359658)
			(stroke
				(width 0.1)
				(type default)
			)
			(layer "B.SilkS")
		)
		(fp_line
			(start -9.603232 -5.171694)
			(end -9.543034 -5.171694)
			(stroke
				(width 0.1)
				(type default)
			)
			(layer "B.SilkS")
		)
		(fp_line
			(start -9.603232 -5.171694)
			(end -9.543034 -5.171694)
			(stroke
				(width 0.1)
				(type default)
			)
			(layer "B.SilkS")
		)
		(fp_line
			(start -9.603232 -5.171694)
			(end -8.365236 -3.98399)
			(stroke
				(width 0.1)
				(type default)
			)
			(layer "B.SilkS")
		)
		(fp_line
			(start -9.603232 -5.171694)
			(end -8.365236 -3.98399)
			(stroke
				(width 0.1)
				(type default)
			)
			(layer "B.SilkS")
		)
		(fp_line
			(start -9.599168 -4.590796)
			(end -9.61136 -4.660138)
			(stroke
				(width 0.1)
				(type default)
			)
			(layer "B.SilkS")
		)
		(fp_line
			(start -9.599168 -4.590796)
			(end -9.61136 -4.660138)
			(stroke
				(width 0.1)
				(type default)
			)
			(layer "B.SilkS")
		)
		(fp_line
			(start -9.599168 -4.590796)
			(end -8.24357 -3.290316)
			(stroke
				(width 0.1)
				(type default)
			)
			(layer "B.SilkS")
		)
		(fp_line
			(start -9.599168 -4.590796)
			(end -8.24357 -3.290316)
			(stroke
				(width 0.1)
				(type default)
			)
			(layer "B.SilkS")
		)
		(fp_line
			(start -9.586976 -4.5212)
			(end -9.599168 -4.590796)
			(stroke
				(width 0.1)
				(type default)
			)
			(layer "B.SilkS")
		)
		(fp_line
			(start -9.586976 -4.5212)
			(end -9.599168 -4.590796)
			(stroke
				(width 0.1)
				(type default)
			)
			(layer "B.SilkS")
		)
		(fp_line
			(start -9.586976 -4.5212)
			(end -8.231378 -3.22072)
			(stroke
				(width 0.1)
				(type default)
			)
			(layer "B.SilkS")
		)
		(fp_line
			(start -9.586976 -4.5212)
			(end -8.231378 -3.22072)
			(stroke
				(width 0.1)
				(type default)
			)
			(layer "B.SilkS")
		)
		(fp_line
			(start -9.574784 -4.452112)
			(end -9.586976 -4.5212)
			(stroke
				(width 0.1)
				(type default)
			)
			(layer "B.SilkS")
		)
		(fp_line
			(start -9.574784 -4.452112)
			(end -9.586976 -4.5212)
			(stroke
				(width 0.1)
				(type default)
			)
			(layer "B.SilkS")
		)
		(fp_line
			(start -9.574784 -4.452112)
			(end -8.219186 -3.151378)
			(stroke
				(width 0.1)
				(type default)
			)
			(layer "B.SilkS")
		)
		(fp_line
			(start -9.574784 -4.452112)
			(end -8.219186 -3.151378)
			(stroke
				(width 0.1)
				(type default)
			)
			(layer "B.SilkS")
		)
		(fp_line
			(start -9.562592 -4.382516)
			(end -9.574784 -4.452112)
			(stroke
				(width 0.1)
				(type default)
			)
			(layer "B.SilkS")
		)
		(fp_line
			(start -9.562592 -4.382516)
			(end -9.574784 -4.452112)
			(stroke
				(width 0.1)
				(type default)
			)
			(layer "B.SilkS")
		)
		(fp_line
			(start -9.562592 -4.382516)
			(end -8.206994 -3.08229)
			(stroke
				(width 0.1)
				(type default)
			)
			(layer "B.SilkS")
		)
		(fp_line
			(start -9.562592 -4.382516)
			(end -8.206994 -3.08229)
			(stroke
				(width 0.1)
				(type default)
			)
			(layer "B.SilkS")
		)
		(fp_line
			(start -9.5504 -4.313174)
			(end -9.562592 -4.382516)
			(stroke
				(width 0.1)
				(type default)
			)
			(layer "B.SilkS")
		)
		(fp_line
			(start -9.5504 -4.313174)
			(end -9.562592 -4.382516)
			(stroke
				(width 0.1)
				(type default)
			)
			(layer "B.SilkS")
		)
		(fp_line
			(start -9.5504 -4.313174)
			(end -8.194802 -3.012694)
			(stroke
				(width 0.1)
				(type default)
			)
			(layer "B.SilkS")
		)
		(fp_line
			(start -9.5504 -4.313174)
			(end -8.194802 -3.012694)
			(stroke
				(width 0.1)
				(type default)
			)
			(layer "B.SilkS")
		)
		(fp_line
			(start -9.543034 -5.171694)
			(end -9.482836 -5.171694)
			(stroke
				(width 0.1)
				(type default)
			)
			(layer "B.SilkS")
		)
		(fp_line
			(start -9.543034 -5.171694)
			(end -9.482836 -5.171694)
			(stroke
				(width 0.1)
				(type default)
			)
			(layer "B.SilkS")
		)
		(fp_line
			(start -9.543034 -5.171694)
			(end -8.377174 -4.053332)
			(stroke
				(width 0.1)
				(type default)
			)
			(layer "B.SilkS")
		)
		(fp_line
			(start -9.543034 -5.171694)
			(end -8.377174 -4.053332)
			(stroke
				(width 0.1)
				(type default)
			)
			(layer "B.SilkS")
		)
		(fp_line
			(start -9.538208 -4.243578)
			(end -9.5504 -4.313174)
			(stroke
				(width 0.1)
				(type default)
			)
			(layer "B.SilkS")
		)
		(fp_line
			(start -9.538208 -4.243578)
			(end -9.5504 -4.313174)
			(stroke
				(width 0.1)
				(type default)
			)
			(layer "B.SilkS")
		)
		(fp_line
			(start -9.538208 -4.243578)
			(end -8.18261 -2.943352)
			(stroke
				(width 0.1)
				(type default)
			)
			(layer "B.SilkS")
		)
		(fp_line
			(start -9.538208 -4.243578)
			(end -8.18261 -2.943352)
			(stroke
				(width 0.1)
				(type default)
			)
			(layer "B.SilkS")
		)
		(fp_line
			(start -9.526016 -4.174236)
			(end -9.538208 -4.243578)
			(stroke
				(width 0.1)
				(type default)
			)
			(layer "B.SilkS")
		)
		(fp_line
			(start -9.526016 -4.174236)
			(end -9.538208 -4.243578)
			(stroke
				(width 0.1)
				(type default)
			)
			(layer "B.SilkS")
		)
		(fp_line
			(start -9.526016 -4.174236)
			(end -8.170418 -2.87401)
			(stroke
				(width 0.1)
				(type default)
			)
			(layer "B.SilkS")
		)
		(fp_line
			(start -9.526016 -4.174236)
			(end -8.170418 -2.87401)
			(stroke
				(width 0.1)
				(type default)
			)
			(layer "B.SilkS")
		)
		(fp_line
			(start -9.513824 -4.104894)
			(end -9.526016 -4.174236)
			(stroke
				(width 0.1)
				(type default)
			)
			(layer "B.SilkS")
		)
		(fp_line
			(start -9.513824 -4.104894)
			(end -9.526016 -4.174236)
			(stroke
				(width 0.1)
				(type default)
			)
			(layer "B.SilkS")
		)
		(fp_line
			(start -9.513824 -4.104894)
			(end -8.156956 -2.803398)
			(stroke
				(width 0.1)
				(type default)
			)
			(layer "B.SilkS")
		)
		(fp_line
			(start -9.513824 -4.104894)
			(end -8.156956 -2.803398)
			(stroke
				(width 0.1)
				(type default)
			)
			(layer "B.SilkS")
		)
		(fp_line
			(start -9.501632 -4.035552)
			(end -9.513824 -4.104894)
			(stroke
				(width 0.1)
				(type default)
			)
			(layer "B.SilkS")
		)
		(fp_line
			(start -9.501632 -4.035552)
			(end -9.513824 -4.104894)
			(stroke
				(width 0.1)
				(type default)
			)
			(layer "B.SilkS")
		)
		(fp_line
			(start -9.501632 -4.035552)
			(end -8.140446 -2.729738)
			(stroke
				(width 0.1)
				(type default)
			)
			(layer "B.SilkS")
		)
		(fp_line
			(start -9.501632 -4.035552)
			(end -8.140446 -2.729738)
			(stroke
				(width 0.1)
				(type default)
			)
			(layer "B.SilkS")
		)
		(fp_line
			(start -9.48944 -3.965956)
			(end -9.501632 -4.035552)
			(stroke
				(width 0.1)
				(type default)
			)
			(layer "B.SilkS")
		)
		(fp_line
			(start -9.48944 -3.965956)
			(end -9.501632 -4.035552)
			(stroke
				(width 0.1)
				(type default)
			)
			(layer "B.SilkS")
		)
		(fp_line
			(start -9.48944 -3.965956)
			(end -8.123682 -2.655824)
			(stroke
				(width 0.1)
				(type default)
			)
			(layer "B.SilkS")
		)
		(fp_line
			(start -9.48944 -3.965956)
			(end -8.123682 -2.655824)
			(stroke
				(width 0.1)
				(type default)
			)
			(layer "B.SilkS")
		)
		(fp_line
			(start -9.482836 -5.171694)
			(end -9.422638 -5.171694)
			(stroke
				(width 0.1)
				(type default)
			)
			(layer "B.SilkS")
		)
		(fp_line
			(start -9.482836 -5.171694)
			(end -9.422638 -5.171694)
			(stroke
				(width 0.1)
				(type default)
			)
			(layer "B.SilkS")
		)
		(fp_line
			(start -9.482836 -5.171694)
			(end -8.389366 -4.122674)
			(stroke
				(width 0.1)
				(type default)
			)
			(layer "B.SilkS")
		)
		(fp_line
			(start -9.482836 -5.171694)
			(end -8.389366 -4.122674)
			(stroke
				(width 0.1)
				(type default)
			)
			(layer "B.SilkS")
		)
		(fp_line
			(start -9.477248 -3.896614)
			(end -9.48944 -3.965956)
			(stroke
				(width 0.1)
				(type default)
			)
			(layer "B.SilkS")
		)
		(fp_line
			(start -9.477248 -3.896614)
			(end -9.48944 -3.965956)
			(stroke
				(width 0.1)
				(type default)
			)
			(layer "B.SilkS")
		)
		(fp_line
			(start -9.477248 -3.896614)
			(end -8.107172 -2.582418)
			(stroke
				(width 0.1)
				(type default)
			)
			(layer "B.SilkS")
		)
		(fp_line
			(start -9.477248 -3.896614)
			(end -8.107172 -2.582418)
			(stroke
				(width 0.1)
				(type default)
			)
			(layer "B.SilkS")
		)
		(fp_line
			(start -9.465056 -3.827526)
			(end -9.477248 -3.896614)
			(stroke
				(width 0.1)
				(type default)
			)
			(layer "B.SilkS")
		)
		(fp_line
			(start -9.465056 -3.827526)
			(end -9.477248 -3.896614)
			(stroke
				(width 0.1)
				(type default)
			)
			(layer "B.SilkS")
		)
		(fp_line
			(start -9.465056 -3.827526)
			(end -9.452864 -3.75793)
			(stroke
				(width 0.1)
				(type default)
			)
			(layer "B.SilkS")
		)
		(fp_line
			(start -9.465056 -3.827526)
			(end -9.452864 -3.75793)
			(stroke
				(width 0.1)
				(type default)
			)
			(layer "B.SilkS")
		)
		(fp_line
			(start -9.440672 -3.688334)
			(end -9.452864 -3.75793)
			(stroke
				(width 0.1)
				(type default)
			)
			(layer "B.SilkS")
		)
		(fp_line
			(start -9.440672 -3.688334)
			(end -9.452864 -3.75793)
			(stroke
				(width 0.1)
				(type default)
			)
			(layer "B.SilkS")
		)
		(fp_line
			(start -9.42848 -3.618992)
			(end -9.440672 -3.688334)
			(stroke
				(width 0.1)
				(type default)
			)
			(layer "B.SilkS")
		)
		(fp_line
			(start -9.42848 -3.618992)
			(end -9.440672 -3.688334)
			(stroke
				(width 0.1)
				(type default)
			)
			(layer "B.SilkS")
		)
		(fp_line
			(start -9.422638 -5.171694)
			(end -9.36244 -5.171694)
			(stroke
				(width 0.1)
				(type default)
			)
			(layer "B.SilkS")
		)
		(fp_line
			(start -9.422638 -5.171694)
			(end -9.36244 -5.171694)
			(stroke
				(width 0.1)
				(type default)
			)
			(layer "B.SilkS")
		)
		(fp_line
			(start -9.422638 -5.171694)
			(end -8.401558 -4.19227)
			(stroke
				(width 0.1)
				(type default)
			)
			(layer "B.SilkS")
		)
		(fp_line
			(start -9.422638 -5.171694)
			(end -8.401558 -4.19227)
			(stroke
				(width 0.1)
				(type default)
			)
			(layer "B.SilkS")
		)
		(fp_line
			(start -9.416288 -3.54965)
			(end -9.42848 -3.618992)
			(stroke
				(width 0.1)
				(type default)
			)
			(layer "B.SilkS")
		)
		(fp_line
			(start -9.416288 -3.54965)
			(end -9.42848 -3.618992)
			(stroke
				(width 0.1)
				(type default)
			)
			(layer "B.SilkS")
		)
		(fp_line
			(start -9.416288 -3.54965)
			(end -9.404096 -3.480054)
			(stroke
				(width 0.1)
				(type default)
			)
			(layer "B.SilkS")
		)
		(fp_line
			(start -9.416288 -3.54965)
			(end -9.404096 -3.480054)
			(stroke
				(width 0.1)
				(type default)
			)
			(layer "B.SilkS")
		)
		(fp_line
			(start -9.416288 -3.54965)
			(end -6.565392 -0.815086)
			(stroke
				(width 0.1)
				(type default)
			)
			(layer "B.SilkS")
		)
		(fp_line
			(start -9.416288 -3.54965)
			(end -6.565392 -0.815086)
			(stroke
				(width 0.1)
				(type default)
			)
			(layer "B.SilkS")
		)
		(fp_line
			(start -9.404096 -3.480054)
			(end -9.391904 -3.410712)
			(stroke
				(width 0.1)
				(type default)
			)
			(layer "B.SilkS")
		)
		(fp_line
			(start -9.404096 -3.480054)
			(end -9.391904 -3.410712)
			(stroke
				(width 0.1)
				(type default)
			)
			(layer "B.SilkS")
		)
		(fp_line
			(start -9.379712 -3.34137)
			(end -9.391904 -3.410712)
			(stroke
				(width 0.1)
				(type default)
			)
			(layer "B.SilkS")
		)
		(fp_line
			(start -9.379712 -3.34137)
			(end -9.391904 -3.410712)
			(stroke
				(width 0.1)
				(type default)
			)
			(layer "B.SilkS")
		)
		(fp_line
			(start -9.36752 -3.272028)
			(end -9.379712 -3.34137)
			(stroke
				(width 0.1)
				(type default)
			)
			(layer "B.SilkS")
		)
		(fp_line
			(start -9.36752 -3.272028)
			(end -9.379712 -3.34137)
			(stroke
				(width 0.1)
				(type default)
			)
			(layer "B.SilkS")
		)
		(fp_line
			(start -9.36244 -5.171694)
			(end -9.302242 -5.171694)
			(stroke
				(width 0.1)
				(type default)
			)
			(layer "B.SilkS")
		)
		(fp_line
			(start -9.36244 -5.171694)
			(end -9.302242 -5.171694)
			(stroke
				(width 0.1)
				(type default)
			)
			(layer "B.SilkS")
		)
		(fp_line
			(start -9.36244 -5.171694)
			(end -8.41375 -4.261612)
			(stroke
				(width 0.1)
				(type default)
			)
			(layer "B.SilkS")
		)
		(fp_line
			(start -9.36244 -5.171694)
			(end -8.41375 -4.261612)
			(stroke
				(width 0.1)
				(type default)
			)
			(layer "B.SilkS")
		)
		(fp_line
			(start -9.355328 -3.202432)
			(end -9.36752 -3.272028)
			(stroke
				(width 0.1)
				(type default)
			)
			(layer "B.SilkS")
		)
		(fp_line
			(start -9.355328 -3.202432)
			(end -9.36752 -3.272028)
			(stroke
				(width 0.1)
				(type default)
			)
			(layer "B.SilkS")
		)
		(fp_line
			(start -9.343136 -3.13309)
			(end -9.355328 -3.202432)
			(stroke
				(width 0.1)
				(type default)
			)
			(layer "B.SilkS")
		)
		(fp_line
			(start -9.343136 -3.13309)
			(end -9.355328 -3.202432)
			(stroke
				(width 0.1)
				(type default)
			)
			(layer "B.SilkS")
		)
		(fp_line
			(start -9.330944 -3.063748)
			(end -9.343136 -3.13309)
			(stroke
				(width 0.1)
				(type default)
			)
			(layer "B.SilkS")
		)
		(fp_line
			(start -9.330944 -3.063748)
			(end -9.343136 -3.13309)
			(stroke
				(width 0.1)
				(type default)
			)
			(layer "B.SilkS")
		)
		(fp_line
			(start -9.318752 -2.994406)
			(end -9.330944 -3.063748)
			(stroke
				(width 0.1)
				(type default)
			)
			(layer "B.SilkS")
		)
		(fp_line
			(start -9.318752 -2.994406)
			(end -9.330944 -3.063748)
			(stroke
				(width 0.1)
				(type default)
			)
			(layer "B.SilkS")
		)
		(fp_line
			(start -9.30656 -2.925064)
			(end -9.318752 -2.994406)
			(stroke
				(width 0.1)
				(type default)
			)
			(layer "B.SilkS")
		)
		(fp_line
			(start -9.30656 -2.925064)
			(end -9.318752 -2.994406)
			(stroke
				(width 0.1)
				(type default)
			)
			(layer "B.SilkS")
		)
		(fp_line
			(start -9.302242 -5.171694)
			(end -9.242298 -5.171694)
			(stroke
				(width 0.1)
				(type default)
			)
			(layer "B.SilkS")
		)
		(fp_line
			(start -9.302242 -5.171694)
			(end -9.242298 -5.171694)
			(stroke
				(width 0.1)
				(type default)
			)
			(layer "B.SilkS")
		)
		(fp_line
			(start -9.302242 -5.171694)
			(end -8.425942 -4.3307)
			(stroke
				(width 0.1)
				(type default)
			)
			(layer "B.SilkS")
		)
		(fp_line
			(start -9.302242 -5.171694)
			(end -8.425942 -4.3307)
			(stroke
				(width 0.1)
				(type default)
			)
			(layer "B.SilkS")
		)
		(fp_line
			(start -9.294368 -2.855468)
			(end -9.30656 -2.925064)
			(stroke
				(width 0.1)
				(type default)
			)
			(layer "B.SilkS")
		)
		(fp_line
			(start -9.294368 -2.855468)
			(end -9.30656 -2.925064)
			(stroke
				(width 0.1)
				(type default)
			)
			(layer "B.SilkS")
		)
		(fp_line
			(start -9.281922 -2.786126)
			(end -9.294368 -2.855468)
			(stroke
				(width 0.1)
				(type default)
			)
			(layer "B.SilkS")
		)
		(fp_line
			(start -9.281922 -2.786126)
			(end -9.294368 -2.855468)
			(stroke
				(width 0.1)
				(type default)
			)
			(layer "B.SilkS")
		)
		(fp_line
			(start -9.269984 -2.716784)
			(end -9.281922 -2.786126)
			(stroke
				(width 0.1)
				(type default)
			)
			(layer "B.SilkS")
		)
		(fp_line
			(start -9.269984 -2.716784)
			(end -9.281922 -2.786126)
			(stroke
				(width 0.1)
				(type default)
			)
			(layer "B.SilkS")
		)
		(fp_line
			(start -9.257792 -2.647188)
			(end -9.269984 -2.716784)
			(stroke
				(width 0.1)
				(type default)
			)
			(layer "B.SilkS")
		)
		(fp_line
			(start -9.257792 -2.647188)
			(end -9.269984 -2.716784)
			(stroke
				(width 0.1)
				(type default)
			)
			(layer "B.SilkS")
		)
		(fp_line
			(start -9.2456 -2.577592)
			(end -9.257792 -2.647188)
			(stroke
				(width 0.1)
				(type default)
			)
			(layer "B.SilkS")
		)
		(fp_line
			(start -9.2456 -2.577592)
			(end -9.257792 -2.647188)
			(stroke
				(width 0.1)
				(type default)
			)
			(layer "B.SilkS")
		)
		(fp_line
			(start -9.242298 -5.171694)
			(end -9.181846 -5.171694)
			(stroke
				(width 0.1)
				(type default)
			)
			(layer "B.SilkS")
		)
		(fp_line
			(start -9.242298 -5.171694)
			(end -9.181846 -5.171694)
			(stroke
				(width 0.1)
				(type default)
			)
			(layer "B.SilkS")
		)
		(fp_line
			(start -9.242298 -5.171694)
			(end -8.43788 -4.400296)
			(stroke
				(width 0.1)
				(type default)
			)
			(layer "B.SilkS")
		)
		(fp_line
			(start -9.242298 -5.171694)
			(end -8.43788 -4.400296)
			(stroke
				(width 0.1)
				(type default)
			)
			(layer "B.SilkS")
		)
		(fp_line
			(start -9.233408 -2.508504)
			(end -9.2456 -2.577592)
			(stroke
				(width 0.1)
				(type default)
			)
			(layer "B.SilkS")
		)
		(fp_line
			(start -9.233408 -2.508504)
			(end -9.2456 -2.577592)
			(stroke
				(width 0.1)
				(type default)
			)
			(layer "B.SilkS")
		)
		(fp_line
			(start -9.220962 -2.438908)
			(end -9.233408 -2.508504)
			(stroke
				(width 0.1)
				(type default)
			)
			(layer "B.SilkS")
		)
		(fp_line
			(start -9.220962 -2.438908)
			(end -9.233408 -2.508504)
			(stroke
				(width 0.1)
				(type default)
			)
			(layer "B.SilkS")
		)
		(fp_line
			(start -9.209024 -2.369566)
			(end -9.220962 -2.438908)
			(stroke
				(width 0.1)
				(type default)
			)
			(layer "B.SilkS")
		)
		(fp_line
			(start -9.209024 -2.369566)
			(end -9.220962 -2.438908)
			(stroke
				(width 0.1)
				(type default)
			)
			(layer "B.SilkS")
		)
		(fp_line
			(start -9.196832 -2.300224)
			(end -9.209024 -2.369566)
			(stroke
				(width 0.1)
				(type default)
			)
			(layer "B.SilkS")
		)
		(fp_line
			(start -9.196832 -2.300224)
			(end -9.209024 -2.369566)
			(stroke
				(width 0.1)
				(type default)
			)
			(layer "B.SilkS")
		)
		(fp_line
			(start -9.18464 -2.230882)
			(end -9.196832 -2.300224)
			(stroke
				(width 0.1)
				(type default)
			)
			(layer "B.SilkS")
		)
		(fp_line
			(start -9.18464 -2.230882)
			(end -9.196832 -2.300224)
			(stroke
				(width 0.1)
				(type default)
			)
			(layer "B.SilkS")
		)
		(fp_line
			(start -9.181846 -5.171694)
			(end -9.121902 -5.171694)
			(stroke
				(width 0.1)
				(type default)
			)
			(layer "B.SilkS")
		)
		(fp_line
			(start -9.181846 -5.171694)
			(end -9.121902 -5.171694)
			(stroke
				(width 0.1)
				(type default)
			)
			(layer "B.SilkS")
		)
		(fp_line
			(start -9.181846 -5.171694)
			(end -8.450326 -4.469638)
			(stroke
				(width 0.1)
				(type default)
			)
			(layer "B.SilkS")
		)
		(fp_line
			(start -9.181846 -5.171694)
			(end -8.450326 -4.469638)
			(stroke
				(width 0.1)
				(type default)
			)
			(layer "B.SilkS")
		)
		(fp_line
			(start -9.172194 -2.161286)
			(end -9.18464 -2.230882)
			(stroke
				(width 0.1)
				(type default)
			)
			(layer "B.SilkS")
		)
		(fp_line
			(start -9.172194 -2.161286)
			(end -9.18464 -2.230882)
			(stroke
				(width 0.1)
				(type default)
			)
			(layer "B.SilkS")
		)
		(fp_line
			(start -9.172194 -2.161286)
			(end -9.160002 -2.091944)
			(stroke
				(width 0.1)
				(type default)
			)
			(layer "B.SilkS")
		)
		(fp_line
			(start -9.172194 -2.161286)
			(end -9.160002 -2.091944)
			(stroke
				(width 0.1)
				(type default)
			)
			(layer "B.SilkS")
		)
		(fp_line
			(start -9.160002 -2.091944)
			(end -9.148064 -2.022602)
			(stroke
				(width 0.1)
				(type default)
			)
			(layer "B.SilkS")
		)
		(fp_line
			(start -9.160002 -2.091944)
			(end -9.148064 -2.022602)
			(stroke
				(width 0.1)
				(type default)
			)
			(layer "B.SilkS")
		)
		(fp_line
			(start -9.148064 -2.022602)
			(end -9.135872 -1.953006)
			(stroke
				(width 0.1)
				(type default)
			)
			(layer "B.SilkS")
		)
		(fp_line
			(start -9.148064 -2.022602)
			(end -9.135872 -1.953006)
			(stroke
				(width 0.1)
				(type default)
			)
			(layer "B.SilkS")
		)
		(fp_line
			(start -9.135872 -1.953006)
			(end -9.12368 -1.883664)
			(stroke
				(width 0.1)
				(type default)
			)
			(layer "B.SilkS")
		)
		(fp_line
			(start -9.135872 -1.953006)
			(end -9.12368 -1.883664)
			(stroke
				(width 0.1)
				(type default)
			)
			(layer "B.SilkS")
		)
		(fp_line
			(start -9.12368 -1.883664)
			(end -9.111234 -1.814322)
			(stroke
				(width 0.1)
				(type default)
			)
			(layer "B.SilkS")
		)
		(fp_line
			(start -9.12368 -1.883664)
			(end -9.111234 -1.814322)
			(stroke
				(width 0.1)
				(type default)
			)
			(layer "B.SilkS")
		)
		(fp_line
			(start -9.121902 -5.171694)
			(end -9.061704 -5.171694)
			(stroke
				(width 0.1)
				(type default)
			)
			(layer "B.SilkS")
		)
		(fp_line
			(start -9.121902 -5.171694)
			(end -9.061704 -5.171694)
			(stroke
				(width 0.1)
				(type default)
			)
			(layer "B.SilkS")
		)
		(fp_line
			(start -9.121902 -5.171694)
			(end -8.462264 -4.53898)
			(stroke
				(width 0.1)
				(type default)
			)
			(layer "B.SilkS")
		)
		(fp_line
			(start -9.121902 -5.171694)
			(end -8.462264 -4.53898)
			(stroke
				(width 0.1)
				(type default)
			)
			(layer "B.SilkS")
		)
		(fp_line
			(start -9.111234 -1.814322)
			(end -9.099042 -1.744726)
			(stroke
				(width 0.1)
				(type default)
			)
			(layer "B.SilkS")
		)
		(fp_line
			(start -9.111234 -1.814322)
			(end -9.099042 -1.744726)
			(stroke
				(width 0.1)
				(type default)
			)
			(layer "B.SilkS")
		)
		(fp_line
			(start -9.099042 -1.744726)
			(end -9.087104 -1.675384)
			(stroke
				(width 0.1)
				(type default)
			)
			(layer "B.SilkS")
		)
		(fp_line
			(start -9.099042 -1.744726)
			(end -9.087104 -1.675384)
			(stroke
				(width 0.1)
				(type default)
			)
			(layer "B.SilkS")
		)
		(fp_line
			(start -9.087104 -1.675384)
			(end -9.074912 -1.606296)
			(stroke
				(width 0.1)
				(type default)
			)
			(layer "B.SilkS")
		)
		(fp_line
			(start -9.087104 -1.675384)
			(end -9.074912 -1.606296)
			(stroke
				(width 0.1)
				(type default)
			)
			(layer "B.SilkS")
		)
		(fp_line
			(start -9.074912 -1.606296)
			(end -9.062466 -1.5367)
			(stroke
				(width 0.1)
				(type default)
			)
			(layer "B.SilkS")
		)
		(fp_line
			(start -9.074912 -1.606296)
			(end -9.062466 -1.5367)
			(stroke
				(width 0.1)
				(type default)
			)
			(layer "B.SilkS")
		)
		(fp_line
			(start -9.062466 -1.5367)
			(end -9.050274 -1.467104)
			(stroke
				(width 0.1)
				(type default)
			)
			(layer "B.SilkS")
		)
		(fp_line
			(start -9.062466 -1.5367)
			(end -9.050274 -1.467104)
			(stroke
				(width 0.1)
				(type default)
			)
			(layer "B.SilkS")
		)
		(fp_line
			(start -9.061704 -5.171694)
			(end -9.001506 -5.171694)
			(stroke
				(width 0.1)
				(type default)
			)
			(layer "B.SilkS")
		)
		(fp_line
			(start -9.061704 -5.171694)
			(end -9.001506 -5.171694)
			(stroke
				(width 0.1)
				(type default)
			)
			(layer "B.SilkS")
		)
		(fp_line
			(start -9.061704 -5.171694)
			(end -8.474456 -4.608322)
			(stroke
				(width 0.1)
				(type default)
			)
			(layer "B.SilkS")
		)
		(fp_line
			(start -9.061704 -5.171694)
			(end -8.474456 -4.608322)
			(stroke
				(width 0.1)
				(type default)
			)
			(layer "B.SilkS")
		)
		(fp_line
			(start -9.050274 -1.467104)
			(end -9.038082 -1.397762)
			(stroke
				(width 0.1)
				(type default)
			)
			(layer "B.SilkS")
		)
		(fp_line
			(start -9.050274 -1.467104)
			(end -9.038082 -1.397762)
			(stroke
				(width 0.1)
				(type default)
			)
			(layer "B.SilkS")
		)
		(fp_line
			(start -9.038082 -1.397762)
			(end -9.026144 -1.32842)
			(stroke
				(width 0.1)
				(type default)
			)
			(layer "B.SilkS")
		)
		(fp_line
			(start -9.038082 -1.397762)
			(end -9.026144 -1.32842)
			(stroke
				(width 0.1)
				(type default)
			)
			(layer "B.SilkS")
		)
		(fp_line
			(start -9.026144 -1.32842)
			(end -9.013952 -1.259078)
			(stroke
				(width 0.1)
				(type default)
			)
			(layer "B.SilkS")
		)
		(fp_line
			(start -9.026144 -1.32842)
			(end -9.013952 -1.259078)
			(stroke
				(width 0.1)
				(type default)
			)
			(layer "B.SilkS")
		)
		(fp_line
			(start -9.013952 -1.259078)
			(end -9.001506 -1.189482)
			(stroke
				(width 0.1)
				(type default)
			)
			(layer "B.SilkS")
		)
		(fp_line
			(start -9.013952 -1.259078)
			(end -9.001506 -1.189482)
			(stroke
				(width 0.1)
				(type default)
			)
			(layer "B.SilkS")
		)
		(fp_line
			(start -9.001506 -5.171694)
			(end -8.941308 -5.171694)
			(stroke
				(width 0.1)
				(type default)
			)
			(layer "B.SilkS")
		)
		(fp_line
			(start -9.001506 -5.171694)
			(end -8.941308 -5.171694)
			(stroke
				(width 0.1)
				(type default)
			)
			(layer "B.SilkS")
		)
		(fp_line
			(start -9.001506 -5.171694)
			(end -8.486648 -4.677664)
			(stroke
				(width 0.1)
				(type default)
			)
			(layer "B.SilkS")
		)
		(fp_line
			(start -9.001506 -5.171694)
			(end -8.486648 -4.677664)
			(stroke
				(width 0.1)
				(type default)
			)
			(layer "B.SilkS")
		)
		(fp_line
			(start -9.001506 -1.189482)
			(end -8.989314 -1.12014)
			(stroke
				(width 0.1)
				(type default)
			)
			(layer "B.SilkS")
		)
		(fp_line
			(start -9.001506 -1.189482)
			(end -8.989314 -1.12014)
			(stroke
				(width 0.1)
				(type default)
			)
			(layer "B.SilkS")
		)
		(fp_line
			(start -8.989314 -1.12014)
			(end -8.977122 -1.050798)
			(stroke
				(width 0.1)
				(type default)
			)
			(layer "B.SilkS")
		)
		(fp_line
			(start -8.989314 -1.12014)
			(end -8.977122 -1.050798)
			(stroke
				(width 0.1)
				(type default)
			)
			(layer "B.SilkS")
		)
		(fp_line
			(start -8.977122 -1.050798)
			(end -8.965184 -0.981456)
			(stroke
				(width 0.1)
				(type default)
			)
			(layer "B.SilkS")
		)
		(fp_line
			(start -8.977122 -1.050798)
			(end -8.965184 -0.981456)
			(stroke
				(width 0.1)
				(type default)
			)
			(layer "B.SilkS")
		)
		(fp_line
			(start -8.965184 -0.981456)
			(end -8.952738 -0.91186)
			(stroke
				(width 0.1)
				(type default)
			)
			(layer "B.SilkS")
		)
		(fp_line
			(start -8.965184 -0.981456)
			(end -8.952738 -0.91186)
			(stroke
				(width 0.1)
				(type default)
			)
			(layer "B.SilkS")
		)
		(fp_line
			(start -8.947658 -0.882904)
			(end -8.952738 -0.91186)
			(stroke
				(width 0.1)
				(type default)
			)
			(layer "B.SilkS")
		)
		(fp_line
			(start -8.947658 -0.882904)
			(end -8.952738 -0.91186)
			(stroke
				(width 0.1)
				(type default)
			)
			(layer "B.SilkS")
		)
		(fp_line
			(start -8.941308 -5.171694)
			(end -8.88111 -5.171694)
			(stroke
				(width 0.1)
				(type default)
			)
			(layer "B.SilkS")
		)
		(fp_line
			(start -8.941308 -5.171694)
			(end -8.88111 -5.171694)
			(stroke
				(width 0.1)
				(type default)
			)
			(layer "B.SilkS")
		)
		(fp_line
			(start -8.941308 -5.171694)
			(end -8.49884 -4.74726)
			(stroke
				(width 0.1)
				(type default)
			)
			(layer "B.SilkS")
		)
		(fp_line
			(start -8.941308 -5.171694)
			(end -8.49884 -4.74726)
			(stroke
				(width 0.1)
				(type default)
			)
			(layer "B.SilkS")
		)
		(fp_line
			(start -8.922512 -0.882904)
			(end -8.952738 -0.91186)
			(stroke
				(width 0.1)
				(type default)
			)
			(layer "B.SilkS")
		)
		(fp_line
			(start -8.922512 -0.882904)
			(end -8.952738 -0.91186)
			(stroke
				(width 0.1)
				(type default)
			)
			(layer "B.SilkS")
		)
		(fp_line
			(start -8.922512 -0.882904)
			(end -8.947658 -0.882904)
			(stroke
				(width 0.1)
				(type default)
			)
			(layer "B.SilkS")
		)
		(fp_line
			(start -8.922512 -0.882904)
			(end -8.947658 -0.882904)
			(stroke
				(width 0.1)
				(type default)
			)
			(layer "B.SilkS")
		)
		(fp_line
			(start -8.88111 -5.171694)
			(end -8.821166 -5.171694)
			(stroke
				(width 0.1)
				(type default)
			)
			(layer "B.SilkS")
		)
		(fp_line
			(start -8.88111 -5.171694)
			(end -8.821166 -5.171694)
			(stroke
				(width 0.1)
				(type default)
			)
			(layer "B.SilkS")
		)
		(fp_line
			(start -8.88111 -5.171694)
			(end -8.511032 -4.816602)
			(stroke
				(width 0.1)
				(type default)
			)
			(layer "B.SilkS")
		)
		(fp_line
			(start -8.88111 -5.171694)
			(end -8.511032 -4.816602)
			(stroke
				(width 0.1)
				(type default)
			)
			(layer "B.SilkS")
		)
		(fp_line
			(start -8.862314 -0.882904)
			(end -8.965184 -0.981456)
			(stroke
				(width 0.1)
				(type default)
			)
			(layer "B.SilkS")
		)
		(fp_line
			(start -8.862314 -0.882904)
			(end -8.965184 -0.981456)
			(stroke
				(width 0.1)
				(type default)
			)
			(layer "B.SilkS")
		)
		(fp_line
			(start -8.862314 -0.882904)
			(end -8.922512 -0.882904)
			(stroke
				(width 0.1)
				(type default)
			)
			(layer "B.SilkS")
		)
		(fp_line
			(start -8.862314 -0.882904)
			(end -8.922512 -0.882904)
			(stroke
				(width 0.1)
				(type default)
			)
			(layer "B.SilkS")
		)
		(fp_line
			(start -8.821166 -5.171694)
			(end -8.760968 -5.171694)
			(stroke
				(width 0.1)
				(type default)
			)
			(layer "B.SilkS")
		)
		(fp_line
			(start -8.821166 -5.171694)
			(end -8.760968 -5.171694)
			(stroke
				(width 0.1)
				(type default)
			)
			(layer "B.SilkS")
		)
		(fp_line
			(start -8.821166 -5.171694)
			(end -8.52297 -4.88569)
			(stroke
				(width 0.1)
				(type default)
			)
			(layer "B.SilkS")
		)
		(fp_line
			(start -8.821166 -5.171694)
			(end -8.52297 -4.88569)
			(stroke
				(width 0.1)
				(type default)
			)
			(layer "B.SilkS")
		)
		(fp_line
			(start -8.802116 -0.882904)
			(end -8.977122 -1.050798)
			(stroke
				(width 0.1)
				(type default)
			)
			(layer "B.SilkS")
		)
		(fp_line
			(start -8.802116 -0.882904)
			(end -8.977122 -1.050798)
			(stroke
				(width 0.1)
				(type default)
			)
			(layer "B.SilkS")
		)
		(fp_line
			(start -8.802116 -0.882904)
			(end -8.862314 -0.882904)
			(stroke
				(width 0.1)
				(type default)
			)
			(layer "B.SilkS")
		)
		(fp_line
			(start -8.802116 -0.882904)
			(end -8.862314 -0.882904)
			(stroke
				(width 0.1)
				(type default)
			)
			(layer "B.SilkS")
		)
		(fp_line
			(start -8.760968 -5.171694)
			(end -8.70077 -5.171694)
			(stroke
				(width 0.1)
				(type default)
			)
			(layer "B.SilkS")
		)
		(fp_line
			(start -8.760968 -5.171694)
			(end -8.70077 -5.171694)
			(stroke
				(width 0.1)
				(type default)
			)
			(layer "B.SilkS")
		)
		(fp_line
			(start -8.760968 -5.171694)
			(end -8.535416 -4.955286)
			(stroke
				(width 0.1)
				(type default)
			)
			(layer "B.SilkS")
		)
		(fp_line
			(start -8.760968 -5.171694)
			(end -8.535416 -4.955286)
			(stroke
				(width 0.1)
				(type default)
			)
			(layer "B.SilkS")
		)
		(fp_line
			(start -8.741918 -0.882904)
			(end -8.989314 -1.12014)
			(stroke
				(width 0.1)
				(type default)
			)
			(layer "B.SilkS")
		)
		(fp_line
			(start -8.741918 -0.882904)
			(end -8.989314 -1.12014)
			(stroke
				(width 0.1)
				(type default)
			)
			(layer "B.SilkS")
		)
		(fp_line
			(start -8.741918 -0.882904)
			(end -8.802116 -0.882904)
			(stroke
				(width 0.1)
				(type default)
			)
			(layer "B.SilkS")
		)
		(fp_line
			(start -8.741918 -0.882904)
			(end -8.802116 -0.882904)
			(stroke
				(width 0.1)
				(type default)
			)
			(layer "B.SilkS")
		)
		(fp_line
			(start -8.70077 -5.171694)
			(end -8.640572 -5.171694)
			(stroke
				(width 0.1)
				(type default)
			)
			(layer "B.SilkS")
		)
		(fp_line
			(start -8.70077 -5.171694)
			(end -8.640572 -5.171694)
			(stroke
				(width 0.1)
				(type default)
			)
			(layer "B.SilkS")
		)
		(fp_line
			(start -8.70077 -5.171694)
			(end -8.547608 -5.024628)
			(stroke
				(width 0.1)
				(type default)
			)
			(layer "B.SilkS")
		)
		(fp_line
			(start -8.70077 -5.171694)
			(end -8.547608 -5.024628)
			(stroke
				(width 0.1)
				(type default)
			)
			(layer "B.SilkS")
		)
		(fp_line
			(start -8.681974 -0.882904)
			(end -9.001506 -1.189482)
			(stroke
				(width 0.1)
				(type default)
			)
			(layer "B.SilkS")
		)
		(fp_line
			(start -8.681974 -0.882904)
			(end -9.001506 -1.189482)
			(stroke
				(width 0.1)
				(type default)
			)
			(layer "B.SilkS")
		)
		(fp_line
			(start -8.681974 -0.882904)
			(end -8.741918 -0.882904)
			(stroke
				(width 0.1)
				(type default)
			)
			(layer "B.SilkS")
		)
		(fp_line
			(start -8.681974 -0.882904)
			(end -8.741918 -0.882904)
			(stroke
				(width 0.1)
				(type default)
			)
			(layer "B.SilkS")
		)
		(fp_line
			(start -8.640572 -5.171694)
			(end -8.580374 -5.171694)
			(stroke
				(width 0.1)
				(type default)
			)
			(layer "B.SilkS")
		)
		(fp_line
			(start -8.640572 -5.171694)
			(end -8.580374 -5.171694)
			(stroke
				(width 0.1)
				(type default)
			)
			(layer "B.SilkS")
		)
		(fp_line
			(start -8.640572 -5.171694)
			(end -8.559546 -5.09397)
			(stroke
				(width 0.1)
				(type default)
			)
			(layer "B.SilkS")
		)
		(fp_line
			(start -8.640572 -5.171694)
			(end -8.559546 -5.09397)
			(stroke
				(width 0.1)
				(type default)
			)
			(layer "B.SilkS")
		)
		(fp_line
			(start -8.621522 -0.882904)
			(end -9.013952 -1.259078)
			(stroke
				(width 0.1)
				(type default)
			)
			(layer "B.SilkS")
		)
		(fp_line
			(start -8.621522 -0.882904)
			(end -9.013952 -1.259078)
			(stroke
				(width 0.1)
				(type default)
			)
			(layer "B.SilkS")
		)
		(fp_line
			(start -8.621522 -0.882904)
			(end -8.681974 -0.882904)
			(stroke
				(width 0.1)
				(type default)
			)
			(layer "B.SilkS")
		)
		(fp_line
			(start -8.621522 -0.882904)
			(end -8.681974 -0.882904)
			(stroke
				(width 0.1)
				(type default)
			)
			(layer "B.SilkS")
		)
		(fp_line
			(start -8.580374 -5.171694)
			(end -8.573262 -5.171694)
			(stroke
				(width 0.1)
				(type default)
			)
			(layer "B.SilkS")
		)
		(fp_line
			(start -8.580374 -5.171694)
			(end -8.573262 -5.171694)
			(stroke
				(width 0.1)
				(type default)
			)
			(layer "B.SilkS")
		)
		(fp_line
			(start -8.580374 -5.171694)
			(end -8.571738 -5.163312)
			(stroke
				(width 0.1)
				(type default)
			)
			(layer "B.SilkS")
		)
		(fp_line
			(start -8.580374 -5.171694)
			(end -8.571738 -5.163312)
			(stroke
				(width 0.1)
				(type default)
			)
			(layer "B.SilkS")
		)
		(fp_line
			(start -8.573262 -5.171694)
			(end -8.571738 -5.163312)
			(stroke
				(width 0.1)
				(type default)
			)
			(layer "B.SilkS")
		)
		(fp_line
			(start -8.573262 -5.171694)
			(end -8.571738 -5.163312)
			(stroke
				(width 0.1)
				(type default)
			)
			(layer "B.SilkS")
		)
		(fp_line
			(start -8.561578 -0.882904)
			(end -9.026144 -1.32842)
			(stroke
				(width 0.1)
				(type default)
			)
			(layer "B.SilkS")
		)
		(fp_line
			(start -8.561578 -0.882904)
			(end -9.026144 -1.32842)
			(stroke
				(width 0.1)
				(type default)
			)
			(layer "B.SilkS")
		)
		(fp_line
			(start -8.561578 -0.882904)
			(end -8.621522 -0.882904)
			(stroke
				(width 0.1)
				(type default)
			)
			(layer "B.SilkS")
		)
		(fp_line
			(start -8.561578 -0.882904)
			(end -8.621522 -0.882904)
			(stroke
				(width 0.1)
				(type default)
			)
			(layer "B.SilkS")
		)
		(fp_line
			(start -8.559546 -5.09397)
			(end -8.571738 -5.163312)
			(stroke
				(width 0.1)
				(type default)
			)
			(layer "B.SilkS")
		)
		(fp_line
			(start -8.559546 -5.09397)
			(end -8.571738 -5.163312)
			(stroke
				(width 0.1)
				(type default)
			)
			(layer "B.SilkS")
		)
		(fp_line
			(start -8.547608 -5.024628)
			(end -8.559546 -5.09397)
			(stroke
				(width 0.1)
				(type default)
			)
			(layer "B.SilkS")
		)
		(fp_line
			(start -8.547608 -5.024628)
			(end -8.559546 -5.09397)
			(stroke
				(width 0.1)
				(type default)
			)
			(layer "B.SilkS")
		)
		(fp_line
			(start -8.535416 -4.955286)
			(end -8.547608 -5.024628)
			(stroke
				(width 0.1)
				(type default)
			)
			(layer "B.SilkS")
		)
		(fp_line
			(start -8.535416 -4.955286)
			(end -8.547608 -5.024628)
			(stroke
				(width 0.1)
				(type default)
			)
			(layer "B.SilkS")
		)
		(fp_line
			(start -8.52297 -4.88569)
			(end -8.535416 -4.955286)
			(stroke
				(width 0.1)
				(type default)
			)
			(layer "B.SilkS")
		)
		(fp_line
			(start -8.52297 -4.88569)
			(end -8.535416 -4.955286)
			(stroke
				(width 0.1)
				(type default)
			)
			(layer "B.SilkS")
		)
		(fp_line
			(start -8.511032 -4.816602)
			(end -8.52297 -4.88569)
			(stroke
				(width 0.1)
				(type default)
			)
			(layer "B.SilkS")
		)
		(fp_line
			(start -8.511032 -4.816602)
			(end -8.52297 -4.88569)
			(stroke
				(width 0.1)
				(type default)
			)
			(layer "B.SilkS")
		)
		(fp_line
			(start -8.50138 -0.882904)
			(end -9.038082 -1.397762)
			(stroke
				(width 0.1)
				(type default)
			)
			(layer "B.SilkS")
		)
		(fp_line
			(start -8.50138 -0.882904)
			(end -9.038082 -1.397762)
			(stroke
				(width 0.1)
				(type default)
			)
			(layer "B.SilkS")
		)
		(fp_line
			(start -8.50138 -0.882904)
			(end -8.561578 -0.882904)
			(stroke
				(width 0.1)
				(type default)
			)
			(layer "B.SilkS")
		)
		(fp_line
			(start -8.50138 -0.882904)
			(end -8.561578 -0.882904)
			(stroke
				(width 0.1)
				(type default)
			)
			(layer "B.SilkS")
		)
		(fp_line
			(start -8.49884 -4.74726)
			(end -8.511032 -4.816602)
			(stroke
				(width 0.1)
				(type default)
			)
			(layer "B.SilkS")
		)
		(fp_line
			(start -8.49884 -4.74726)
			(end -8.511032 -4.816602)
			(stroke
				(width 0.1)
				(type default)
			)
			(layer "B.SilkS")
		)
		(fp_line
			(start -8.486648 -4.677664)
			(end -8.49884 -4.74726)
			(stroke
				(width 0.1)
				(type default)
			)
			(layer "B.SilkS")
		)
		(fp_line
			(start -8.486648 -4.677664)
			(end -8.49884 -4.74726)
			(stroke
				(width 0.1)
				(type default)
			)
			(layer "B.SilkS")
		)
		(fp_line
			(start -8.474456 -4.608322)
			(end -8.486648 -4.677664)
			(stroke
				(width 0.1)
				(type default)
			)
			(layer "B.SilkS")
		)
		(fp_line
			(start -8.474456 -4.608322)
			(end -8.486648 -4.677664)
			(stroke
				(width 0.1)
				(type default)
			)
			(layer "B.SilkS")
		)
		(fp_line
			(start -8.462264 -4.53898)
			(end -8.474456 -4.608322)
			(stroke
				(width 0.1)
				(type default)
			)
			(layer "B.SilkS")
		)
		(fp_line
			(start -8.462264 -4.53898)
			(end -8.474456 -4.608322)
			(stroke
				(width 0.1)
				(type default)
			)
			(layer "B.SilkS")
		)
		(fp_line
			(start -8.450326 -4.469638)
			(end -8.462264 -4.53898)
			(stroke
				(width 0.1)
				(type default)
			)
			(layer "B.SilkS")
		)
		(fp_line
			(start -8.450326 -4.469638)
			(end -8.462264 -4.53898)
			(stroke
				(width 0.1)
				(type default)
			)
			(layer "B.SilkS")
		)
		(fp_line
			(start -8.450326 -4.469638)
			(end -8.43788 -4.400296)
			(stroke
				(width 0.1)
				(type default)
			)
			(layer "B.SilkS")
		)
		(fp_line
			(start -8.450326 -4.469638)
			(end -8.43788 -4.400296)
			(stroke
				(width 0.1)
				(type default)
			)
			(layer "B.SilkS")
		)
		(fp_line
			(start -8.441182 -0.882904)
			(end -9.050274 -1.467104)
			(stroke
				(width 0.1)
				(type default)
			)
			(layer "B.SilkS")
		)
		(fp_line
			(start -8.441182 -0.882904)
			(end -9.050274 -1.467104)
			(stroke
				(width 0.1)
				(type default)
			)
			(layer "B.SilkS")
		)
		(fp_line
			(start -8.441182 -0.882904)
			(end -8.50138 -0.882904)
			(stroke
				(width 0.1)
				(type default)
			)
			(layer "B.SilkS")
		)
		(fp_line
			(start -8.441182 -0.882904)
			(end -8.50138 -0.882904)
			(stroke
				(width 0.1)
				(type default)
			)
			(layer "B.SilkS")
		)
		(fp_line
			(start -8.43788 -4.400296)
			(end -8.425942 -4.3307)
			(stroke
				(width 0.1)
				(type default)
			)
			(layer "B.SilkS")
		)
		(fp_line
			(start -8.43788 -4.400296)
			(end -8.425942 -4.3307)
			(stroke
				(width 0.1)
				(type default)
			)
			(layer "B.SilkS")
		)
		(fp_line
			(start -8.425942 -4.3307)
			(end -8.41375 -4.261612)
			(stroke
				(width 0.1)
				(type default)
			)
			(layer "B.SilkS")
		)
		(fp_line
			(start -8.425942 -4.3307)
			(end -8.41375 -4.261612)
			(stroke
				(width 0.1)
				(type default)
			)
			(layer "B.SilkS")
		)
		(fp_line
			(start -8.41375 -4.261612)
			(end -8.401558 -4.19227)
			(stroke
				(width 0.1)
				(type default)
			)
			(layer "B.SilkS")
		)
		(fp_line
			(start -8.41375 -4.261612)
			(end -8.401558 -4.19227)
			(stroke
				(width 0.1)
				(type default)
			)
			(layer "B.SilkS")
		)
		(fp_line
			(start -8.401558 -4.19227)
			(end -8.389366 -4.122674)
			(stroke
				(width 0.1)
				(type default)
			)
			(layer "B.SilkS")
		)
		(fp_line
			(start -8.401558 -4.19227)
			(end -8.389366 -4.122674)
			(stroke
				(width 0.1)
				(type default)
			)
			(layer "B.SilkS")
		)
		(fp_line
			(start -8.389366 -4.122674)
			(end -8.377174 -4.053332)
			(stroke
				(width 0.1)
				(type default)
			)
			(layer "B.SilkS")
		)
		(fp_line
			(start -8.389366 -4.122674)
			(end -8.377174 -4.053332)
			(stroke
				(width 0.1)
				(type default)
			)
			(layer "B.SilkS")
		)
		(fp_line
			(start -8.381238 -0.882904)
			(end -9.062466 -1.5367)
			(stroke
				(width 0.1)
				(type default)
			)
			(layer "B.SilkS")
		)
		(fp_line
			(start -8.381238 -0.882904)
			(end -9.062466 -1.5367)
			(stroke
				(width 0.1)
				(type default)
			)
			(layer "B.SilkS")
		)
		(fp_line
			(start -8.381238 -0.882904)
			(end -8.441182 -0.882904)
			(stroke
				(width 0.1)
				(type default)
			)
			(layer "B.SilkS")
		)
		(fp_line
			(start -8.381238 -0.882904)
			(end -8.441182 -0.882904)
			(stroke
				(width 0.1)
				(type default)
			)
			(layer "B.SilkS")
		)
		(fp_line
			(start -8.377174 -4.053332)
			(end -8.365236 -3.98399)
			(stroke
				(width 0.1)
				(type default)
			)
			(layer "B.SilkS")
		)
		(fp_line
			(start -8.377174 -4.053332)
			(end -8.365236 -3.98399)
			(stroke
				(width 0.1)
				(type default)
			)
			(layer "B.SilkS")
		)
		(fp_line
			(start -8.365236 -3.98399)
			(end -8.35279 -3.914648)
			(stroke
				(width 0.1)
				(type default)
			)
			(layer "B.SilkS")
		)
		(fp_line
			(start -8.365236 -3.98399)
			(end -8.35279 -3.914648)
			(stroke
				(width 0.1)
				(type default)
			)
			(layer "B.SilkS")
		)
		(fp_line
			(start -8.35279 -3.914648)
			(end -8.340852 -3.845306)
			(stroke
				(width 0.1)
				(type default)
			)
			(layer "B.SilkS")
		)
		(fp_line
			(start -8.35279 -3.914648)
			(end -8.340852 -3.845306)
			(stroke
				(width 0.1)
				(type default)
			)
			(layer "B.SilkS")
		)
		(fp_line
			(start -8.340852 -3.845306)
			(end -8.32866 -3.77571)
			(stroke
				(width 0.1)
				(type default)
			)
			(layer "B.SilkS")
		)
		(fp_line
			(start -8.340852 -3.845306)
			(end -8.32866 -3.77571)
			(stroke
				(width 0.1)
				(type default)
			)
			(layer "B.SilkS")
		)
		(fp_line
			(start -8.32866 -3.77571)
			(end -8.316468 -3.706368)
			(stroke
				(width 0.1)
				(type default)
			)
			(layer "B.SilkS")
		)
		(fp_line
			(start -8.32866 -3.77571)
			(end -8.316468 -3.706368)
			(stroke
				(width 0.1)
				(type default)
			)
			(layer "B.SilkS")
		)
		(fp_line
			(start -8.320786 -0.882904)
			(end -9.074912 -1.606296)
			(stroke
				(width 0.1)
				(type default)
			)
			(layer "B.SilkS")
		)
		(fp_line
			(start -8.320786 -0.882904)
			(end -9.074912 -1.606296)
			(stroke
				(width 0.1)
				(type default)
			)
			(layer "B.SilkS")
		)
		(fp_line
			(start -8.320786 -0.882904)
			(end -8.381238 -0.882904)
			(stroke
				(width 0.1)
				(type default)
			)
			(layer "B.SilkS")
		)
		(fp_line
			(start -8.320786 -0.882904)
			(end -8.381238 -0.882904)
			(stroke
				(width 0.1)
				(type default)
			)
			(layer "B.SilkS")
		)
		(fp_line
			(start -8.316468 -3.706368)
			(end -8.304276 -3.63728)
			(stroke
				(width 0.1)
				(type default)
			)
			(layer "B.SilkS")
		)
		(fp_line
			(start -8.316468 -3.706368)
			(end -8.304276 -3.63728)
			(stroke
				(width 0.1)
				(type default)
			)
			(layer "B.SilkS")
		)
		(fp_line
			(start -8.304276 -3.63728)
			(end -8.292084 -3.567684)
			(stroke
				(width 0.1)
				(type default)
			)
			(layer "B.SilkS")
		)
		(fp_line
			(start -8.304276 -3.63728)
			(end -8.292084 -3.567684)
			(stroke
				(width 0.1)
				(type default)
			)
			(layer "B.SilkS")
		)
		(fp_line
			(start -8.292084 -3.567684)
			(end -8.279892 -3.498342)
			(stroke
				(width 0.1)
				(type default)
			)
			(layer "B.SilkS")
		)
		(fp_line
			(start -8.292084 -3.567684)
			(end -8.279892 -3.498342)
			(stroke
				(width 0.1)
				(type default)
			)
			(layer "B.SilkS")
		)
		(fp_line
			(start -8.279892 -3.498342)
			(end -8.2677 -3.429)
			(stroke
				(width 0.1)
				(type default)
			)
			(layer "B.SilkS")
		)
		(fp_line
			(start -8.279892 -3.498342)
			(end -8.2677 -3.429)
			(stroke
				(width 0.1)
				(type default)
			)
			(layer "B.SilkS")
		)
		(fp_line
			(start -8.2677 -3.429)
			(end -8.255762 -3.359658)
			(stroke
				(width 0.1)
				(type default)
			)
			(layer "B.SilkS")
		)
		(fp_line
			(start -8.2677 -3.429)
			(end -8.255762 -3.359658)
			(stroke
				(width 0.1)
				(type default)
			)
			(layer "B.SilkS")
		)
		(fp_line
			(start -8.260842 -0.882904)
			(end -9.087104 -1.675384)
			(stroke
				(width 0.1)
				(type default)
			)
			(layer "B.SilkS")
		)
		(fp_line
			(start -8.260842 -0.882904)
			(end -9.087104 -1.675384)
			(stroke
				(width 0.1)
				(type default)
			)
			(layer "B.SilkS")
		)
		(fp_line
			(start -8.260842 -0.882904)
			(end -8.320786 -0.882904)
			(stroke
				(width 0.1)
				(type default)
			)
			(layer "B.SilkS")
		)
		(fp_line
			(start -8.260842 -0.882904)
			(end -8.320786 -0.882904)
			(stroke
				(width 0.1)
				(type default)
			)
			(layer "B.SilkS")
		)
		(fp_line
			(start -8.255762 -3.359658)
			(end -8.24357 -3.290316)
			(stroke
				(width 0.1)
				(type default)
			)
			(layer "B.SilkS")
		)
		(fp_line
			(start -8.255762 -3.359658)
			(end -8.24357 -3.290316)
			(stroke
				(width 0.1)
				(type default)
			)
			(layer "B.SilkS")
		)
		(fp_line
			(start -8.24357 -3.290316)
			(end -8.231378 -3.22072)
			(stroke
				(width 0.1)
				(type default)
			)
			(layer "B.SilkS")
		)
		(fp_line
			(start -8.24357 -3.290316)
			(end -8.231378 -3.22072)
			(stroke
				(width 0.1)
				(type default)
			)
			(layer "B.SilkS")
		)
		(fp_line
			(start -8.231378 -3.22072)
			(end -8.219186 -3.151378)
			(stroke
				(width 0.1)
				(type default)
			)
			(layer "B.SilkS")
		)
		(fp_line
			(start -8.231378 -3.22072)
			(end -8.219186 -3.151378)
			(stroke
				(width 0.1)
				(type default)
			)
			(layer "B.SilkS")
		)
		(fp_line
			(start -8.219186 -3.151378)
			(end -8.206994 -3.08229)
			(stroke
				(width 0.1)
				(type default)
			)
			(layer "B.SilkS")
		)
		(fp_line
			(start -8.219186 -3.151378)
			(end -8.206994 -3.08229)
			(stroke
				(width 0.1)
				(type default)
			)
			(layer "B.SilkS")
		)
		(fp_line
			(start -8.206994 -3.08229)
			(end -8.194802 -3.012694)
			(stroke
				(width 0.1)
				(type default)
			)
			(layer "B.SilkS")
		)
		(fp_line
			(start -8.206994 -3.08229)
			(end -8.194802 -3.012694)
			(stroke
				(width 0.1)
				(type default)
			)
			(layer "B.SilkS")
		)
		(fp_line
			(start -8.200644 -0.882904)
			(end -9.099042 -1.744726)
			(stroke
				(width 0.1)
				(type default)
			)
			(layer "B.SilkS")
		)
		(fp_line
			(start -8.200644 -0.882904)
			(end -9.099042 -1.744726)
			(stroke
				(width 0.1)
				(type default)
			)
			(layer "B.SilkS")
		)
		(fp_line
			(start -8.200644 -0.882904)
			(end -8.260842 -0.882904)
			(stroke
				(width 0.1)
				(type default)
			)
			(layer "B.SilkS")
		)
		(fp_line
			(start -8.200644 -0.882904)
			(end -8.260842 -0.882904)
			(stroke
				(width 0.1)
				(type default)
			)
			(layer "B.SilkS")
		)
		(fp_line
			(start -8.194802 -3.012694)
			(end -8.18261 -2.943352)
			(stroke
				(width 0.1)
				(type default)
			)
			(layer "B.SilkS")
		)
		(fp_line
			(start -8.194802 -3.012694)
			(end -8.18261 -2.943352)
			(stroke
				(width 0.1)
				(type default)
			)
			(layer "B.SilkS")
		)
		(fp_line
			(start -8.18261 -2.943352)
			(end -8.170418 -2.87401)
			(stroke
				(width 0.1)
				(type default)
			)
			(layer "B.SilkS")
		)
		(fp_line
			(start -8.18261 -2.943352)
			(end -8.170418 -2.87401)
			(stroke
				(width 0.1)
				(type default)
			)
			(layer "B.SilkS")
		)
		(fp_line
			(start -8.140446 -0.882904)
			(end -9.111234 -1.814322)
			(stroke
				(width 0.1)
				(type default)
			)
			(layer "B.SilkS")
		)
		(fp_line
			(start -8.140446 -0.882904)
			(end -9.111234 -1.814322)
			(stroke
				(width 0.1)
				(type default)
			)
			(layer "B.SilkS")
		)
		(fp_line
			(start -8.140446 -0.882904)
			(end -8.200644 -0.882904)
			(stroke
				(width 0.1)
				(type default)
			)
			(layer "B.SilkS")
		)
		(fp_line
			(start -8.140446 -0.882904)
			(end -8.200644 -0.882904)
			(stroke
				(width 0.1)
				(type default)
			)
			(layer "B.SilkS")
		)
		(fp_line
			(start -8.080248 -0.882904)
			(end -9.12368 -1.883664)
			(stroke
				(width 0.1)
				(type default)
			)
			(layer "B.SilkS")
		)
		(fp_line
			(start -8.080248 -0.882904)
			(end -9.12368 -1.883664)
			(stroke
				(width 0.1)
				(type default)
			)
			(layer "B.SilkS")
		)
		(fp_line
			(start -8.080248 -0.882904)
			(end -8.140446 -0.882904)
			(stroke
				(width 0.1)
				(type default)
			)
			(layer "B.SilkS")
		)
		(fp_line
			(start -8.080248 -0.882904)
			(end -8.140446 -0.882904)
			(stroke
				(width 0.1)
				(type default)
			)
			(layer "B.SilkS")
		)
		(fp_line
			(start -8.078724 -2.497328)
			(end -9.465056 -3.827526)
			(stroke
				(width 0.1)
				(type default)
			)
			(layer "B.SilkS")
		)
		(fp_line
			(start -8.078724 -2.497328)
			(end -9.465056 -3.827526)
			(stroke
				(width 0.1)
				(type default)
			)
			(layer "B.SilkS")
		)
		(fp_line
			(start -8.04799 -2.410206)
			(end -9.452864 -3.75793)
			(stroke
				(width 0.1)
				(type default)
			)
			(layer "B.SilkS")
		)
		(fp_line
			(start -8.04799 -2.410206)
			(end -9.452864 -3.75793)
			(stroke
				(width 0.1)
				(type default)
			)
			(layer "B.SilkS")
		)
		(fp_line
			(start -8.02005 -0.882904)
			(end -9.135872 -1.953006)
			(stroke
				(width 0.1)
				(type default)
			)
			(layer "B.SilkS")
		)
		(fp_line
			(start -8.02005 -0.882904)
			(end -9.135872 -1.953006)
			(stroke
				(width 0.1)
				(type default)
			)
			(layer "B.SilkS")
		)
		(fp_line
			(start -8.02005 -0.882904)
			(end -8.080248 -0.882904)
			(stroke
				(width 0.1)
				(type default)
			)
			(layer "B.SilkS")
		)
		(fp_line
			(start -8.02005 -0.882904)
			(end -8.080248 -0.882904)
			(stroke
				(width 0.1)
				(type default)
			)
			(layer "B.SilkS")
		)
		(fp_line
			(start -8.002778 -2.30886)
			(end -9.440672 -3.688334)
			(stroke
				(width 0.1)
				(type default)
			)
			(layer "B.SilkS")
		)
		(fp_line
			(start -8.002778 -2.30886)
			(end -9.440672 -3.688334)
			(stroke
				(width 0.1)
				(type default)
			)
			(layer "B.SilkS")
		)
		(fp_line
			(start -7.960106 -0.882904)
			(end -9.148064 -2.022602)
			(stroke
				(width 0.1)
				(type default)
			)
			(layer "B.SilkS")
		)
		(fp_line
			(start -7.960106 -0.882904)
			(end -9.148064 -2.022602)
			(stroke
				(width 0.1)
				(type default)
			)
			(layer "B.SilkS")
		)
		(fp_line
			(start -7.960106 -0.882904)
			(end -8.02005 -0.882904)
			(stroke
				(width 0.1)
				(type default)
			)
			(layer "B.SilkS")
		)
		(fp_line
			(start -7.960106 -0.882904)
			(end -8.02005 -0.882904)
			(stroke
				(width 0.1)
				(type default)
			)
			(layer "B.SilkS")
		)
		(fp_line
			(start -7.936484 -2.187702)
			(end -9.42848 -3.618992)
			(stroke
				(width 0.1)
				(type default)
			)
			(layer "B.SilkS")
		)
		(fp_line
			(start -7.936484 -2.187702)
			(end -9.42848 -3.618992)
			(stroke
				(width 0.1)
				(type default)
			)
			(layer "B.SilkS")
		)
		(fp_line
			(start -7.899908 -0.882904)
			(end -9.160002 -2.091944)
			(stroke
				(width 0.1)
				(type default)
			)
			(layer "B.SilkS")
		)
		(fp_line
			(start -7.899908 -0.882904)
			(end -9.160002 -2.091944)
			(stroke
				(width 0.1)
				(type default)
			)
			(layer "B.SilkS")
		)
		(fp_line
			(start -7.899908 -0.882904)
			(end -7.960106 -0.882904)
			(stroke
				(width 0.1)
				(type default)
			)
			(layer "B.SilkS")
		)
		(fp_line
			(start -7.899908 -0.882904)
			(end -7.960106 -0.882904)
			(stroke
				(width 0.1)
				(type default)
			)
			(layer "B.SilkS")
		)
		(fp_line
			(start -7.865364 -1.138428)
			(end -9.220962 -2.438908)
			(stroke
				(width 0.1)
				(type default)
			)
			(layer "B.SilkS")
		)
		(fp_line
			(start -7.865364 -1.138428)
			(end -9.220962 -2.438908)
			(stroke
				(width 0.1)
				(type default)
			)
			(layer "B.SilkS")
		)
		(fp_line
			(start -7.865364 -1.138428)
			(end -7.852918 -1.068832)
			(stroke
				(width 0.1)
				(type default)
			)
			(layer "B.SilkS")
		)
		(fp_line
			(start -7.865364 -1.138428)
			(end -7.852918 -1.068832)
			(stroke
				(width 0.1)
				(type default)
			)
			(layer "B.SilkS")
		)
		(fp_line
			(start -7.852918 -1.068832)
			(end -9.209024 -2.369566)
			(stroke
				(width 0.1)
				(type default)
			)
			(layer "B.SilkS")
		)
		(fp_line
			(start -7.852918 -1.068832)
			(end -9.209024 -2.369566)
			(stroke
				(width 0.1)
				(type default)
			)
			(layer "B.SilkS")
		)
		(fp_line
			(start -7.852918 -1.068832)
			(end -7.84098 -0.999744)
			(stroke
				(width 0.1)
				(type default)
			)
			(layer "B.SilkS")
		)
		(fp_line
			(start -7.852918 -1.068832)
			(end -7.84098 -0.999744)
			(stroke
				(width 0.1)
				(type default)
			)
			(layer "B.SilkS")
		)
		(fp_line
			(start -7.84098 -0.999744)
			(end -9.196832 -2.300224)
			(stroke
				(width 0.1)
				(type default)
			)
			(layer "B.SilkS")
		)
		(fp_line
			(start -7.84098 -0.999744)
			(end -9.196832 -2.300224)
			(stroke
				(width 0.1)
				(type default)
			)
			(layer "B.SilkS")
		)
		(fp_line
			(start -7.84098 -0.999744)
			(end -7.828788 -0.930148)
			(stroke
				(width 0.1)
				(type default)
			)
			(layer "B.SilkS")
		)
		(fp_line
			(start -7.84098 -0.999744)
			(end -7.828788 -0.930148)
			(stroke
				(width 0.1)
				(type default)
			)
			(layer "B.SilkS")
		)
		(fp_line
			(start -7.839456 -0.882904)
			(end -9.172194 -2.161286)
			(stroke
				(width 0.1)
				(type default)
			)
			(layer "B.SilkS")
		)
		(fp_line
			(start -7.839456 -0.882904)
			(end -9.172194 -2.161286)
			(stroke
				(width 0.1)
				(type default)
			)
			(layer "B.SilkS")
		)
		(fp_line
			(start -7.839456 -0.882904)
			(end -7.899908 -0.882904)
			(stroke
				(width 0.1)
				(type default)
			)
			(layer "B.SilkS")
		)
		(fp_line
			(start -7.839456 -0.882904)
			(end -7.899908 -0.882904)
			(stroke
				(width 0.1)
				(type default)
			)
			(layer "B.SilkS")
		)
		(fp_line
			(start -7.828788 -0.930148)
			(end -9.18464 -2.230882)
			(stroke
				(width 0.1)
				(type default)
			)
			(layer "B.SilkS")
		)
		(fp_line
			(start -7.828788 -0.930148)
			(end -9.18464 -2.230882)
			(stroke
				(width 0.1)
				(type default)
			)
			(layer "B.SilkS")
		)
		(fp_line
			(start -7.828788 -0.930148)
			(end -7.82066 -0.882904)
			(stroke
				(width 0.1)
				(type default)
			)
			(layer "B.SilkS")
		)
		(fp_line
			(start -7.828788 -0.930148)
			(end -7.82066 -0.882904)
			(stroke
				(width 0.1)
				(type default)
			)
			(layer "B.SilkS")
		)
		(fp_line
			(start -7.82066 -0.882904)
			(end -7.839456 -0.882904)
			(stroke
				(width 0.1)
				(type default)
			)
			(layer "B.SilkS")
		)
		(fp_line
			(start -7.82066 -0.882904)
			(end -7.839456 -0.882904)
			(stroke
				(width 0.1)
				(type default)
			)
			(layer "B.SilkS")
		)
		(fp_line
			(start -7.737348 -1.07315)
			(end -9.233408 -2.508504)
			(stroke
				(width 0.1)
				(type default)
			)
			(layer "B.SilkS")
		)
		(fp_line
			(start -7.737348 -1.07315)
			(end -9.233408 -2.508504)
			(stroke
				(width 0.1)
				(type default)
			)
			(layer "B.SilkS")
		)
		(fp_line
			(start -7.583678 -0.983488)
			(end -9.2456 -2.577592)
			(stroke
				(width 0.1)
				(type default)
			)
			(layer "B.SilkS")
		)
		(fp_line
			(start -7.583678 -0.983488)
			(end -9.2456 -2.577592)
			(stroke
				(width 0.1)
				(type default)
			)
			(layer "B.SilkS")
		)
		(fp_line
			(start -7.464298 -0.926846)
			(end -9.257792 -2.647188)
			(stroke
				(width 0.1)
				(type default)
			)
			(layer "B.SilkS")
		)
		(fp_line
			(start -7.464298 -0.926846)
			(end -9.257792 -2.647188)
			(stroke
				(width 0.1)
				(type default)
			)
			(layer "B.SilkS")
		)
		(fp_line
			(start -7.366 -0.890016)
			(end -9.269984 -2.716784)
			(stroke
				(width 0.1)
				(type default)
			)
			(layer "B.SilkS")
		)
		(fp_line
			(start -7.366 -0.890016)
			(end -9.269984 -2.716784)
			(stroke
				(width 0.1)
				(type default)
			)
			(layer "B.SilkS")
		)
		(fp_line
			(start -7.281418 -0.866648)
			(end -9.281922 -2.786126)
			(stroke
				(width 0.1)
				(type default)
			)
			(layer "B.SilkS")
		)
		(fp_line
			(start -7.281418 -0.866648)
			(end -9.281922 -2.786126)
			(stroke
				(width 0.1)
				(type default)
			)
			(layer "B.SilkS")
		)
		(fp_line
			(start -7.196582 -0.84328)
			(end -9.294368 -2.855468)
			(stroke
				(width 0.1)
				(type default)
			)
			(layer "B.SilkS")
		)
		(fp_line
			(start -7.196582 -0.84328)
			(end -9.294368 -2.855468)
			(stroke
				(width 0.1)
				(type default)
			)
			(layer "B.SilkS")
		)
		(fp_line
			(start -7.11454 -0.822198)
			(end -9.30656 -2.925064)
			(stroke
				(width 0.1)
				(type default)
			)
			(layer "B.SilkS")
		)
		(fp_line
			(start -7.11454 -0.822198)
			(end -9.30656 -2.925064)
			(stroke
				(width 0.1)
				(type default)
			)
			(layer "B.SilkS")
		)
		(fp_line
			(start -7.110984 -5.171694)
			(end -7.07644 -5.171694)
			(stroke
				(width 0.1)
				(type default)
			)
			(layer "B.SilkS")
		)
		(fp_line
			(start -7.110984 -5.171694)
			(end -7.07644 -5.171694)
			(stroke
				(width 0.1)
				(type default)
			)
			(layer "B.SilkS")
		)
		(fp_line
			(start -7.10565 -5.141976)
			(end -7.110984 -5.171694)
			(stroke
				(width 0.1)
				(type default)
			)
			(layer "B.SilkS")
		)
		(fp_line
			(start -7.10565 -5.141976)
			(end -7.110984 -5.171694)
			(stroke
				(width 0.1)
				(type default)
			)
			(layer "B.SilkS")
		)
		(fp_line
			(start -7.10565 -5.141976)
			(end -5.751068 -3.842512)
			(stroke
				(width 0.1)
				(type default)
			)
			(layer "B.SilkS")
		)
		(fp_line
			(start -7.10565 -5.141976)
			(end -5.751068 -3.842512)
			(stroke
				(width 0.1)
				(type default)
			)
			(layer "B.SilkS")
		)
		(fp_line
			(start -7.093458 -5.072888)
			(end -7.10565 -5.141976)
			(stroke
				(width 0.1)
				(type default)
			)
			(layer "B.SilkS")
		)
		(fp_line
			(start -7.093458 -5.072888)
			(end -7.10565 -5.141976)
			(stroke
				(width 0.1)
				(type default)
			)
			(layer "B.SilkS")
		)
		(fp_line
			(start -7.093458 -5.072888)
			(end -5.738876 -3.772916)
			(stroke
				(width 0.1)
				(type default)
			)
			(layer "B.SilkS")
		)
		(fp_line
			(start -7.093458 -5.072888)
			(end -5.738876 -3.772916)
			(stroke
				(width 0.1)
				(type default)
			)
			(layer "B.SilkS")
		)
		(fp_line
			(start -7.081266 -5.003292)
			(end -7.093458 -5.072888)
			(stroke
				(width 0.1)
				(type default)
			)
			(layer "B.SilkS")
		)
		(fp_line
			(start -7.081266 -5.003292)
			(end -7.093458 -5.072888)
			(stroke
				(width 0.1)
				(type default)
			)
			(layer "B.SilkS")
		)
		(fp_line
			(start -7.081266 -5.003292)
			(end -5.72643 -3.703828)
			(stroke
				(width 0.1)
				(type default)
			)
			(layer "B.SilkS")
		)
		(fp_line
			(start -7.081266 -5.003292)
			(end -5.72643 -3.703828)
			(stroke
				(width 0.1)
				(type default)
			)
			(layer "B.SilkS")
		)
		(fp_line
			(start -7.07644 -5.171694)
			(end -7.016242 -5.171694)
			(stroke
				(width 0.1)
				(type default)
			)
			(layer "B.SilkS")
		)
		(fp_line
			(start -7.07644 -5.171694)
			(end -7.016242 -5.171694)
			(stroke
				(width 0.1)
				(type default)
			)
			(layer "B.SilkS")
		)
		(fp_line
			(start -7.07644 -5.171694)
			(end -5.763006 -3.911854)
			(stroke
				(width 0.1)
				(type default)
			)
			(layer "B.SilkS")
		)
		(fp_line
			(start -7.07644 -5.171694)
			(end -5.763006 -3.911854)
			(stroke
				(width 0.1)
				(type default)
			)
			(layer "B.SilkS")
		)
		(fp_line
			(start -7.069328 -4.93395)
			(end -7.081266 -5.003292)
			(stroke
				(width 0.1)
				(type default)
			)
			(layer "B.SilkS")
		)
		(fp_line
			(start -7.069328 -4.93395)
			(end -7.081266 -5.003292)
			(stroke
				(width 0.1)
				(type default)
			)
			(layer "B.SilkS")
		)
		(fp_line
			(start -7.069328 -4.93395)
			(end -5.714238 -3.634232)
			(stroke
				(width 0.1)
				(type default)
			)
			(layer "B.SilkS")
		)
		(fp_line
			(start -7.069328 -4.93395)
			(end -5.714238 -3.634232)
			(stroke
				(width 0.1)
				(type default)
			)
			(layer "B.SilkS")
		)
		(fp_line
			(start -7.057136 -4.864354)
			(end -7.069328 -4.93395)
			(stroke
				(width 0.1)
				(type default)
			)
			(layer "B.SilkS")
		)
		(fp_line
			(start -7.057136 -4.864354)
			(end -7.069328 -4.93395)
			(stroke
				(width 0.1)
				(type default)
			)
			(layer "B.SilkS")
		)
		(fp_line
			(start -7.057136 -4.864354)
			(end -5.7023 -3.56489)
			(stroke
				(width 0.1)
				(type default)
			)
			(layer "B.SilkS")
		)
		(fp_line
			(start -7.057136 -4.864354)
			(end -5.7023 -3.56489)
			(stroke
				(width 0.1)
				(type default)
			)
			(layer "B.SilkS")
		)
		(fp_line
			(start -7.047992 -0.816102)
			(end -9.318752 -2.994406)
			(stroke
				(width 0.1)
				(type default)
			)
			(layer "B.SilkS")
		)
		(fp_line
			(start -7.047992 -0.816102)
			(end -9.318752 -2.994406)
			(stroke
				(width 0.1)
				(type default)
			)
			(layer "B.SilkS")
		)
		(fp_line
			(start -7.04469 -4.795012)
			(end -7.057136 -4.864354)
			(stroke
				(width 0.1)
				(type default)
			)
			(layer "B.SilkS")
		)
		(fp_line
			(start -7.04469 -4.795012)
			(end -7.057136 -4.864354)
			(stroke
				(width 0.1)
				(type default)
			)
			(layer "B.SilkS")
		)
		(fp_line
			(start -7.04469 -4.795012)
			(end -5.690108 -3.495548)
			(stroke
				(width 0.1)
				(type default)
			)
			(layer "B.SilkS")
		)
		(fp_line
			(start -7.04469 -4.795012)
			(end -5.690108 -3.495548)
			(stroke
				(width 0.1)
				(type default)
			)
			(layer "B.SilkS")
		)
		(fp_line
			(start -7.032752 -4.725924)
			(end -7.04469 -4.795012)
			(stroke
				(width 0.1)
				(type default)
			)
			(layer "B.SilkS")
		)
		(fp_line
			(start -7.032752 -4.725924)
			(end -7.04469 -4.795012)
			(stroke
				(width 0.1)
				(type default)
			)
			(layer "B.SilkS")
		)
		(fp_line
			(start -7.032752 -4.725924)
			(end -5.677662 -3.425952)
			(stroke
				(width 0.1)
				(type default)
			)
			(layer "B.SilkS")
		)
		(fp_line
			(start -7.032752 -4.725924)
			(end -5.677662 -3.425952)
			(stroke
				(width 0.1)
				(type default)
			)
			(layer "B.SilkS")
		)
		(fp_line
			(start -7.02056 -4.656328)
			(end -7.032752 -4.725924)
			(stroke
				(width 0.1)
				(type default)
			)
			(layer "B.SilkS")
		)
		(fp_line
			(start -7.02056 -4.656328)
			(end -7.032752 -4.725924)
			(stroke
				(width 0.1)
				(type default)
			)
			(layer "B.SilkS")
		)
		(fp_line
			(start -7.02056 -4.656328)
			(end -5.665724 -3.35661)
			(stroke
				(width 0.1)
				(type default)
			)
			(layer "B.SilkS")
		)
		(fp_line
			(start -7.02056 -4.656328)
			(end -5.665724 -3.35661)
			(stroke
				(width 0.1)
				(type default)
			)
			(layer "B.SilkS")
		)
		(fp_line
			(start -7.016242 -5.171694)
			(end -6.956044 -5.171694)
			(stroke
				(width 0.1)
				(type default)
			)
			(layer "B.SilkS")
		)
		(fp_line
			(start -7.016242 -5.171694)
			(end -6.956044 -5.171694)
			(stroke
				(width 0.1)
				(type default)
			)
			(layer "B.SilkS")
		)
		(fp_line
			(start -7.016242 -5.171694)
			(end -5.775198 -3.98145)
			(stroke
				(width 0.1)
				(type default)
			)
			(layer "B.SilkS")
		)
		(fp_line
			(start -7.016242 -5.171694)
			(end -5.775198 -3.98145)
			(stroke
				(width 0.1)
				(type default)
			)
			(layer "B.SilkS")
		)
		(fp_line
			(start -7.008368 -4.586986)
			(end -7.02056 -4.656328)
			(stroke
				(width 0.1)
				(type default)
			)
			(layer "B.SilkS")
		)
		(fp_line
			(start -7.008368 -4.586986)
			(end -7.02056 -4.656328)
			(stroke
				(width 0.1)
				(type default)
			)
			(layer "B.SilkS")
		)
		(fp_line
			(start -7.008368 -4.586986)
			(end -5.653532 -3.287268)
			(stroke
				(width 0.1)
				(type default)
			)
			(layer "B.SilkS")
		)
		(fp_line
			(start -7.008368 -4.586986)
			(end -5.653532 -3.287268)
			(stroke
				(width 0.1)
				(type default)
			)
			(layer "B.SilkS")
		)
		(fp_line
			(start -6.996176 -4.51739)
			(end -7.008368 -4.586986)
			(stroke
				(width 0.1)
				(type default)
			)
			(layer "B.SilkS")
		)
		(fp_line
			(start -6.996176 -4.51739)
			(end -7.008368 -4.586986)
			(stroke
				(width 0.1)
				(type default)
			)
			(layer "B.SilkS")
		)
		(fp_line
			(start -6.996176 -4.51739)
			(end -5.64134 -3.217926)
			(stroke
				(width 0.1)
				(type default)
			)
			(layer "B.SilkS")
		)
		(fp_line
			(start -6.996176 -4.51739)
			(end -5.64134 -3.217926)
			(stroke
				(width 0.1)
				(type default)
			)
			(layer "B.SilkS")
		)
		(fp_line
			(start -6.983984 -4.448302)
			(end -6.996176 -4.51739)
			(stroke
				(width 0.1)
				(type default)
			)
			(layer "B.SilkS")
		)
		(fp_line
			(start -6.983984 -4.448302)
			(end -6.996176 -4.51739)
			(stroke
				(width 0.1)
				(type default)
			)
			(layer "B.SilkS")
		)
		(fp_line
			(start -6.983984 -4.448302)
			(end -5.629148 -3.148584)
			(stroke
				(width 0.1)
				(type default)
			)
			(layer "B.SilkS")
		)
		(fp_line
			(start -6.983984 -4.448302)
			(end -5.629148 -3.148584)
			(stroke
				(width 0.1)
				(type default)
			)
			(layer "B.SilkS")
		)
		(fp_line
			(start -6.981444 -0.809752)
			(end -9.330944 -3.063748)
			(stroke
				(width 0.1)
				(type default)
			)
			(layer "B.SilkS")
		)
		(fp_line
			(start -6.981444 -0.809752)
			(end -9.330944 -3.063748)
			(stroke
				(width 0.1)
				(type default)
			)
			(layer "B.SilkS")
		)
		(fp_line
			(start -6.971792 -4.378706)
			(end -6.983984 -4.448302)
			(stroke
				(width 0.1)
				(type default)
			)
			(layer "B.SilkS")
		)
		(fp_line
			(start -6.971792 -4.378706)
			(end -6.983984 -4.448302)
			(stroke
				(width 0.1)
				(type default)
			)
			(layer "B.SilkS")
		)
		(fp_line
			(start -6.971792 -4.378706)
			(end -5.616956 -3.079242)
			(stroke
				(width 0.1)
				(type default)
			)
			(layer "B.SilkS")
		)
		(fp_line
			(start -6.971792 -4.378706)
			(end -5.616956 -3.079242)
			(stroke
				(width 0.1)
				(type default)
			)
			(layer "B.SilkS")
		)
		(fp_line
			(start -6.9596 -4.309364)
			(end -6.971792 -4.378706)
			(stroke
				(width 0.1)
				(type default)
			)
			(layer "B.SilkS")
		)
		(fp_line
			(start -6.9596 -4.309364)
			(end -6.971792 -4.378706)
			(stroke
				(width 0.1)
				(type default)
			)
			(layer "B.SilkS")
		)
		(fp_line
			(start -6.9596 -4.309364)
			(end -5.604764 -3.009646)
			(stroke
				(width 0.1)
				(type default)
			)
			(layer "B.SilkS")
		)
		(fp_line
			(start -6.9596 -4.309364)
			(end -5.604764 -3.009646)
			(stroke
				(width 0.1)
				(type default)
			)
			(layer "B.SilkS")
		)
		(fp_line
			(start -6.956044 -5.171694)
			(end -6.895846 -5.171694)
			(stroke
				(width 0.1)
				(type default)
			)
			(layer "B.SilkS")
		)
		(fp_line
			(start -6.956044 -5.171694)
			(end -6.895846 -5.171694)
			(stroke
				(width 0.1)
				(type default)
			)
			(layer "B.SilkS")
		)
		(fp_line
			(start -6.956044 -5.171694)
			(end -5.78739 -4.050538)
			(stroke
				(width 0.1)
				(type default)
			)
			(layer "B.SilkS")
		)
		(fp_line
			(start -6.956044 -5.171694)
			(end -5.78739 -4.050538)
			(stroke
				(width 0.1)
				(type default)
			)
			(layer "B.SilkS")
		)
		(fp_line
			(start -6.947408 -4.240022)
			(end -6.9596 -4.309364)
			(stroke
				(width 0.1)
				(type default)
			)
			(layer "B.SilkS")
		)
		(fp_line
			(start -6.947408 -4.240022)
			(end -6.9596 -4.309364)
			(stroke
				(width 0.1)
				(type default)
			)
			(layer "B.SilkS")
		)
		(fp_line
			(start -6.947408 -4.240022)
			(end -5.592572 -2.940304)
			(stroke
				(width 0.1)
				(type default)
			)
			(layer "B.SilkS")
		)
		(fp_line
			(start -6.947408 -4.240022)
			(end -5.592572 -2.940304)
			(stroke
				(width 0.1)
				(type default)
			)
			(layer "B.SilkS")
		)
		(fp_line
			(start -6.935216 -4.170426)
			(end -6.947408 -4.240022)
			(stroke
				(width 0.1)
				(type default)
			)
			(layer "B.SilkS")
		)
		(fp_line
			(start -6.935216 -4.170426)
			(end -6.947408 -4.240022)
			(stroke
				(width 0.1)
				(type default)
			)
			(layer "B.SilkS")
		)
		(fp_line
			(start -6.935216 -4.170426)
			(end -5.58038 -2.870962)
			(stroke
				(width 0.1)
				(type default)
			)
			(layer "B.SilkS")
		)
		(fp_line
			(start -6.935216 -4.170426)
			(end -5.58038 -2.870962)
			(stroke
				(width 0.1)
				(type default)
			)
			(layer "B.SilkS")
		)
		(fp_line
			(start -6.923024 -4.101084)
			(end -6.935216 -4.170426)
			(stroke
				(width 0.1)
				(type default)
			)
			(layer "B.SilkS")
		)
		(fp_line
			(start -6.923024 -4.101084)
			(end -6.935216 -4.170426)
			(stroke
				(width 0.1)
				(type default)
			)
			(layer "B.SilkS")
		)
		(fp_line
			(start -6.923024 -4.101084)
			(end -5.568188 -2.801366)
			(stroke
				(width 0.1)
				(type default)
			)
			(layer "B.SilkS")
		)
		(fp_line
			(start -6.923024 -4.101084)
			(end -5.568188 -2.801366)
			(stroke
				(width 0.1)
				(type default)
			)
			(layer "B.SilkS")
		)
		(fp_line
			(start -6.914896 -0.80391)
			(end -9.343136 -3.13309)
			(stroke
				(width 0.1)
				(type default)
			)
			(layer "B.SilkS")
		)
		(fp_line
			(start -6.914896 -0.80391)
			(end -9.343136 -3.13309)
			(stroke
				(width 0.1)
				(type default)
			)
			(layer "B.SilkS")
		)
		(fp_line
			(start -6.910832 -4.031742)
			(end -6.923024 -4.101084)
			(stroke
				(width 0.1)
				(type default)
			)
			(layer "B.SilkS")
		)
		(fp_line
			(start -6.910832 -4.031742)
			(end -6.923024 -4.101084)
			(stroke
				(width 0.1)
				(type default)
			)
			(layer "B.SilkS")
		)
		(fp_line
			(start -6.910832 -4.031742)
			(end -5.557266 -2.733294)
			(stroke
				(width 0.1)
				(type default)
			)
			(layer "B.SilkS")
		)
		(fp_line
			(start -6.910832 -4.031742)
			(end -5.557266 -2.733294)
			(stroke
				(width 0.1)
				(type default)
			)
			(layer "B.SilkS")
		)
		(fp_line
			(start -6.89864 -3.9624)
			(end -6.910832 -4.031742)
			(stroke
				(width 0.1)
				(type default)
			)
			(layer "B.SilkS")
		)
		(fp_line
			(start -6.89864 -3.9624)
			(end -6.910832 -4.031742)
			(stroke
				(width 0.1)
				(type default)
			)
			(layer "B.SilkS")
		)
		(fp_line
			(start -6.89864 -3.9624)
			(end -5.549392 -2.668016)
			(stroke
				(width 0.1)
				(type default)
			)
			(layer "B.SilkS")
		)
		(fp_line
			(start -6.89864 -3.9624)
			(end -5.549392 -2.668016)
			(stroke
				(width 0.1)
				(type default)
			)
			(layer "B.SilkS")
		)
		(fp_line
			(start -6.895846 -5.171694)
			(end -6.835648 -5.171694)
			(stroke
				(width 0.1)
				(type default)
			)
			(layer "B.SilkS")
		)
		(fp_line
			(start -6.895846 -5.171694)
			(end -6.835648 -5.171694)
			(stroke
				(width 0.1)
				(type default)
			)
			(layer "B.SilkS")
		)
		(fp_line
			(start -6.895846 -5.171694)
			(end -5.799582 -4.11988)
			(stroke
				(width 0.1)
				(type default)
			)
			(layer "B.SilkS")
		)
		(fp_line
			(start -6.895846 -5.171694)
			(end -5.799582 -4.11988)
			(stroke
				(width 0.1)
				(type default)
			)
			(layer "B.SilkS")
		)
		(fp_line
			(start -6.886448 -3.893058)
			(end -6.89864 -3.9624)
			(stroke
				(width 0.1)
				(type default)
			)
			(layer "B.SilkS")
		)
		(fp_line
			(start -6.886448 -3.893058)
			(end -6.89864 -3.9624)
			(stroke
				(width 0.1)
				(type default)
			)
			(layer "B.SilkS")
		)
		(fp_line
			(start -6.886448 -3.893058)
			(end -5.541264 -2.602738)
			(stroke
				(width 0.1)
				(type default)
			)
			(layer "B.SilkS")
		)
		(fp_line
			(start -6.886448 -3.893058)
			(end -5.541264 -2.602738)
			(stroke
				(width 0.1)
				(type default)
			)
			(layer "B.SilkS")
		)
		(fp_line
			(start -6.874256 -3.823716)
			(end -6.886448 -3.893058)
			(stroke
				(width 0.1)
				(type default)
			)
			(layer "B.SilkS")
		)
		(fp_line
			(start -6.874256 -3.823716)
			(end -6.886448 -3.893058)
			(stroke
				(width 0.1)
				(type default)
			)
			(layer "B.SilkS")
		)
		(fp_line
			(start -6.874256 -3.823716)
			(end -5.53339 -2.537206)
			(stroke
				(width 0.1)
				(type default)
			)
			(layer "B.SilkS")
		)
		(fp_line
			(start -6.874256 -3.823716)
			(end -5.53339 -2.537206)
			(stroke
				(width 0.1)
				(type default)
			)
			(layer "B.SilkS")
		)
		(fp_line
			(start -6.862318 -3.75412)
			(end -6.874256 -3.823716)
			(stroke
				(width 0.1)
				(type default)
			)
			(layer "B.SilkS")
		)
		(fp_line
			(start -6.862318 -3.75412)
			(end -6.874256 -3.823716)
			(stroke
				(width 0.1)
				(type default)
			)
			(layer "B.SilkS")
		)
		(fp_line
			(start -6.862318 -3.75412)
			(end -5.525516 -2.471928)
			(stroke
				(width 0.1)
				(type default)
			)
			(layer "B.SilkS")
		)
		(fp_line
			(start -6.862318 -3.75412)
			(end -5.525516 -2.471928)
			(stroke
				(width 0.1)
				(type default)
			)
			(layer "B.SilkS")
		)
		(fp_line
			(start -6.849872 -3.684778)
			(end -6.862318 -3.75412)
			(stroke
				(width 0.1)
				(type default)
			)
			(layer "B.SilkS")
		)
		(fp_line
			(start -6.849872 -3.684778)
			(end -6.862318 -3.75412)
			(stroke
				(width 0.1)
				(type default)
			)
			(layer "B.SilkS")
		)
		(fp_line
			(start -6.849872 -3.684778)
			(end -5.517642 -2.40665)
			(stroke
				(width 0.1)
				(type default)
			)
			(layer "B.SilkS")
		)
		(fp_line
			(start -6.849872 -3.684778)
			(end -5.517642 -2.40665)
			(stroke
				(width 0.1)
				(type default)
			)
			(layer "B.SilkS")
		)
		(fp_line
			(start -6.848348 -0.797814)
			(end -9.355328 -3.202432)
			(stroke
				(width 0.1)
				(type default)
			)
			(layer "B.SilkS")
		)
		(fp_line
			(start -6.848348 -0.797814)
			(end -9.355328 -3.202432)
			(stroke
				(width 0.1)
				(type default)
			)
			(layer "B.SilkS")
		)
		(fp_line
			(start -6.83768 -3.615436)
			(end -6.849872 -3.684778)
			(stroke
				(width 0.1)
				(type default)
			)
			(layer "B.SilkS")
		)
		(fp_line
			(start -6.83768 -3.615436)
			(end -6.849872 -3.684778)
			(stroke
				(width 0.1)
				(type default)
			)
			(layer "B.SilkS")
		)
		(fp_line
			(start -6.83768 -3.615436)
			(end -5.509514 -2.341372)
			(stroke
				(width 0.1)
				(type default)
			)
			(layer "B.SilkS")
		)
		(fp_line
			(start -6.83768 -3.615436)
			(end -5.509514 -2.341372)
			(stroke
				(width 0.1)
				(type default)
			)
			(layer "B.SilkS")
		)
		(fp_line
			(start -6.835648 -5.171694)
			(end -6.77545 -5.171694)
			(stroke
				(width 0.1)
				(type default)
			)
			(layer "B.SilkS")
		)
		(fp_line
			(start -6.835648 -5.171694)
			(end -6.77545 -5.171694)
			(stroke
				(width 0.1)
				(type default)
			)
			(layer "B.SilkS")
		)
		(fp_line
			(start -6.835648 -5.171694)
			(end -5.811774 -4.189476)
			(stroke
				(width 0.1)
				(type default)
			)
			(layer "B.SilkS")
		)
		(fp_line
			(start -6.835648 -5.171694)
			(end -5.811774 -4.189476)
			(stroke
				(width 0.1)
				(type default)
			)
			(layer "B.SilkS")
		)
		(fp_line
			(start -6.825488 -3.54584)
			(end -6.83768 -3.615436)
			(stroke
				(width 0.1)
				(type default)
			)
			(layer "B.SilkS")
		)
		(fp_line
			(start -6.825488 -3.54584)
			(end -6.83768 -3.615436)
			(stroke
				(width 0.1)
				(type default)
			)
			(layer "B.SilkS")
		)
		(fp_line
			(start -6.825488 -3.54584)
			(end -6.81355 -3.476498)
			(stroke
				(width 0.1)
				(type default)
			)
			(layer "B.SilkS")
		)
		(fp_line
			(start -6.825488 -3.54584)
			(end -6.81355 -3.476498)
			(stroke
				(width 0.1)
				(type default)
			)
			(layer "B.SilkS")
		)
		(fp_line
			(start -6.801104 -3.407156)
			(end -6.81355 -3.476498)
			(stroke
				(width 0.1)
				(type default)
			)
			(layer "B.SilkS")
		)
		(fp_line
			(start -6.801104 -3.407156)
			(end -6.81355 -3.476498)
			(stroke
				(width 0.1)
				(type default)
			)
			(layer "B.SilkS")
		)
		(fp_line
			(start -6.788912 -3.337814)
			(end -6.801104 -3.407156)
			(stroke
				(width 0.1)
				(type default)
			)
			(layer "B.SilkS")
		)
		(fp_line
			(start -6.788912 -3.337814)
			(end -6.801104 -3.407156)
			(stroke
				(width 0.1)
				(type default)
			)
			(layer "B.SilkS")
		)
		(fp_line
			(start -6.784848 -0.794258)
			(end -9.36752 -3.272028)
			(stroke
				(width 0.1)
				(type default)
			)
			(layer "B.SilkS")
		)
		(fp_line
			(start -6.784848 -0.794258)
			(end -9.36752 -3.272028)
			(stroke
				(width 0.1)
				(type default)
			)
			(layer "B.SilkS")
		)
		(fp_line
			(start -6.776974 -3.268472)
			(end -6.788912 -3.337814)
			(stroke
				(width 0.1)
				(type default)
			)
			(layer "B.SilkS")
		)
		(fp_line
			(start -6.776974 -3.268472)
			(end -6.788912 -3.337814)
			(stroke
				(width 0.1)
				(type default)
			)
			(layer "B.SilkS")
		)
		(fp_line
			(start -6.77545 -5.171694)
			(end -6.715506 -5.171694)
			(stroke
				(width 0.1)
				(type default)
			)
			(layer "B.SilkS")
		)
		(fp_line
			(start -6.77545 -5.171694)
			(end -6.715506 -5.171694)
			(stroke
				(width 0.1)
				(type default)
			)
			(layer "B.SilkS")
		)
		(fp_line
			(start -6.77545 -5.171694)
			(end -5.823966 -4.258818)
			(stroke
				(width 0.1)
				(type default)
			)
			(layer "B.SilkS")
		)
		(fp_line
			(start -6.77545 -5.171694)
			(end -5.823966 -4.258818)
			(stroke
				(width 0.1)
				(type default)
			)
			(layer "B.SilkS")
		)
		(fp_line
			(start -6.764782 -3.19913)
			(end -6.776974 -3.268472)
			(stroke
				(width 0.1)
				(type default)
			)
			(layer "B.SilkS")
		)
		(fp_line
			(start -6.764782 -3.19913)
			(end -6.776974 -3.268472)
			(stroke
				(width 0.1)
				(type default)
			)
			(layer "B.SilkS")
		)
		(fp_line
			(start -6.75259 -3.129534)
			(end -6.764782 -3.19913)
			(stroke
				(width 0.1)
				(type default)
			)
			(layer "B.SilkS")
		)
		(fp_line
			(start -6.75259 -3.129534)
			(end -6.764782 -3.19913)
			(stroke
				(width 0.1)
				(type default)
			)
			(layer "B.SilkS")
		)
		(fp_line
			(start -6.740144 -3.060192)
			(end -6.75259 -3.129534)
			(stroke
				(width 0.1)
				(type default)
			)
			(layer "B.SilkS")
		)
		(fp_line
			(start -6.740144 -3.060192)
			(end -6.75259 -3.129534)
			(stroke
				(width 0.1)
				(type default)
			)
			(layer "B.SilkS")
		)
		(fp_line
			(start -6.729984 -0.799592)
			(end -9.379712 -3.34137)
			(stroke
				(width 0.1)
				(type default)
			)
			(layer "B.SilkS")
		)
		(fp_line
			(start -6.729984 -0.799592)
			(end -9.379712 -3.34137)
			(stroke
				(width 0.1)
				(type default)
			)
			(layer "B.SilkS")
		)
		(fp_line
			(start -6.728206 -2.99085)
			(end -6.740144 -3.060192)
			(stroke
				(width 0.1)
				(type default)
			)
			(layer "B.SilkS")
		)
		(fp_line
			(start -6.728206 -2.99085)
			(end -6.740144 -3.060192)
			(stroke
				(width 0.1)
				(type default)
			)
			(layer "B.SilkS")
		)
		(fp_line
			(start -6.716014 -2.921254)
			(end -6.728206 -2.99085)
			(stroke
				(width 0.1)
				(type default)
			)
			(layer "B.SilkS")
		)
		(fp_line
			(start -6.716014 -2.921254)
			(end -6.728206 -2.99085)
			(stroke
				(width 0.1)
				(type default)
			)
			(layer "B.SilkS")
		)
		(fp_line
			(start -6.715506 -5.171694)
			(end -6.655308 -5.171694)
			(stroke
				(width 0.1)
				(type default)
			)
			(layer "B.SilkS")
		)
		(fp_line
			(start -6.715506 -5.171694)
			(end -6.655308 -5.171694)
			(stroke
				(width 0.1)
				(type default)
			)
			(layer "B.SilkS")
		)
		(fp_line
			(start -6.715506 -5.171694)
			(end -5.836158 -4.328414)
			(stroke
				(width 0.1)
				(type default)
			)
			(layer "B.SilkS")
		)
		(fp_line
			(start -6.715506 -5.171694)
			(end -5.836158 -4.328414)
			(stroke
				(width 0.1)
				(type default)
			)
			(layer "B.SilkS")
		)
		(fp_line
			(start -6.703822 -2.852166)
			(end -6.716014 -2.921254)
			(stroke
				(width 0.1)
				(type default)
			)
			(layer "B.SilkS")
		)
		(fp_line
			(start -6.703822 -2.852166)
			(end -6.716014 -2.921254)
			(stroke
				(width 0.1)
				(type default)
			)
			(layer "B.SilkS")
		)
		(fp_line
			(start -6.67512 -0.804672)
			(end -9.391904 -3.410712)
			(stroke
				(width 0.1)
				(type default)
			)
			(layer "B.SilkS")
		)
		(fp_line
			(start -6.67512 -0.804672)
			(end -9.391904 -3.410712)
			(stroke
				(width 0.1)
				(type default)
			)
			(layer "B.SilkS")
		)
		(fp_line
			(start -6.655308 -5.171694)
			(end -6.59511 -5.171694)
			(stroke
				(width 0.1)
				(type default)
			)
			(layer "B.SilkS")
		)
		(fp_line
			(start -6.655308 -5.171694)
			(end -6.59511 -5.171694)
			(stroke
				(width 0.1)
				(type default)
			)
			(layer "B.SilkS")
		)
		(fp_line
			(start -6.655308 -5.171694)
			(end -5.84835 -4.397502)
			(stroke
				(width 0.1)
				(type default)
			)
			(layer "B.SilkS")
		)
		(fp_line
			(start -6.655308 -5.171694)
			(end -5.84835 -4.397502)
			(stroke
				(width 0.1)
				(type default)
			)
			(layer "B.SilkS")
		)
		(fp_line
			(start -6.620256 -0.809498)
			(end -9.404096 -3.480054)
			(stroke
				(width 0.1)
				(type default)
			)
			(layer "B.SilkS")
		)
		(fp_line
			(start -6.620256 -0.809498)
			(end -9.404096 -3.480054)
			(stroke
				(width 0.1)
				(type default)
			)
			(layer "B.SilkS")
		)
		(fp_line
			(start -6.59511 -5.171694)
			(end -6.534912 -5.171694)
			(stroke
				(width 0.1)
				(type default)
			)
			(layer "B.SilkS")
		)
		(fp_line
			(start -6.59511 -5.171694)
			(end -6.534912 -5.171694)
			(stroke
				(width 0.1)
				(type default)
			)
			(layer "B.SilkS")
		)
		(fp_line
			(start -6.59511 -5.171694)
			(end -5.860542 -4.467098)
			(stroke
				(width 0.1)
				(type default)
			)
			(layer "B.SilkS")
		)
		(fp_line
			(start -6.59511 -5.171694)
			(end -5.860542 -4.467098)
			(stroke
				(width 0.1)
				(type default)
			)
			(layer "B.SilkS")
		)
		(fp_line
			(start -6.534912 -5.171694)
			(end -6.474714 -5.171694)
			(stroke
				(width 0.1)
				(type default)
			)
			(layer "B.SilkS")
		)
		(fp_line
			(start -6.534912 -5.171694)
			(end -6.474714 -5.171694)
			(stroke
				(width 0.1)
				(type default)
			)
			(layer "B.SilkS")
		)
		(fp_line
			(start -6.534912 -5.171694)
			(end -5.872734 -4.53644)
			(stroke
				(width 0.1)
				(type default)
			)
			(layer "B.SilkS")
		)
		(fp_line
			(start -6.534912 -5.171694)
			(end -5.872734 -4.53644)
			(stroke
				(width 0.1)
				(type default)
			)
			(layer "B.SilkS")
		)
		(fp_line
			(start -6.510528 -0.819912)
			(end -7.699756 -1.96088)
			(stroke
				(width 0.1)
				(type default)
			)
			(layer "B.SilkS")
		)
		(fp_line
			(start -6.510528 -0.819912)
			(end -7.699756 -1.96088)
			(stroke
				(width 0.1)
				(type default)
			)
			(layer "B.SilkS")
		)
		(fp_line
			(start -6.474714 -5.171694)
			(end -6.41477 -5.171694)
			(stroke
				(width 0.1)
				(type default)
			)
			(layer "B.SilkS")
		)
		(fp_line
			(start -6.474714 -5.171694)
			(end -6.41477 -5.171694)
			(stroke
				(width 0.1)
				(type default)
			)
			(layer "B.SilkS")
		)
		(fp_line
			(start -6.474714 -5.171694)
			(end -5.884926 -4.605782)
			(stroke
				(width 0.1)
				(type default)
			)
			(layer "B.SilkS")
		)
		(fp_line
			(start -6.474714 -5.171694)
			(end -5.884926 -4.605782)
			(stroke
				(width 0.1)
				(type default)
			)
			(layer "B.SilkS")
		)
		(fp_line
			(start -6.455664 -0.824738)
			(end -7.582662 -1.906016)
			(stroke
				(width 0.1)
				(type default)
			)
			(layer "B.SilkS")
		)
		(fp_line
			(start -6.455664 -0.824738)
			(end -7.582662 -1.906016)
			(stroke
				(width 0.1)
				(type default)
			)
			(layer "B.SilkS")
		)
		(fp_line
			(start -6.41477 -5.171694)
			(end -6.354318 -5.171694)
			(stroke
				(width 0.1)
				(type default)
			)
			(layer "B.SilkS")
		)
		(fp_line
			(start -6.41477 -5.171694)
			(end -6.354318 -5.171694)
			(stroke
				(width 0.1)
				(type default)
			)
			(layer "B.SilkS")
		)
		(fp_line
			(start -6.41477 -5.171694)
			(end -5.897118 -4.675124)
			(stroke
				(width 0.1)
				(type default)
			)
			(layer "B.SilkS")
		)
		(fp_line
			(start -6.41477 -5.171694)
			(end -5.897118 -4.675124)
			(stroke
				(width 0.1)
				(type default)
			)
			(layer "B.SilkS")
		)
		(fp_line
			(start -6.405118 -0.833882)
			(end -7.500366 -1.884934)
			(stroke
				(width 0.1)
				(type default)
			)
			(layer "B.SilkS")
		)
		(fp_line
			(start -6.405118 -0.833882)
			(end -7.500366 -1.884934)
			(stroke
				(width 0.1)
				(type default)
			)
			(layer "B.SilkS")
		)
		(fp_line
			(start -6.36016 -0.848868)
			(end -7.421118 -1.866392)
			(stroke
				(width 0.1)
				(type default)
			)
			(layer "B.SilkS")
		)
		(fp_line
			(start -6.36016 -0.848868)
			(end -7.421118 -1.866392)
			(stroke
				(width 0.1)
				(type default)
			)
			(layer "B.SilkS")
		)
		(fp_line
			(start -6.354318 -5.171694)
			(end -6.294374 -5.171694)
			(stroke
				(width 0.1)
				(type default)
			)
			(layer "B.SilkS")
		)
		(fp_line
			(start -6.354318 -5.171694)
			(end -6.294374 -5.171694)
			(stroke
				(width 0.1)
				(type default)
			)
			(layer "B.SilkS")
		)
		(fp_line
			(start -6.354318 -5.171694)
			(end -5.90931 -4.74472)
			(stroke
				(width 0.1)
				(type default)
			)
			(layer "B.SilkS")
		)
		(fp_line
			(start -6.354318 -5.171694)
			(end -5.90931 -4.74472)
			(stroke
				(width 0.1)
				(type default)
			)
			(layer "B.SilkS")
		)
		(fp_line
			(start -6.315456 -0.8636)
			(end -7.356348 -1.862074)
			(stroke
				(width 0.1)
				(type default)
			)
			(layer "B.SilkS")
		)
		(fp_line
			(start -6.315456 -0.8636)
			(end -7.356348 -1.862074)
			(stroke
				(width 0.1)
				(type default)
			)
			(layer "B.SilkS")
		)
		(fp_line
			(start -6.294374 -5.171694)
			(end -6.234176 -5.171694)
			(stroke
				(width 0.1)
				(type default)
			)
			(layer "B.SilkS")
		)
		(fp_line
			(start -6.294374 -5.171694)
			(end -6.234176 -5.171694)
			(stroke
				(width 0.1)
				(type default)
			)
			(layer "B.SilkS")
		)
		(fp_line
			(start -6.294374 -5.171694)
			(end -5.921502 -4.814062)
			(stroke
				(width 0.1)
				(type default)
			)
			(layer "B.SilkS")
		)
		(fp_line
			(start -6.294374 -5.171694)
			(end -5.921502 -4.814062)
			(stroke
				(width 0.1)
				(type default)
			)
			(layer "B.SilkS")
		)
		(fp_line
			(start -6.270752 -0.878332)
			(end -7.291832 -1.857756)
			(stroke
				(width 0.1)
				(type default)
			)
			(layer "B.SilkS")
		)
		(fp_line
			(start -6.270752 -0.878332)
			(end -7.291832 -1.857756)
			(stroke
				(width 0.1)
				(type default)
			)
			(layer "B.SilkS")
		)
		(fp_line
			(start -6.234176 -5.171694)
			(end -6.173978 -5.171694)
			(stroke
				(width 0.1)
				(type default)
			)
			(layer "B.SilkS")
		)
		(fp_line
			(start -6.234176 -5.171694)
			(end -6.173978 -5.171694)
			(stroke
				(width 0.1)
				(type default)
			)
			(layer "B.SilkS")
		)
		(fp_line
			(start -6.234176 -5.171694)
			(end -5.933694 -4.883404)
			(stroke
				(width 0.1)
				(type default)
			)
			(layer "B.SilkS")
		)
		(fp_line
			(start -6.234176 -5.171694)
			(end -5.933694 -4.883404)
			(stroke
				(width 0.1)
				(type default)
			)
			(layer "B.SilkS")
		)
		(fp_line
			(start -6.225794 -0.89281)
			(end -7.231126 -1.857248)
			(stroke
				(width 0.1)
				(type default)
			)
			(layer "B.SilkS")
		)
		(fp_line
			(start -6.225794 -0.89281)
			(end -7.231126 -1.857248)
			(stroke
				(width 0.1)
				(type default)
			)
			(layer "B.SilkS")
		)
		(fp_line
			(start -6.180836 -0.907796)
			(end -7.174738 -1.861058)
			(stroke
				(width 0.1)
				(type default)
			)
			(layer "B.SilkS")
		)
		(fp_line
			(start -6.180836 -0.907796)
			(end -7.174738 -1.861058)
			(stroke
				(width 0.1)
				(type default)
			)
			(layer "B.SilkS")
		)
		(fp_line
			(start -6.173978 -5.171694)
			(end -6.11378 -5.171694)
			(stroke
				(width 0.1)
				(type default)
			)
			(layer "B.SilkS")
		)
		(fp_line
			(start -6.173978 -5.171694)
			(end -6.11378 -5.171694)
			(stroke
				(width 0.1)
				(type default)
			)
			(layer "B.SilkS")
		)
		(fp_line
			(start -6.173978 -5.171694)
			(end -5.945886 -4.952746)
			(stroke
				(width 0.1)
				(type default)
			)
			(layer "B.SilkS")
		)
		(fp_line
			(start -6.173978 -5.171694)
			(end -5.945886 -4.952746)
			(stroke
				(width 0.1)
				(type default)
			)
			(layer "B.SilkS")
		)
		(fp_line
			(start -6.136132 -0.922528)
			(end -7.118604 -1.865122)
			(stroke
				(width 0.1)
				(type default)
			)
			(layer "B.SilkS")
		)
		(fp_line
			(start -6.136132 -0.922528)
			(end -7.118604 -1.865122)
			(stroke
				(width 0.1)
				(type default)
			)
			(layer "B.SilkS")
		)
		(fp_line
			(start -6.11378 -5.171694)
			(end -6.053582 -5.171694)
			(stroke
				(width 0.1)
				(type default)
			)
			(layer "B.SilkS")
		)
		(fp_line
			(start -6.11378 -5.171694)
			(end -6.053582 -5.171694)
			(stroke
				(width 0.1)
				(type default)
			)
			(layer "B.SilkS")
		)
		(fp_line
			(start -6.11378 -5.171694)
			(end -5.958078 -5.022088)
			(stroke
				(width 0.1)
				(type default)
			)
			(layer "B.SilkS")
		)
		(fp_line
			(start -6.11378 -5.171694)
			(end -5.958078 -5.022088)
			(stroke
				(width 0.1)
				(type default)
			)
			(layer "B.SilkS")
		)
		(fp_line
			(start -6.096254 -0.942086)
			(end -7.06755 -1.873504)
			(stroke
				(width 0.1)
				(type default)
			)
			(layer "B.SilkS")
		)
		(fp_line
			(start -6.096254 -0.942086)
			(end -7.06755 -1.873504)
			(stroke
				(width 0.1)
				(type default)
			)
			(layer "B.SilkS")
		)
		(fp_line
			(start -6.060948 -0.965962)
			(end -7.020306 -1.88595)
			(stroke
				(width 0.1)
				(type default)
			)
			(layer "B.SilkS")
		)
		(fp_line
			(start -6.060948 -0.965962)
			(end -7.020306 -1.88595)
			(stroke
				(width 0.1)
				(type default)
			)
			(layer "B.SilkS")
		)
		(fp_line
			(start -6.053582 -5.171694)
			(end -5.993638 -5.171694)
			(stroke
				(width 0.1)
				(type default)
			)
			(layer "B.SilkS")
		)
		(fp_line
			(start -6.053582 -5.171694)
			(end -5.993638 -5.171694)
			(stroke
				(width 0.1)
				(type default)
			)
			(layer "B.SilkS")
		)
		(fp_line
			(start -6.053582 -5.171694)
			(end -5.97027 -5.091684)
			(stroke
				(width 0.1)
				(type default)
			)
			(layer "B.SilkS")
		)
		(fp_line
			(start -6.053582 -5.171694)
			(end -5.97027 -5.091684)
			(stroke
				(width 0.1)
				(type default)
			)
			(layer "B.SilkS")
		)
		(fp_line
			(start -6.025642 -0.989584)
			(end -6.973062 -1.898396)
			(stroke
				(width 0.1)
				(type default)
			)
			(layer "B.SilkS")
		)
		(fp_line
			(start -6.025642 -0.989584)
			(end -6.973062 -1.898396)
			(stroke
				(width 0.1)
				(type default)
			)
			(layer "B.SilkS")
		)
		(fp_line
			(start -5.993638 -5.171694)
			(end -5.98424 -5.171694)
			(stroke
				(width 0.1)
				(type default)
			)
			(layer "B.SilkS")
		)
		(fp_line
			(start -5.993638 -5.171694)
			(end -5.98424 -5.171694)
			(stroke
				(width 0.1)
				(type default)
			)
			(layer "B.SilkS")
		)
		(fp_line
			(start -5.993638 -5.171694)
			(end -5.982208 -5.161026)
			(stroke
				(width 0.1)
				(type default)
			)
			(layer "B.SilkS")
		)
		(fp_line
			(start -5.993638 -5.171694)
			(end -5.982208 -5.161026)
			(stroke
				(width 0.1)
				(type default)
			)
			(layer "B.SilkS")
		)
		(fp_line
			(start -5.99059 -1.013714)
			(end -6.93166 -1.91643)
			(stroke
				(width 0.1)
				(type default)
			)
			(layer "B.SilkS")
		)
		(fp_line
			(start -5.99059 -1.013714)
			(end -6.93166 -1.91643)
			(stroke
				(width 0.1)
				(type default)
			)
			(layer "B.SilkS")
		)
		(fp_line
			(start -5.98424 -5.171694)
			(end -5.982208 -5.161026)
			(stroke
				(width 0.1)
				(type default)
			)
			(layer "B.SilkS")
		)
		(fp_line
			(start -5.98424 -5.171694)
			(end -5.982208 -5.161026)
			(stroke
				(width 0.1)
				(type default)
			)
			(layer "B.SilkS")
		)
		(fp_line
			(start -5.97027 -5.091684)
			(end -5.982208 -5.161026)
			(stroke
				(width 0.1)
				(type default)
			)
			(layer "B.SilkS")
		)
		(fp_line
			(start -5.97027 -5.091684)
			(end -5.982208 -5.161026)
			(stroke
				(width 0.1)
				(type default)
			)
			(layer "B.SilkS")
		)
		(fp_line
			(start -5.958078 -5.022088)
			(end -5.97027 -5.091684)
			(stroke
				(width 0.1)
				(type default)
			)
			(layer "B.SilkS")
		)
		(fp_line
			(start -5.958078 -5.022088)
			(end -5.97027 -5.091684)
			(stroke
				(width 0.1)
				(type default)
			)
			(layer "B.SilkS")
		)
		(fp_line
			(start -5.955284 -1.03759)
			(end -6.894068 -1.93802)
			(stroke
				(width 0.1)
				(type default)
			)
			(layer "B.SilkS")
		)
		(fp_line
			(start -5.955284 -1.03759)
			(end -6.894068 -1.93802)
			(stroke
				(width 0.1)
				(type default)
			)
			(layer "B.SilkS")
		)
		(fp_line
			(start -5.945886 -4.952746)
			(end -5.958078 -5.022088)
			(stroke
				(width 0.1)
				(type default)
			)
			(layer "B.SilkS")
		)
		(fp_line
			(start -5.945886 -4.952746)
			(end -5.958078 -5.022088)
			(stroke
				(width 0.1)
				(type default)
			)
			(layer "B.SilkS")
		)
		(fp_line
			(start -5.933694 -4.883404)
			(end -5.945886 -4.952746)
			(stroke
				(width 0.1)
				(type default)
			)
			(layer "B.SilkS")
		)
		(fp_line
			(start -5.933694 -4.883404)
			(end -5.945886 -4.952746)
			(stroke
				(width 0.1)
				(type default)
			)
			(layer "B.SilkS")
		)
		(fp_line
			(start -5.921502 -4.814062)
			(end -5.933694 -4.883404)
			(stroke
				(width 0.1)
				(type default)
			)
			(layer "B.SilkS")
		)
		(fp_line
			(start -5.921502 -4.814062)
			(end -5.933694 -4.883404)
			(stroke
				(width 0.1)
				(type default)
			)
			(layer "B.SilkS")
		)
		(fp_line
			(start -5.919978 -1.061212)
			(end -6.856222 -1.95961)
			(stroke
				(width 0.1)
				(type default)
			)
			(layer "B.SilkS")
		)
		(fp_line
			(start -5.919978 -1.061212)
			(end -6.856222 -1.95961)
			(stroke
				(width 0.1)
				(type default)
			)
			(layer "B.SilkS")
		)
		(fp_line
			(start -5.90931 -4.74472)
			(end -5.921502 -4.814062)
			(stroke
				(width 0.1)
				(type default)
			)
			(layer "B.SilkS")
		)
		(fp_line
			(start -5.90931 -4.74472)
			(end -5.921502 -4.814062)
			(stroke
				(width 0.1)
				(type default)
			)
			(layer "B.SilkS")
		)
		(fp_line
			(start -5.897118 -4.675124)
			(end -5.90931 -4.74472)
			(stroke
				(width 0.1)
				(type default)
			)
			(layer "B.SilkS")
		)
		(fp_line
			(start -5.897118 -4.675124)
			(end -5.90931 -4.74472)
			(stroke
				(width 0.1)
				(type default)
			)
			(layer "B.SilkS")
		)
		(fp_line
			(start -5.884926 -4.605782)
			(end -5.897118 -4.675124)
			(stroke
				(width 0.1)
				(type default)
			)
			(layer "B.SilkS")
		)
		(fp_line
			(start -5.884926 -4.605782)
			(end -5.897118 -4.675124)
			(stroke
				(width 0.1)
				(type default)
			)
			(layer "B.SilkS")
		)
		(fp_line
			(start -5.884926 -1.085342)
			(end -6.824726 -1.987042)
			(stroke
				(width 0.1)
				(type default)
			)
			(layer "B.SilkS")
		)
		(fp_line
			(start -5.884926 -1.085342)
			(end -6.824726 -1.987042)
			(stroke
				(width 0.1)
				(type default)
			)
			(layer "B.SilkS")
		)
		(fp_line
			(start -5.872734 -4.53644)
			(end -5.884926 -4.605782)
			(stroke
				(width 0.1)
				(type default)
			)
			(layer "B.SilkS")
		)
		(fp_line
			(start -5.872734 -4.53644)
			(end -5.884926 -4.605782)
			(stroke
				(width 0.1)
				(type default)
			)
			(layer "B.SilkS")
		)
		(fp_line
			(start -5.872734 -4.53644)
			(end -5.860542 -4.467098)
			(stroke
				(width 0.1)
				(type default)
			)
			(layer "B.SilkS")
		)
		(fp_line
			(start -5.872734 -4.53644)
			(end -5.860542 -4.467098)
			(stroke
				(width 0.1)
				(type default)
			)
			(layer "B.SilkS")
		)
		(fp_line
			(start -5.860542 -4.467098)
			(end -5.84835 -4.397502)
			(stroke
				(width 0.1)
				(type default)
			)
			(layer "B.SilkS")
		)
		(fp_line
			(start -5.860542 -4.467098)
			(end -5.84835 -4.397502)
			(stroke
				(width 0.1)
				(type default)
			)
			(layer "B.SilkS")
		)
		(fp_line
			(start -5.854954 -1.114298)
			(end -6.79704 -2.018284)
			(stroke
				(width 0.1)
				(type default)
			)
			(layer "B.SilkS")
		)
		(fp_line
			(start -5.854954 -1.114298)
			(end -6.79704 -2.018284)
			(stroke
				(width 0.1)
				(type default)
			)
			(layer "B.SilkS")
		)
		(fp_line
			(start -5.84835 -4.397502)
			(end -5.836158 -4.328414)
			(stroke
				(width 0.1)
				(type default)
			)
			(layer "B.SilkS")
		)
		(fp_line
			(start -5.84835 -4.397502)
			(end -5.836158 -4.328414)
			(stroke
				(width 0.1)
				(type default)
			)
			(layer "B.SilkS")
		)
		(fp_line
			(start -5.836158 -4.328414)
			(end -5.823966 -4.258818)
			(stroke
				(width 0.1)
				(type default)
			)
			(layer "B.SilkS")
		)
		(fp_line
			(start -5.836158 -4.328414)
			(end -5.823966 -4.258818)
			(stroke
				(width 0.1)
				(type default)
			)
			(layer "B.SilkS")
		)
		(fp_line
			(start -5.828792 -1.147064)
			(end -6.769608 -2.049272)
			(stroke
				(width 0.1)
				(type default)
			)
			(layer "B.SilkS")
		)
		(fp_line
			(start -5.828792 -1.147064)
			(end -6.769608 -2.049272)
			(stroke
				(width 0.1)
				(type default)
			)
			(layer "B.SilkS")
		)
		(fp_line
			(start -5.823966 -4.258818)
			(end -5.811774 -4.189476)
			(stroke
				(width 0.1)
				(type default)
			)
			(layer "B.SilkS")
		)
		(fp_line
			(start -5.823966 -4.258818)
			(end -5.811774 -4.189476)
			(stroke
				(width 0.1)
				(type default)
			)
			(layer "B.SilkS")
		)
		(fp_line
			(start -5.811774 -4.189476)
			(end -5.799582 -4.11988)
			(stroke
				(width 0.1)
				(type default)
			)
			(layer "B.SilkS")
		)
		(fp_line
			(start -5.811774 -4.189476)
			(end -5.799582 -4.11988)
			(stroke
				(width 0.1)
				(type default)
			)
			(layer "B.SilkS")
		)
		(fp_line
			(start -5.80263 -1.179576)
			(end -6.746494 -2.084832)
			(stroke
				(width 0.1)
				(type default)
			)
			(layer "B.SilkS")
		)
		(fp_line
			(start -5.80263 -1.179576)
			(end -6.746494 -2.084832)
			(stroke
				(width 0.1)
				(type default)
			)
			(layer "B.SilkS")
		)
		(fp_line
			(start -5.799582 -4.11988)
			(end -5.78739 -4.050538)
			(stroke
				(width 0.1)
				(type default)
			)
			(layer "B.SilkS")
		)
		(fp_line
			(start -5.799582 -4.11988)
			(end -5.78739 -4.050538)
			(stroke
				(width 0.1)
				(type default)
			)
			(layer "B.SilkS")
		)
		(fp_line
			(start -5.78739 -4.050538)
			(end -5.775198 -3.98145)
			(stroke
				(width 0.1)
				(type default)
			)
			(layer "B.SilkS")
		)
		(fp_line
			(start -5.78739 -4.050538)
			(end -5.775198 -3.98145)
			(stroke
				(width 0.1)
				(type default)
			)
			(layer "B.SilkS")
		)
		(fp_line
			(start -5.776468 -1.212342)
			(end -6.728714 -2.125726)
			(stroke
				(width 0.1)
				(type default)
			)
			(layer "B.SilkS")
		)
		(fp_line
			(start -5.776468 -1.212342)
			(end -6.728714 -2.125726)
			(stroke
				(width 0.1)
				(type default)
			)
			(layer "B.SilkS")
		)
		(fp_line
			(start -5.775198 -3.98145)
			(end -5.763006 -3.911854)
			(stroke
				(width 0.1)
				(type default)
			)
			(layer "B.SilkS")
		)
		(fp_line
			(start -5.775198 -3.98145)
			(end -5.763006 -3.911854)
			(stroke
				(width 0.1)
				(type default)
			)
			(layer "B.SilkS")
		)
		(fp_line
			(start -5.763006 -3.911854)
			(end -5.751068 -3.842512)
			(stroke
				(width 0.1)
				(type default)
			)
			(layer "B.SilkS")
		)
		(fp_line
			(start -5.763006 -3.911854)
			(end -5.751068 -3.842512)
			(stroke
				(width 0.1)
				(type default)
			)
			(layer "B.SilkS")
		)
		(fp_line
			(start -5.751068 -3.842512)
			(end -5.738876 -3.772916)
			(stroke
				(width 0.1)
				(type default)
			)
			(layer "B.SilkS")
		)
		(fp_line
			(start -5.751068 -3.842512)
			(end -5.738876 -3.772916)
			(stroke
				(width 0.1)
				(type default)
			)
			(layer "B.SilkS")
		)
		(fp_line
			(start -5.750306 -1.244854)
			(end -6.710934 -2.166366)
			(stroke
				(width 0.1)
				(type default)
			)
			(layer "B.SilkS")
		)
		(fp_line
			(start -5.750306 -1.244854)
			(end -6.710934 -2.166366)
			(stroke
				(width 0.1)
				(type default)
			)
			(layer "B.SilkS")
		)
		(fp_line
			(start -5.738876 -3.772916)
			(end -5.72643 -3.703828)
			(stroke
				(width 0.1)
				(type default)
			)
			(layer "B.SilkS")
		)
		(fp_line
			(start -5.738876 -3.772916)
			(end -5.72643 -3.703828)
			(stroke
				(width 0.1)
				(type default)
			)
			(layer "B.SilkS")
		)
		(fp_line
			(start -5.72643 -3.703828)
			(end -5.714238 -3.634232)
			(stroke
				(width 0.1)
				(type default)
			)
			(layer "B.SilkS")
		)
		(fp_line
			(start -5.72643 -3.703828)
			(end -5.714238 -3.634232)
			(stroke
				(width 0.1)
				(type default)
			)
			(layer "B.SilkS")
		)
		(fp_line
			(start -5.724398 -1.27762)
			(end -6.694932 -2.20853)
			(stroke
				(width 0.1)
				(type default)
			)
			(layer "B.SilkS")
		)
		(fp_line
			(start -5.724398 -1.27762)
			(end -6.694932 -2.20853)
			(stroke
				(width 0.1)
				(type default)
			)
			(layer "B.SilkS")
		)
		(fp_line
			(start -5.714238 -3.634232)
			(end -5.7023 -3.56489)
			(stroke
				(width 0.1)
				(type default)
			)
			(layer "B.SilkS")
		)
		(fp_line
			(start -5.714238 -3.634232)
			(end -5.7023 -3.56489)
			(stroke
				(width 0.1)
				(type default)
			)
			(layer "B.SilkS")
		)
		(fp_line
			(start -5.7023 -3.56489)
			(end -5.690108 -3.495548)
			(stroke
				(width 0.1)
				(type default)
			)
			(layer "B.SilkS")
		)
		(fp_line
			(start -5.7023 -3.56489)
			(end -5.690108 -3.495548)
			(stroke
				(width 0.1)
				(type default)
			)
			(layer "B.SilkS")
		)
		(fp_line
			(start -5.697982 -1.310132)
			(end -6.68655 -2.258568)
			(stroke
				(width 0.1)
				(type default)
			)
			(layer "B.SilkS")
		)
		(fp_line
			(start -5.697982 -1.310132)
			(end -6.68655 -2.258568)
			(stroke
				(width 0.1)
				(type default)
			)
			(layer "B.SilkS")
		)
		(fp_line
			(start -5.690108 -3.495548)
			(end -5.677662 -3.425952)
			(stroke
				(width 0.1)
				(type default)
			)
			(layer "B.SilkS")
		)
		(fp_line
			(start -5.690108 -3.495548)
			(end -5.677662 -3.425952)
			(stroke
				(width 0.1)
				(type default)
			)
			(layer "B.SilkS")
		)
		(fp_line
			(start -5.677916 -1.34874)
			(end -6.678168 -2.308352)
			(stroke
				(width 0.1)
				(type default)
			)
			(layer "B.SilkS")
		)
		(fp_line
			(start -5.677916 -1.34874)
			(end -6.678168 -2.308352)
			(stroke
				(width 0.1)
				(type default)
			)
			(layer "B.SilkS")
		)
		(fp_line
			(start -5.677662 -3.425952)
			(end -5.665724 -3.35661)
			(stroke
				(width 0.1)
				(type default)
			)
			(layer "B.SilkS")
		)
		(fp_line
			(start -5.677662 -3.425952)
			(end -5.665724 -3.35661)
			(stroke
				(width 0.1)
				(type default)
			)
			(layer "B.SilkS")
		)
		(fp_line
			(start -5.665724 -3.35661)
			(end -5.653532 -3.287268)
			(stroke
				(width 0.1)
				(type default)
			)
			(layer "B.SilkS")
		)
		(fp_line
			(start -5.665724 -3.35661)
			(end -5.653532 -3.287268)
			(stroke
				(width 0.1)
				(type default)
			)
			(layer "B.SilkS")
		)
		(fp_line
			(start -5.660644 -1.389634)
			(end -6.67004 -2.357882)
			(stroke
				(width 0.1)
				(type default)
			)
			(layer "B.SilkS")
		)
		(fp_line
			(start -5.660644 -1.389634)
			(end -6.67004 -2.357882)
			(stroke
				(width 0.1)
				(type default)
			)
			(layer "B.SilkS")
		)
		(fp_line
			(start -5.653532 -3.287268)
			(end -5.64134 -3.217926)
			(stroke
				(width 0.1)
				(type default)
			)
			(layer "B.SilkS")
		)
		(fp_line
			(start -5.653532 -3.287268)
			(end -5.64134 -3.217926)
			(stroke
				(width 0.1)
				(type default)
			)
			(layer "B.SilkS")
		)
		(fp_line
			(start -5.643118 -1.430528)
			(end -6.668008 -2.413762)
			(stroke
				(width 0.1)
				(type default)
			)
			(layer "B.SilkS")
		)
		(fp_line
			(start -5.643118 -1.430528)
			(end -6.668008 -2.413762)
			(stroke
				(width 0.1)
				(type default)
			)
			(layer "B.SilkS")
		)
		(fp_line
			(start -5.64134 -3.217926)
			(end -5.629148 -3.148584)
			(stroke
				(width 0.1)
				(type default)
			)
			(layer "B.SilkS")
		)
		(fp_line
			(start -5.64134 -3.217926)
			(end -5.629148 -3.148584)
			(stroke
				(width 0.1)
				(type default)
			)
			(layer "B.SilkS")
		)
		(fp_line
			(start -5.629148 -3.148584)
			(end -5.616956 -3.079242)
			(stroke
				(width 0.1)
				(type default)
			)
			(layer "B.SilkS")
		)
		(fp_line
			(start -5.629148 -3.148584)
			(end -5.616956 -3.079242)
			(stroke
				(width 0.1)
				(type default)
			)
			(layer "B.SilkS")
		)
		(fp_line
			(start -5.625846 -1.471676)
			(end -6.668516 -2.471928)
			(stroke
				(width 0.1)
				(type default)
			)
			(layer "B.SilkS")
		)
		(fp_line
			(start -5.625846 -1.471676)
			(end -6.668516 -2.471928)
			(stroke
				(width 0.1)
				(type default)
			)
			(layer "B.SilkS")
		)
		(fp_line
			(start -5.616956 -3.079242)
			(end -5.604764 -3.009646)
			(stroke
				(width 0.1)
				(type default)
			)
			(layer "B.SilkS")
		)
		(fp_line
			(start -5.616956 -3.079242)
			(end -5.604764 -3.009646)
			(stroke
				(width 0.1)
				(type default)
			)
			(layer "B.SilkS")
		)
		(fp_line
			(start -5.60832 -1.51257)
			(end -6.669024 -2.530094)
			(stroke
				(width 0.1)
				(type default)
			)
			(layer "B.SilkS")
		)
		(fp_line
			(start -5.60832 -1.51257)
			(end -6.669024 -2.530094)
			(stroke
				(width 0.1)
				(type default)
			)
			(layer "B.SilkS")
		)
		(fp_line
			(start -5.604764 -3.009646)
			(end -5.592572 -2.940304)
			(stroke
				(width 0.1)
				(type default)
			)
			(layer "B.SilkS")
		)
		(fp_line
			(start -5.604764 -3.009646)
			(end -5.592572 -2.940304)
			(stroke
				(width 0.1)
				(type default)
			)
			(layer "B.SilkS")
		)
		(fp_line
			(start -5.592572 -2.940304)
			(end -5.58038 -2.870962)
			(stroke
				(width 0.1)
				(type default)
			)
			(layer "B.SilkS")
		)
		(fp_line
			(start -5.592572 -2.940304)
			(end -5.58038 -2.870962)
			(stroke
				(width 0.1)
				(type default)
			)
			(layer "B.SilkS")
		)
		(fp_line
			(start -5.591048 -1.553718)
			(end -6.669532 -2.58826)
			(stroke
				(width 0.1)
				(type default)
			)
			(layer "B.SilkS")
		)
		(fp_line
			(start -5.591048 -1.553718)
			(end -6.669532 -2.58826)
			(stroke
				(width 0.1)
				(type default)
			)
			(layer "B.SilkS")
		)
		(fp_line
			(start -5.58038 -2.870962)
			(end -5.568188 -2.801366)
			(stroke
				(width 0.1)
				(type default)
			)
			(layer "B.SilkS")
		)
		(fp_line
			(start -5.58038 -2.870962)
			(end -5.568188 -2.801366)
			(stroke
				(width 0.1)
				(type default)
			)
			(layer "B.SilkS")
		)
		(fp_line
			(start -5.573522 -1.594612)
			(end -6.678168 -2.6543)
			(stroke
				(width 0.1)
				(type default)
			)
			(layer "B.SilkS")
		)
		(fp_line
			(start -5.573522 -1.594612)
			(end -6.678168 -2.6543)
			(stroke
				(width 0.1)
				(type default)
			)
			(layer "B.SilkS")
		)
		(fp_line
			(start -5.563108 -1.642364)
			(end -6.68655 -2.720086)
			(stroke
				(width 0.1)
				(type default)
			)
			(layer "B.SilkS")
		)
		(fp_line
			(start -5.563108 -1.642364)
			(end -6.68655 -2.720086)
			(stroke
				(width 0.1)
				(type default)
			)
			(layer "B.SilkS")
		)
		(fp_line
			(start -5.554218 -1.69164)
			(end -6.695186 -2.786126)
			(stroke
				(width 0.1)
				(type default)
			)
			(layer "B.SilkS")
		)
		(fp_line
			(start -5.554218 -1.69164)
			(end -6.695186 -2.786126)
			(stroke
				(width 0.1)
				(type default)
			)
			(layer "B.SilkS")
		)
		(fp_line
			(start -5.545582 -1.740916)
			(end -6.703822 -2.852166)
			(stroke
				(width 0.1)
				(type default)
			)
			(layer "B.SilkS")
		)
		(fp_line
			(start -5.545582 -1.740916)
			(end -6.703822 -2.852166)
			(stroke
				(width 0.1)
				(type default)
			)
			(layer "B.SilkS")
		)
		(fp_line
			(start -5.536438 -1.789938)
			(end -6.716014 -2.921254)
			(stroke
				(width 0.1)
				(type default)
			)
			(layer "B.SilkS")
		)
		(fp_line
			(start -5.536438 -1.789938)
			(end -6.716014 -2.921254)
			(stroke
				(width 0.1)
				(type default)
			)
			(layer "B.SilkS")
		)
		(fp_line
			(start -5.527802 -1.839214)
			(end -6.728206 -2.99085)
			(stroke
				(width 0.1)
				(type default)
			)
			(layer "B.SilkS")
		)
		(fp_line
			(start -5.527802 -1.839214)
			(end -6.728206 -2.99085)
			(stroke
				(width 0.1)
				(type default)
			)
			(layer "B.SilkS")
		)
		(fp_line
			(start -5.518912 -1.88849)
			(end -6.740144 -3.060192)
			(stroke
				(width 0.1)
				(type default)
			)
			(layer "B.SilkS")
		)
		(fp_line
			(start -5.518912 -1.88849)
			(end -6.740144 -3.060192)
			(stroke
				(width 0.1)
				(type default)
			)
			(layer "B.SilkS")
		)
		(fp_line
			(start -5.510276 -1.937766)
			(end -6.75259 -3.129534)
			(stroke
				(width 0.1)
				(type default)
			)
			(layer "B.SilkS")
		)
		(fp_line
			(start -5.510276 -1.937766)
			(end -6.75259 -3.129534)
			(stroke
				(width 0.1)
				(type default)
			)
			(layer "B.SilkS")
		)
		(fp_line
			(start -5.509768 -1.99517)
			(end -6.764782 -3.19913)
			(stroke
				(width 0.1)
				(type default)
			)
			(layer "B.SilkS")
		)
		(fp_line
			(start -5.509768 -1.99517)
			(end -6.764782 -3.19913)
			(stroke
				(width 0.1)
				(type default)
			)
			(layer "B.SilkS")
		)
		(fp_line
			(start -5.50926 -2.052574)
			(end -6.776974 -3.268472)
			(stroke
				(width 0.1)
				(type default)
			)
			(layer "B.SilkS")
		)
		(fp_line
			(start -5.50926 -2.052574)
			(end -6.776974 -3.268472)
			(stroke
				(width 0.1)
				(type default)
			)
			(layer "B.SilkS")
		)
		(fp_line
			(start -5.508752 -2.109724)
			(end -6.788912 -3.337814)
			(stroke
				(width 0.1)
				(type default)
			)
			(layer "B.SilkS")
		)
		(fp_line
			(start -5.508752 -2.109724)
			(end -6.788912 -3.337814)
			(stroke
				(width 0.1)
				(type default)
			)
			(layer "B.SilkS")
		)
		(fp_line
			(start -5.508498 -2.167128)
			(end -6.801104 -3.407156)
			(stroke
				(width 0.1)
				(type default)
			)
			(layer "B.SilkS")
		)
		(fp_line
			(start -5.508498 -2.167128)
			(end -6.801104 -3.407156)
			(stroke
				(width 0.1)
				(type default)
			)
			(layer "B.SilkS")
		)
		(fp_line
			(start -5.50799 -2.224278)
			(end -6.81355 -3.476498)
			(stroke
				(width 0.1)
				(type default)
			)
			(layer "B.SilkS")
		)
		(fp_line
			(start -5.50799 -2.224278)
			(end -6.81355 -3.476498)
			(stroke
				(width 0.1)
				(type default)
			)
			(layer "B.SilkS")
		)
		(fp_line
			(start -5.507482 -2.281682)
			(end -6.825488 -3.54584)
			(stroke
				(width 0.1)
				(type default)
			)
			(layer "B.SilkS")
		)
		(fp_line
			(start -5.507482 -2.281682)
			(end -6.825488 -3.54584)
			(stroke
				(width 0.1)
				(type default)
			)
			(layer "B.SilkS")
		)
		(fp_line
			(start -5.287264 -0.259588)
			(end -5.289296 -0.261366)
			(stroke
				(width 0.1)
				(type default)
			)
			(layer "B.SilkS")
		)
		(fp_line
			(start -5.287264 -0.259588)
			(end -5.289296 -0.261366)
			(stroke
				(width 0.1)
				(type default)
			)
			(layer "B.SilkS")
		)
		(fp_line
			(start -5.287264 -0.259588)
			(end -5.205222 -0.238252)
			(stroke
				(width 0.1)
				(type default)
			)
			(layer "B.SilkS")
		)
		(fp_line
			(start -5.287264 -0.259588)
			(end -5.205222 -0.238252)
			(stroke
				(width 0.1)
				(type default)
			)
			(layer "B.SilkS")
		)
		(fp_line
			(start -5.205222 -0.238252)
			(end -5.254752 -0.28575)
			(stroke
				(width 0.1)
				(type default)
			)
			(layer "B.SilkS")
		)
		(fp_line
			(start -5.205222 -0.238252)
			(end -5.254752 -0.28575)
			(stroke
				(width 0.1)
				(type default)
			)
			(layer "B.SilkS")
		)
		(fp_line
			(start -5.13588 -3.576828)
			(end -2.15773 -0.719836)
			(stroke
				(width 0.1)
				(type default)
			)
			(layer "B.SilkS")
		)
		(fp_line
			(start -5.13588 -3.576828)
			(end -2.15773 -0.719836)
			(stroke
				(width 0.1)
				(type default)
			)
			(layer "B.SilkS")
		)
		(fp_line
			(start -5.127498 -3.626612)
			(end -3.618992 -2.17932)
			(stroke
				(width 0.1)
				(type default)
			)
			(layer "B.SilkS")
		)
		(fp_line
			(start -5.127498 -3.626612)
			(end -3.618992 -2.17932)
			(stroke
				(width 0.1)
				(type default)
			)
			(layer "B.SilkS")
		)
		(fp_line
			(start -5.12318 -0.217678)
			(end -5.219954 -0.310388)
			(stroke
				(width 0.1)
				(type default)
			)
			(layer "B.SilkS")
		)
		(fp_line
			(start -5.12318 -0.217678)
			(end -5.219954 -0.310388)
			(stroke
				(width 0.1)
				(type default)
			)
			(layer "B.SilkS")
		)
		(fp_line
			(start -5.12318 -0.217678)
			(end -5.205222 -0.238252)
			(stroke
				(width 0.1)
				(type default)
			)
			(layer "B.SilkS")
		)
		(fp_line
			(start -5.12318 -0.217678)
			(end -5.205222 -0.238252)
			(stroke
				(width 0.1)
				(type default)
			)
			(layer "B.SilkS")
		)
		(fp_line
			(start -5.11937 -3.676396)
			(end -3.710686 -2.32537)
			(stroke
				(width 0.1)
				(type default)
			)
			(layer "B.SilkS")
		)
		(fp_line
			(start -5.11937 -3.676396)
			(end -3.710686 -2.32537)
			(stroke
				(width 0.1)
				(type default)
			)
			(layer "B.SilkS")
		)
		(fp_line
			(start -5.110734 -3.72618)
			(end -3.756406 -2.426716)
			(stroke
				(width 0.1)
				(type default)
			)
			(layer "B.SilkS")
		)
		(fp_line
			(start -5.110734 -3.72618)
			(end -3.756406 -2.426716)
			(stroke
				(width 0.1)
				(type default)
			)
			(layer "B.SilkS")
		)
		(fp_line
			(start -5.101336 -3.774694)
			(end -3.802126 -2.528316)
			(stroke
				(width 0.1)
				(type default)
			)
			(layer "B.SilkS")
		)
		(fp_line
			(start -5.101336 -3.774694)
			(end -3.802126 -2.528316)
			(stroke
				(width 0.1)
				(type default)
			)
			(layer "B.SilkS")
		)
		(fp_line
			(start -5.089652 -3.821176)
			(end -3.824478 -2.607564)
			(stroke
				(width 0.1)
				(type default)
			)
			(layer "B.SilkS")
		)
		(fp_line
			(start -5.089652 -3.821176)
			(end -3.824478 -2.607564)
			(stroke
				(width 0.1)
				(type default)
			)
			(layer "B.SilkS")
		)
		(fp_line
			(start -5.078222 -3.867658)
			(end -3.843782 -2.68351)
			(stroke
				(width 0.1)
				(type default)
			)
			(layer "B.SilkS")
		)
		(fp_line
			(start -5.078222 -3.867658)
			(end -3.843782 -2.68351)
			(stroke
				(width 0.1)
				(type default)
			)
			(layer "B.SilkS")
		)
		(fp_line
			(start -5.066284 -3.91414)
			(end -3.863086 -2.75971)
			(stroke
				(width 0.1)
				(type default)
			)
			(layer "B.SilkS")
		)
		(fp_line
			(start -5.066284 -3.91414)
			(end -3.863086 -2.75971)
			(stroke
				(width 0.1)
				(type default)
			)
			(layer "B.SilkS")
		)
		(fp_line
			(start -5.0546 -3.960622)
			(end -3.879088 -2.832862)
			(stroke
				(width 0.1)
				(type default)
			)
			(layer "B.SilkS")
		)
		(fp_line
			(start -5.0546 -3.960622)
			(end -3.879088 -2.832862)
			(stroke
				(width 0.1)
				(type default)
			)
			(layer "B.SilkS")
		)
		(fp_line
			(start -5.041392 -4.00558)
			(end -3.884168 -2.8956)
			(stroke
				(width 0.1)
				(type default)
			)
			(layer "B.SilkS")
		)
		(fp_line
			(start -5.041392 -4.00558)
			(end -3.884168 -2.8956)
			(stroke
				(width 0.1)
				(type default)
			)
			(layer "B.SilkS")
		)
		(fp_line
			(start -5.041392 -0.196596)
			(end -5.185156 -0.334772)
			(stroke
				(width 0.1)
				(type default)
			)
			(layer "B.SilkS")
		)
		(fp_line
			(start -5.041392 -0.196596)
			(end -5.185156 -0.334772)
			(stroke
				(width 0.1)
				(type default)
			)
			(layer "B.SilkS")
		)
		(fp_line
			(start -5.041392 -0.196596)
			(end -5.12318 -0.217678)
			(stroke
				(width 0.1)
				(type default)
			)
			(layer "B.SilkS")
		)
		(fp_line
			(start -5.041392 -0.196596)
			(end -5.12318 -0.217678)
			(stroke
				(width 0.1)
				(type default)
			)
			(layer "B.SilkS")
		)
		(fp_line
			(start -5.026152 -4.04876)
			(end -3.889248 -2.958084)
			(stroke
				(width 0.1)
				(type default)
			)
			(layer "B.SilkS")
		)
		(fp_line
			(start -5.026152 -4.04876)
			(end -3.889248 -2.958084)
			(stroke
				(width 0.1)
				(type default)
			)
			(layer "B.SilkS")
		)
		(fp_line
			(start -5.011166 -4.09194)
			(end -3.894328 -3.020822)
			(stroke
				(width 0.1)
				(type default)
			)
			(layer "B.SilkS")
		)
		(fp_line
			(start -5.011166 -4.09194)
			(end -3.894328 -3.020822)
			(stroke
				(width 0.1)
				(type default)
			)
			(layer "B.SilkS")
		)
		(fp_line
			(start -4.995672 -4.13512)
			(end -3.899408 -3.083306)
			(stroke
				(width 0.1)
				(type default)
			)
			(layer "B.SilkS")
		)
		(fp_line
			(start -4.995672 -4.13512)
			(end -3.899408 -3.083306)
			(stroke
				(width 0.1)
				(type default)
			)
			(layer "B.SilkS")
		)
		(fp_line
			(start -4.980686 -4.1783)
			(end -3.900424 -3.14198)
			(stroke
				(width 0.1)
				(type default)
			)
			(layer "B.SilkS")
		)
		(fp_line
			(start -4.980686 -4.1783)
			(end -3.900424 -3.14198)
			(stroke
				(width 0.1)
				(type default)
			)
			(layer "B.SilkS")
		)
		(fp_line
			(start -4.965446 -4.221226)
			(end -3.895852 -3.19532)
			(stroke
				(width 0.1)
				(type default)
			)
			(layer "B.SilkS")
		)
		(fp_line
			(start -4.965446 -4.221226)
			(end -3.895852 -3.19532)
			(stroke
				(width 0.1)
				(type default)
			)
			(layer "B.SilkS")
		)
		(fp_line
			(start -4.95935 -0.175514)
			(end -5.150612 -0.359156)
			(stroke
				(width 0.1)
				(type default)
			)
			(layer "B.SilkS")
		)
		(fp_line
			(start -4.95935 -0.175514)
			(end -5.150612 -0.359156)
			(stroke
				(width 0.1)
				(type default)
			)
			(layer "B.SilkS")
		)
		(fp_line
			(start -4.95935 -0.175514)
			(end -5.041392 -0.196596)
			(stroke
				(width 0.1)
				(type default)
			)
			(layer "B.SilkS")
		)
		(fp_line
			(start -4.95935 -0.175514)
			(end -5.041392 -0.196596)
			(stroke
				(width 0.1)
				(type default)
			)
			(layer "B.SilkS")
		)
		(fp_line
			(start -4.946904 -4.261358)
			(end -3.891534 -3.248914)
			(stroke
				(width 0.1)
				(type default)
			)
			(layer "B.SilkS")
		)
		(fp_line
			(start -4.946904 -4.261358)
			(end -3.891534 -3.248914)
			(stroke
				(width 0.1)
				(type default)
			)
			(layer "B.SilkS")
		)
		(fp_line
			(start -4.927854 -4.300728)
			(end -3.886962 -3.302254)
			(stroke
				(width 0.1)
				(type default)
			)
			(layer "B.SilkS")
		)
		(fp_line
			(start -4.927854 -4.300728)
			(end -3.886962 -3.302254)
			(stroke
				(width 0.1)
				(type default)
			)
			(layer "B.SilkS")
		)
		(fp_line
			(start -4.908804 -4.340098)
			(end -3.88239 -3.355848)
			(stroke
				(width 0.1)
				(type default)
			)
			(layer "B.SilkS")
		)
		(fp_line
			(start -4.908804 -4.340098)
			(end -3.88239 -3.355848)
			(stroke
				(width 0.1)
				(type default)
			)
			(layer "B.SilkS")
		)
		(fp_line
			(start -4.889754 -4.379722)
			(end -3.878072 -3.409188)
			(stroke
				(width 0.1)
				(type default)
			)
			(layer "B.SilkS")
		)
		(fp_line
			(start -4.889754 -4.379722)
			(end -3.878072 -3.409188)
			(stroke
				(width 0.1)
				(type default)
			)
			(layer "B.SilkS")
		)
		(fp_line
			(start -4.877308 -0.15494)
			(end -5.115814 -0.383794)
			(stroke
				(width 0.1)
				(type default)
			)
			(layer "B.SilkS")
		)
		(fp_line
			(start -4.877308 -0.15494)
			(end -5.115814 -0.383794)
			(stroke
				(width 0.1)
				(type default)
			)
			(layer "B.SilkS")
		)
		(fp_line
			(start -4.877308 -0.15494)
			(end -4.95935 -0.175514)
			(stroke
				(width 0.1)
				(type default)
			)
			(layer "B.SilkS")
		)
		(fp_line
			(start -4.877308 -0.15494)
			(end -4.95935 -0.175514)
			(stroke
				(width 0.1)
				(type default)
			)
			(layer "B.SilkS")
		)
		(fp_line
			(start -4.870958 -4.419092)
			(end -3.870198 -3.459226)
			(stroke
				(width 0.1)
				(type default)
			)
			(layer "B.SilkS")
		)
		(fp_line
			(start -4.870958 -4.419092)
			(end -3.870198 -3.459226)
			(stroke
				(width 0.1)
				(type default)
			)
			(layer "B.SilkS")
		)
		(fp_line
			(start -4.851654 -4.458462)
			(end -3.858006 -3.505454)
			(stroke
				(width 0.1)
				(type default)
			)
			(layer "B.SilkS")
		)
		(fp_line
			(start -4.851654 -4.458462)
			(end -3.858006 -3.505454)
			(stroke
				(width 0.1)
				(type default)
			)
			(layer "B.SilkS")
		)
		(fp_line
			(start -4.82981 -4.495292)
			(end -3.846068 -3.551682)
			(stroke
				(width 0.1)
				(type default)
			)
			(layer "B.SilkS")
		)
		(fp_line
			(start -4.82981 -4.495292)
			(end -3.846068 -3.551682)
			(stroke
				(width 0.1)
				(type default)
			)
			(layer "B.SilkS")
		)
		(fp_line
			(start -4.806696 -4.530852)
			(end -3.83413 -3.59791)
			(stroke
				(width 0.1)
				(type default)
			)
			(layer "B.SilkS")
		)
		(fp_line
			(start -4.806696 -4.530852)
			(end -3.83413 -3.59791)
			(stroke
				(width 0.1)
				(type default)
			)
			(layer "B.SilkS")
		)
		(fp_line
			(start -4.795266 -0.133604)
			(end -5.08127 -0.408178)
			(stroke
				(width 0.1)
				(type default)
			)
			(layer "B.SilkS")
		)
		(fp_line
			(start -4.795266 -0.133604)
			(end -5.08127 -0.408178)
			(stroke
				(width 0.1)
				(type default)
			)
			(layer "B.SilkS")
		)
		(fp_line
			(start -4.795266 -0.133604)
			(end -4.877308 -0.15494)
			(stroke
				(width 0.1)
				(type default)
			)
			(layer "B.SilkS")
		)
		(fp_line
			(start -4.795266 -0.133604)
			(end -4.877308 -0.15494)
			(stroke
				(width 0.1)
				(type default)
			)
			(layer "B.SilkS")
		)
		(fp_line
			(start -4.783582 -4.566158)
			(end -3.821938 -3.643884)
			(stroke
				(width 0.1)
				(type default)
			)
			(layer "B.SilkS")
		)
		(fp_line
			(start -4.783582 -4.566158)
			(end -3.821938 -3.643884)
			(stroke
				(width 0.1)
				(type default)
			)
			(layer "B.SilkS")
		)
		(fp_line
			(start -4.760214 -4.601718)
			(end -3.81 -3.689858)
			(stroke
				(width 0.1)
				(type default)
			)
			(layer "B.SilkS")
		)
		(fp_line
			(start -4.760214 -4.601718)
			(end -3.81 -3.689858)
			(stroke
				(width 0.1)
				(type default)
			)
			(layer "B.SilkS")
		)
		(fp_line
			(start -4.7371 -4.637278)
			(end -3.7973 -3.735578)
			(stroke
				(width 0.1)
				(type default)
			)
			(layer "B.SilkS")
		)
		(fp_line
			(start -4.7371 -4.637278)
			(end -3.7973 -3.735578)
			(stroke
				(width 0.1)
				(type default)
			)
			(layer "B.SilkS")
		)
		(fp_line
			(start -4.713732 -4.672584)
			(end -3.778758 -3.775456)
			(stroke
				(width 0.1)
				(type default)
			)
			(layer "B.SilkS")
		)
		(fp_line
			(start -4.713732 -4.672584)
			(end -3.778758 -3.775456)
			(stroke
				(width 0.1)
				(type default)
			)
			(layer "B.SilkS")
		)
		(fp_line
			(start -4.713478 -0.112776)
			(end -5.046726 -0.432562)
			(stroke
				(width 0.1)
				(type default)
			)
			(layer "B.SilkS")
		)
		(fp_line
			(start -4.713478 -0.112776)
			(end -5.046726 -0.432562)
			(stroke
				(width 0.1)
				(type default)
			)
			(layer "B.SilkS")
		)
		(fp_line
			(start -4.713478 -0.112776)
			(end -4.795266 -0.133604)
			(stroke
				(width 0.1)
				(type default)
			)
			(layer "B.SilkS")
		)
		(fp_line
			(start -4.713478 -0.112776)
			(end -4.795266 -0.133604)
			(stroke
				(width 0.1)
				(type default)
			)
			(layer "B.SilkS")
		)
		(fp_line
			(start -4.690618 -4.70789)
			(end -3.76047 -3.815588)
			(stroke
				(width 0.1)
				(type default)
			)
			(layer "B.SilkS")
		)
		(fp_line
			(start -4.690618 -4.70789)
			(end -3.76047 -3.815588)
			(stroke
				(width 0.1)
				(type default)
			)
			(layer "B.SilkS")
		)
		(fp_line
			(start -4.663186 -4.739386)
			(end -3.741928 -3.85572)
			(stroke
				(width 0.1)
				(type default)
			)
			(layer "B.SilkS")
		)
		(fp_line
			(start -4.663186 -4.739386)
			(end -3.741928 -3.85572)
			(stroke
				(width 0.1)
				(type default)
			)
			(layer "B.SilkS")
		)
		(fp_line
			(start -4.635246 -4.770374)
			(end -3.723386 -3.895598)
			(stroke
				(width 0.1)
				(type default)
			)
			(layer "B.SilkS")
		)
		(fp_line
			(start -4.635246 -4.770374)
			(end -3.723386 -3.895598)
			(stroke
				(width 0.1)
				(type default)
			)
			(layer "B.SilkS")
		)
		(fp_line
			(start -4.631182 -0.091948)
			(end -5.012182 -0.456946)
			(stroke
				(width 0.1)
				(type default)
			)
			(layer "B.SilkS")
		)
		(fp_line
			(start -4.631182 -0.091948)
			(end -5.012182 -0.456946)
			(stroke
				(width 0.1)
				(type default)
			)
			(layer "B.SilkS")
		)
		(fp_line
			(start -4.631182 -0.091948)
			(end -4.713478 -0.112776)
			(stroke
				(width 0.1)
				(type default)
			)
			(layer "B.SilkS")
		)
		(fp_line
			(start -4.631182 -0.091948)
			(end -4.713478 -0.112776)
			(stroke
				(width 0.1)
				(type default)
			)
			(layer "B.SilkS")
		)
		(fp_line
			(start -4.60756 -4.801362)
			(end -3.704844 -3.935476)
			(stroke
				(width 0.1)
				(type default)
			)
			(layer "B.SilkS")
		)
		(fp_line
			(start -4.60756 -4.801362)
			(end -3.704844 -3.935476)
			(stroke
				(width 0.1)
				(type default)
			)
			(layer "B.SilkS")
		)
		(fp_line
			(start -4.57962 -4.83235)
			(end -3.686556 -3.975608)
			(stroke
				(width 0.1)
				(type default)
			)
			(layer "B.SilkS")
		)
		(fp_line
			(start -4.57962 -4.83235)
			(end -3.686556 -3.975608)
			(stroke
				(width 0.1)
				(type default)
			)
			(layer "B.SilkS")
		)
		(fp_line
			(start -4.561586 -0.08255)
			(end -4.977384 -0.481584)
			(stroke
				(width 0.1)
				(type default)
			)
			(layer "B.SilkS")
		)
		(fp_line
			(start -4.561586 -0.08255)
			(end -4.977384 -0.481584)
			(stroke
				(width 0.1)
				(type default)
			)
			(layer "B.SilkS")
		)
		(fp_line
			(start -4.55168 -4.863338)
			(end -3.664712 -4.012438)
			(stroke
				(width 0.1)
				(type default)
			)
			(layer "B.SilkS")
		)
		(fp_line
			(start -4.55168 -4.863338)
			(end -3.664712 -4.012438)
			(stroke
				(width 0.1)
				(type default)
			)
			(layer "B.SilkS")
		)
		(fp_line
			(start -4.52374 -4.894072)
			(end -3.640328 -4.046728)
			(stroke
				(width 0.1)
				(type default)
			)
			(layer "B.SilkS")
		)
		(fp_line
			(start -4.52374 -4.894072)
			(end -3.640328 -4.046728)
			(stroke
				(width 0.1)
				(type default)
			)
			(layer "B.SilkS")
		)
		(fp_line
			(start -4.519168 -0.099822)
			(end -4.94284 -0.506222)
			(stroke
				(width 0.1)
				(type default)
			)
			(layer "B.SilkS")
		)
		(fp_line
			(start -4.519168 -0.099822)
			(end -4.94284 -0.506222)
			(stroke
				(width 0.1)
				(type default)
			)
			(layer "B.SilkS")
		)
		(fp_line
			(start -4.4958 -4.92506)
			(end -3.615944 -4.081018)
			(stroke
				(width 0.1)
				(type default)
			)
			(layer "B.SilkS")
		)
		(fp_line
			(start -4.4958 -4.92506)
			(end -3.615944 -4.081018)
			(stroke
				(width 0.1)
				(type default)
			)
			(layer "B.SilkS")
		)
		(fp_line
			(start -4.476496 -0.116332)
			(end -4.908296 -0.530352)
			(stroke
				(width 0.1)
				(type default)
			)
			(layer "B.SilkS")
		)
		(fp_line
			(start -4.476496 -0.116332)
			(end -4.908296 -0.530352)
			(stroke
				(width 0.1)
				(type default)
			)
			(layer "B.SilkS")
		)
		(fp_line
			(start -4.46532 -4.953508)
			(end -3.59156 -4.115308)
			(stroke
				(width 0.1)
				(type default)
			)
			(layer "B.SilkS")
		)
		(fp_line
			(start -4.46532 -4.953508)
			(end -3.59156 -4.115308)
			(stroke
				(width 0.1)
				(type default)
			)
			(layer "B.SilkS")
		)
		(fp_line
			(start -4.433824 -0.133604)
			(end -4.873752 -0.555244)
			(stroke
				(width 0.1)
				(type default)
			)
			(layer "B.SilkS")
		)
		(fp_line
			(start -4.433824 -0.133604)
			(end -4.873752 -0.555244)
			(stroke
				(width 0.1)
				(type default)
			)
			(layer "B.SilkS")
		)
		(fp_line
			(start -4.43357 -4.98094)
			(end -3.567176 -4.149598)
			(stroke
				(width 0.1)
				(type default)
			)
			(layer "B.SilkS")
		)
		(fp_line
			(start -4.43357 -4.98094)
			(end -3.567176 -4.149598)
			(stroke
				(width 0.1)
				(type default)
			)
			(layer "B.SilkS")
		)
		(fp_line
			(start -4.401566 -5.008118)
			(end -3.542792 -4.183888)
			(stroke
				(width 0.1)
				(type default)
			)
			(layer "B.SilkS")
		)
		(fp_line
			(start -4.401566 -5.008118)
			(end -3.542792 -4.183888)
			(stroke
				(width 0.1)
				(type default)
			)
			(layer "B.SilkS")
		)
		(fp_line
			(start -4.391406 -0.150114)
			(end -4.838954 -0.579628)
			(stroke
				(width 0.1)
				(type default)
			)
			(layer "B.SilkS")
		)
		(fp_line
			(start -4.391406 -0.150114)
			(end -4.838954 -0.579628)
			(stroke
				(width 0.1)
				(type default)
			)
			(layer "B.SilkS")
		)
		(fp_line
			(start -4.37007 -5.035296)
			(end -3.518408 -4.218432)
			(stroke
				(width 0.1)
				(type default)
			)
			(layer "B.SilkS")
		)
		(fp_line
			(start -4.37007 -5.035296)
			(end -3.518408 -4.218432)
			(stroke
				(width 0.1)
				(type default)
			)
			(layer "B.SilkS")
		)
		(fp_line
			(start -4.348734 -0.166878)
			(end -4.80441 -0.604266)
			(stroke
				(width 0.1)
				(type default)
			)
			(layer "B.SilkS")
		)
		(fp_line
			(start -4.348734 -0.166878)
			(end -4.80441 -0.604266)
			(stroke
				(width 0.1)
				(type default)
			)
			(layer "B.SilkS")
		)
		(fp_line
			(start -4.338066 -5.06222)
			(end -3.488436 -4.247388)
			(stroke
				(width 0.1)
				(type default)
			)
			(layer "B.SilkS")
		)
		(fp_line
			(start -4.338066 -5.06222)
			(end -3.488436 -4.247388)
			(stroke
				(width 0.1)
				(type default)
			)
			(layer "B.SilkS")
		)
		(fp_line
			(start -4.306316 -5.089398)
			(end -3.45821 -4.275836)
			(stroke
				(width 0.1)
				(type default)
			)
			(layer "B.SilkS")
		)
		(fp_line
			(start -4.306316 -5.089398)
			(end -3.45821 -4.275836)
			(stroke
				(width 0.1)
				(type default)
			)
			(layer "B.SilkS")
		)
		(fp_line
			(start -4.306062 -0.183896)
			(end -4.769866 -0.62865)
			(stroke
				(width 0.1)
				(type default)
			)
			(layer "B.SilkS")
		)
		(fp_line
			(start -4.306062 -0.183896)
			(end -4.769866 -0.62865)
			(stroke
				(width 0.1)
				(type default)
			)
			(layer "B.SilkS")
		)
		(fp_line
			(start -4.272534 -5.115052)
			(end -3.427984 -4.304792)
			(stroke
				(width 0.1)
				(type default)
			)
			(layer "B.SilkS")
		)
		(fp_line
			(start -4.272534 -5.115052)
			(end -3.427984 -4.304792)
			(stroke
				(width 0.1)
				(type default)
			)
			(layer "B.SilkS")
		)
		(fp_line
			(start -4.26339 -0.200406)
			(end -4.735068 -0.653034)
			(stroke
				(width 0.1)
				(type default)
			)
			(layer "B.SilkS")
		)
		(fp_line
			(start -4.26339 -0.200406)
			(end -4.735068 -0.653034)
			(stroke
				(width 0.1)
				(type default)
			)
			(layer "B.SilkS")
		)
		(fp_line
			(start -4.237736 -5.139182)
			(end -3.397504 -4.33324)
			(stroke
				(width 0.1)
				(type default)
			)
			(layer "B.SilkS")
		)
		(fp_line
			(start -4.237736 -5.139182)
			(end -3.397504 -4.33324)
			(stroke
				(width 0.1)
				(type default)
			)
			(layer "B.SilkS")
		)
		(fp_line
			(start -4.220718 -0.217678)
			(end -4.700524 -0.677926)
			(stroke
				(width 0.1)
				(type default)
			)
			(layer "B.SilkS")
		)
		(fp_line
			(start -4.220718 -0.217678)
			(end -4.700524 -0.677926)
			(stroke
				(width 0.1)
				(type default)
			)
			(layer "B.SilkS")
		)
		(fp_line
			(start -4.202938 -5.163312)
			(end -3.367532 -4.362196)
			(stroke
				(width 0.1)
				(type default)
			)
			(layer "B.SilkS")
		)
		(fp_line
			(start -4.202938 -5.163312)
			(end -3.367532 -4.362196)
			(stroke
				(width 0.1)
				(type default)
			)
			(layer "B.SilkS")
		)
		(fp_line
			(start -4.181856 -1.045718)
			(end -3.576828 -0.465582)
			(stroke
				(width 0.1)
				(type default)
			)
			(layer "B.SilkS")
		)
		(fp_line
			(start -4.181856 -1.045718)
			(end -3.576828 -0.465582)
			(stroke
				(width 0.1)
				(type default)
			)
			(layer "B.SilkS")
		)
		(fp_line
			(start -4.178046 -0.234188)
			(end -4.66598 -0.702056)
			(stroke
				(width 0.1)
				(type default)
			)
			(layer "B.SilkS")
		)
		(fp_line
			(start -4.178046 -0.234188)
			(end -4.66598 -0.702056)
			(stroke
				(width 0.1)
				(type default)
			)
			(layer "B.SilkS")
		)
		(fp_line
			(start -4.16814 -5.187696)
			(end -3.337052 -4.390644)
			(stroke
				(width 0.1)
				(type default)
			)
			(layer "B.SilkS")
		)
		(fp_line
			(start -4.16814 -5.187696)
			(end -3.337052 -4.390644)
			(stroke
				(width 0.1)
				(type default)
			)
			(layer "B.SilkS")
		)
		(fp_line
			(start -4.135374 -0.250698)
			(end -4.631436 -0.726694)
			(stroke
				(width 0.1)
				(type default)
			)
			(layer "B.SilkS")
		)
		(fp_line
			(start -4.135374 -0.250698)
			(end -4.631436 -0.726694)
			(stroke
				(width 0.1)
				(type default)
			)
			(layer "B.SilkS")
		)
		(fp_line
			(start -4.133088 -5.21208)
			(end -3.303524 -4.416044)
			(stroke
				(width 0.1)
				(type default)
			)
			(layer "B.SilkS")
		)
		(fp_line
			(start -4.133088 -5.21208)
			(end -3.303524 -4.416044)
			(stroke
				(width 0.1)
				(type default)
			)
			(layer "B.SilkS")
		)
		(fp_line
			(start -4.09829 -5.23621)
			(end -3.266948 -4.438904)
			(stroke
				(width 0.1)
				(type default)
			)
			(layer "B.SilkS")
		)
		(fp_line
			(start -4.09829 -5.23621)
			(end -3.266948 -4.438904)
			(stroke
				(width 0.1)
				(type default)
			)
			(layer "B.SilkS")
		)
		(fp_line
			(start -4.092448 -0.267462)
			(end -4.596892 -0.751332)
			(stroke
				(width 0.1)
				(type default)
			)
			(layer "B.SilkS")
		)
		(fp_line
			(start -4.092448 -0.267462)
			(end -4.596892 -0.751332)
			(stroke
				(width 0.1)
				(type default)
			)
			(layer "B.SilkS")
		)
		(fp_line
			(start -4.060952 -5.258054)
			(end -3.230372 -4.461256)
			(stroke
				(width 0.1)
				(type default)
			)
			(layer "B.SilkS")
		)
		(fp_line
			(start -4.060952 -5.258054)
			(end -3.230372 -4.461256)
			(stroke
				(width 0.1)
				(type default)
			)
			(layer "B.SilkS")
		)
		(fp_line
			(start -4.049776 -0.284226)
			(end -4.562094 -0.775716)
			(stroke
				(width 0.1)
				(type default)
			)
			(layer "B.SilkS")
		)
		(fp_line
			(start -4.049776 -0.284226)
			(end -4.562094 -0.775716)
			(stroke
				(width 0.1)
				(type default)
			)
			(layer "B.SilkS")
		)
		(fp_line
			(start -4.022852 -5.27939)
			(end -3.193796 -4.484116)
			(stroke
				(width 0.1)
				(type default)
			)
			(layer "B.SilkS")
		)
		(fp_line
			(start -4.022852 -5.27939)
			(end -3.193796 -4.484116)
			(stroke
				(width 0.1)
				(type default)
			)
			(layer "B.SilkS")
		)
		(fp_line
			(start -4.00685 -0.30099)
			(end -4.52755 -0.800608)
			(stroke
				(width 0.1)
				(type default)
			)
			(layer "B.SilkS")
		)
		(fp_line
			(start -4.00685 -0.30099)
			(end -4.52755 -0.800608)
			(stroke
				(width 0.1)
				(type default)
			)
			(layer "B.SilkS")
		)
		(fp_line
			(start -3.984752 -5.300472)
			(end -3.15722 -4.506722)
			(stroke
				(width 0.1)
				(type default)
			)
			(layer "B.SilkS")
		)
		(fp_line
			(start -3.984752 -5.300472)
			(end -3.15722 -4.506722)
			(stroke
				(width 0.1)
				(type default)
			)
			(layer "B.SilkS")
		)
		(fp_line
			(start -3.964178 -0.3175)
			(end -4.493006 -0.824738)
			(stroke
				(width 0.1)
				(type default)
			)
			(layer "B.SilkS")
		)
		(fp_line
			(start -3.964178 -0.3175)
			(end -4.493006 -0.824738)
			(stroke
				(width 0.1)
				(type default)
			)
			(layer "B.SilkS")
		)
		(fp_line
			(start -3.946652 -5.321808)
			(end -3.12039 -4.529074)
			(stroke
				(width 0.1)
				(type default)
			)
			(layer "B.SilkS")
		)
		(fp_line
			(start -3.946652 -5.321808)
			(end -3.12039 -4.529074)
			(stroke
				(width 0.1)
				(type default)
			)
			(layer "B.SilkS")
		)
		(fp_line
			(start -3.921252 -0.33401)
			(end -4.458462 -0.849376)
			(stroke
				(width 0.1)
				(type default)
			)
			(layer "B.SilkS")
		)
		(fp_line
			(start -3.921252 -0.33401)
			(end -4.458462 -0.849376)
			(stroke
				(width 0.1)
				(type default)
			)
			(layer "B.SilkS")
		)
		(fp_line
			(start -3.908552 -5.34289)
			(end -3.080766 -4.548886)
			(stroke
				(width 0.1)
				(type default)
			)
			(layer "B.SilkS")
		)
		(fp_line
			(start -3.908552 -5.34289)
			(end -3.080766 -4.548886)
			(stroke
				(width 0.1)
				(type default)
			)
			(layer "B.SilkS")
		)
		(fp_line
			(start -3.878326 -0.35052)
			(end -4.423918 -0.874014)
			(stroke
				(width 0.1)
				(type default)
			)
			(layer "B.SilkS")
		)
		(fp_line
			(start -3.878326 -0.35052)
			(end -4.423918 -0.874014)
			(stroke
				(width 0.1)
				(type default)
			)
			(layer "B.SilkS")
		)
		(fp_line
			(start -3.870198 -5.363464)
			(end -3.036824 -4.56438)
			(stroke
				(width 0.1)
				(type default)
			)
			(layer "B.SilkS")
		)
		(fp_line
			(start -3.870198 -5.363464)
			(end -3.036824 -4.56438)
			(stroke
				(width 0.1)
				(type default)
			)
			(layer "B.SilkS")
		)
		(fp_line
			(start -3.8354 -0.36703)
			(end -4.389374 -0.898398)
			(stroke
				(width 0.1)
				(type default)
			)
			(layer "B.SilkS")
		)
		(fp_line
			(start -3.8354 -0.36703)
			(end -4.389374 -0.898398)
			(stroke
				(width 0.1)
				(type default)
			)
			(layer "B.SilkS")
		)
		(fp_line
			(start -3.828288 -5.381498)
			(end -2.992628 -4.57962)
			(stroke
				(width 0.1)
				(type default)
			)
			(layer "B.SilkS")
		)
		(fp_line
			(start -3.828288 -5.381498)
			(end -2.992628 -4.57962)
			(stroke
				(width 0.1)
				(type default)
			)
			(layer "B.SilkS")
		)
		(fp_line
			(start -3.792474 -0.383794)
			(end -4.35483 -0.923036)
			(stroke
				(width 0.1)
				(type default)
			)
			(layer "B.SilkS")
		)
		(fp_line
			(start -3.792474 -0.383794)
			(end -4.35483 -0.923036)
			(stroke
				(width 0.1)
				(type default)
			)
			(layer "B.SilkS")
		)
		(fp_line
			(start -3.786886 -5.399278)
			(end -2.948432 -4.595114)
			(stroke
				(width 0.1)
				(type default)
			)
			(layer "B.SilkS")
		)
		(fp_line
			(start -3.786886 -5.399278)
			(end -2.948432 -4.595114)
			(stroke
				(width 0.1)
				(type default)
			)
			(layer "B.SilkS")
		)
		(fp_line
			(start -3.749548 -0.400304)
			(end -4.320286 -0.947674)
			(stroke
				(width 0.1)
				(type default)
			)
			(layer "B.SilkS")
		)
		(fp_line
			(start -3.749548 -0.400304)
			(end -4.320286 -0.947674)
			(stroke
				(width 0.1)
				(type default)
			)
			(layer "B.SilkS")
		)
		(fp_line
			(start -3.745484 -5.417058)
			(end -2.90449 -4.610354)
			(stroke
				(width 0.1)
				(type default)
			)
			(layer "B.SilkS")
		)
		(fp_line
			(start -3.745484 -5.417058)
			(end -2.90449 -4.610354)
			(stroke
				(width 0.1)
				(type default)
			)
			(layer "B.SilkS")
		)
		(fp_line
			(start -3.706368 -0.416814)
			(end -4.285488 -0.972058)
			(stroke
				(width 0.1)
				(type default)
			)
			(layer "B.SilkS")
		)
		(fp_line
			(start -3.706368 -0.416814)
			(end -4.285488 -0.972058)
			(stroke
				(width 0.1)
				(type default)
			)
			(layer "B.SilkS")
		)
		(fp_line
			(start -3.703828 -5.435092)
			(end -2.860548 -4.626102)
			(stroke
				(width 0.1)
				(type default)
			)
			(layer "B.SilkS")
		)
		(fp_line
			(start -3.703828 -5.435092)
			(end -2.860548 -4.626102)
			(stroke
				(width 0.1)
				(type default)
			)
			(layer "B.SilkS")
		)
		(fp_line
			(start -3.663442 -0.43307)
			(end -4.250944 -0.996696)
			(stroke
				(width 0.1)
				(type default)
			)
			(layer "B.SilkS")
		)
		(fp_line
			(start -3.663442 -0.43307)
			(end -4.250944 -0.996696)
			(stroke
				(width 0.1)
				(type default)
			)
			(layer "B.SilkS")
		)
		(fp_line
			(start -3.662426 -5.452872)
			(end -2.808478 -4.633976)
			(stroke
				(width 0.1)
				(type default)
			)
			(layer "B.SilkS")
		)
		(fp_line
			(start -3.662426 -5.452872)
			(end -2.808478 -4.633976)
			(stroke
				(width 0.1)
				(type default)
			)
			(layer "B.SilkS")
		)
		(fp_line
			(start -3.620008 -0.449072)
			(end -4.2164 -1.02108)
			(stroke
				(width 0.1)
				(type default)
			)
			(layer "B.SilkS")
		)
		(fp_line
			(start -3.620008 -0.449072)
			(end -4.2164 -1.02108)
			(stroke
				(width 0.1)
				(type default)
			)
			(layer "B.SilkS")
		)
		(fp_line
			(start -3.61823 -5.468366)
			(end -2.75463 -4.639818)
			(stroke
				(width 0.1)
				(type default)
			)
			(layer "B.SilkS")
		)
		(fp_line
			(start -3.61823 -5.468366)
			(end -2.75463 -4.639818)
			(stroke
				(width 0.1)
				(type default)
			)
			(layer "B.SilkS")
		)
		(fp_line
			(start -3.573018 -5.482844)
			(end -2.700782 -4.645914)
			(stroke
				(width 0.1)
				(type default)
			)
			(layer "B.SilkS")
		)
		(fp_line
			(start -3.573018 -5.482844)
			(end -2.700782 -4.645914)
			(stroke
				(width 0.1)
				(type default)
			)
			(layer "B.SilkS")
		)
		(fp_line
			(start -3.533648 -0.481838)
			(end -4.147312 -1.070356)
			(stroke
				(width 0.1)
				(type default)
			)
			(layer "B.SilkS")
		)
		(fp_line
			(start -3.533648 -0.481838)
			(end -4.147312 -1.070356)
			(stroke
				(width 0.1)
				(type default)
			)
			(layer "B.SilkS")
		)
		(fp_line
			(start -3.527806 -5.497068)
			(end -2.647188 -4.652264)
			(stroke
				(width 0.1)
				(type default)
			)
			(layer "B.SilkS")
		)
		(fp_line
			(start -3.527806 -5.497068)
			(end -2.647188 -4.652264)
			(stroke
				(width 0.1)
				(type default)
			)
			(layer "B.SilkS")
		)
		(fp_line
			(start -3.490468 -0.498094)
			(end -4.77901 -1.734058)
			(stroke
				(width 0.1)
				(type default)
			)
			(layer "B.SilkS")
		)
		(fp_line
			(start -3.490468 -0.498094)
			(end -4.77901 -1.734058)
			(stroke
				(width 0.1)
				(type default)
			)
			(layer "B.SilkS")
		)
		(fp_line
			(start -3.482594 -5.511292)
			(end -2.593086 -4.658106)
			(stroke
				(width 0.1)
				(type default)
			)
			(layer "B.SilkS")
		)
		(fp_line
			(start -3.482594 -5.511292)
			(end -2.593086 -4.658106)
			(stroke
				(width 0.1)
				(type default)
			)
			(layer "B.SilkS")
		)
		(fp_line
			(start -3.447034 -0.513842)
			(end -4.85267 -1.862582)
			(stroke
				(width 0.1)
				(type default)
			)
			(layer "B.SilkS")
		)
		(fp_line
			(start -3.447034 -0.513842)
			(end -4.85267 -1.862582)
			(stroke
				(width 0.1)
				(type default)
			)
			(layer "B.SilkS")
		)
		(fp_line
			(start -3.437382 -5.52577)
			(end -2.526538 -4.65201)
			(stroke
				(width 0.1)
				(type default)
			)
			(layer "B.SilkS")
		)
		(fp_line
			(start -3.437382 -5.52577)
			(end -2.526538 -4.65201)
			(stroke
				(width 0.1)
				(type default)
			)
			(layer "B.SilkS")
		)
		(fp_line
			(start -3.4036 -0.530098)
			(end -4.915916 -1.980946)
			(stroke
				(width 0.1)
				(type default)
			)
			(layer "B.SilkS")
		)
		(fp_line
			(start -3.4036 -0.530098)
			(end -4.915916 -1.980946)
			(stroke
				(width 0.1)
				(type default)
			)
			(layer "B.SilkS")
		)
		(fp_line
			(start -3.390392 -5.53847)
			(end -2.458212 -4.644136)
			(stroke
				(width 0.1)
				(type default)
			)
			(layer "B.SilkS")
		)
		(fp_line
			(start -3.390392 -5.53847)
			(end -2.458212 -4.644136)
			(stroke
				(width 0.1)
				(type default)
			)
			(layer "B.SilkS")
		)
		(fp_line
			(start -3.359912 -0.545846)
			(end -4.953254 -2.074418)
			(stroke
				(width 0.1)
				(type default)
			)
			(layer "B.SilkS")
		)
		(fp_line
			(start -3.359912 -0.545846)
			(end -4.953254 -2.074418)
			(stroke
				(width 0.1)
				(type default)
			)
			(layer "B.SilkS")
		)
		(fp_line
			(start -3.34137 -5.549138)
			(end -2.389632 -4.636262)
			(stroke
				(width 0.1)
				(type default)
			)
			(layer "B.SilkS")
		)
		(fp_line
			(start -3.34137 -5.549138)
			(end -2.389632 -4.636262)
			(stroke
				(width 0.1)
				(type default)
			)
			(layer "B.SilkS")
		)
		(fp_line
			(start -3.316224 -0.561848)
			(end -4.990338 -2.167636)
			(stroke
				(width 0.1)
				(type default)
			)
			(layer "B.SilkS")
		)
		(fp_line
			(start -3.316224 -0.561848)
			(end -4.990338 -2.167636)
			(stroke
				(width 0.1)
				(type default)
			)
			(layer "B.SilkS")
		)
		(fp_line
			(start -3.292094 -5.559552)
			(end -2.310892 -4.618228)
			(stroke
				(width 0.1)
				(type default)
			)
			(layer "B.SilkS")
		)
		(fp_line
			(start -3.292094 -5.559552)
			(end -2.310892 -4.618228)
			(stroke
				(width 0.1)
				(type default)
			)
			(layer "B.SilkS")
		)
		(fp_line
			(start -3.272536 -0.577342)
			(end -5.02285 -2.256536)
			(stroke
				(width 0.1)
				(type default)
			)
			(layer "B.SilkS")
		)
		(fp_line
			(start -3.272536 -0.577342)
			(end -5.02285 -2.256536)
			(stroke
				(width 0.1)
				(type default)
			)
			(layer "B.SilkS")
		)
		(fp_line
			(start -3.243072 -5.57022)
			(end -2.217166 -4.586224)
			(stroke
				(width 0.1)
				(type default)
			)
			(layer "B.SilkS")
		)
		(fp_line
			(start -3.243072 -5.57022)
			(end -2.217166 -4.586224)
			(stroke
				(width 0.1)
				(type default)
			)
			(layer "B.SilkS")
		)
		(fp_line
			(start -3.22834 -0.592836)
			(end -5.042408 -2.33299)
			(stroke
				(width 0.1)
				(type default)
			)
			(layer "B.SilkS")
		)
		(fp_line
			(start -3.22834 -0.592836)
			(end -5.042408 -2.33299)
			(stroke
				(width 0.1)
				(type default)
			)
			(layer "B.SilkS")
		)
		(fp_line
			(start -3.19405 -5.580888)
			(end -2.123694 -4.553966)
			(stroke
				(width 0.1)
				(type default)
			)
			(layer "B.SilkS")
		)
		(fp_line
			(start -3.19405 -5.580888)
			(end -2.123694 -4.553966)
			(stroke
				(width 0.1)
				(type default)
			)
			(layer "B.SilkS")
		)
		(fp_line
			(start -3.184144 -0.60833)
			(end -5.061966 -2.409698)
			(stroke
				(width 0.1)
				(type default)
			)
			(layer "B.SilkS")
		)
		(fp_line
			(start -3.184144 -0.60833)
			(end -5.061966 -2.409698)
			(stroke
				(width 0.1)
				(type default)
			)
			(layer "B.SilkS")
		)
		(fp_line
			(start -3.14325 -5.589778)
			(end -1.972818 -4.467098)
			(stroke
				(width 0.1)
				(type default)
			)
			(layer "B.SilkS")
		)
		(fp_line
			(start -3.14325 -5.589778)
			(end -1.972818 -4.467098)
			(stroke
				(width 0.1)
				(type default)
			)
			(layer "B.SilkS")
		)
		(fp_line
			(start -3.13944 -0.622808)
			(end -5.081524 -2.485898)
			(stroke
				(width 0.1)
				(type default)
			)
			(layer "B.SilkS")
		)
		(fp_line
			(start -3.13944 -0.622808)
			(end -5.081524 -2.485898)
			(stroke
				(width 0.1)
				(type default)
			)
			(layer "B.SilkS")
		)
		(fp_line
			(start -3.094482 -0.637286)
			(end -5.09905 -2.560574)
			(stroke
				(width 0.1)
				(type default)
			)
			(layer "B.SilkS")
		)
		(fp_line
			(start -3.094482 -0.637286)
			(end -5.09905 -2.560574)
			(stroke
				(width 0.1)
				(type default)
			)
			(layer "B.SilkS")
		)
		(fp_line
			(start -3.089656 -5.596382)
			(end -0.080264 -2.709418)
			(stroke
				(width 0.1)
				(type default)
			)
			(layer "B.SilkS")
		)
		(fp_line
			(start -3.089656 -5.596382)
			(end -0.080264 -2.709418)
			(stroke
				(width 0.1)
				(type default)
			)
			(layer "B.SilkS")
		)
		(fp_line
			(start -3.048 -0.651002)
			(end -5.108194 -2.627122)
			(stroke
				(width 0.1)
				(type default)
			)
			(layer "B.SilkS")
		)
		(fp_line
			(start -3.048 -0.651002)
			(end -5.108194 -2.627122)
			(stroke
				(width 0.1)
				(type default)
			)
			(layer "B.SilkS")
		)
		(fp_line
			(start -3.03657 -5.602732)
			(end -0.073914 -2.76098)
			(stroke
				(width 0.1)
				(type default)
			)
			(layer "B.SilkS")
		)
		(fp_line
			(start -3.03657 -5.602732)
			(end -0.073914 -2.76098)
			(stroke
				(width 0.1)
				(type default)
			)
			(layer "B.SilkS")
		)
		(fp_line
			(start -2.9972 -0.659638)
			(end -5.117592 -2.69367)
			(stroke
				(width 0.1)
				(type default)
			)
			(layer "B.SilkS")
		)
		(fp_line
			(start -2.9972 -0.659638)
			(end -5.117592 -2.69367)
			(stroke
				(width 0.1)
				(type default)
			)
			(layer "B.SilkS")
		)
		(fp_line
			(start -2.98323 -5.609336)
			(end -0.067818 -2.812542)
			(stroke
				(width 0.1)
				(type default)
			)
			(layer "B.SilkS")
		)
		(fp_line
			(start -2.98323 -5.609336)
			(end -0.067818 -2.812542)
			(stroke
				(width 0.1)
				(type default)
			)
			(layer "B.SilkS")
		)
		(fp_line
			(start -2.93878 -0.661416)
			(end -5.126736 -2.760218)
			(stroke
				(width 0.1)
				(type default)
			)
			(layer "B.SilkS")
		)
		(fp_line
			(start -2.93878 -0.661416)
			(end -5.126736 -2.760218)
			(stroke
				(width 0.1)
				(type default)
			)
			(layer "B.SilkS")
		)
		(fp_line
			(start -2.92989 -5.616194)
			(end -0.061468 -2.864358)
			(stroke
				(width 0.1)
				(type default)
			)
			(layer "B.SilkS")
		)
		(fp_line
			(start -2.92989 -5.616194)
			(end -0.061468 -2.864358)
			(stroke
				(width 0.1)
				(type default)
			)
			(layer "B.SilkS")
		)
		(fp_line
			(start -2.88036 -0.662686)
			(end -5.13588 -2.826512)
			(stroke
				(width 0.1)
				(type default)
			)
			(layer "B.SilkS")
		)
		(fp_line
			(start -2.88036 -0.662686)
			(end -5.13588 -2.826512)
			(stroke
				(width 0.1)
				(type default)
			)
			(layer "B.SilkS")
		)
		(fp_line
			(start -2.87401 -5.620258)
			(end -0.054864 -2.91592)
			(stroke
				(width 0.1)
				(type default)
			)
			(layer "B.SilkS")
		)
		(fp_line
			(start -2.87401 -5.620258)
			(end -0.054864 -2.91592)
			(stroke
				(width 0.1)
				(type default)
			)
			(layer "B.SilkS")
		)
		(fp_line
			(start -2.82194 -0.664718)
			(end -5.145024 -2.89306)
			(stroke
				(width 0.1)
				(type default)
			)
			(layer "B.SilkS")
		)
		(fp_line
			(start -2.82194 -0.664718)
			(end -5.145024 -2.89306)
			(stroke
				(width 0.1)
				(type default)
			)
			(layer "B.SilkS")
		)
		(fp_line
			(start -2.816098 -5.622544)
			(end -0.051562 -2.970276)
			(stroke
				(width 0.1)
				(type default)
			)
			(layer "B.SilkS")
		)
		(fp_line
			(start -2.816098 -5.622544)
			(end -0.051562 -2.970276)
			(stroke
				(width 0.1)
				(type default)
			)
			(layer "B.SilkS")
		)
		(fp_line
			(start -2.76352 -0.666242)
			(end -5.14731 -2.953258)
			(stroke
				(width 0.1)
				(type default)
			)
			(layer "B.SilkS")
		)
		(fp_line
			(start -2.76352 -0.666242)
			(end -5.14731 -2.953258)
			(stroke
				(width 0.1)
				(type default)
			)
			(layer "B.SilkS")
		)
		(fp_line
			(start -2.75844 -5.62483)
			(end -0.048006 -3.024632)
			(stroke
				(width 0.1)
				(type default)
			)
			(layer "B.SilkS")
		)
		(fp_line
			(start -2.75844 -5.62483)
			(end -0.048006 -3.024632)
			(stroke
				(width 0.1)
				(type default)
			)
			(layer "B.SilkS")
		)
		(fp_line
			(start -2.704846 -0.66802)
			(end -5.14985 -3.013202)
			(stroke
				(width 0.1)
				(type default)
			)
			(layer "B.SilkS")
		)
		(fp_line
			(start -2.704846 -0.66802)
			(end -5.14985 -3.013202)
			(stroke
				(width 0.1)
				(type default)
			)
			(layer "B.SilkS")
		)
		(fp_line
			(start -2.700528 -5.626862)
			(end -0.04445 -3.078734)
			(stroke
				(width 0.1)
				(type default)
			)
			(layer "B.SilkS")
		)
		(fp_line
			(start -2.700528 -5.626862)
			(end -0.04445 -3.078734)
			(stroke
				(width 0.1)
				(type default)
			)
			(layer "B.SilkS")
		)
		(fp_line
			(start -2.646426 -0.669544)
			(end -5.15239 -3.073146)
			(stroke
				(width 0.1)
				(type default)
			)
			(layer "B.SilkS")
		)
		(fp_line
			(start -2.646426 -0.669544)
			(end -5.15239 -3.073146)
			(stroke
				(width 0.1)
				(type default)
			)
			(layer "B.SilkS")
		)
		(fp_line
			(start -2.64287 -5.629148)
			(end -0.042672 -3.135122)
			(stroke
				(width 0.1)
				(type default)
			)
			(layer "B.SilkS")
		)
		(fp_line
			(start -2.64287 -5.629148)
			(end -0.042672 -3.135122)
			(stroke
				(width 0.1)
				(type default)
			)
			(layer "B.SilkS")
		)
		(fp_line
			(start -2.589276 -0.672338)
			(end -5.15493 -3.133598)
			(stroke
				(width 0.1)
				(type default)
			)
			(layer "B.SilkS")
		)
		(fp_line
			(start -2.589276 -0.672338)
			(end -5.15493 -3.133598)
			(stroke
				(width 0.1)
				(type default)
			)
			(layer "B.SilkS")
		)
		(fp_line
			(start -2.580386 -5.626862)
			(end -0.041656 -3.19151)
			(stroke
				(width 0.1)
				(type default)
			)
			(layer "B.SilkS")
		)
		(fp_line
			(start -2.580386 -5.626862)
			(end -0.041656 -3.19151)
			(stroke
				(width 0.1)
				(type default)
			)
			(layer "B.SilkS")
		)
		(fp_line
			(start -2.534666 -0.677672)
			(end -5.15747 -3.193796)
			(stroke
				(width 0.1)
				(type default)
			)
			(layer "B.SilkS")
		)
		(fp_line
			(start -2.534666 -0.677672)
			(end -5.15747 -3.193796)
			(stroke
				(width 0.1)
				(type default)
			)
			(layer "B.SilkS")
		)
		(fp_line
			(start -2.517394 -5.624322)
			(end -0.042926 -3.250438)
			(stroke
				(width 0.1)
				(type default)
			)
			(layer "B.SilkS")
		)
		(fp_line
			(start -2.517394 -5.624322)
			(end -0.042926 -3.250438)
			(stroke
				(width 0.1)
				(type default)
			)
			(layer "B.SilkS")
		)
		(fp_line
			(start -2.479802 -0.682752)
			(end -5.16001 -3.25374)
			(stroke
				(width 0.1)
				(type default)
			)
			(layer "B.SilkS")
		)
		(fp_line
			(start -2.479802 -0.682752)
			(end -5.16001 -3.25374)
			(stroke
				(width 0.1)
				(type default)
			)
			(layer "B.SilkS")
		)
		(fp_line
			(start -2.454148 -5.621274)
			(end -0.04572 -3.31089)
			(stroke
				(width 0.1)
				(type default)
			)
			(layer "B.SilkS")
		)
		(fp_line
			(start -2.454148 -5.621274)
			(end -0.04572 -3.31089)
			(stroke
				(width 0.1)
				(type default)
			)
			(layer "B.SilkS")
		)
		(fp_line
			(start -2.424938 -0.687832)
			(end -5.158994 -3.310382)
			(stroke
				(width 0.1)
				(type default)
			)
			(layer "B.SilkS")
		)
		(fp_line
			(start -2.424938 -0.687832)
			(end -5.158994 -3.310382)
			(stroke
				(width 0.1)
				(type default)
			)
			(layer "B.SilkS")
		)
		(fp_line
			(start -2.390902 -5.61848)
			(end -0.048514 -3.371342)
			(stroke
				(width 0.1)
				(type default)
			)
			(layer "B.SilkS")
		)
		(fp_line
			(start -2.390902 -5.61848)
			(end -0.048514 -3.371342)
			(stroke
				(width 0.1)
				(type default)
			)
			(layer "B.SilkS")
		)
		(fp_line
			(start -2.370328 -0.693166)
			(end -5.156708 -3.366262)
			(stroke
				(width 0.1)
				(type default)
			)
			(layer "B.SilkS")
		)
		(fp_line
			(start -2.370328 -0.693166)
			(end -5.156708 -3.366262)
			(stroke
				(width 0.1)
				(type default)
			)
			(layer "B.SilkS")
		)
		(fp_line
			(start -2.32791 -5.615686)
			(end -0.051308 -3.431794)
			(stroke
				(width 0.1)
				(type default)
			)
			(layer "B.SilkS")
		)
		(fp_line
			(start -2.32791 -5.615686)
			(end -0.051308 -3.431794)
			(stroke
				(width 0.1)
				(type default)
			)
			(layer "B.SilkS")
		)
		(fp_line
			(start -2.315464 -0.698246)
			(end -5.152898 -3.42011)
			(stroke
				(width 0.1)
				(type default)
			)
			(layer "B.SilkS")
		)
		(fp_line
			(start -2.315464 -0.698246)
			(end -5.152898 -3.42011)
			(stroke
				(width 0.1)
				(type default)
			)
			(layer "B.SilkS")
		)
		(fp_line
			(start -2.2606 -0.703326)
			(end -5.147564 -3.472942)
			(stroke
				(width 0.1)
				(type default)
			)
			(layer "B.SilkS")
		)
		(fp_line
			(start -2.2606 -0.703326)
			(end -5.147564 -3.472942)
			(stroke
				(width 0.1)
				(type default)
			)
			(layer "B.SilkS")
		)
		(fp_line
			(start -2.257552 -5.60578)
			(end -0.059944 -3.49758)
			(stroke
				(width 0.1)
				(type default)
			)
			(layer "B.SilkS")
		)
		(fp_line
			(start -2.257552 -5.60578)
			(end -0.059944 -3.49758)
			(stroke
				(width 0.1)
				(type default)
			)
			(layer "B.SilkS")
		)
		(fp_line
			(start -2.208784 -0.710946)
			(end -5.142484 -3.52552)
			(stroke
				(width 0.1)
				(type default)
			)
			(layer "B.SilkS")
		)
		(fp_line
			(start -2.208784 -0.710946)
			(end -5.142484 -3.52552)
			(stroke
				(width 0.1)
				(type default)
			)
			(layer "B.SilkS")
		)
		(fp_line
			(start -2.18694 -5.595874)
			(end -0.069342 -3.564382)
			(stroke
				(width 0.1)
				(type default)
			)
			(layer "B.SilkS")
		)
		(fp_line
			(start -2.18694 -5.595874)
			(end -0.069342 -3.564382)
			(stroke
				(width 0.1)
				(type default)
			)
			(layer "B.SilkS")
		)
		(fp_line
			(start -2.116328 -5.585968)
			(end -0.07874 -3.631184)
			(stroke
				(width 0.1)
				(type default)
			)
			(layer "B.SilkS")
		)
		(fp_line
			(start -2.116328 -5.585968)
			(end -0.07874 -3.631184)
			(stroke
				(width 0.1)
				(type default)
			)
			(layer "B.SilkS")
		)
		(fp_line
			(start -2.10693 -0.72898)
			(end -3.238246 -1.814322)
			(stroke
				(width 0.1)
				(type default)
			)
			(layer "B.SilkS")
		)
		(fp_line
			(start -2.10693 -0.72898)
			(end -3.238246 -1.814322)
			(stroke
				(width 0.1)
				(type default)
			)
			(layer "B.SilkS")
		)
		(fp_line
			(start -2.05613 -0.73787)
			(end -3.094228 -1.733804)
			(stroke
				(width 0.1)
				(type default)
			)
			(layer "B.SilkS")
		)
		(fp_line
			(start -2.05613 -0.73787)
			(end -3.094228 -1.733804)
			(stroke
				(width 0.1)
				(type default)
			)
			(layer "B.SilkS")
		)
		(fp_line
			(start -2.04597 -5.576062)
			(end -0.092456 -3.70205)
			(stroke
				(width 0.1)
				(type default)
			)
			(layer "B.SilkS")
		)
		(fp_line
			(start -2.04597 -5.576062)
			(end -0.092456 -3.70205)
			(stroke
				(width 0.1)
				(type default)
			)
			(layer "B.SilkS")
		)
		(fp_line
			(start -2.00533 -0.74676)
			(end -3.000248 -1.701546)
			(stroke
				(width 0.1)
				(type default)
			)
			(layer "B.SilkS")
		)
		(fp_line
			(start -2.00533 -0.74676)
			(end -3.000248 -1.701546)
			(stroke
				(width 0.1)
				(type default)
			)
			(layer "B.SilkS")
		)
		(fp_line
			(start -1.966722 -5.557774)
			(end -0.110236 -3.776726)
			(stroke
				(width 0.1)
				(type default)
			)
			(layer "B.SilkS")
		)
		(fp_line
			(start -1.966722 -5.557774)
			(end -0.110236 -3.776726)
			(stroke
				(width 0.1)
				(type default)
			)
			(layer "B.SilkS")
		)
		(fp_line
			(start -1.954276 -0.75565)
			(end -2.906014 -1.66878)
			(stroke
				(width 0.1)
				(type default)
			)
			(layer "B.SilkS")
		)
		(fp_line
			(start -1.954276 -0.75565)
			(end -2.906014 -1.66878)
			(stroke
				(width 0.1)
				(type default)
			)
			(layer "B.SilkS")
		)
		(fp_line
			(start -1.90373 -0.765048)
			(end -2.828544 -1.65227)
			(stroke
				(width 0.1)
				(type default)
			)
			(layer "B.SilkS")
		)
		(fp_line
			(start -1.90373 -0.765048)
			(end -2.828544 -1.65227)
			(stroke
				(width 0.1)
				(type default)
			)
			(layer "B.SilkS")
		)
		(fp_line
			(start -1.886458 -5.538216)
			(end -0.128016 -3.851402)
			(stroke
				(width 0.1)
				(type default)
			)
			(layer "B.SilkS")
		)
		(fp_line
			(start -1.886458 -5.538216)
			(end -0.128016 -3.851402)
			(stroke
				(width 0.1)
				(type default)
			)
			(layer "B.SilkS")
		)
		(fp_line
			(start -1.856994 -0.777748)
			(end -2.760726 -1.64465)
			(stroke
				(width 0.1)
				(type default)
			)
			(layer "B.SilkS")
		)
		(fp_line
			(start -1.856994 -0.777748)
			(end -2.760726 -1.64465)
			(stroke
				(width 0.1)
				(type default)
			)
			(layer "B.SilkS")
		)
		(fp_line
			(start -1.810512 -0.790956)
			(end -2.692654 -1.637284)
			(stroke
				(width 0.1)
				(type default)
			)
			(layer "B.SilkS")
		)
		(fp_line
			(start -1.810512 -0.790956)
			(end -2.692654 -1.637284)
			(stroke
				(width 0.1)
				(type default)
			)
			(layer "B.SilkS")
		)
		(fp_line
			(start -1.805686 -5.518658)
			(end -0.1524 -3.932682)
			(stroke
				(width 0.1)
				(type default)
			)
			(layer "B.SilkS")
		)
		(fp_line
			(start -1.805686 -5.518658)
			(end -0.1524 -3.932682)
			(stroke
				(width 0.1)
				(type default)
			)
			(layer "B.SilkS")
		)
		(fp_line
			(start -1.763522 -0.803656)
			(end -2.624582 -1.629664)
			(stroke
				(width 0.1)
				(type default)
			)
			(layer "B.SilkS")
		)
		(fp_line
			(start -1.763522 -0.803656)
			(end -2.624582 -1.629664)
			(stroke
				(width 0.1)
				(type default)
			)
			(layer "B.SilkS")
		)
		(fp_line
			(start -1.717802 -5.492242)
			(end -0.181356 -4.018026)
			(stroke
				(width 0.1)
				(type default)
			)
			(layer "B.SilkS")
		)
		(fp_line
			(start -1.717802 -5.492242)
			(end -0.181356 -4.018026)
			(stroke
				(width 0.1)
				(type default)
			)
			(layer "B.SilkS")
		)
		(fp_line
			(start -1.716786 -0.816356)
			(end -2.56413 -1.62941)
			(stroke
				(width 0.1)
				(type default)
			)
			(layer "B.SilkS")
		)
		(fp_line
			(start -1.716786 -0.816356)
			(end -2.56413 -1.62941)
			(stroke
				(width 0.1)
				(type default)
			)
			(layer "B.SilkS")
		)
		(fp_line
			(start -1.67005 -0.829564)
			(end -2.511044 -1.636014)
			(stroke
				(width 0.1)
				(type default)
			)
			(layer "B.SilkS")
		)
		(fp_line
			(start -1.67005 -0.829564)
			(end -2.511044 -1.636014)
			(stroke
				(width 0.1)
				(type default)
			)
			(layer "B.SilkS")
		)
		(fp_line
			(start -1.623314 -0.842264)
			(end -2.457704 -1.642618)
			(stroke
				(width 0.1)
				(type default)
			)
			(layer "B.SilkS")
		)
		(fp_line
			(start -1.623314 -0.842264)
			(end -2.457704 -1.642618)
			(stroke
				(width 0.1)
				(type default)
			)
			(layer "B.SilkS")
		)
		(fp_line
			(start -1.62306 -5.458714)
			(end -0.211328 -4.10464)
			(stroke
				(width 0.1)
				(type default)
			)
			(layer "B.SilkS")
		)
		(fp_line
			(start -1.62306 -5.458714)
			(end -0.211328 -4.10464)
			(stroke
				(width 0.1)
				(type default)
			)
			(layer "B.SilkS")
		)
		(fp_line
			(start -1.578864 -0.857504)
			(end -2.404364 -1.649222)
			(stroke
				(width 0.1)
				(type default)
			)
			(layer "B.SilkS")
		)
		(fp_line
			(start -1.578864 -0.857504)
			(end -2.404364 -1.649222)
			(stroke
				(width 0.1)
				(type default)
			)
			(layer "B.SilkS")
		)
		(fp_line
			(start -1.536446 -0.874268)
			(end -2.351024 -1.655826)
			(stroke
				(width 0.1)
				(type default)
			)
			(layer "B.SilkS")
		)
		(fp_line
			(start -1.536446 -0.874268)
			(end -2.351024 -1.655826)
			(stroke
				(width 0.1)
				(type default)
			)
			(layer "B.SilkS")
		)
		(fp_line
			(start -1.52781 -5.425186)
			(end -0.256794 -4.205732)
			(stroke
				(width 0.1)
				(type default)
			)
			(layer "B.SilkS")
		)
		(fp_line
			(start -1.52781 -5.425186)
			(end -0.256794 -4.205732)
			(stroke
				(width 0.1)
				(type default)
			)
			(layer "B.SilkS")
		)
		(fp_line
			(start -1.493774 -0.891032)
			(end -2.301748 -1.66624)
			(stroke
				(width 0.1)
				(type default)
			)
			(layer "B.SilkS")
		)
		(fp_line
			(start -1.493774 -0.891032)
			(end -2.301748 -1.66624)
			(stroke
				(width 0.1)
				(type default)
			)
			(layer "B.SilkS")
		)
		(fp_line
			(start -1.451356 -0.90805)
			(end -2.259076 -1.68275)
			(stroke
				(width 0.1)
				(type default)
			)
			(layer "B.SilkS")
		)
		(fp_line
			(start -1.451356 -0.90805)
			(end -2.259076 -1.68275)
			(stroke
				(width 0.1)
				(type default)
			)
			(layer "B.SilkS")
		)
		(fp_line
			(start -1.41224 -5.3721)
			(end -0.302768 -4.307586)
			(stroke
				(width 0.1)
				(type default)
			)
			(layer "B.SilkS")
		)
		(fp_line
			(start -1.41224 -5.3721)
			(end -0.302768 -4.307586)
			(stroke
				(width 0.1)
				(type default)
			)
			(layer "B.SilkS")
		)
		(fp_line
			(start -1.408684 -0.924814)
			(end -2.21615 -1.699514)
			(stroke
				(width 0.1)
				(type default)
			)
			(layer "B.SilkS")
		)
		(fp_line
			(start -1.408684 -0.924814)
			(end -2.21615 -1.699514)
			(stroke
				(width 0.1)
				(type default)
			)
			(layer "B.SilkS")
		)
		(fp_line
			(start -1.366266 -0.941832)
			(end -2.173478 -1.716024)
			(stroke
				(width 0.1)
				(type default)
			)
			(layer "B.SilkS")
		)
		(fp_line
			(start -1.366266 -0.941832)
			(end -2.173478 -1.716024)
			(stroke
				(width 0.1)
				(type default)
			)
			(layer "B.SilkS")
		)
		(fp_line
			(start -1.323594 -0.958596)
			(end -2.130552 -1.732788)
			(stroke
				(width 0.1)
				(type default)
			)
			(layer "B.SilkS")
		)
		(fp_line
			(start -1.323594 -0.958596)
			(end -2.130552 -1.732788)
			(stroke
				(width 0.1)
				(type default)
			)
			(layer "B.SilkS")
		)
		(fp_line
			(start -1.293368 -5.315966)
			(end -0.37465 -4.434332)
			(stroke
				(width 0.1)
				(type default)
			)
			(layer "B.SilkS")
		)
		(fp_line
			(start -1.293368 -5.315966)
			(end -0.37465 -4.434332)
			(stroke
				(width 0.1)
				(type default)
			)
			(layer "B.SilkS")
		)
		(fp_line
			(start -1.28524 -0.979424)
			(end -2.087626 -1.749298)
			(stroke
				(width 0.1)
				(type default)
			)
			(layer "B.SilkS")
		)
		(fp_line
			(start -1.28524 -0.979424)
			(end -2.087626 -1.749298)
			(stroke
				(width 0.1)
				(type default)
			)
			(layer "B.SilkS")
		)
		(fp_line
			(start -1.246886 -1.000506)
			(end -2.048764 -1.769872)
			(stroke
				(width 0.1)
				(type default)
			)
			(layer "B.SilkS")
		)
		(fp_line
			(start -1.246886 -1.000506)
			(end -2.048764 -1.769872)
			(stroke
				(width 0.1)
				(type default)
			)
			(layer "B.SilkS")
		)
		(fp_line
			(start -1.208532 -1.021334)
			(end -2.013458 -1.793748)
			(stroke
				(width 0.1)
				(type default)
			)
			(layer "B.SilkS")
		)
		(fp_line
			(start -1.208532 -1.021334)
			(end -2.013458 -1.793748)
			(stroke
				(width 0.1)
				(type default)
			)
			(layer "B.SilkS")
		)
		(fp_line
			(start -1.170178 -1.042416)
			(end -1.978406 -1.817624)
			(stroke
				(width 0.1)
				(type default)
			)
			(layer "B.SilkS")
		)
		(fp_line
			(start -1.170178 -1.042416)
			(end -1.978406 -1.817624)
			(stroke
				(width 0.1)
				(type default)
			)
			(layer "B.SilkS")
		)
		(fp_line
			(start -1.133856 -5.220462)
			(end -0.47117 -4.5847)
			(stroke
				(width 0.1)
				(type default)
			)
			(layer "B.SilkS")
		)
		(fp_line
			(start -1.133856 -5.220462)
			(end -0.47117 -4.5847)
			(stroke
				(width 0.1)
				(type default)
			)
			(layer "B.SilkS")
		)
		(fp_line
			(start -1.131824 -1.063498)
			(end -1.9431 -1.8415)
			(stroke
				(width 0.1)
				(type default)
			)
			(layer "B.SilkS")
		)
		(fp_line
			(start -1.131824 -1.063498)
			(end -1.9431 -1.8415)
			(stroke
				(width 0.1)
				(type default)
			)
			(layer "B.SilkS")
		)
		(fp_line
			(start -1.09347 -1.084326)
			(end -1.907794 -1.865376)
			(stroke
				(width 0.1)
				(type default)
			)
			(layer "B.SilkS")
		)
		(fp_line
			(start -1.09347 -1.084326)
			(end -1.907794 -1.865376)
			(stroke
				(width 0.1)
				(type default)
			)
			(layer "B.SilkS")
		)
		(fp_line
			(start -1.05664 -1.106678)
			(end -1.872488 -1.889252)
			(stroke
				(width 0.1)
				(type default)
			)
			(layer "B.SilkS")
		)
		(fp_line
			(start -1.05664 -1.106678)
			(end -1.872488 -1.889252)
			(stroke
				(width 0.1)
				(type default)
			)
			(layer "B.SilkS")
		)
		(fp_line
			(start -1.02235 -1.13157)
			(end -1.838452 -1.914144)
			(stroke
				(width 0.1)
				(type default)
			)
			(layer "B.SilkS")
		)
		(fp_line
			(start -1.02235 -1.13157)
			(end -1.838452 -1.914144)
			(stroke
				(width 0.1)
				(type default)
			)
			(layer "B.SilkS")
		)
		(fp_line
			(start -0.988314 -1.156462)
			(end -1.809242 -1.943862)
			(stroke
				(width 0.1)
				(type default)
			)
			(layer "B.SilkS")
		)
		(fp_line
			(start -0.988314 -1.156462)
			(end -1.809242 -1.943862)
			(stroke
				(width 0.1)
				(type default)
			)
			(layer "B.SilkS")
		)
		(fp_line
			(start -0.954024 -1.1811)
			(end -1.780032 -1.973834)
			(stroke
				(width 0.1)
				(type default)
			)
			(layer "B.SilkS")
		)
		(fp_line
			(start -0.954024 -1.1811)
			(end -1.780032 -1.973834)
			(stroke
				(width 0.1)
				(type default)
			)
			(layer "B.SilkS")
		)
		(fp_line
			(start -0.919734 -1.206246)
			(end -1.751076 -2.003552)
			(stroke
				(width 0.1)
				(type default)
			)
			(layer "B.SilkS")
		)
		(fp_line
			(start -0.919734 -1.206246)
			(end -1.751076 -2.003552)
			(stroke
				(width 0.1)
				(type default)
			)
			(layer "B.SilkS")
		)
		(fp_line
			(start -0.885698 -1.230884)
			(end -1.72212 -2.03327)
			(stroke
				(width 0.1)
				(type default)
			)
			(layer "B.SilkS")
		)
		(fp_line
			(start -0.885698 -1.230884)
			(end -1.72212 -2.03327)
			(stroke
				(width 0.1)
				(type default)
			)
			(layer "B.SilkS")
		)
		(fp_line
			(start -0.851408 -1.25603)
			(end -1.69291 -2.063242)
			(stroke
				(width 0.1)
				(type default)
			)
			(layer "B.SilkS")
		)
		(fp_line
			(start -0.851408 -1.25603)
			(end -1.69291 -2.063242)
			(stroke
				(width 0.1)
				(type default)
			)
			(layer "B.SilkS")
		)
		(fp_line
			(start -0.819404 -1.282954)
			(end -1.663954 -2.09296)
			(stroke
				(width 0.1)
				(type default)
			)
			(layer "B.SilkS")
		)
		(fp_line
			(start -0.819404 -1.282954)
			(end -1.663954 -2.09296)
			(stroke
				(width 0.1)
				(type default)
			)
			(layer "B.SilkS")
		)
		(fp_line
			(start -0.789178 -1.31191)
			(end -1.637792 -2.125726)
			(stroke
				(width 0.1)
				(type default)
			)
			(layer "B.SilkS")
		)
		(fp_line
			(start -0.789178 -1.31191)
			(end -1.637792 -2.125726)
			(stroke
				(width 0.1)
				(type default)
			)
			(layer "B.SilkS")
		)
		(fp_line
			(start -0.758952 -1.340358)
			(end -1.61417 -2.160778)
			(stroke
				(width 0.1)
				(type default)
			)
			(layer "B.SilkS")
		)
		(fp_line
			(start -0.758952 -1.340358)
			(end -1.61417 -2.160778)
			(stroke
				(width 0.1)
				(type default)
			)
			(layer "B.SilkS")
		)
		(fp_line
			(start -0.728726 -1.36906)
			(end -1.590802 -2.196084)
			(stroke
				(width 0.1)
				(type default)
			)
			(layer "B.SilkS")
		)
		(fp_line
			(start -0.728726 -1.36906)
			(end -1.590802 -2.196084)
			(stroke
				(width 0.1)
				(type default)
			)
			(layer "B.SilkS")
		)
		(fp_line
			(start -0.6985 -1.397762)
			(end -1.56718 -2.231136)
			(stroke
				(width 0.1)
				(type default)
			)
			(layer "B.SilkS")
		)
		(fp_line
			(start -0.6985 -1.397762)
			(end -1.56718 -2.231136)
			(stroke
				(width 0.1)
				(type default)
			)
			(layer "B.SilkS")
		)
		(fp_line
			(start -0.668274 -1.426464)
			(end -1.543558 -2.266188)
			(stroke
				(width 0.1)
				(type default)
			)
			(layer "B.SilkS")
		)
		(fp_line
			(start -0.668274 -1.426464)
			(end -1.543558 -2.266188)
			(stroke
				(width 0.1)
				(type default)
			)
			(layer "B.SilkS")
		)
		(fp_line
			(start -0.637794 -1.455166)
			(end -1.52019 -2.301494)
			(stroke
				(width 0.1)
				(type default)
			)
			(layer "B.SilkS")
		)
		(fp_line
			(start -0.637794 -1.455166)
			(end -1.52019 -2.301494)
			(stroke
				(width 0.1)
				(type default)
			)
			(layer "B.SilkS")
		)
		(fp_line
			(start -0.610616 -1.486916)
			(end -1.496568 -2.336546)
			(stroke
				(width 0.1)
				(type default)
			)
			(layer "B.SilkS")
		)
		(fp_line
			(start -0.610616 -1.486916)
			(end -1.496568 -2.336546)
			(stroke
				(width 0.1)
				(type default)
			)
			(layer "B.SilkS")
		)
		(fp_line
			(start -0.584962 -1.519682)
			(end -1.477772 -2.376424)
			(stroke
				(width 0.1)
				(type default)
			)
			(layer "B.SilkS")
		)
		(fp_line
			(start -0.584962 -1.519682)
			(end -1.477772 -2.376424)
			(stroke
				(width 0.1)
				(type default)
			)
			(layer "B.SilkS")
		)
		(fp_line
			(start -0.559054 -1.552702)
			(end -1.459992 -2.41681)
			(stroke
				(width 0.1)
				(type default)
			)
			(layer "B.SilkS")
		)
		(fp_line
			(start -0.559054 -1.552702)
			(end -1.459992 -2.41681)
			(stroke
				(width 0.1)
				(type default)
			)
			(layer "B.SilkS")
		)
		(fp_line
			(start -0.5334 -1.585722)
			(end -1.441958 -2.457196)
			(stroke
				(width 0.1)
				(type default)
			)
			(layer "B.SilkS")
		)
		(fp_line
			(start -0.5334 -1.585722)
			(end -1.441958 -2.457196)
			(stroke
				(width 0.1)
				(type default)
			)
			(layer "B.SilkS")
		)
		(fp_line
			(start -0.507746 -1.618742)
			(end -1.423924 -2.497836)
			(stroke
				(width 0.1)
				(type default)
			)
			(layer "B.SilkS")
		)
		(fp_line
			(start -0.507746 -1.618742)
			(end -1.423924 -2.497836)
			(stroke
				(width 0.1)
				(type default)
			)
			(layer "B.SilkS")
		)
		(fp_line
			(start -0.481838 -1.651762)
			(end -1.40589 -2.538222)
			(stroke
				(width 0.1)
				(type default)
			)
			(layer "B.SilkS")
		)
		(fp_line
			(start -0.481838 -1.651762)
			(end -1.40589 -2.538222)
			(stroke
				(width 0.1)
				(type default)
			)
			(layer "B.SilkS")
		)
		(fp_line
			(start -0.456184 -1.684782)
			(end -1.387856 -2.578608)
			(stroke
				(width 0.1)
				(type default)
			)
			(layer "B.SilkS")
		)
		(fp_line
			(start -0.456184 -1.684782)
			(end -1.387856 -2.578608)
			(stroke
				(width 0.1)
				(type default)
			)
			(layer "B.SilkS")
		)
		(fp_line
			(start -0.432816 -1.720088)
			(end -1.372362 -2.62128)
			(stroke
				(width 0.1)
				(type default)
			)
			(layer "B.SilkS")
		)
		(fp_line
			(start -0.432816 -1.720088)
			(end -1.372362 -2.62128)
			(stroke
				(width 0.1)
				(type default)
			)
			(layer "B.SilkS")
		)
		(fp_line
			(start -0.411988 -1.75768)
			(end -1.360424 -2.667508)
			(stroke
				(width 0.1)
				(type default)
			)
			(layer "B.SilkS")
		)
		(fp_line
			(start -0.411988 -1.75768)
			(end -1.360424 -2.667508)
			(stroke
				(width 0.1)
				(type default)
			)
			(layer "B.SilkS")
		)
		(fp_line
			(start -0.390906 -1.795272)
			(end -1.348486 -2.714244)
			(stroke
				(width 0.1)
				(type default)
			)
			(layer "B.SilkS")
		)
		(fp_line
			(start -0.390906 -1.795272)
			(end -1.348486 -2.714244)
			(stroke
				(width 0.1)
				(type default)
			)
			(layer "B.SilkS")
		)
		(fp_line
			(start -0.369824 -1.832864)
			(end -1.336802 -2.760472)
			(stroke
				(width 0.1)
				(type default)
			)
			(layer "B.SilkS")
		)
		(fp_line
			(start -0.369824 -1.832864)
			(end -1.336802 -2.760472)
			(stroke
				(width 0.1)
				(type default)
			)
			(layer "B.SilkS")
		)
		(fp_line
			(start -0.348996 -1.870456)
			(end -1.325118 -2.8067)
			(stroke
				(width 0.1)
				(type default)
			)
			(layer "B.SilkS")
		)
		(fp_line
			(start -0.348996 -1.870456)
			(end -1.325118 -2.8067)
			(stroke
				(width 0.1)
				(type default)
			)
			(layer "B.SilkS")
		)
		(fp_line
			(start -0.327914 -1.908048)
			(end -1.31318 -2.853182)
			(stroke
				(width 0.1)
				(type default)
			)
			(layer "B.SilkS")
		)
		(fp_line
			(start -0.327914 -1.908048)
			(end -1.31318 -2.853182)
			(stroke
				(width 0.1)
				(type default)
			)
			(layer "B.SilkS")
		)
		(fp_line
			(start -0.307086 -1.94564)
			(end -1.303528 -2.901696)
			(stroke
				(width 0.1)
				(type default)
			)
			(layer "B.SilkS")
		)
		(fp_line
			(start -0.307086 -1.94564)
			(end -1.303528 -2.901696)
			(stroke
				(width 0.1)
				(type default)
			)
			(layer "B.SilkS")
		)
		(fp_line
			(start -0.289306 -1.986534)
			(end -1.299464 -2.955544)
			(stroke
				(width 0.1)
				(type default)
			)
			(layer "B.SilkS")
		)
		(fp_line
			(start -0.289306 -1.986534)
			(end -1.299464 -2.955544)
			(stroke
				(width 0.1)
				(type default)
			)
			(layer "B.SilkS")
		)
		(fp_line
			(start -0.272796 -2.02819)
			(end -1.295146 -3.009138)
			(stroke
				(width 0.1)
				(type default)
			)
			(layer "B.SilkS")
		)
		(fp_line
			(start -0.272796 -2.02819)
			(end -1.295146 -3.009138)
			(stroke
				(width 0.1)
				(type default)
			)
			(layer "B.SilkS")
		)
		(fp_line
			(start -0.256032 -2.069846)
			(end -1.291082 -3.062732)
			(stroke
				(width 0.1)
				(type default)
			)
			(layer "B.SilkS")
		)
		(fp_line
			(start -0.256032 -2.069846)
			(end -1.291082 -3.062732)
			(stroke
				(width 0.1)
				(type default)
			)
			(layer "B.SilkS")
		)
		(fp_line
			(start -0.239268 -2.111502)
			(end -1.287018 -3.11658)
			(stroke
				(width 0.1)
				(type default)
			)
			(layer "B.SilkS")
		)
		(fp_line
			(start -0.239268 -2.111502)
			(end -1.287018 -3.11658)
			(stroke
				(width 0.1)
				(type default)
			)
			(layer "B.SilkS")
		)
		(fp_line
			(start -0.222504 -2.153158)
			(end -1.2827 -3.170174)
			(stroke
				(width 0.1)
				(type default)
			)
			(layer "B.SilkS")
		)
		(fp_line
			(start -0.222504 -2.153158)
			(end -1.2827 -3.170174)
			(stroke
				(width 0.1)
				(type default)
			)
			(layer "B.SilkS")
		)
		(fp_line
			(start -0.205994 -2.195068)
			(end -1.287526 -3.232404)
			(stroke
				(width 0.1)
				(type default)
			)
			(layer "B.SilkS")
		)
		(fp_line
			(start -0.205994 -2.195068)
			(end -1.287526 -3.232404)
			(stroke
				(width 0.1)
				(type default)
			)
			(layer "B.SilkS")
		)
		(fp_line
			(start -0.191516 -2.238756)
			(end -1.29413 -3.296412)
			(stroke
				(width 0.1)
				(type default)
			)
			(layer "B.SilkS")
		)
		(fp_line
			(start -0.191516 -2.238756)
			(end -1.29413 -3.296412)
			(stroke
				(width 0.1)
				(type default)
			)
			(layer "B.SilkS")
		)
		(fp_line
			(start -0.178562 -2.284222)
			(end -1.300988 -3.360674)
			(stroke
				(width 0.1)
				(type default)
			)
			(layer "B.SilkS")
		)
		(fp_line
			(start -0.178562 -2.284222)
			(end -1.300988 -3.360674)
			(stroke
				(width 0.1)
				(type default)
			)
			(layer "B.SilkS")
		)
		(fp_line
			(start -0.165608 -2.329434)
			(end -1.307592 -3.424936)
			(stroke
				(width 0.1)
				(type default)
			)
			(layer "B.SilkS")
		)
		(fp_line
			(start -0.165608 -2.329434)
			(end -1.307592 -3.424936)
			(stroke
				(width 0.1)
				(type default)
			)
			(layer "B.SilkS")
		)
		(fp_line
			(start -0.152908 -2.3749)
			(end -1.31445 -3.489198)
			(stroke
				(width 0.1)
				(type default)
			)
			(layer "B.SilkS")
		)
		(fp_line
			(start -0.152908 -2.3749)
			(end -1.31445 -3.489198)
			(stroke
				(width 0.1)
				(type default)
			)
			(layer "B.SilkS")
		)
		(fp_line
			(start -0.139954 -2.420366)
			(end -1.336548 -3.568192)
			(stroke
				(width 0.1)
				(type default)
			)
			(layer "B.SilkS")
		)
		(fp_line
			(start -0.139954 -2.420366)
			(end -1.336548 -3.568192)
			(stroke
				(width 0.1)
				(type default)
			)
			(layer "B.SilkS")
		)
		(fp_line
			(start -0.127254 -2.465832)
			(end -1.360932 -3.649218)
			(stroke
				(width 0.1)
				(type default)
			)
			(layer "B.SilkS")
		)
		(fp_line
			(start -0.127254 -2.465832)
			(end -1.360932 -3.649218)
			(stroke
				(width 0.1)
				(type default)
			)
			(layer "B.SilkS")
		)
		(fp_line
			(start -0.117602 -2.514346)
			(end -1.38557 -3.730498)
			(stroke
				(width 0.1)
				(type default)
			)
			(layer "B.SilkS")
		)
		(fp_line
			(start -0.117602 -2.514346)
			(end -1.38557 -3.730498)
			(stroke
				(width 0.1)
				(type default)
			)
			(layer "B.SilkS")
		)
		(fp_line
			(start -0.108204 -2.563114)
			(end -1.4224 -3.823716)
			(stroke
				(width 0.1)
				(type default)
			)
			(layer "B.SilkS")
		)
		(fp_line
			(start -0.108204 -2.563114)
			(end -1.4224 -3.823716)
			(stroke
				(width 0.1)
				(type default)
			)
			(layer "B.SilkS")
		)
		(fp_line
			(start -0.098806 -2.611628)
			(end -1.482344 -3.938778)
			(stroke
				(width 0.1)
				(type default)
			)
			(layer "B.SilkS")
		)
		(fp_line
			(start -0.098806 -2.611628)
			(end -1.482344 -3.938778)
			(stroke
				(width 0.1)
				(type default)
			)
			(layer "B.SilkS")
		)
		(fp_line
			(start -0.089408 -2.660396)
			(end -1.561846 -4.072636)
			(stroke
				(width 0.1)
				(type default)
			)
			(layer "B.SilkS")
		)
		(fp_line
			(start -0.089408 -2.660396)
			(end -1.561846 -4.072636)
			(stroke
				(width 0.1)
				(type default)
			)
			(layer "B.SilkS")
		)
	)
	(footprint ""
		(layer "B.Cu")
		(at 41.42994 -92.498926 -90)
		(property "Reference" "U22"
			(at 1.847596 4.09194 0)
			(unlocked yes)
			(layer "B.SilkS")
			(effects
				(font
					(size 0.7874 0.5842)
					(thickness 0.1524)
				)
				(justify left mirror)
			)
		)
		(property "Value" ""
			(at 0 0 90)
			(layer "B.Fab")
			(effects
				(font
					(size 1.27 1.27)
				)
				(justify mirror)
			)
		)
		(duplicate_pad_numbers_are_jumpers no)
		(fp_line
			(start 0.254 2.5908)
			(end 0.254 2.99974)
			(stroke
				(width 0.1524)
				(type default)
			)
			(layer "B.SilkS")
		)
		(fp_line
			(start -1.299972 2.29997)
			(end -1.299972 2.032)
			(stroke
				(width 0.1524)
				(type default)
			)
			(layer "B.SilkS")
		)
		(fp_line
			(start -0.5334 2.29997)
			(end -1.299972 2.29997)
			(stroke
				(width 0.1524)
				(type default)
			)
			(layer "B.SilkS")
		)
		(fp_line
			(start 1.299972 2.29997)
			(end 0.5334 2.29997)
			(stroke
				(width 0.1524)
				(type default)
			)
			(layer "B.SilkS")
		)
		(fp_line
			(start 1.299972 2.032)
			(end 1.299972 2.29997)
			(stroke
				(width 0.1524)
				(type default)
			)
			(layer "B.SilkS")
		)
		(fp_line
			(start 1.299972 2.032)
			(end 1.299972 2.29997)
			(stroke
				(width 0.1524)
				(type default)
			)
			(layer "B.SilkS")
		)
		(fp_line
			(start -1.6002 0.254)
			(end -2.1082 0.254)
			(stroke
				(width 0.1524)
				(type default)
			)
			(layer "B.SilkS")
		)
		(fp_line
			(start 1.6002 -0.254)
			(end 2.1082 -0.254)
			(stroke
				(width 0.1524)
				(type default)
			)
			(layer "B.SilkS")
		)
		(fp_line
			(start -1.299972 -2.032)
			(end -1.299972 -2.29997)
			(stroke
				(width 0.1524)
				(type default)
			)
			(layer "B.SilkS")
		)
		(fp_line
			(start -1.299972 -2.29997)
			(end -0.5334 -2.29997)
			(stroke
				(width 0.1524)
				(type default)
			)
			(layer "B.SilkS")
		)
		(fp_line
			(start 0.5334 -2.29997)
			(end 1.299972 -2.29997)
			(stroke
				(width 0.1524)
				(type default)
			)
			(layer "B.SilkS")
		)
		(fp_line
			(start 1.299972 -2.29997)
			(end 1.299972 -2.032)
			(stroke
				(width 0.1524)
				(type default)
			)
			(layer "B.SilkS")
		)
		(fp_line
			(start -0.254 -2.5908)
			(end -0.254 -3.12166)
			(stroke
				(width 0.1524)
				(type default)
			)
			(layer "B.SilkS")
		)
		(fp_poly
			(pts
				(xy 0.249936 -2.516886) (xy 0.55245 -3.121914) (xy -0.052578 -3.121914)
			)
			(stroke
				(width 0)
				(type default)
			)
			(fill yes)
			(layer "B.SilkS")
		)
		(fp_line
			(start 0.254 2.5908)
			(end 0.254 3.6068)
			(stroke
				(width 0.1)
				(type default)
			)
			(layer "B.Fab")
		)
		(fp_line
			(start -1.299972 2.29997)
			(end -1.299972 -2.29997)
			(stroke
				(width 0.1)
				(type default)
			)
			(layer "B.Fab")
		)
		(fp_line
			(start 1.299972 2.29997)
			(end -1.299972 2.29997)
			(stroke
				(width 0.1)
				(type default)
			)
			(layer "B.Fab")
		)
		(fp_line
			(start -1.6002 0.254)
			(end -2.1082 0.254)
			(stroke
				(width 0.1)
				(type default)
			)
			(layer "B.Fab")
		)
		(fp_line
			(start 1.6002 -0.254)
			(end 2.1082 -0.254)
			(stroke
				(width 0.1)
				(type default)
			)
			(layer "B.Fab")
		)
		(fp_line
			(start -1.299972 -2.29997)
			(end 1.299972 -2.29997)
			(stroke
				(width 0.1)
				(type default)
			)
			(layer "B.Fab")
		)
		(fp_line
			(start 1.299972 -2.29997)
			(end 1.299972 2.29997)
			(stroke
				(width 0.1)
				(type default)
			)
			(layer "B.Fab")
		)
		(fp_line
			(start -0.254 -2.5908)
			(end -0.254 -3.6068)
			(stroke
				(width 0.1)
				(type default)
			)
			(layer "B.Fab")
		)
		(fp_poly
			(pts
				(xy 0.249936 -2.516886) (xy 0.55245 -3.121914) (xy -0.052578 -3.121914)
			)
			(stroke
				(width 0)
				(type default)
			)
			(fill yes)
			(layer "B.Fab")
		)
		(fp_text user "9"
			(at 2.0574 1.82245 270)
			(unlocked yes)
			(layer "B.SilkS")
			(effects
				(font
					(size 0.635 0.4064)
					(thickness 0.1524)
				)
				(justify left mirror)
			)
		)
		(fp_text user "12"
			(at -1.608074 1.52019 270)
			(unlocked yes)
			(layer "B.SilkS")
			(effects
				(font
					(size 0.635 0.4064)
					(thickness 0.1524)
				)
				(justify left mirror)
			)
		)
		(fp_text user "2"
			(at 2.032 -1.86055 270)
			(unlocked yes)
			(layer "B.SilkS")
			(effects
				(font
					(size 0.635 0.4064)
					(thickness 0.1524)
				)
				(justify left mirror)
			)
		)
		(fp_text user "19"
			(at -2.370074 -2.03581 270)
			(unlocked yes)
			(layer "B.SilkS")
			(effects
				(font
					(size 0.635 0.4064)
					(thickness 0.1524)
				)
				(justify left mirror)
			)
		)
		(fp_text user "9"
			(at 2.0574 1.82245 270)
			(unlocked yes)
			(layer "B.Fab")
			(effects
				(font
					(size 0.635 0.4064)
					(thickness 0.1524)
				)
				(justify left mirror)
			)
		)
		(fp_text user "12"
			(at -1.524 1.77165 270)
			(unlocked yes)
			(layer "B.Fab")
			(effects
				(font
					(size 0.635 0.4064)
					(thickness 0.1524)
				)
				(justify left mirror)
			)
		)
		(fp_text user "19"
			(at -1.4986 -1.86055 270)
			(unlocked yes)
			(layer "B.Fab")
			(effects
				(font
					(size 0.635 0.4064)
					(thickness 0.1524)
				)
				(justify left mirror)
			)
		)
		(fp_text user "2"
			(at 2.032 -1.86055 270)
			(unlocked yes)
			(layer "B.Fab")
			(effects
				(font
					(size 0.635 0.4064)
					(thickness 0.1524)
				)
				(justify left mirror)
			)
		)
		(pad "1" smd rect
			(at 0.249936 -2.100072 90)
			(size 0.2794 0.6604)
			(layers "B.Cu" "B.Mask" "B.Paste")
			(net "P3V3_AUX")
		)
		(pad "2" smd rect
			(at 1.100074 -1.75006 180)
			(size 0.2794 0.6604)
			(layers "B.Cu" "B.Mask" "B.Paste")
			(net "USB3_MUX_PD")
		)
		(pad "3" smd rect
			(at 1.100074 -1.249934 180)
			(size 0.2794 0.6604)
			(layers "B.Cu" "B.Mask" "B.Paste")
			(net "USB3_01_MUX_FB_TXP")
		)
		(pad "4" smd rect
			(at 1.100074 -0.750062 180)
			(size 0.2794 0.6604)
			(layers "B.Cu" "B.Mask" "B.Paste")
			(net "USB3_01_MUX_FB_TXN")
		)
		(pad "5" smd rect
			(at 1.100074 -0.249936 180)
			(size 0.2794 0.6604)
			(layers "B.Cu" "B.Mask" "B.Paste")
			(net "GND")
		)
		(pad "6" smd rect
			(at 1.100074 0.249936 180)
			(size 0.2794 0.6604)
			(layers "B.Cu" "B.Mask" "B.Paste")
			(net "P3V3_AUX")
		)
		(pad "7" smd rect
			(at 1.100074 0.750062 180)
			(size 0.2794 0.6604)
			(layers "B.Cu" "B.Mask" "B.Paste")
			(net "USB3_01_MUX_FB_RXP")
		)
		(pad "8" smd rect
			(at 1.100074 1.249934 180)
			(size 0.2794 0.6604)
			(layers "B.Cu" "B.Mask" "B.Paste")
			(net "USB3_01_MUX_FB_RXN")
		)
		(pad "9" smd rect
			(at 1.100074 1.75006 180)
			(size 0.2794 0.6604)
			(layers "B.Cu" "B.Mask" "B.Paste")
			(net "DEBUG_PORT_PRSNT")
		)
		(pad "10" smd rect
			(at 0.249936 2.100072 90)
			(size 0.2794 0.6604)
			(layers "B.Cu" "B.Mask" "B.Paste")
			(net "P3V3_AUX")
		)
		(pad "11" smd rect
			(at -0.249936 2.100072 90)
			(size 0.2794 0.6604)
			(layers "B.Cu" "B.Mask" "B.Paste")
			(net "GND")
		)
		(pad "12" smd rect
			(at -1.100074 1.75006 180)
			(size 0.2794 0.6604)
			(layers "B.Cu" "B.Mask" "B.Paste")
			(net "SMB_DEBUG_AUX_LVC3_USB_R2_SCL")
		)
		(pad "13" smd rect
			(at -1.100074 1.249934 180)
			(size 0.2794 0.6604)
			(layers "B.Cu" "B.Mask" "B.Paste")
			(net "SMB_DEBUG_AUX_LVC3_USB_R2_SDA")
		)
		(pad "14" smd rect
			(at -1.100074 0.750062 180)
			(size 0.2794 0.6604)
			(layers "B.Cu" "B.Mask" "B.Paste")
			(net "DEBUG_PORT_UART_TX")
		)
		(pad "15" smd rect
			(at -1.100074 0.249936 180)
			(size 0.2794 0.6604)
			(layers "B.Cu" "B.Mask" "B.Paste")
			(net "DEBUG_PORT_UART_RX")
		)
		(pad "16" smd rect
			(at -1.100074 -0.249936 180)
			(size 0.2794 0.6604)
			(layers "B.Cu" "B.Mask" "B.Paste")
			(net "USB3_FPNL_RXN")
		)
		(pad "17" smd rect
			(at -1.100074 -0.750062 180)
			(size 0.2794 0.6604)
			(layers "B.Cu" "B.Mask" "B.Paste")
			(net "USB3_FPNL_RXP")
		)
		(pad "18" smd rect
			(at -1.100074 -1.249934 180)
			(size 0.2794 0.6604)
			(layers "B.Cu" "B.Mask" "B.Paste")
			(net "USB3_01_TXN_C")
		)
		(pad "19" smd rect
			(at -1.100074 -1.75006 180)
			(size 0.2794 0.6604)
			(layers "B.Cu" "B.Mask" "B.Paste")
			(net "USB3_01_TXP_C")
		)
		(pad "20" smd rect
			(at -0.249936 -2.100072 90)
			(size 0.2794 0.6604)
			(layers "B.Cu" "B.Mask" "B.Paste")
			(net "GND")
		)
		(pad "TH" smd rect
			(at 0 0 90)
			(size 0.9144 2.921)
			(layers "B.Cu" "B.Mask" "B.Paste")
			(net "Net_321")
		)
		(zone
			(layer "B.Cu")
			(hatch none 0.5)
			(connect_pads
				(clearance 0)
			)
			(min_thickness 0.25)
			(keepout
				(tracks not_allowed)
				(vias allowed)
				(pads allowed)
				(copperpour not_allowed)
				(footprints allowed)
			)
			(placement
				(enabled no)
				(sheetname "")
			)
			(fill
				(thermal_gap 0.5)
				(thermal_bridge_width 0.5)
				(island_removal_mode 0)
			)
			(polygon
				(pts
					(xy 43.13174 -92.473526) (xy 42.95394 -92.473526) (xy 42.95394 -91.990926) (xy 39.90594 -91.990926)
					(xy 39.90594 -93.006926) (xy 42.95394 -93.006926) (xy 42.95394 -92.498926) (xy 43.13174 -92.498926)
					(xy 43.13174 -93.210126) (xy 39.72814 -93.210126) (xy 39.72814 -91.787726) (xy 43.13174 -91.787726)
				)
			)
		)
	)
	(footprint ""
		(layer "B.Cu")
		(at 51.682904 -47.617126 -90)
		(property "Reference" "C122"
			(at 0 0 90)
			(layer "B.SilkS")
			(hide yes)
			(effects
				(font
					(size 1.27 1.27)
				)
				(justify mirror)
			)
		)
		(property "Value" ""
			(at 0 0 90)
			(layer "B.Fab")
			(effects
				(font
					(size 1.27 1.27)
				)
				(justify mirror)
			)
		)
		(duplicate_pad_numbers_are_jumpers no)
		(fp_line
			(start -0.7874 0.4064)
			(end 0.7874 0.4064)
			(stroke
				(width 0.1524)
				(type default)
			)
			(layer "B.SilkS")
		)
		(fp_line
			(start 0.7874 0.4064)
			(end 0.7874 -0.4064)
			(stroke
				(width 0.1524)
				(type default)
			)
			(layer "B.SilkS")
		)
		(fp_line
			(start -0.7874 -0.4064)
			(end -0.7874 0.4064)
			(stroke
				(width 0.1524)
				(type default)
			)
			(layer "B.SilkS")
		)
		(fp_line
			(start 0.7874 -0.4064)
			(end -0.7874 -0.4064)
			(stroke
				(width 0.1524)
				(type default)
			)
			(layer "B.SilkS")
		)
		(fp_line
			(start -0.67945 0.3048)
			(end -0.120396 0.3048)
			(stroke
				(width 0.1)
				(type default)
			)
			(layer "B.Fab")
		)
		(fp_line
			(start -0.120396 0.3048)
			(end -0.120396 0.2794)
			(stroke
				(width 0.1)
				(type default)
			)
			(layer "B.Fab")
		)
		(fp_line
			(start 0.12065 0.3048)
			(end 0.67945 0.3048)
			(stroke
				(width 0.1)
				(type default)
			)
			(layer "B.Fab")
		)
		(fp_line
			(start 0.67945 0.3048)
			(end 0.67945 -0.305054)
			(stroke
				(width 0.1)
				(type default)
			)
			(layer "B.Fab")
		)
		(fp_line
			(start -0.120396 0.2794)
			(end 0.12065 0.2794)
			(stroke
				(width 0.1)
				(type default)
			)
			(layer "B.Fab")
		)
		(fp_line
			(start 0.12065 0.2794)
			(end 0.12065 0.3048)
			(stroke
				(width 0.1)
				(type default)
			)
			(layer "B.Fab")
		)
		(fp_line
			(start -0.12065 -0.2794)
			(end -0.12065 -0.3048)
			(stroke
				(width 0.1)
				(type default)
			)
			(layer "B.Fab")
		)
		(fp_line
			(start 0.12065 -0.2794)
			(end -0.12065 -0.2794)
			(stroke
				(width 0.1)
				(type default)
			)
			(layer "B.Fab")
		)
		(fp_line
			(start -0.67945 -0.3048)
			(end -0.67945 0.3048)
			(stroke
				(width 0.1)
				(type default)
			)
			(layer "B.Fab")
		)
		(fp_line
			(start -0.12065 -0.3048)
			(end -0.67945 -0.3048)
			(stroke
				(width 0.1)
				(type default)
			)
			(layer "B.Fab")
		)
		(fp_line
			(start 0.12065 -0.305054)
			(end 0.12065 -0.2794)
			(stroke
				(width 0.1)
				(type default)
			)
			(layer "B.Fab")
		)
		(fp_line
			(start 0.67945 -0.305054)
			(end 0.12065 -0.305054)
			(stroke
				(width 0.1)
				(type default)
			)
			(layer "B.Fab")
		)
		(pad "1" smd circle
			(at 0.40005 0 90)
			(size 0 0)
			(layers "B.Cu" "B.Mask" "B.Paste")
			(net "P1V2_AUX")
		)
		(pad "2" smd circle
			(at -0.40005 0 90)
			(size 0 0)
			(layers "B.Cu" "B.Mask" "B.Paste")
			(net "GND")
		)
	)
	(footprint ""
		(layer "B.Cu")
		(at 62.59322 -61.985906 -90)
		(property "Reference" "C24"
			(at 0 0 90)
			(layer "B.SilkS")
			(hide yes)
			(effects
				(font
					(size 1.27 1.27)
				)
				(justify mirror)
			)
		)
		(property "Value" ""
			(at 0 0 90)
			(layer "B.Fab")
			(effects
				(font
					(size 1.27 1.27)
				)
				(justify mirror)
			)
		)
		(duplicate_pad_numbers_are_jumpers no)
		(fp_line
			(start -0.541274 0.4064)
			(end 0.477266 0.4064)
			(stroke
				(width 0.1524)
				(type default)
			)
			(layer "B.SilkS")
		)
		(fp_line
			(start 0.7874 0.05842)
			(end 0.7874 -0.4064)
			(stroke
				(width 0.1524)
				(type default)
			)
			(layer "B.SilkS")
		)
		(fp_line
			(start -0.7874 -0.4064)
			(end -0.7874 0.11684)
			(stroke
				(width 0.1524)
				(type default)
			)
			(layer "B.SilkS")
		)
		(fp_line
			(start 0.7874 -0.4064)
			(end -0.7874 -0.4064)
			(stroke
				(width 0.1524)
				(type default)
			)
			(layer "B.SilkS")
		)
		(fp_line
			(start -0.67945 0.3048)
			(end -0.120396 0.3048)
			(stroke
				(width 0.1)
				(type default)
			)
			(layer "B.Fab")
		)
		(fp_line
			(start -0.120396 0.3048)
			(end -0.120396 0.2794)
			(stroke
				(width 0.1)
				(type default)
			)
			(layer "B.Fab")
		)
		(fp_line
			(start 0.12065 0.3048)
			(end 0.67945 0.3048)
			(stroke
				(width 0.1)
				(type default)
			)
			(layer "B.Fab")
		)
		(fp_line
			(start 0.67945 0.3048)
			(end 0.67945 -0.305054)
			(stroke
				(width 0.1)
				(type default)
			)
			(layer "B.Fab")
		)
		(fp_line
			(start -0.120396 0.2794)
			(end 0.12065 0.2794)
			(stroke
				(width 0.1)
				(type default)
			)
			(layer "B.Fab")
		)
		(fp_line
			(start 0.12065 0.2794)
			(end 0.12065 0.3048)
			(stroke
				(width 0.1)
				(type default)
			)
			(layer "B.Fab")
		)
		(fp_line
			(start -0.12065 -0.2794)
			(end -0.12065 -0.3048)
			(stroke
				(width 0.1)
				(type default)
			)
			(layer "B.Fab")
		)
		(fp_line
			(start 0.12065 -0.2794)
			(end -0.12065 -0.2794)
			(stroke
				(width 0.1)
				(type default)
			)
			(layer "B.Fab")
		)
		(fp_line
			(start -0.67945 -0.3048)
			(end -0.67945 0.3048)
			(stroke
				(width 0.1)
				(type default)
			)
			(layer "B.Fab")
		)
		(fp_line
			(start -0.12065 -0.3048)
			(end -0.67945 -0.3048)
			(stroke
				(width 0.1)
				(type default)
			)
			(layer "B.Fab")
		)
		(fp_line
			(start 0.12065 -0.305054)
			(end 0.12065 -0.2794)
			(stroke
				(width 0.1)
				(type default)
			)
			(layer "B.Fab")
		)
		(fp_line
			(start 0.67945 -0.305054)
			(end 0.12065 -0.305054)
			(stroke
				(width 0.1)
				(type default)
			)
			(layer "B.Fab")
		)
		(pad "1" smd circle
			(at 0.40005 0 90)
			(size 0 0)
			(layers "B.Cu" "B.Mask" "B.Paste")
			(net "P2E_PCH_TX_DP")
		)
		(pad "2" smd circle
			(at -0.40005 0 90)
			(size 0 0)
			(layers "B.Cu" "B.Mask" "B.Paste")
			(net "P2E_PCH_TX_C_DP")
		)
	)
	(footprint ""
		(layer "B.Cu")
		(at 59.81954 -30.867604 90)
		(property "Reference" "R93"
			(at 0 0 90)
			(layer "B.SilkS")
			(hide yes)
			(effects
				(font
					(size 1.27 1.27)
				)
				(justify mirror)
			)
		)
		(property "Value" ""
			(at 0 0 90)
			(layer "B.Fab")
			(effects
				(font
					(size 1.27 1.27)
				)
				(justify mirror)
			)
		)
		(duplicate_pad_numbers_are_jumpers no)
		(fp_line
			(start 0.7874 -0.4064)
			(end -0.7874 -0.4064)
			(stroke
				(width 0.1524)
				(type default)
			)
			(layer "B.SilkS")
		)
		(fp_line
			(start -0.7874 -0.4064)
			(end -0.7874 0.4064)
			(stroke
				(width 0.1524)
				(type default)
			)
			(layer "B.SilkS")
		)
		(fp_line
			(start 0.7874 0.4064)
			(end 0.7874 -0.4064)
			(stroke
				(width 0.1524)
				(type default)
			)
			(layer "B.SilkS")
		)
		(fp_line
			(start -0.7874 0.4064)
			(end 0.7874 0.4064)
			(stroke
				(width 0.1524)
				(type default)
			)
			(layer "B.SilkS")
		)
		(fp_line
			(start 0.67945 -0.305054)
			(end 0.12065 -0.305054)
			(stroke
				(width 0.1)
				(type default)
			)
			(layer "B.Fab")
		)
		(fp_line
			(start 0.12065 -0.305054)
			(end 0.12065 -0.2794)
			(stroke
				(width 0.1)
				(type default)
			)
			(layer "B.Fab")
		)
		(fp_line
			(start -0.12065 -0.3048)
			(end -0.67945 -0.3048)
			(stroke
				(width 0.1)
				(type default)
			)
			(layer "B.Fab")
		)
		(fp_line
			(start -0.67945 -0.3048)
			(end -0.67945 0.3048)
			(stroke
				(width 0.1)
				(type default)
			)
			(layer "B.Fab")
		)
		(fp_line
			(start 0.12065 -0.2794)
			(end -0.12065 -0.2794)
			(stroke
				(width 0.1)
				(type default)
			)
			(layer "B.Fab")
		)
		(fp_line
			(start -0.12065 -0.2794)
			(end -0.12065 -0.3048)
			(stroke
				(width 0.1)
				(type default)
			)
			(layer "B.Fab")
		)
		(fp_line
			(start 0.12065 0.2794)
			(end 0.12065 0.3048)
			(stroke
				(width 0.1)
				(type default)
			)
			(layer "B.Fab")
		)
		(fp_line
			(start -0.120396 0.2794)
			(end 0.12065 0.2794)
			(stroke
				(width 0.1)
				(type default)
			)
			(layer "B.Fab")
		)
		(fp_line
			(start 0.67945 0.3048)
			(end 0.67945 -0.305054)
			(stroke
				(width 0.1)
				(type default)
			)
			(layer "B.Fab")
		)
		(fp_line
			(start 0.12065 0.3048)
			(end 0.67945 0.3048)
			(stroke
				(width 0.1)
				(type default)
			)
			(layer "B.Fab")
		)
		(fp_line
			(start -0.120396 0.3048)
			(end -0.120396 0.2794)
			(stroke
				(width 0.1)
				(type default)
			)
			(layer "B.Fab")
		)
		(fp_line
			(start -0.67945 0.3048)
			(end -0.120396 0.3048)
			(stroke
				(width 0.1)
				(type default)
			)
			(layer "B.Fab")
		)
		(pad "1" smd circle
			(at 0.40005 0 270)
			(size 0 0)
			(layers "B.Cu" "B.Mask" "B.Paste")
			(net "SMB_BMC_MM5_R_SDA")
		)
		(pad "2" smd circle
			(at -0.40005 0 270)
			(size 0 0)
			(layers "B.Cu" "B.Mask" "B.Paste")
			(net "SMB_BMC_MM5_SDA")
		)
	)
	(footprint ""
		(layer "B.Cu")
		(at 41.1988 -37.338 180)
		(property "Reference" "R760"
			(at 0 0 0)
			(layer "B.SilkS")
			(hide yes)
			(effects
				(font
					(size 1.27 1.27)
				)
				(justify mirror)
			)
		)
		(property "Value" ""
			(at 0 0 0)
			(layer "B.Fab")
			(effects
				(font
					(size 1.27 1.27)
				)
				(justify mirror)
			)
		)
		(duplicate_pad_numbers_are_jumpers no)
		(fp_line
			(start 0.7874 0.4064)
			(end 0.7874 -0.4064)
			(stroke
				(width 0.1524)
				(type default)
			)
			(layer "B.SilkS")
		)
		(fp_line
			(start 0.7874 -0.4064)
			(end -0.7874 -0.4064)
			(stroke
				(width 0.1524)
				(type default)
			)
			(layer "B.SilkS")
		)
		(fp_line
			(start -0.7874 0.4064)
			(end 0.7874 0.4064)
			(stroke
				(width 0.1524)
				(type default)
			)
			(layer "B.SilkS")
		)
		(fp_line
			(start -0.7874 -0.4064)
			(end -0.7874 0.4064)
			(stroke
				(width 0.1524)
				(type default)
			)
			(layer "B.SilkS")
		)
		(fp_line
			(start 0.67945 0.3048)
			(end 0.67945 -0.305054)
			(stroke
				(width 0.1)
				(type default)
			)
			(layer "B.Fab")
		)
		(fp_line
			(start 0.67945 -0.305054)
			(end 0.12065 -0.305054)
			(stroke
				(width 0.1)
				(type default)
			)
			(layer "B.Fab")
		)
		(fp_line
			(start 0.12065 0.3048)
			(end 0.67945 0.3048)
			(stroke
				(width 0.1)
				(type default)
			)
			(layer "B.Fab")
		)
		(fp_line
			(start 0.12065 0.2794)
			(end 0.12065 0.3048)
			(stroke
				(width 0.1)
				(type default)
			)
			(layer "B.Fab")
		)
		(fp_line
			(start 0.12065 -0.2794)
			(end -0.12065 -0.2794)
			(stroke
				(width 0.1)
				(type default)
			)
			(layer "B.Fab")
		)
		(fp_line
			(start 0.12065 -0.305054)
			(end 0.12065 -0.2794)
			(stroke
				(width 0.1)
				(type default)
			)
			(layer "B.Fab")
		)
		(fp_line
			(start -0.120396 0.3048)
			(end -0.120396 0.2794)
			(stroke
				(width 0.1)
				(type default)
			)
			(layer "B.Fab")
		)
		(fp_line
			(start -0.120396 0.2794)
			(end 0.12065 0.2794)
			(stroke
				(width 0.1)
				(type default)
			)
			(layer "B.Fab")
		)
		(fp_line
			(start -0.12065 -0.2794)
			(end -0.12065 -0.3048)
			(stroke
				(width 0.1)
				(type default)
			)
			(layer "B.Fab")
		)
		(fp_line
			(start -0.12065 -0.3048)
			(end -0.67945 -0.3048)
			(stroke
				(width 0.1)
				(type default)
			)
			(layer "B.Fab")
		)
		(fp_line
			(start -0.67945 0.3048)
			(end -0.120396 0.3048)
			(stroke
				(width 0.1)
				(type default)
			)
			(layer "B.Fab")
		)
		(fp_line
			(start -0.67945 -0.3048)
			(end -0.67945 0.3048)
			(stroke
				(width 0.1)
				(type default)
			)
			(layer "B.Fab")
		)
		(pad "1" smd circle
			(at 0.40005 0)
			(size 0 0)
			(layers "B.Cu" "B.Mask" "B.Paste")
			(net "FM_BMC_CRASHLOG_TRIG_N")
		)
		(pad "2" smd circle
			(at -0.40005 0)
			(size 0 0)
			(layers "B.Cu" "B.Mask" "B.Paste")
			(net "FM_BMC_CRASHLOG_TRIG_R1_N")
		)
	)
	(footprint ""
		(layer "B.Cu")
		(at 68.58 -14.478)
		(property "Reference" "R883"
			(at 0 0 0)
			(layer "B.SilkS")
			(hide yes)
			(effects
				(font
					(size 1.27 1.27)
				)
				(justify mirror)
			)
		)
		(property "Value" ""
			(at 0 0 0)
			(layer "B.Fab")
			(effects
				(font
					(size 1.27 1.27)
				)
				(justify mirror)
			)
		)
		(duplicate_pad_numbers_are_jumpers no)
		(fp_line
			(start -0.7874 -0.4064)
			(end -0.7874 0.4064)
			(stroke
				(width 0.1524)
				(type default)
			)
			(layer "B.SilkS")
		)
		(fp_line
			(start -0.7874 0.4064)
			(end 0.7874 0.4064)
			(stroke
				(width 0.1524)
				(type default)
			)
			(layer "B.SilkS")
		)
		(fp_line
			(start 0.7874 -0.4064)
			(end -0.7874 -0.4064)
			(stroke
				(width 0.1524)
				(type default)
			)
			(layer "B.SilkS")
		)
		(fp_line
			(start 0.7874 0.4064)
			(end 0.7874 -0.4064)
			(stroke
				(width 0.1524)
				(type default)
			)
			(layer "B.SilkS")
		)
		(fp_line
			(start -0.67945 -0.3048)
			(end -0.67945 0.3048)
			(stroke
				(width 0.1)
				(type default)
			)
			(layer "B.Fab")
		)
		(fp_line
			(start -0.67945 0.3048)
			(end -0.120396 0.3048)
			(stroke
				(width 0.1)
				(type default)
			)
			(layer "B.Fab")
		)
		(fp_line
			(start -0.12065 -0.3048)
			(end -0.67945 -0.3048)
			(stroke
				(width 0.1)
				(type default)
			)
			(layer "B.Fab")
		)
		(fp_line
			(start -0.12065 -0.2794)
			(end -0.12065 -0.3048)
			(stroke
				(width 0.1)
				(type default)
			)
			(layer "B.Fab")
		)
		(fp_line
			(start -0.120396 0.2794)
			(end 0.12065 0.2794)
			(stroke
				(width 0.1)
				(type default)
			)
			(layer "B.Fab")
		)
		(fp_line
			(start -0.120396 0.3048)
			(end -0.120396 0.2794)
			(stroke
				(width 0.1)
				(type default)
			)
			(layer "B.Fab")
		)
		(fp_line
			(start 0.12065 -0.305054)
			(end 0.12065 -0.2794)
			(stroke
				(width 0.1)
				(type default)
			)
			(layer "B.Fab")
		)
		(fp_line
			(start 0.12065 -0.2794)
			(end -0.12065 -0.2794)
			(stroke
				(width 0.1)
				(type default)
			)
			(layer "B.Fab")
		)
		(fp_line
			(start 0.12065 0.2794)
			(end 0.12065 0.3048)
			(stroke
				(width 0.1)
				(type default)
			)
			(layer "B.Fab")
		)
		(fp_line
			(start 0.12065 0.3048)
			(end 0.67945 0.3048)
			(stroke
				(width 0.1)
				(type default)
			)
			(layer "B.Fab")
		)
		(fp_line
			(start 0.67945 -0.305054)
			(end 0.12065 -0.305054)
			(stroke
				(width 0.1)
				(type default)
			)
			(layer "B.Fab")
		)
		(fp_line
			(start 0.67945 0.3048)
			(end 0.67945 -0.305054)
			(stroke
				(width 0.1)
				(type default)
			)
			(layer "B.Fab")
		)
		(pad "1" smd circle
			(at 0.40005 0 180)
			(size 0 0)
			(layers "B.Cu" "B.Mask" "B.Paste")
			(net "P3V3_AUX")
		)
		(pad "2" smd circle
			(at -0.40005 0 180)
			(size 0 0)
			(layers "B.Cu" "B.Mask" "B.Paste")
			(net "REAR_AC_PWR_BMC_BTN_N")
		)
	)
	(footprint ""
		(layer "B.Cu")
		(at 68.95338 -55.353966 90)
		(property "Reference" "C47"
			(at 0 0 90)
			(layer "B.SilkS")
			(hide yes)
			(effects
				(font
					(size 1.27 1.27)
				)
				(justify mirror)
			)
		)
		(property "Value" ""
			(at 0 0 90)
			(layer "B.Fab")
			(effects
				(font
					(size 1.27 1.27)
				)
				(justify mirror)
			)
		)
		(duplicate_pad_numbers_are_jumpers no)
		(fp_line
			(start 0.7874 -0.4064)
			(end -0.7874 -0.4064)
			(stroke
				(width 0.1524)
				(type default)
			)
			(layer "B.SilkS")
		)
		(fp_line
			(start -0.7874 -0.4064)
			(end -0.7874 0.4064)
			(stroke
				(width 0.1524)
				(type default)
			)
			(layer "B.SilkS")
		)
		(fp_line
			(start 0.7874 0.4064)
			(end 0.7874 -0.4064)
			(stroke
				(width 0.1524)
				(type default)
			)
			(layer "B.SilkS")
		)
		(fp_line
			(start -0.7874 0.4064)
			(end 0.7874 0.4064)
			(stroke
				(width 0.1524)
				(type default)
			)
			(layer "B.SilkS")
		)
		(fp_line
			(start 0.67945 -0.305054)
			(end 0.12065 -0.305054)
			(stroke
				(width 0.1)
				(type default)
			)
			(layer "B.Fab")
		)
		(fp_line
			(start 0.12065 -0.305054)
			(end 0.12065 -0.2794)
			(stroke
				(width 0.1)
				(type default)
			)
			(layer "B.Fab")
		)
		(fp_line
			(start -0.12065 -0.3048)
			(end -0.67945 -0.3048)
			(stroke
				(width 0.1)
				(type default)
			)
			(layer "B.Fab")
		)
		(fp_line
			(start -0.67945 -0.3048)
			(end -0.67945 0.3048)
			(stroke
				(width 0.1)
				(type default)
			)
			(layer "B.Fab")
		)
		(fp_line
			(start 0.12065 -0.2794)
			(end -0.12065 -0.2794)
			(stroke
				(width 0.1)
				(type default)
			)
			(layer "B.Fab")
		)
		(fp_line
			(start -0.12065 -0.2794)
			(end -0.12065 -0.3048)
			(stroke
				(width 0.1)
				(type default)
			)
			(layer "B.Fab")
		)
		(fp_line
			(start 0.12065 0.2794)
			(end 0.12065 0.3048)
			(stroke
				(width 0.1)
				(type default)
			)
			(layer "B.Fab")
		)
		(fp_line
			(start -0.120396 0.2794)
			(end 0.12065 0.2794)
			(stroke
				(width 0.1)
				(type default)
			)
			(layer "B.Fab")
		)
		(fp_line
			(start 0.67945 0.3048)
			(end 0.67945 -0.305054)
			(stroke
				(width 0.1)
				(type default)
			)
			(layer "B.Fab")
		)
		(fp_line
			(start 0.12065 0.3048)
			(end 0.67945 0.3048)
			(stroke
				(width 0.1)
				(type default)
			)
			(layer "B.Fab")
		)
		(fp_line
			(start -0.120396 0.3048)
			(end -0.120396 0.2794)
			(stroke
				(width 0.1)
				(type default)
			)
			(layer "B.Fab")
		)
		(fp_line
			(start -0.67945 0.3048)
			(end -0.120396 0.3048)
			(stroke
				(width 0.1)
				(type default)
			)
			(layer "B.Fab")
		)
		(pad "1" smd circle
			(at 0.40005 0 270)
			(size 0 0)
			(layers "B.Cu" "B.Mask" "B.Paste")
			(net "P1V0_STBY_RC_VCC10A")
		)
		(pad "2" smd circle
			(at -0.40005 0 270)
			(size 0 0)
			(layers "B.Cu" "B.Mask" "B.Paste")
			(net "GND")
		)
	)
	(footprint ""
		(layer "B.Cu")
		(at 24.003 -101.981 -90)
		(property "Reference" "R621"
			(at 0 0 90)
			(layer "B.SilkS")
			(hide yes)
			(effects
				(font
					(size 1.27 1.27)
				)
				(justify mirror)
			)
		)
		(property "Value" ""
			(at 0 0 90)
			(layer "B.Fab")
			(effects
				(font
					(size 1.27 1.27)
				)
				(justify mirror)
			)
		)
		(duplicate_pad_numbers_are_jumpers no)
		(fp_line
			(start -0.7874 0.4064)
			(end 0.7874 0.4064)
			(stroke
				(width 0.1524)
				(type default)
			)
			(layer "B.SilkS")
		)
		(fp_line
			(start 0.7874 0.4064)
			(end 0.7874 -0.4064)
			(stroke
				(width 0.1524)
				(type default)
			)
			(layer "B.SilkS")
		)
		(fp_line
			(start -0.7874 -0.4064)
			(end -0.7874 0.4064)
			(stroke
				(width 0.1524)
				(type default)
			)
			(layer "B.SilkS")
		)
		(fp_line
			(start 0.7874 -0.4064)
			(end -0.7874 -0.4064)
			(stroke
				(width 0.1524)
				(type default)
			)
			(layer "B.SilkS")
		)
		(fp_line
			(start -0.67945 0.3048)
			(end -0.120396 0.3048)
			(stroke
				(width 0.1)
				(type default)
			)
			(layer "B.Fab")
		)
		(fp_line
			(start -0.120396 0.3048)
			(end -0.120396 0.2794)
			(stroke
				(width 0.1)
				(type default)
			)
			(layer "B.Fab")
		)
		(fp_line
			(start 0.12065 0.3048)
			(end 0.67945 0.3048)
			(stroke
				(width 0.1)
				(type default)
			)
			(layer "B.Fab")
		)
		(fp_line
			(start 0.67945 0.3048)
			(end 0.67945 -0.305054)
			(stroke
				(width 0.1)
				(type default)
			)
			(layer "B.Fab")
		)
		(fp_line
			(start -0.120396 0.2794)
			(end 0.12065 0.2794)
			(stroke
				(width 0.1)
				(type default)
			)
			(layer "B.Fab")
		)
		(fp_line
			(start 0.12065 0.2794)
			(end 0.12065 0.3048)
			(stroke
				(width 0.1)
				(type default)
			)
			(layer "B.Fab")
		)
		(fp_line
			(start -0.12065 -0.2794)
			(end -0.12065 -0.3048)
			(stroke
				(width 0.1)
				(type default)
			)
			(layer "B.Fab")
		)
		(fp_line
			(start 0.12065 -0.2794)
			(end -0.12065 -0.2794)
			(stroke
				(width 0.1)
				(type default)
			)
			(layer "B.Fab")
		)
		(fp_line
			(start -0.67945 -0.3048)
			(end -0.67945 0.3048)
			(stroke
				(width 0.1)
				(type default)
			)
			(layer "B.Fab")
		)
		(fp_line
			(start -0.12065 -0.3048)
			(end -0.67945 -0.3048)
			(stroke
				(width 0.1)
				(type default)
			)
			(layer "B.Fab")
		)
		(fp_line
			(start 0.12065 -0.305054)
			(end 0.12065 -0.2794)
			(stroke
				(width 0.1)
				(type default)
			)
			(layer "B.Fab")
		)
		(fp_line
			(start 0.67945 -0.305054)
			(end 0.12065 -0.305054)
			(stroke
				(width 0.1)
				(type default)
			)
			(layer "B.Fab")
		)
		(pad "1" smd circle
			(at 0.40005 0 90)
			(size 0 0)
			(layers "B.Cu" "B.Mask" "B.Paste")
			(net "P3V3_AUX")
		)
		(pad "2" smd circle
			(at -0.40005 0 90)
			(size 0 0)
			(layers "B.Cu" "B.Mask" "B.Paste")
			(net "FM_P12V_HSC_ENABLE")
		)
	)
	(footprint ""
		(layer "B.Cu")
		(at 114.554 -77.216 -90)
		(property "Reference" "X8"
			(at 1.94437 1.3462 0)
			(unlocked yes)
			(layer "B.SilkS")
			(effects
				(font
					(size 0.7874 0.5842)
					(thickness 0.1524)
				)
				(justify left mirror)
			)
		)
		(property "Value" ""
			(at 0 0 90)
			(layer "B.Fab")
			(effects
				(font
					(size 1.27 1.27)
				)
				(justify mirror)
			)
		)
		(property "Device Type" "TP_TDR_4P_FTS_TH-TP_TDR_4P_DIPA"
			(at -1.30175 1.27 180)
			(unlocked yes)
			(layer "B.Fab")
			(hide yes)
			(effects
				(font
					(size 0.635 0.4064)
					(thickness 0.1524)
				)
				(justify mirror)
			)
		)
		(property "User Part Number" "N_A"
			(at -1.30175 1.27 180)
			(unlocked yes)
			(layer "Cmts.User")
			(hide yes)
			(effects
				(font
					(size 0.635 0.4064)
					(thickness 0.1524)
				)
				(justify mirror)
			)
		)
		(duplicate_pad_numbers_are_jumpers no)
		(fp_line
			(start -2.54 3.81)
			(end -2.54 3.6703)
			(stroke
				(width 0.1524)
				(type default)
			)
			(layer "B.SilkS")
		)
		(fp_line
			(start 0 3.81)
			(end -2.54 3.81)
			(stroke
				(width 0.1524)
				(type default)
			)
			(layer "B.SilkS")
		)
		(fp_line
			(start 0 3.175)
			(end 0 3.81)
			(stroke
				(width 0.1524)
				(type default)
			)
			(layer "B.SilkS")
		)
		(fp_line
			(start -2.54 1.4097)
			(end -2.54 1.1303)
			(stroke
				(width 0.1524)
				(type default)
			)
			(layer "B.SilkS")
		)
		(fp_line
			(start 0 0.635)
			(end 0 1.905)
			(stroke
				(width 0.1524)
				(type default)
			)
			(layer "B.SilkS")
		)
		(fp_line
			(start -2.54 -1.1303)
			(end -2.54 -1.27)
			(stroke
				(width 0.1524)
				(type default)
			)
			(layer "B.SilkS")
		)
		(fp_line
			(start -2.54 -1.27)
			(end 0 -1.27)
			(stroke
				(width 0.1524)
				(type default)
			)
			(layer "B.SilkS")
		)
		(fp_line
			(start 0 -1.27)
			(end 0 -0.635)
			(stroke
				(width 0.1524)
				(type default)
			)
			(layer "B.SilkS")
		)
		(fp_poly
			(pts
				(xy 0.761746 0) (xy 2.285746 -0.762) (xy 2.285746 0.762)
			)
			(stroke
				(width 0)
				(type default)
			)
			(fill yes)
			(layer "B.SilkS")
		)
		(fp_line
			(start -2.54 3.81)
			(end -2.54 -1.27)
			(stroke
				(width 0.1)
				(type default)
			)
			(layer "B.Fab")
		)
		(fp_line
			(start 0 3.81)
			(end -2.54 3.81)
			(stroke
				(width 0.1)
				(type default)
			)
			(layer "B.Fab")
		)
		(fp_line
			(start -2.54 -1.27)
			(end 0 -1.27)
			(stroke
				(width 0.1)
				(type default)
			)
			(layer "B.Fab")
		)
		(fp_line
			(start 0 -1.27)
			(end 0 3.81)
			(stroke
				(width 0.1)
				(type default)
			)
			(layer "B.Fab")
		)
		(fp_poly
			(pts
				(xy 0.761746 0) (xy 2.285746 -0.762) (xy 2.285746 0.762)
			)
			(stroke
				(width 0)
				(type default)
			)
			(fill yes)
			(layer "B.Fab")
		)
		(pad "1" thru_hole circle
			(at 0 0 90)
			(size 1.0033 1.0033)
			(drill 0.249936)
			(layers "*.Cu" "*.Mask")
			(remove_unused_layers no)
			(net "TDR_DIFF_85_IN1_DN")
			(clearance 0.10795)
			(padstack
				(mode front_inner_back)
				(layer "Inner"
					(shape circle)
					(size 0.8001 0.8001)
					(clearance 0.1524)
				)
				(layer "B.Cu"
					(shape circle)
					(size 1.0033 1.0033)
					(thermal_gap 0.10795)
					(clearance 0.10795)
				)
			)
		)
		(pad "2" thru_hole circle
			(at -2.54 0 90)
			(size 1.9939 1.9939)
			(drill 0.249936)
			(layers "*.Cu" "*.Mask")
			(remove_unused_layers no)
			(net "GND_P1")
			(clearance 0.10795)
			(padstack
				(mode front_inner_back)
				(layer "Inner"
					(shape circle)
					(size 0.8001 0.8001)
					(clearance 0.1524)
				)
				(layer "B.Cu"
					(shape circle)
					(size 1.9939 1.9939)
					(thermal_gap 0.10795)
					(clearance 0.10795)
				)
			)
		)
		(pad "3" thru_hole circle
			(at -2.54 2.54 90)
			(size 1.9939 1.9939)
			(drill 0.249936)
			(layers "*.Cu" "*.Mask")
			(remove_unused_layers no)
			(net "GND_P1")
			(clearance 0.10795)
			(padstack
				(mode front_inner_back)
				(layer "Inner"
					(shape circle)
					(size 0.8001 0.8001)
					(clearance 0.1524)
				)
				(layer "B.Cu"
					(shape circle)
					(size 1.9939 1.9939)
					(thermal_gap 0.10795)
					(clearance 0.10795)
				)
			)
		)
		(pad "4" thru_hole circle
			(at 0 2.54 90)
			(size 1.0033 1.0033)
			(drill 0.249936)
			(layers "*.Cu" "*.Mask")
			(remove_unused_layers no)
			(net "TDR_DIFF_85_IN1_DP")
			(clearance 0.10795)
			(padstack
				(mode front_inner_back)
				(layer "Inner"
					(shape circle)
					(size 0.8001 0.8001)
					(clearance 0.1524)
				)
				(layer "B.Cu"
					(shape circle)
					(size 1.0033 1.0033)
					(thermal_gap 0.10795)
					(clearance 0.10795)
				)
			)
		)
	)
	(footprint ""
		(layer "B.Cu")
		(at 29.972 -102.108 180)
		(property "Reference" "C194"
			(at 0 0 0)
			(layer "B.SilkS")
			(hide yes)
			(effects
				(font
					(size 1.27 1.27)
				)
				(justify mirror)
			)
		)
		(property "Value" ""
			(at 0 0 0)
			(layer "B.Fab")
			(effects
				(font
					(size 1.27 1.27)
				)
				(justify mirror)
			)
		)
		(duplicate_pad_numbers_are_jumpers no)
		(fp_line
			(start 1.2954 0.5842)
			(end 1.2954 -0.5842)
			(stroke
				(width 0.1524)
				(type default)
			)
			(layer "B.SilkS")
		)
		(fp_line
			(start 1.2954 -0.5842)
			(end -1.2954 -0.5842)
			(stroke
				(width 0.1524)
				(type default)
			)
			(layer "B.SilkS")
		)
		(fp_line
			(start 0 -0.5842)
			(end 0 0.5842)
			(stroke
				(width 0.1524)
				(type default)
			)
			(layer "B.SilkS")
		)
		(fp_line
			(start -1.2954 0.5842)
			(end 1.2954 0.5842)
			(stroke
				(width 0.1524)
				(type default)
			)
			(layer "B.SilkS")
		)
		(fp_line
			(start -1.2954 -0.5842)
			(end -1.2954 0.5842)
			(stroke
				(width 0.1524)
				(type default)
			)
			(layer "B.SilkS")
		)
		(fp_line
			(start 1.1938 0.4064)
			(end 1.1938 -0.4064)
			(stroke
				(width 0.1)
				(type default)
			)
			(layer "B.Fab")
		)
		(fp_line
			(start 1.1938 -0.4064)
			(end 0.8636 -0.4064)
			(stroke
				(width 0.1)
				(type default)
			)
			(layer "B.Fab")
		)
		(fp_line
			(start 0.8636 0.4572)
			(end 0.8636 0.4064)
			(stroke
				(width 0.1)
				(type default)
			)
			(layer "B.Fab")
		)
		(fp_line
			(start 0.8636 0.4064)
			(end 1.1938 0.4064)
			(stroke
				(width 0.1)
				(type default)
			)
			(layer "B.Fab")
		)
		(fp_line
			(start 0.8636 -0.4064)
			(end 0.8636 -0.4572)
			(stroke
				(width 0.1)
				(type default)
			)
			(layer "B.Fab")
		)
		(fp_line
			(start 0.8636 -0.4572)
			(end -0.8636 -0.4572)
			(stroke
				(width 0.1)
				(type default)
			)
			(layer "B.Fab")
		)
		(fp_line
			(start -0.8636 0.4572)
			(end 0.8636 0.4572)
			(stroke
				(width 0.1)
				(type default)
			)
			(layer "B.Fab")
		)
		(fp_line
			(start -0.8636 0.4064)
			(end -0.8636 0.4572)
			(stroke
				(width 0.1)
				(type default)
			)
			(layer "B.Fab")
		)
		(fp_line
			(start -0.8636 -0.4064)
			(end -1.1938 -0.4064)
			(stroke
				(width 0.1)
				(type default)
			)
			(layer "B.Fab")
		)
		(fp_line
			(start -0.8636 -0.4572)
			(end -0.8636 -0.4064)
			(stroke
				(width 0.1)
				(type default)
			)
			(layer "B.Fab")
		)
		(fp_line
			(start -1.1938 0.4064)
			(end -0.8636 0.4064)
			(stroke
				(width 0.1)
				(type default)
			)
			(layer "B.Fab")
		)
		(fp_line
			(start -1.1938 -0.4064)
			(end -1.1938 0.4064)
			(stroke
				(width 0.1)
				(type default)
			)
			(layer "B.Fab")
		)
		(pad "1" smd rect
			(at 0.7366 0 90)
			(size 0.7112 0.8128)
			(layers "B.Cu" "B.Mask" "B.Paste")
			(net "P3V3_AUX")
		)
		(pad "2" smd rect
			(at -0.7366 0 90)
			(size 0.7112 0.8128)
			(layers "B.Cu" "B.Mask" "B.Paste")
			(net "GND")
		)
	)
	(footprint ""
		(layer "B.Cu")
		(at 80.547464 -51.0413 -90)
		(property "Reference" "R6"
			(at 0 0 90)
			(layer "B.SilkS")
			(hide yes)
			(effects
				(font
					(size 1.27 1.27)
				)
				(justify mirror)
			)
		)
		(property "Value" ""
			(at 0 0 90)
			(layer "B.Fab")
			(effects
				(font
					(size 1.27 1.27)
				)
				(justify mirror)
			)
		)
		(duplicate_pad_numbers_are_jumpers no)
		(fp_line
			(start -0.7874 0.4064)
			(end 0.7874 0.4064)
			(stroke
				(width 0.1524)
				(type default)
			)
			(layer "B.SilkS")
		)
		(fp_line
			(start 0.7874 0.4064)
			(end 0.7874 -0.4064)
			(stroke
				(width 0.1524)
				(type default)
			)
			(layer "B.SilkS")
		)
		(fp_line
			(start -0.7874 -0.4064)
			(end -0.7874 0.4064)
			(stroke
				(width 0.1524)
				(type default)
			)
			(layer "B.SilkS")
		)
		(fp_line
			(start 0.7874 -0.4064)
			(end -0.7874 -0.4064)
			(stroke
				(width 0.1524)
				(type default)
			)
			(layer "B.SilkS")
		)
		(fp_line
			(start -0.67945 0.3048)
			(end -0.120396 0.3048)
			(stroke
				(width 0.1)
				(type default)
			)
			(layer "B.Fab")
		)
		(fp_line
			(start -0.120396 0.3048)
			(end -0.120396 0.2794)
			(stroke
				(width 0.1)
				(type default)
			)
			(layer "B.Fab")
		)
		(fp_line
			(start 0.12065 0.3048)
			(end 0.67945 0.3048)
			(stroke
				(width 0.1)
				(type default)
			)
			(layer "B.Fab")
		)
		(fp_line
			(start 0.67945 0.3048)
			(end 0.67945 -0.305054)
			(stroke
				(width 0.1)
				(type default)
			)
			(layer "B.Fab")
		)
		(fp_line
			(start -0.120396 0.2794)
			(end 0.12065 0.2794)
			(stroke
				(width 0.1)
				(type default)
			)
			(layer "B.Fab")
		)
		(fp_line
			(start 0.12065 0.2794)
			(end 0.12065 0.3048)
			(stroke
				(width 0.1)
				(type default)
			)
			(layer "B.Fab")
		)
		(fp_line
			(start -0.12065 -0.2794)
			(end -0.12065 -0.3048)
			(stroke
				(width 0.1)
				(type default)
			)
			(layer "B.Fab")
		)
		(fp_line
			(start 0.12065 -0.2794)
			(end -0.12065 -0.2794)
			(stroke
				(width 0.1)
				(type default)
			)
			(layer "B.Fab")
		)
		(fp_line
			(start -0.67945 -0.3048)
			(end -0.67945 0.3048)
			(stroke
				(width 0.1)
				(type default)
			)
			(layer "B.Fab")
		)
		(fp_line
			(start -0.12065 -0.3048)
			(end -0.67945 -0.3048)
			(stroke
				(width 0.1)
				(type default)
			)
			(layer "B.Fab")
		)
		(fp_line
			(start 0.12065 -0.305054)
			(end 0.12065 -0.2794)
			(stroke
				(width 0.1)
				(type default)
			)
			(layer "B.Fab")
		)
		(fp_line
			(start 0.67945 -0.305054)
			(end 0.12065 -0.305054)
			(stroke
				(width 0.1)
				(type default)
			)
			(layer "B.Fab")
		)
		(pad "1" smd circle
			(at 0.40005 0 90)
			(size 0 0)
			(layers "B.Cu" "B.Mask" "B.Paste")
			(net "PD_M_BMC_DDR4_ZQ")
		)
		(pad "2" smd circle
			(at -0.40005 0 90)
			(size 0 0)
			(layers "B.Cu" "B.Mask" "B.Paste")
			(net "GND")
		)
	)
	(footprint ""
		(layer "B.Cu")
		(at 49.657 -30.861 -90)
		(property "Reference" "R265"
			(at 0 0 90)
			(layer "B.SilkS")
			(hide yes)
			(effects
				(font
					(size 1.27 1.27)
				)
				(justify mirror)
			)
		)
		(property "Value" ""
			(at 0 0 90)
			(layer "B.Fab")
			(effects
				(font
					(size 1.27 1.27)
				)
				(justify mirror)
			)
		)
		(duplicate_pad_numbers_are_jumpers no)
		(fp_line
			(start -0.7874 0.4064)
			(end 0.7874 0.4064)
			(stroke
				(width 0.1524)
				(type default)
			)
			(layer "B.SilkS")
		)
		(fp_line
			(start 0.7874 0.4064)
			(end 0.7874 -0.4064)
			(stroke
				(width 0.1524)
				(type default)
			)
			(layer "B.SilkS")
		)
		(fp_line
			(start -0.7874 -0.4064)
			(end -0.7874 0.4064)
			(stroke
				(width 0.1524)
				(type default)
			)
			(layer "B.SilkS")
		)
		(fp_line
			(start 0.7874 -0.4064)
			(end -0.7874 -0.4064)
			(stroke
				(width 0.1524)
				(type default)
			)
			(layer "B.SilkS")
		)
		(fp_line
			(start -0.67945 0.3048)
			(end -0.120396 0.3048)
			(stroke
				(width 0.1)
				(type default)
			)
			(layer "B.Fab")
		)
		(fp_line
			(start -0.120396 0.3048)
			(end -0.120396 0.2794)
			(stroke
				(width 0.1)
				(type default)
			)
			(layer "B.Fab")
		)
		(fp_line
			(start 0.12065 0.3048)
			(end 0.67945 0.3048)
			(stroke
				(width 0.1)
				(type default)
			)
			(layer "B.Fab")
		)
		(fp_line
			(start 0.67945 0.3048)
			(end 0.67945 -0.305054)
			(stroke
				(width 0.1)
				(type default)
			)
			(layer "B.Fab")
		)
		(fp_line
			(start -0.120396 0.2794)
			(end 0.12065 0.2794)
			(stroke
				(width 0.1)
				(type default)
			)
			(layer "B.Fab")
		)
		(fp_line
			(start 0.12065 0.2794)
			(end 0.12065 0.3048)
			(stroke
				(width 0.1)
				(type default)
			)
			(layer "B.Fab")
		)
		(fp_line
			(start -0.12065 -0.2794)
			(end -0.12065 -0.3048)
			(stroke
				(width 0.1)
				(type default)
			)
			(layer "B.Fab")
		)
		(fp_line
			(start 0.12065 -0.2794)
			(end -0.12065 -0.2794)
			(stroke
				(width 0.1)
				(type default)
			)
			(layer "B.Fab")
		)
		(fp_line
			(start -0.67945 -0.3048)
			(end -0.67945 0.3048)
			(stroke
				(width 0.1)
				(type default)
			)
			(layer "B.Fab")
		)
		(fp_line
			(start -0.12065 -0.3048)
			(end -0.67945 -0.3048)
			(stroke
				(width 0.1)
				(type default)
			)
			(layer "B.Fab")
		)
		(fp_line
			(start 0.12065 -0.305054)
			(end 0.12065 -0.2794)
			(stroke
				(width 0.1)
				(type default)
			)
			(layer "B.Fab")
		)
		(fp_line
			(start 0.67945 -0.305054)
			(end 0.12065 -0.305054)
			(stroke
				(width 0.1)
				(type default)
			)
			(layer "B.Fab")
		)
		(pad "1" smd circle
			(at 0.40005 0 90)
			(size 0 0)
			(layers "B.Cu" "B.Mask" "B.Paste")
			(net "P3V3_AUX")
		)
		(pad "2" smd circle
			(at -0.40005 0 90)
			(size 0 0)
			(layers "B.Cu" "B.Mask" "B.Paste")
			(net "SMB_BMC_MM16_SDA")
		)
	)
	(footprint ""
		(layer "B.Cu")
		(at 64.662304 -51.586638)
		(property "Reference" "R127"
			(at 0 0 0)
			(layer "B.SilkS")
			(hide yes)
			(effects
				(font
					(size 1.27 1.27)
				)
				(justify mirror)
			)
		)
		(property "Value" ""
			(at 0 0 0)
			(layer "B.Fab")
			(effects
				(font
					(size 1.27 1.27)
				)
				(justify mirror)
			)
		)
		(duplicate_pad_numbers_are_jumpers no)
		(fp_line
			(start -0.7874 -0.4064)
			(end -0.7874 0.4064)
			(stroke
				(width 0.1524)
				(type default)
			)
			(layer "B.SilkS")
		)
		(fp_line
			(start -0.7874 0.4064)
			(end 0.7874 0.4064)
			(stroke
				(width 0.1524)
				(type default)
			)
			(layer "B.SilkS")
		)
		(fp_line
			(start 0.7874 -0.4064)
			(end -0.7874 -0.4064)
			(stroke
				(width 0.1524)
				(type default)
			)
			(layer "B.SilkS")
		)
		(fp_line
			(start 0.7874 0.4064)
			(end 0.7874 -0.4064)
			(stroke
				(width 0.1524)
				(type default)
			)
			(layer "B.SilkS")
		)
		(fp_line
			(start -0.67945 -0.3048)
			(end -0.67945 0.3048)
			(stroke
				(width 0.1)
				(type default)
			)
			(layer "B.Fab")
		)
		(fp_line
			(start -0.67945 0.3048)
			(end -0.120396 0.3048)
			(stroke
				(width 0.1)
				(type default)
			)
			(layer "B.Fab")
		)
		(fp_line
			(start -0.12065 -0.3048)
			(end -0.67945 -0.3048)
			(stroke
				(width 0.1)
				(type default)
			)
			(layer "B.Fab")
		)
		(fp_line
			(start -0.12065 -0.2794)
			(end -0.12065 -0.3048)
			(stroke
				(width 0.1)
				(type default)
			)
			(layer "B.Fab")
		)
		(fp_line
			(start -0.120396 0.2794)
			(end 0.12065 0.2794)
			(stroke
				(width 0.1)
				(type default)
			)
			(layer "B.Fab")
		)
		(fp_line
			(start -0.120396 0.3048)
			(end -0.120396 0.2794)
			(stroke
				(width 0.1)
				(type default)
			)
			(layer "B.Fab")
		)
		(fp_line
			(start 0.12065 -0.305054)
			(end 0.12065 -0.2794)
			(stroke
				(width 0.1)
				(type default)
			)
			(layer "B.Fab")
		)
		(fp_line
			(start 0.12065 -0.2794)
			(end -0.12065 -0.2794)
			(stroke
				(width 0.1)
				(type default)
			)
			(layer "B.Fab")
		)
		(fp_line
			(start 0.12065 0.2794)
			(end 0.12065 0.3048)
			(stroke
				(width 0.1)
				(type default)
			)
			(layer "B.Fab")
		)
		(fp_line
			(start 0.12065 0.3048)
			(end 0.67945 0.3048)
			(stroke
				(width 0.1)
				(type default)
			)
			(layer "B.Fab")
		)
		(fp_line
			(start 0.67945 -0.305054)
			(end 0.12065 -0.305054)
			(stroke
				(width 0.1)
				(type default)
			)
			(layer "B.Fab")
		)
		(fp_line
			(start 0.67945 0.3048)
			(end 0.67945 -0.305054)
			(stroke
				(width 0.1)
				(type default)
			)
			(layer "B.Fab")
		)
		(pad "1" smd circle
			(at 0.40005 0 180)
			(size 0 0)
			(layers "B.Cu" "B.Mask" "B.Paste")
			(net "GND")
		)
		(pad "2" smd circle
			(at -0.40005 0 180)
			(size 0 0)
			(layers "B.Cu" "B.Mask" "B.Paste")
			(net "IBMC_MIOZ")
		)
	)
	(footprint ""
		(layer "B.Cu")
		(at 59.551316 -49.314354)
		(property "Reference" "C86"
			(at 0 0 0)
			(layer "B.SilkS")
			(hide yes)
			(effects
				(font
					(size 1.27 1.27)
				)
				(justify mirror)
			)
		)
		(property "Value" ""
			(at 0 0 0)
			(layer "B.Fab")
			(effects
				(font
					(size 1.27 1.27)
				)
				(justify mirror)
			)
		)
		(duplicate_pad_numbers_are_jumpers no)
		(fp_line
			(start -0.7874 -0.4064)
			(end -0.7874 0.4064)
			(stroke
				(width 0.1524)
				(type default)
			)
			(layer "B.SilkS")
		)
		(fp_line
			(start -0.7874 0.4064)
			(end 0.7874 0.4064)
			(stroke
				(width 0.1524)
				(type default)
			)
			(layer "B.SilkS")
		)
		(fp_line
			(start 0.7874 -0.4064)
			(end -0.7874 -0.4064)
			(stroke
				(width 0.1524)
				(type default)
			)
			(layer "B.SilkS")
		)
		(fp_line
			(start 0.7874 0.4064)
			(end 0.7874 -0.4064)
			(stroke
				(width 0.1524)
				(type default)
			)
			(layer "B.SilkS")
		)
		(fp_line
			(start -0.67945 -0.3048)
			(end -0.67945 0.3048)
			(stroke
				(width 0.1)
				(type default)
			)
			(layer "B.Fab")
		)
		(fp_line
			(start -0.67945 0.3048)
			(end -0.120396 0.3048)
			(stroke
				(width 0.1)
				(type default)
			)
			(layer "B.Fab")
		)
		(fp_line
			(start -0.12065 -0.3048)
			(end -0.67945 -0.3048)
			(stroke
				(width 0.1)
				(type default)
			)
			(layer "B.Fab")
		)
		(fp_line
			(start -0.12065 -0.2794)
			(end -0.12065 -0.3048)
			(stroke
				(width 0.1)
				(type default)
			)
			(layer "B.Fab")
		)
		(fp_line
			(start -0.120396 0.2794)
			(end 0.12065 0.2794)
			(stroke
				(width 0.1)
				(type default)
			)
			(layer "B.Fab")
		)
		(fp_line
			(start -0.120396 0.3048)
			(end -0.120396 0.2794)
			(stroke
				(width 0.1)
				(type default)
			)
			(layer "B.Fab")
		)
		(fp_line
			(start 0.12065 -0.305054)
			(end 0.12065 -0.2794)
			(stroke
				(width 0.1)
				(type default)
			)
			(layer "B.Fab")
		)
		(fp_line
			(start 0.12065 -0.2794)
			(end -0.12065 -0.2794)
			(stroke
				(width 0.1)
				(type default)
			)
			(layer "B.Fab")
		)
		(fp_line
			(start 0.12065 0.2794)
			(end 0.12065 0.3048)
			(stroke
				(width 0.1)
				(type default)
			)
			(layer "B.Fab")
		)
		(fp_line
			(start 0.12065 0.3048)
			(end 0.67945 0.3048)
			(stroke
				(width 0.1)
				(type default)
			)
			(layer "B.Fab")
		)
		(fp_line
			(start 0.67945 -0.305054)
			(end 0.12065 -0.305054)
			(stroke
				(width 0.1)
				(type default)
			)
			(layer "B.Fab")
		)
		(fp_line
			(start 0.67945 0.3048)
			(end 0.67945 -0.305054)
			(stroke
				(width 0.1)
				(type default)
			)
			(layer "B.Fab")
		)
		(pad "1" smd circle
			(at 0.40005 0 180)
			(size 0 0)
			(layers "B.Cu" "B.Mask" "B.Paste")
			(net "P1V0_AUX")
		)
		(pad "2" smd circle
			(at -0.40005 0 180)
			(size 0 0)
			(layers "B.Cu" "B.Mask" "B.Paste")
			(net "GND")
		)
	)
	(footprint ""
		(layer "B.Cu")
		(at 83.283552 -28.627578 180)
		(property "Reference" "R411"
			(at 0 0 0)
			(layer "B.SilkS")
			(hide yes)
			(effects
				(font
					(size 1.27 1.27)
				)
				(justify mirror)
			)
		)
		(property "Value" ""
			(at 0 0 0)
			(layer "B.Fab")
			(effects
				(font
					(size 1.27 1.27)
				)
				(justify mirror)
			)
		)
		(duplicate_pad_numbers_are_jumpers no)
		(fp_line
			(start 0.7874 0.4064)
			(end 0.7874 -0.4064)
			(stroke
				(width 0.1524)
				(type default)
			)
			(layer "B.SilkS")
		)
		(fp_line
			(start 0.7874 -0.4064)
			(end -0.7874 -0.4064)
			(stroke
				(width 0.1524)
				(type default)
			)
			(layer "B.SilkS")
		)
		(fp_line
			(start -0.7874 0.4064)
			(end 0.7874 0.4064)
			(stroke
				(width 0.1524)
				(type default)
			)
			(layer "B.SilkS")
		)
		(fp_line
			(start -0.7874 -0.4064)
			(end -0.7874 0.4064)
			(stroke
				(width 0.1524)
				(type default)
			)
			(layer "B.SilkS")
		)
		(fp_line
			(start 0.67945 0.3048)
			(end 0.67945 -0.305054)
			(stroke
				(width 0.1)
				(type default)
			)
			(layer "B.Fab")
		)
		(fp_line
			(start 0.67945 -0.305054)
			(end 0.12065 -0.305054)
			(stroke
				(width 0.1)
				(type default)
			)
			(layer "B.Fab")
		)
		(fp_line
			(start 0.12065 0.3048)
			(end 0.67945 0.3048)
			(stroke
				(width 0.1)
				(type default)
			)
			(layer "B.Fab")
		)
		(fp_line
			(start 0.12065 0.2794)
			(end 0.12065 0.3048)
			(stroke
				(width 0.1)
				(type default)
			)
			(layer "B.Fab")
		)
		(fp_line
			(start 0.12065 -0.2794)
			(end -0.12065 -0.2794)
			(stroke
				(width 0.1)
				(type default)
			)
			(layer "B.Fab")
		)
		(fp_line
			(start 0.12065 -0.305054)
			(end 0.12065 -0.2794)
			(stroke
				(width 0.1)
				(type default)
			)
			(layer "B.Fab")
		)
		(fp_line
			(start -0.120396 0.3048)
			(end -0.120396 0.2794)
			(stroke
				(width 0.1)
				(type default)
			)
			(layer "B.Fab")
		)
		(fp_line
			(start -0.120396 0.2794)
			(end 0.12065 0.2794)
			(stroke
				(width 0.1)
				(type default)
			)
			(layer "B.Fab")
		)
		(fp_line
			(start -0.12065 -0.2794)
			(end -0.12065 -0.3048)
			(stroke
				(width 0.1)
				(type default)
			)
			(layer "B.Fab")
		)
		(fp_line
			(start -0.12065 -0.3048)
			(end -0.67945 -0.3048)
			(stroke
				(width 0.1)
				(type default)
			)
			(layer "B.Fab")
		)
		(fp_line
			(start -0.67945 0.3048)
			(end -0.120396 0.3048)
			(stroke
				(width 0.1)
				(type default)
			)
			(layer "B.Fab")
		)
		(fp_line
			(start -0.67945 -0.3048)
			(end -0.67945 0.3048)
			(stroke
				(width 0.1)
				(type default)
			)
			(layer "B.Fab")
		)
		(pad "1" smd circle
			(at 0.40005 0)
			(size 0 0)
			(layers "B.Cu" "B.Mask" "B.Paste")
			(net "FRU_E0")
		)
		(pad "2" smd circle
			(at -0.40005 0)
			(size 0 0)
			(layers "B.Cu" "B.Mask" "B.Paste")
			(net "GND")
		)
	)
	(footprint ""
		(layer "B.Cu")
		(at 72.621394 -72.047608 -90)
		(property "Reference" "R684"
			(at 0 0 90)
			(layer "B.SilkS")
			(hide yes)
			(effects
				(font
					(size 1.27 1.27)
				)
				(justify mirror)
			)
		)
		(property "Value" ""
			(at 0 0 90)
			(layer "B.Fab")
			(effects
				(font
					(size 1.27 1.27)
				)
				(justify mirror)
			)
		)
		(duplicate_pad_numbers_are_jumpers no)
		(fp_line
			(start -0.7874 0.4064)
			(end 0.7874 0.4064)
			(stroke
				(width 0.1524)
				(type default)
			)
			(layer "B.SilkS")
		)
		(fp_line
			(start 0.7874 0.4064)
			(end 0.7874 -0.4064)
			(stroke
				(width 0.1524)
				(type default)
			)
			(layer "B.SilkS")
		)
		(fp_line
			(start -0.7874 -0.4064)
			(end -0.7874 0.4064)
			(stroke
				(width 0.1524)
				(type default)
			)
			(layer "B.SilkS")
		)
		(fp_line
			(start 0.7874 -0.4064)
			(end -0.7874 -0.4064)
			(stroke
				(width 0.1524)
				(type default)
			)
			(layer "B.SilkS")
		)
		(fp_line
			(start -0.67945 0.3048)
			(end -0.120396 0.3048)
			(stroke
				(width 0.1)
				(type default)
			)
			(layer "B.Fab")
		)
		(fp_line
			(start -0.120396 0.3048)
			(end -0.120396 0.2794)
			(stroke
				(width 0.1)
				(type default)
			)
			(layer "B.Fab")
		)
		(fp_line
			(start 0.12065 0.3048)
			(end 0.67945 0.3048)
			(stroke
				(width 0.1)
				(type default)
			)
			(layer "B.Fab")
		)
		(fp_line
			(start 0.67945 0.3048)
			(end 0.67945 -0.305054)
			(stroke
				(width 0.1)
				(type default)
			)
			(layer "B.Fab")
		)
		(fp_line
			(start -0.120396 0.2794)
			(end 0.12065 0.2794)
			(stroke
				(width 0.1)
				(type default)
			)
			(layer "B.Fab")
		)
		(fp_line
			(start 0.12065 0.2794)
			(end 0.12065 0.3048)
			(stroke
				(width 0.1)
				(type default)
			)
			(layer "B.Fab")
		)
		(fp_line
			(start -0.12065 -0.2794)
			(end -0.12065 -0.3048)
			(stroke
				(width 0.1)
				(type default)
			)
			(layer "B.Fab")
		)
		(fp_line
			(start 0.12065 -0.2794)
			(end -0.12065 -0.2794)
			(stroke
				(width 0.1)
				(type default)
			)
			(layer "B.Fab")
		)
		(fp_line
			(start -0.67945 -0.3048)
			(end -0.67945 0.3048)
			(stroke
				(width 0.1)
				(type default)
			)
			(layer "B.Fab")
		)
		(fp_line
			(start -0.12065 -0.3048)
			(end -0.67945 -0.3048)
			(stroke
				(width 0.1)
				(type default)
			)
			(layer "B.Fab")
		)
		(fp_line
			(start 0.12065 -0.305054)
			(end 0.12065 -0.2794)
			(stroke
				(width 0.1)
				(type default)
			)
			(layer "B.Fab")
		)
		(fp_line
			(start 0.67945 -0.305054)
			(end 0.12065 -0.305054)
			(stroke
				(width 0.1)
				(type default)
			)
			(layer "B.Fab")
		)
		(pad "1" smd circle
			(at 0.40005 0 90)
			(size 0 0)
			(layers "B.Cu" "B.Mask" "B.Paste")
			(net "BMC_EMMC_WP_N")
		)
		(pad "2" smd circle
			(at -0.40005 0 90)
			(size 0 0)
			(layers "B.Cu" "B.Mask" "B.Paste")
			(net "GND")
		)
	)
	(footprint ""
		(layer "B.Cu")
		(at 44.38396 -34.637726 90)
		(property "Reference" "R139"
			(at 0 0 90)
			(layer "B.SilkS")
			(hide yes)
			(effects
				(font
					(size 1.27 1.27)
				)
				(justify mirror)
			)
		)
		(property "Value" ""
			(at 0 0 90)
			(layer "B.Fab")
			(effects
				(font
					(size 1.27 1.27)
				)
				(justify mirror)
			)
		)
		(duplicate_pad_numbers_are_jumpers no)
		(fp_line
			(start 0.7874 -0.4064)
			(end -0.7874 -0.4064)
			(stroke
				(width 0.1524)
				(type default)
			)
			(layer "B.SilkS")
		)
		(fp_line
			(start -0.7874 -0.4064)
			(end -0.7874 0.4064)
			(stroke
				(width 0.1524)
				(type default)
			)
			(layer "B.SilkS")
		)
		(fp_line
			(start 0.7874 0.4064)
			(end 0.7874 -0.4064)
			(stroke
				(width 0.1524)
				(type default)
			)
			(layer "B.SilkS")
		)
		(fp_line
			(start -0.7874 0.4064)
			(end 0.7874 0.4064)
			(stroke
				(width 0.1524)
				(type default)
			)
			(layer "B.SilkS")
		)
		(fp_line
			(start 0.67945 -0.305054)
			(end 0.12065 -0.305054)
			(stroke
				(width 0.1)
				(type default)
			)
			(layer "B.Fab")
		)
		(fp_line
			(start 0.12065 -0.305054)
			(end 0.12065 -0.2794)
			(stroke
				(width 0.1)
				(type default)
			)
			(layer "B.Fab")
		)
		(fp_line
			(start -0.12065 -0.3048)
			(end -0.67945 -0.3048)
			(stroke
				(width 0.1)
				(type default)
			)
			(layer "B.Fab")
		)
		(fp_line
			(start -0.67945 -0.3048)
			(end -0.67945 0.3048)
			(stroke
				(width 0.1)
				(type default)
			)
			(layer "B.Fab")
		)
		(fp_line
			(start 0.12065 -0.2794)
			(end -0.12065 -0.2794)
			(stroke
				(width 0.1)
				(type default)
			)
			(layer "B.Fab")
		)
		(fp_line
			(start -0.12065 -0.2794)
			(end -0.12065 -0.3048)
			(stroke
				(width 0.1)
				(type default)
			)
			(layer "B.Fab")
		)
		(fp_line
			(start 0.12065 0.2794)
			(end 0.12065 0.3048)
			(stroke
				(width 0.1)
				(type default)
			)
			(layer "B.Fab")
		)
		(fp_line
			(start -0.120396 0.2794)
			(end 0.12065 0.2794)
			(stroke
				(width 0.1)
				(type default)
			)
			(layer "B.Fab")
		)
		(fp_line
			(start 0.67945 0.3048)
			(end 0.67945 -0.305054)
			(stroke
				(width 0.1)
				(type default)
			)
			(layer "B.Fab")
		)
		(fp_line
			(start 0.12065 0.3048)
			(end 0.67945 0.3048)
			(stroke
				(width 0.1)
				(type default)
			)
			(layer "B.Fab")
		)
		(fp_line
			(start -0.120396 0.3048)
			(end -0.120396 0.2794)
			(stroke
				(width 0.1)
				(type default)
			)
			(layer "B.Fab")
		)
		(fp_line
			(start -0.67945 0.3048)
			(end -0.120396 0.3048)
			(stroke
				(width 0.1)
				(type default)
			)
			(layer "B.Fab")
		)
		(pad "1" smd circle
			(at 0.40005 0 270)
			(size 0 0)
			(layers "B.Cu" "B.Mask" "B.Paste")
			(net "SMB_BMC_MM4_R_SDA")
		)
		(pad "2" smd circle
			(at -0.40005 0 270)
			(size 0 0)
			(layers "B.Cu" "B.Mask" "B.Paste")
			(net "SMB_BMC_MM4_SDA")
		)
	)
	(footprint ""
		(layer "B.Cu")
		(at 17.272 -80.772 90)
		(property "Reference" "R272"
			(at 0 0 90)
			(layer "B.SilkS")
			(hide yes)
			(effects
				(font
					(size 1.27 1.27)
				)
				(justify mirror)
			)
		)
		(property "Value" ""
			(at 0 0 90)
			(layer "B.Fab")
			(effects
				(font
					(size 1.27 1.27)
				)
				(justify mirror)
			)
		)
		(duplicate_pad_numbers_are_jumpers no)
		(fp_line
			(start 0.7874 -0.4064)
			(end -0.7874 -0.4064)
			(stroke
				(width 0.1524)
				(type default)
			)
			(layer "B.SilkS")
		)
		(fp_line
			(start -0.7874 -0.4064)
			(end -0.7874 0.4064)
			(stroke
				(width 0.1524)
				(type default)
			)
			(layer "B.SilkS")
		)
		(fp_line
			(start 0.7874 0.4064)
			(end 0.7874 -0.4064)
			(stroke
				(width 0.1524)
				(type default)
			)
			(layer "B.SilkS")
		)
		(fp_line
			(start -0.7874 0.4064)
			(end 0.7874 0.4064)
			(stroke
				(width 0.1524)
				(type default)
			)
			(layer "B.SilkS")
		)
		(fp_line
			(start 0.67945 -0.305054)
			(end 0.12065 -0.305054)
			(stroke
				(width 0.1)
				(type default)
			)
			(layer "B.Fab")
		)
		(fp_line
			(start 0.12065 -0.305054)
			(end 0.12065 -0.2794)
			(stroke
				(width 0.1)
				(type default)
			)
			(layer "B.Fab")
		)
		(fp_line
			(start -0.12065 -0.3048)
			(end -0.67945 -0.3048)
			(stroke
				(width 0.1)
				(type default)
			)
			(layer "B.Fab")
		)
		(fp_line
			(start -0.67945 -0.3048)
			(end -0.67945 0.3048)
			(stroke
				(width 0.1)
				(type default)
			)
			(layer "B.Fab")
		)
		(fp_line
			(start 0.12065 -0.2794)
			(end -0.12065 -0.2794)
			(stroke
				(width 0.1)
				(type default)
			)
			(layer "B.Fab")
		)
		(fp_line
			(start -0.12065 -0.2794)
			(end -0.12065 -0.3048)
			(stroke
				(width 0.1)
				(type default)
			)
			(layer "B.Fab")
		)
		(fp_line
			(start 0.12065 0.2794)
			(end 0.12065 0.3048)
			(stroke
				(width 0.1)
				(type default)
			)
			(layer "B.Fab")
		)
		(fp_line
			(start -0.120396 0.2794)
			(end 0.12065 0.2794)
			(stroke
				(width 0.1)
				(type default)
			)
			(layer "B.Fab")
		)
		(fp_line
			(start 0.67945 0.3048)
			(end 0.67945 -0.305054)
			(stroke
				(width 0.1)
				(type default)
			)
			(layer "B.Fab")
		)
		(fp_line
			(start 0.12065 0.3048)
			(end 0.67945 0.3048)
			(stroke
				(width 0.1)
				(type default)
			)
			(layer "B.Fab")
		)
		(fp_line
			(start -0.120396 0.3048)
			(end -0.120396 0.2794)
			(stroke
				(width 0.1)
				(type default)
			)
			(layer "B.Fab")
		)
		(fp_line
			(start -0.67945 0.3048)
			(end -0.120396 0.3048)
			(stroke
				(width 0.1)
				(type default)
			)
			(layer "B.Fab")
		)
		(pad "1" smd circle
			(at 0.40005 0 270)
			(size 0 0)
			(layers "B.Cu" "B.Mask" "B.Paste")
			(net "SMB_BMC_MM16_R3_SCL")
		)
		(pad "2" smd circle
			(at -0.40005 0 270)
			(size 0 0)
			(layers "B.Cu" "B.Mask" "B.Paste")
			(net "SMB_BMC_MM16_R5_SCL")
		)
	)
	(footprint ""
		(layer "B.Cu")
		(at 83.8454 -30.5435 180)
		(property "Reference" "C125"
			(at 0 0 0)
			(layer "B.SilkS")
			(hide yes)
			(effects
				(font
					(size 1.27 1.27)
				)
				(justify mirror)
			)
		)
		(property "Value" ""
			(at 0 0 0)
			(layer "B.Fab")
			(effects
				(font
					(size 1.27 1.27)
				)
				(justify mirror)
			)
		)
		(duplicate_pad_numbers_are_jumpers no)
		(fp_line
			(start 1.2954 0.5842)
			(end 1.2954 -0.5842)
			(stroke
				(width 0.1524)
				(type default)
			)
			(layer "B.SilkS")
		)
		(fp_line
			(start 1.2954 -0.5842)
			(end -1.2954 -0.5842)
			(stroke
				(width 0.1524)
				(type default)
			)
			(layer "B.SilkS")
		)
		(fp_line
			(start 0 -0.5842)
			(end 0 0.5842)
			(stroke
				(width 0.1524)
				(type default)
			)
			(layer "B.SilkS")
		)
		(fp_line
			(start -1.2954 0.5842)
			(end 1.2954 0.5842)
			(stroke
				(width 0.1524)
				(type default)
			)
			(layer "B.SilkS")
		)
		(fp_line
			(start -1.2954 -0.5842)
			(end -1.2954 0.5842)
			(stroke
				(width 0.1524)
				(type default)
			)
			(layer "B.SilkS")
		)
		(fp_line
			(start 1.1938 0.4064)
			(end 1.1938 -0.4064)
			(stroke
				(width 0.1)
				(type default)
			)
			(layer "B.Fab")
		)
		(fp_line
			(start 1.1938 -0.4064)
			(end 0.8636 -0.4064)
			(stroke
				(width 0.1)
				(type default)
			)
			(layer "B.Fab")
		)
		(fp_line
			(start 0.8636 0.4572)
			(end 0.8636 0.4064)
			(stroke
				(width 0.1)
				(type default)
			)
			(layer "B.Fab")
		)
		(fp_line
			(start 0.8636 0.4064)
			(end 1.1938 0.4064)
			(stroke
				(width 0.1)
				(type default)
			)
			(layer "B.Fab")
		)
		(fp_line
			(start 0.8636 -0.4064)
			(end 0.8636 -0.4572)
			(stroke
				(width 0.1)
				(type default)
			)
			(layer "B.Fab")
		)
		(fp_line
			(start 0.8636 -0.4572)
			(end -0.8636 -0.4572)
			(stroke
				(width 0.1)
				(type default)
			)
			(layer "B.Fab")
		)
		(fp_line
			(start -0.8636 0.4572)
			(end 0.8636 0.4572)
			(stroke
				(width 0.1)
				(type default)
			)
			(layer "B.Fab")
		)
		(fp_line
			(start -0.8636 0.4064)
			(end -0.8636 0.4572)
			(stroke
				(width 0.1)
				(type default)
			)
			(layer "B.Fab")
		)
		(fp_line
			(start -0.8636 -0.4064)
			(end -1.1938 -0.4064)
			(stroke
				(width 0.1)
				(type default)
			)
			(layer "B.Fab")
		)
		(fp_line
			(start -0.8636 -0.4572)
			(end -0.8636 -0.4064)
			(stroke
				(width 0.1)
				(type default)
			)
			(layer "B.Fab")
		)
		(fp_line
			(start -1.1938 0.4064)
			(end -0.8636 0.4064)
			(stroke
				(width 0.1)
				(type default)
			)
			(layer "B.Fab")
		)
		(fp_line
			(start -1.1938 -0.4064)
			(end -1.1938 0.4064)
			(stroke
				(width 0.1)
				(type default)
			)
			(layer "B.Fab")
		)
		(pad "1" smd rect
			(at 0.7366 0 90)
			(size 0.7112 0.8128)
			(layers "B.Cu" "B.Mask" "B.Paste")
			(net "P3V3_AUX")
		)
		(pad "2" smd rect
			(at -0.7366 0 90)
			(size 0.7112 0.8128)
			(layers "B.Cu" "B.Mask" "B.Paste")
			(net "GND")
		)
	)
	(footprint ""
		(layer "B.Cu")
		(at 60.440316 -45.029628 -90)
		(property "Reference" "C105"
			(at 0 0 90)
			(layer "B.SilkS")
			(hide yes)
			(effects
				(font
					(size 1.27 1.27)
				)
				(justify mirror)
			)
		)
		(property "Value" ""
			(at 0 0 90)
			(layer "B.Fab")
			(effects
				(font
					(size 1.27 1.27)
				)
				(justify mirror)
			)
		)
		(duplicate_pad_numbers_are_jumpers no)
		(fp_line
			(start -0.7874 0.4064)
			(end 0.7874 0.4064)
			(stroke
				(width 0.1524)
				(type default)
			)
			(layer "B.SilkS")
		)
		(fp_line
			(start 0.7874 0.4064)
			(end 0.7874 -0.4064)
			(stroke
				(width 0.1524)
				(type default)
			)
			(layer "B.SilkS")
		)
		(fp_line
			(start -0.7874 -0.4064)
			(end -0.7874 0.4064)
			(stroke
				(width 0.1524)
				(type default)
			)
			(layer "B.SilkS")
		)
		(fp_line
			(start 0.7874 -0.4064)
			(end -0.7874 -0.4064)
			(stroke
				(width 0.1524)
				(type default)
			)
			(layer "B.SilkS")
		)
		(fp_line
			(start -0.67945 0.3048)
			(end -0.120396 0.3048)
			(stroke
				(width 0.1)
				(type default)
			)
			(layer "B.Fab")
		)
		(fp_line
			(start -0.120396 0.3048)
			(end -0.120396 0.2794)
			(stroke
				(width 0.1)
				(type default)
			)
			(layer "B.Fab")
		)
		(fp_line
			(start 0.12065 0.3048)
			(end 0.67945 0.3048)
			(stroke
				(width 0.1)
				(type default)
			)
			(layer "B.Fab")
		)
		(fp_line
			(start 0.67945 0.3048)
			(end 0.67945 -0.305054)
			(stroke
				(width 0.1)
				(type default)
			)
			(layer "B.Fab")
		)
		(fp_line
			(start -0.120396 0.2794)
			(end 0.12065 0.2794)
			(stroke
				(width 0.1)
				(type default)
			)
			(layer "B.Fab")
		)
		(fp_line
			(start 0.12065 0.2794)
			(end 0.12065 0.3048)
			(stroke
				(width 0.1)
				(type default)
			)
			(layer "B.Fab")
		)
		(fp_line
			(start -0.12065 -0.2794)
			(end -0.12065 -0.3048)
			(stroke
				(width 0.1)
				(type default)
			)
			(layer "B.Fab")
		)
		(fp_line
			(start 0.12065 -0.2794)
			(end -0.12065 -0.2794)
			(stroke
				(width 0.1)
				(type default)
			)
			(layer "B.Fab")
		)
		(fp_line
			(start -0.67945 -0.3048)
			(end -0.67945 0.3048)
			(stroke
				(width 0.1)
				(type default)
			)
			(layer "B.Fab")
		)
		(fp_line
			(start -0.12065 -0.3048)
			(end -0.67945 -0.3048)
			(stroke
				(width 0.1)
				(type default)
			)
			(layer "B.Fab")
		)
		(fp_line
			(start 0.12065 -0.305054)
			(end 0.12065 -0.2794)
			(stroke
				(width 0.1)
				(type default)
			)
			(layer "B.Fab")
		)
		(fp_line
			(start 0.67945 -0.305054)
			(end 0.12065 -0.305054)
			(stroke
				(width 0.1)
				(type default)
			)
			(layer "B.Fab")
		)
		(pad "1" smd circle
			(at 0.40005 0 90)
			(size 0 0)
			(layers "B.Cu" "B.Mask" "B.Paste")
			(net "P1V8_AUX")
		)
		(pad "2" smd circle
			(at -0.40005 0 90)
			(size 0 0)
			(layers "B.Cu" "B.Mask" "B.Paste")
			(net "GND")
		)
	)
	(footprint ""
		(layer "B.Cu")
		(at 54.736492 -43.358054 90)
		(property "Reference" "C65"
			(at 0 0 90)
			(layer "B.SilkS")
			(hide yes)
			(effects
				(font
					(size 1.27 1.27)
				)
				(justify mirror)
			)
		)
		(property "Value" ""
			(at 0 0 90)
			(layer "B.Fab")
			(effects
				(font
					(size 1.27 1.27)
				)
				(justify mirror)
			)
		)
		(duplicate_pad_numbers_are_jumpers no)
		(fp_line
			(start 0.7874 -0.4064)
			(end -0.7874 -0.4064)
			(stroke
				(width 0.1524)
				(type default)
			)
			(layer "B.SilkS")
		)
		(fp_line
			(start -0.7874 -0.4064)
			(end -0.7874 0.4064)
			(stroke
				(width 0.1524)
				(type default)
			)
			(layer "B.SilkS")
		)
		(fp_line
			(start 0.7874 0.4064)
			(end 0.7874 -0.4064)
			(stroke
				(width 0.1524)
				(type default)
			)
			(layer "B.SilkS")
		)
		(fp_line
			(start -0.7874 0.4064)
			(end 0.7874 0.4064)
			(stroke
				(width 0.1524)
				(type default)
			)
			(layer "B.SilkS")
		)
		(fp_line
			(start 0.67945 -0.305054)
			(end 0.12065 -0.305054)
			(stroke
				(width 0.1)
				(type default)
			)
			(layer "B.Fab")
		)
		(fp_line
			(start 0.12065 -0.305054)
			(end 0.12065 -0.2794)
			(stroke
				(width 0.1)
				(type default)
			)
			(layer "B.Fab")
		)
		(fp_line
			(start -0.12065 -0.3048)
			(end -0.67945 -0.3048)
			(stroke
				(width 0.1)
				(type default)
			)
			(layer "B.Fab")
		)
		(fp_line
			(start -0.67945 -0.3048)
			(end -0.67945 0.3048)
			(stroke
				(width 0.1)
				(type default)
			)
			(layer "B.Fab")
		)
		(fp_line
			(start 0.12065 -0.2794)
			(end -0.12065 -0.2794)
			(stroke
				(width 0.1)
				(type default)
			)
			(layer "B.Fab")
		)
		(fp_line
			(start -0.12065 -0.2794)
			(end -0.12065 -0.3048)
			(stroke
				(width 0.1)
				(type default)
			)
			(layer "B.Fab")
		)
		(fp_line
			(start 0.12065 0.2794)
			(end 0.12065 0.3048)
			(stroke
				(width 0.1)
				(type default)
			)
			(layer "B.Fab")
		)
		(fp_line
			(start -0.120396 0.2794)
			(end 0.12065 0.2794)
			(stroke
				(width 0.1)
				(type default)
			)
			(layer "B.Fab")
		)
		(fp_line
			(start 0.67945 0.3048)
			(end 0.67945 -0.305054)
			(stroke
				(width 0.1)
				(type default)
			)
			(layer "B.Fab")
		)
		(fp_line
			(start 0.12065 0.3048)
			(end 0.67945 0.3048)
			(stroke
				(width 0.1)
				(type default)
			)
			(layer "B.Fab")
		)
		(fp_line
			(start -0.120396 0.3048)
			(end -0.120396 0.2794)
			(stroke
				(width 0.1)
				(type default)
			)
			(layer "B.Fab")
		)
		(fp_line
			(start -0.67945 0.3048)
			(end -0.120396 0.3048)
			(stroke
				(width 0.1)
				(type default)
			)
			(layer "B.Fab")
		)
		(pad "1" smd circle
			(at 0.40005 0 270)
			(size 0 0)
			(layers "B.Cu" "B.Mask" "B.Paste")
			(net "P3V3_STBY_PLLAHVDD")
		)
		(pad "2" smd circle
			(at -0.40005 0 270)
			(size 0 0)
			(layers "B.Cu" "B.Mask" "B.Paste")
			(net "GND")
		)
	)
	(footprint ""
		(layer "B.Cu")
		(at 54.8132 -107.0102 -90)
		(property "Reference" "R41"
			(at 0 0 90)
			(layer "B.SilkS")
			(hide yes)
			(effects
				(font
					(size 1.27 1.27)
				)
				(justify mirror)
			)
		)
		(property "Value" ""
			(at 0 0 90)
			(layer "B.Fab")
			(effects
				(font
					(size 1.27 1.27)
				)
				(justify mirror)
			)
		)
		(duplicate_pad_numbers_are_jumpers no)
		(fp_line
			(start -0.7874 0.4064)
			(end 0.7874 0.4064)
			(stroke
				(width 0.1524)
				(type default)
			)
			(layer "B.SilkS")
		)
		(fp_line
			(start 0.7874 0.4064)
			(end 0.7874 -0.4064)
			(stroke
				(width 0.1524)
				(type default)
			)
			(layer "B.SilkS")
		)
		(fp_line
			(start -0.7874 -0.4064)
			(end -0.7874 0.4064)
			(stroke
				(width 0.1524)
				(type default)
			)
			(layer "B.SilkS")
		)
		(fp_line
			(start 0.7874 -0.4064)
			(end -0.7874 -0.4064)
			(stroke
				(width 0.1524)
				(type default)
			)
			(layer "B.SilkS")
		)
		(fp_line
			(start -0.67945 0.3048)
			(end -0.120396 0.3048)
			(stroke
				(width 0.1)
				(type default)
			)
			(layer "B.Fab")
		)
		(fp_line
			(start -0.120396 0.3048)
			(end -0.120396 0.2794)
			(stroke
				(width 0.1)
				(type default)
			)
			(layer "B.Fab")
		)
		(fp_line
			(start 0.12065 0.3048)
			(end 0.67945 0.3048)
			(stroke
				(width 0.1)
				(type default)
			)
			(layer "B.Fab")
		)
		(fp_line
			(start 0.67945 0.3048)
			(end 0.67945 -0.305054)
			(stroke
				(width 0.1)
				(type default)
			)
			(layer "B.Fab")
		)
		(fp_line
			(start -0.120396 0.2794)
			(end 0.12065 0.2794)
			(stroke
				(width 0.1)
				(type default)
			)
			(layer "B.Fab")
		)
		(fp_line
			(start 0.12065 0.2794)
			(end 0.12065 0.3048)
			(stroke
				(width 0.1)
				(type default)
			)
			(layer "B.Fab")
		)
		(fp_line
			(start -0.12065 -0.2794)
			(end -0.12065 -0.3048)
			(stroke
				(width 0.1)
				(type default)
			)
			(layer "B.Fab")
		)
		(fp_line
			(start 0.12065 -0.2794)
			(end -0.12065 -0.2794)
			(stroke
				(width 0.1)
				(type default)
			)
			(layer "B.Fab")
		)
		(fp_line
			(start -0.67945 -0.3048)
			(end -0.67945 0.3048)
			(stroke
				(width 0.1)
				(type default)
			)
			(layer "B.Fab")
		)
		(fp_line
			(start -0.12065 -0.3048)
			(end -0.67945 -0.3048)
			(stroke
				(width 0.1)
				(type default)
			)
			(layer "B.Fab")
		)
		(fp_line
			(start 0.12065 -0.305054)
			(end 0.12065 -0.2794)
			(stroke
				(width 0.1)
				(type default)
			)
			(layer "B.Fab")
		)
		(fp_line
			(start 0.67945 -0.305054)
			(end 0.12065 -0.305054)
			(stroke
				(width 0.1)
				(type default)
			)
			(layer "B.Fab")
		)
		(pad "1" smd circle
			(at 0.40005 0 90)
			(size 0 0)
			(layers "B.Cu" "B.Mask" "B.Paste")
			(net "P3V3_AUX")
		)
		(pad "2" smd circle
			(at -0.40005 0 90)
			(size 0 0)
			(layers "B.Cu" "B.Mask" "B.Paste")
			(net "LPC_ESPI_SEL")
		)
	)
	(footprint ""
		(layer "B.Cu")
		(at 51.2445 -90.4875 180)
		(property "Reference" "R721"
			(at 0 0 0)
			(layer "B.SilkS")
			(hide yes)
			(effects
				(font
					(size 1.27 1.27)
				)
				(justify mirror)
			)
		)
		(property "Value" ""
			(at 0 0 0)
			(layer "B.Fab")
			(effects
				(font
					(size 1.27 1.27)
				)
				(justify mirror)
			)
		)
		(duplicate_pad_numbers_are_jumpers no)
		(fp_line
			(start 0.7874 0.4064)
			(end 0.7874 -0.4064)
			(stroke
				(width 0.1524)
				(type default)
			)
			(layer "B.SilkS")
		)
		(fp_line
			(start 0.7874 -0.4064)
			(end -0.7874 -0.4064)
			(stroke
				(width 0.1524)
				(type default)
			)
			(layer "B.SilkS")
		)
		(fp_line
			(start -0.7874 0.4064)
			(end 0.7874 0.4064)
			(stroke
				(width 0.1524)
				(type default)
			)
			(layer "B.SilkS")
		)
		(fp_line
			(start -0.7874 -0.4064)
			(end -0.7874 0.4064)
			(stroke
				(width 0.1524)
				(type default)
			)
			(layer "B.SilkS")
		)
		(fp_line
			(start 0.67945 0.3048)
			(end 0.67945 -0.305054)
			(stroke
				(width 0.1)
				(type default)
			)
			(layer "B.Fab")
		)
		(fp_line
			(start 0.67945 -0.305054)
			(end 0.12065 -0.305054)
			(stroke
				(width 0.1)
				(type default)
			)
			(layer "B.Fab")
		)
		(fp_line
			(start 0.12065 0.3048)
			(end 0.67945 0.3048)
			(stroke
				(width 0.1)
				(type default)
			)
			(layer "B.Fab")
		)
		(fp_line
			(start 0.12065 0.2794)
			(end 0.12065 0.3048)
			(stroke
				(width 0.1)
				(type default)
			)
			(layer "B.Fab")
		)
		(fp_line
			(start 0.12065 -0.2794)
			(end -0.12065 -0.2794)
			(stroke
				(width 0.1)
				(type default)
			)
			(layer "B.Fab")
		)
		(fp_line
			(start 0.12065 -0.305054)
			(end 0.12065 -0.2794)
			(stroke
				(width 0.1)
				(type default)
			)
			(layer "B.Fab")
		)
		(fp_line
			(start -0.120396 0.3048)
			(end -0.120396 0.2794)
			(stroke
				(width 0.1)
				(type default)
			)
			(layer "B.Fab")
		)
		(fp_line
			(start -0.120396 0.2794)
			(end 0.12065 0.2794)
			(stroke
				(width 0.1)
				(type default)
			)
			(layer "B.Fab")
		)
		(fp_line
			(start -0.12065 -0.2794)
			(end -0.12065 -0.3048)
			(stroke
				(width 0.1)
				(type default)
			)
			(layer "B.Fab")
		)
		(fp_line
			(start -0.12065 -0.3048)
			(end -0.67945 -0.3048)
			(stroke
				(width 0.1)
				(type default)
			)
			(layer "B.Fab")
		)
		(fp_line
			(start -0.67945 0.3048)
			(end -0.120396 0.3048)
			(stroke
				(width 0.1)
				(type default)
			)
			(layer "B.Fab")
		)
		(fp_line
			(start -0.67945 -0.3048)
			(end -0.67945 0.3048)
			(stroke
				(width 0.1)
				(type default)
			)
			(layer "B.Fab")
		)
		(pad "1" smd circle
			(at 0.40005 0)
			(size 0 0)
			(layers "B.Cu" "B.Mask" "B.Paste")
			(net "FM_SLPS3_GF_N")
		)
		(pad "2" smd circle
			(at -0.40005 0)
			(size 0 0)
			(layers "B.Cu" "B.Mask" "B.Paste")
			(net "FM_SLPS3_GF_R2_N")
		)
	)
	(footprint ""
		(layer "B.Cu")
		(at 54.675024 -72.842628)
		(property "Reference" "R782"
			(at 0 0 0)
			(layer "B.SilkS")
			(hide yes)
			(effects
				(font
					(size 1.27 1.27)
				)
				(justify mirror)
			)
		)
		(property "Value" ""
			(at 0 0 0)
			(layer "B.Fab")
			(effects
				(font
					(size 1.27 1.27)
				)
				(justify mirror)
			)
		)
		(duplicate_pad_numbers_are_jumpers no)
		(fp_line
			(start -0.7874 -0.4064)
			(end -0.7874 0.4064)
			(stroke
				(width 0.1524)
				(type default)
			)
			(layer "B.SilkS")
		)
		(fp_line
			(start -0.7874 0.4064)
			(end 0.7874 0.4064)
			(stroke
				(width 0.1524)
				(type default)
			)
			(layer "B.SilkS")
		)
		(fp_line
			(start 0.7874 -0.4064)
			(end -0.7874 -0.4064)
			(stroke
				(width 0.1524)
				(type default)
			)
			(layer "B.SilkS")
		)
		(fp_line
			(start 0.7874 0.4064)
			(end 0.7874 -0.4064)
			(stroke
				(width 0.1524)
				(type default)
			)
			(layer "B.SilkS")
		)
		(fp_line
			(start -0.67945 -0.3048)
			(end -0.67945 0.3048)
			(stroke
				(width 0.1)
				(type default)
			)
			(layer "B.Fab")
		)
		(fp_line
			(start -0.67945 0.3048)
			(end -0.120396 0.3048)
			(stroke
				(width 0.1)
				(type default)
			)
			(layer "B.Fab")
		)
		(fp_line
			(start -0.12065 -0.3048)
			(end -0.67945 -0.3048)
			(stroke
				(width 0.1)
				(type default)
			)
			(layer "B.Fab")
		)
		(fp_line
			(start -0.12065 -0.2794)
			(end -0.12065 -0.3048)
			(stroke
				(width 0.1)
				(type default)
			)
			(layer "B.Fab")
		)
		(fp_line
			(start -0.120396 0.2794)
			(end 0.12065 0.2794)
			(stroke
				(width 0.1)
				(type default)
			)
			(layer "B.Fab")
		)
		(fp_line
			(start -0.120396 0.3048)
			(end -0.120396 0.2794)
			(stroke
				(width 0.1)
				(type default)
			)
			(layer "B.Fab")
		)
		(fp_line
			(start 0.12065 -0.305054)
			(end 0.12065 -0.2794)
			(stroke
				(width 0.1)
				(type default)
			)
			(layer "B.Fab")
		)
		(fp_line
			(start 0.12065 -0.2794)
			(end -0.12065 -0.2794)
			(stroke
				(width 0.1)
				(type default)
			)
			(layer "B.Fab")
		)
		(fp_line
			(start 0.12065 0.2794)
			(end 0.12065 0.3048)
			(stroke
				(width 0.1)
				(type default)
			)
			(layer "B.Fab")
		)
		(fp_line
			(start 0.12065 0.3048)
			(end 0.67945 0.3048)
			(stroke
				(width 0.1)
				(type default)
			)
			(layer "B.Fab")
		)
		(fp_line
			(start 0.67945 -0.305054)
			(end 0.12065 -0.305054)
			(stroke
				(width 0.1)
				(type default)
			)
			(layer "B.Fab")
		)
		(fp_line
			(start 0.67945 0.3048)
			(end 0.67945 -0.305054)
			(stroke
				(width 0.1)
				(type default)
			)
			(layer "B.Fab")
		)
		(pad "1" smd circle
			(at 0.40005 0 180)
			(size 0 0)
			(layers "B.Cu" "B.Mask" "B.Paste")
			(net "P1V2_AUX")
		)
		(pad "2" smd circle
			(at -0.40005 0 180)
			(size 0 0)
			(layers "B.Cu" "B.Mask" "B.Paste")
			(net "ADCVREFEXT1")
		)
	)
	(footprint ""
		(layer "B.Cu")
		(at 58.702194 -44.406312 -90)
		(property "Reference" "C54"
			(at 0 0 90)
			(layer "B.SilkS")
			(hide yes)
			(effects
				(font
					(size 1.27 1.27)
				)
				(justify mirror)
			)
		)
		(property "Value" ""
			(at 0 0 90)
			(layer "B.Fab")
			(effects
				(font
					(size 1.27 1.27)
				)
				(justify mirror)
			)
		)
		(duplicate_pad_numbers_are_jumpers no)
		(fp_line
			(start -0.7874 0.4064)
			(end 0.7874 0.4064)
			(stroke
				(width 0.1524)
				(type default)
			)
			(layer "B.SilkS")
		)
		(fp_line
			(start 0.7874 0.4064)
			(end 0.7874 -0.4064)
			(stroke
				(width 0.1524)
				(type default)
			)
			(layer "B.SilkS")
		)
		(fp_line
			(start -0.7874 -0.4064)
			(end -0.7874 0.4064)
			(stroke
				(width 0.1524)
				(type default)
			)
			(layer "B.SilkS")
		)
		(fp_line
			(start 0.7874 -0.4064)
			(end -0.7874 -0.4064)
			(stroke
				(width 0.1524)
				(type default)
			)
			(layer "B.SilkS")
		)
		(fp_line
			(start -0.67945 0.3048)
			(end -0.120396 0.3048)
			(stroke
				(width 0.1)
				(type default)
			)
			(layer "B.Fab")
		)
		(fp_line
			(start -0.120396 0.3048)
			(end -0.120396 0.2794)
			(stroke
				(width 0.1)
				(type default)
			)
			(layer "B.Fab")
		)
		(fp_line
			(start 0.12065 0.3048)
			(end 0.67945 0.3048)
			(stroke
				(width 0.1)
				(type default)
			)
			(layer "B.Fab")
		)
		(fp_line
			(start 0.67945 0.3048)
			(end 0.67945 -0.305054)
			(stroke
				(width 0.1)
				(type default)
			)
			(layer "B.Fab")
		)
		(fp_line
			(start -0.120396 0.2794)
			(end 0.12065 0.2794)
			(stroke
				(width 0.1)
				(type default)
			)
			(layer "B.Fab")
		)
		(fp_line
			(start 0.12065 0.2794)
			(end 0.12065 0.3048)
			(stroke
				(width 0.1)
				(type default)
			)
			(layer "B.Fab")
		)
		(fp_line
			(start -0.12065 -0.2794)
			(end -0.12065 -0.3048)
			(stroke
				(width 0.1)
				(type default)
			)
			(layer "B.Fab")
		)
		(fp_line
			(start 0.12065 -0.2794)
			(end -0.12065 -0.2794)
			(stroke
				(width 0.1)
				(type default)
			)
			(layer "B.Fab")
		)
		(fp_line
			(start -0.67945 -0.3048)
			(end -0.67945 0.3048)
			(stroke
				(width 0.1)
				(type default)
			)
			(layer "B.Fab")
		)
		(fp_line
			(start -0.12065 -0.3048)
			(end -0.67945 -0.3048)
			(stroke
				(width 0.1)
				(type default)
			)
			(layer "B.Fab")
		)
		(fp_line
			(start 0.12065 -0.305054)
			(end 0.12065 -0.2794)
			(stroke
				(width 0.1)
				(type default)
			)
			(layer "B.Fab")
		)
		(fp_line
			(start 0.67945 -0.305054)
			(end 0.12065 -0.305054)
			(stroke
				(width 0.1)
				(type default)
			)
			(layer "B.Fab")
		)
		(pad "1" smd circle
			(at 0.40005 0 90)
			(size 0 0)
			(layers "B.Cu" "B.Mask" "B.Paste")
			(net "P1V0_STBY_PLAVDD")
		)
		(pad "2" smd circle
			(at -0.40005 0 90)
			(size 0 0)
			(layers "B.Cu" "B.Mask" "B.Paste")
			(net "GND")
		)
	)
	(footprint ""
		(layer "B.Cu")
		(at 15.621 -88.5952 -135)
		(property "Reference" "C190"
			(at 0 0 45)
			(layer "B.SilkS")
			(hide yes)
			(effects
				(font
					(size 1.27 1.27)
				)
				(justify mirror)
			)
		)
		(property "Value" ""
			(at 0 0 45)
			(layer "B.Fab")
			(effects
				(font
					(size 1.27 1.27)
				)
				(justify mirror)
			)
		)
		(duplicate_pad_numbers_are_jumpers no)
		(fp_line
			(start 0.787389 0.406267)
			(end 0.787389 -0.406267)
			(stroke
				(width 0.1524)
				(type default)
			)
			(layer "B.SilkS")
		)
		(fp_line
			(start 0.787389 -0.406267)
			(end -0.787389 -0.406267)
			(stroke
				(width 0.1524)
				(type default)
			)
			(layer "B.SilkS")
		)
		(fp_line
			(start -0.787389 0.406267)
			(end 0.787389 0.406267)
			(stroke
				(width 0.1524)
				(type default)
			)
			(layer "B.SilkS")
		)
		(fp_line
			(start -0.787389 -0.406267)
			(end -0.787389 0.406267)
			(stroke
				(width 0.1524)
				(type default)
			)
			(layer "B.SilkS")
		)
		(fp_line
			(start 0.679446 0.30479)
			(end 0.679446 -0.305149)
			(stroke
				(width 0.1)
				(type default)
			)
			(layer "B.Fab")
		)
		(fp_line
			(start 0.120515 0.30479)
			(end 0.679446 0.30479)
			(stroke
				(width 0.1)
				(type default)
			)
			(layer "B.Fab")
		)
		(fp_line
			(start 0.120695 0.279466)
			(end 0.120515 0.30479)
			(stroke
				(width 0.1)
				(type default)
			)
			(layer "B.Fab")
		)
		(fp_line
			(start 0.679446 -0.305149)
			(end 0.120695 -0.304969)
			(stroke
				(width 0.1)
				(type default)
			)
			(layer "B.Fab")
		)
		(fp_line
			(start -0.120515 0.30479)
			(end -0.120335 0.279466)
			(stroke
				(width 0.1)
				(type default)
			)
			(layer "B.Fab")
		)
		(fp_line
			(start -0.120335 0.279466)
			(end 0.120695 0.279466)
			(stroke
				(width 0.1)
				(type default)
			)
			(layer "B.Fab")
		)
		(fp_line
			(start 0.120695 -0.279466)
			(end -0.120695 -0.279466)
			(stroke
				(width 0.1)
				(type default)
			)
			(layer "B.Fab")
		)
		(fp_line
			(start 0.120695 -0.304969)
			(end 0.120695 -0.279466)
			(stroke
				(width 0.1)
				(type default)
			)
			(layer "B.Fab")
		)
		(fp_line
			(start -0.679446 0.30479)
			(end -0.120515 0.30479)
			(stroke
				(width 0.1)
				(type default)
			)
			(layer "B.Fab")
		)
		(fp_line
			(start -0.120695 -0.279466)
			(end -0.120515 -0.30479)
			(stroke
				(width 0.1)
				(type default)
			)
			(layer "B.Fab")
		)
		(fp_line
			(start -0.120515 -0.30479)
			(end -0.679446 -0.30479)
			(stroke
				(width 0.1)
				(type default)
			)
			(layer "B.Fab")
		)
		(fp_line
			(start -0.679446 -0.30479)
			(end -0.679446 0.30479)
			(stroke
				(width 0.1)
				(type default)
			)
			(layer "B.Fab")
		)
		(pad "1" smd circle
			(at 0.40005 0 45)
			(size 0 0)
			(layers "B.Cu" "B.Mask" "B.Paste")
			(net "PVCCA_AUX_PLD")
		)
		(pad "2" smd circle
			(at -0.40005 0 45)
			(size 0 0)
			(layers "B.Cu" "B.Mask" "B.Paste")
			(net "GND")
		)
	)
	(footprint ""
		(layer "B.Cu")
		(at 25.019 -18.034 -90)
		(property "Reference" "R418"
			(at 0 0 90)
			(layer "B.SilkS")
			(hide yes)
			(effects
				(font
					(size 1.27 1.27)
				)
				(justify mirror)
			)
		)
		(property "Value" ""
			(at 0 0 90)
			(layer "B.Fab")
			(effects
				(font
					(size 1.27 1.27)
				)
				(justify mirror)
			)
		)
		(duplicate_pad_numbers_are_jumpers no)
		(fp_line
			(start -0.7874 0.4064)
			(end 0.7874 0.4064)
			(stroke
				(width 0.1524)
				(type default)
			)
			(layer "B.SilkS")
		)
		(fp_line
			(start 0.7874 0.4064)
			(end 0.7874 -0.4064)
			(stroke
				(width 0.1524)
				(type default)
			)
			(layer "B.SilkS")
		)
		(fp_line
			(start -0.7874 -0.4064)
			(end -0.7874 0.4064)
			(stroke
				(width 0.1524)
				(type default)
			)
			(layer "B.SilkS")
		)
		(fp_line
			(start 0.7874 -0.4064)
			(end -0.7874 -0.4064)
			(stroke
				(width 0.1524)
				(type default)
			)
			(layer "B.SilkS")
		)
		(fp_line
			(start -0.67945 0.3048)
			(end -0.120396 0.3048)
			(stroke
				(width 0.1)
				(type default)
			)
			(layer "B.Fab")
		)
		(fp_line
			(start -0.120396 0.3048)
			(end -0.120396 0.2794)
			(stroke
				(width 0.1)
				(type default)
			)
			(layer "B.Fab")
		)
		(fp_line
			(start 0.12065 0.3048)
			(end 0.67945 0.3048)
			(stroke
				(width 0.1)
				(type default)
			)
			(layer "B.Fab")
		)
		(fp_line
			(start 0.67945 0.3048)
			(end 0.67945 -0.305054)
			(stroke
				(width 0.1)
				(type default)
			)
			(layer "B.Fab")
		)
		(fp_line
			(start -0.120396 0.2794)
			(end 0.12065 0.2794)
			(stroke
				(width 0.1)
				(type default)
			)
			(layer "B.Fab")
		)
		(fp_line
			(start 0.12065 0.2794)
			(end 0.12065 0.3048)
			(stroke
				(width 0.1)
				(type default)
			)
			(layer "B.Fab")
		)
		(fp_line
			(start -0.12065 -0.2794)
			(end -0.12065 -0.3048)
			(stroke
				(width 0.1)
				(type default)
			)
			(layer "B.Fab")
		)
		(fp_line
			(start 0.12065 -0.2794)
			(end -0.12065 -0.2794)
			(stroke
				(width 0.1)
				(type default)
			)
			(layer "B.Fab")
		)
		(fp_line
			(start -0.67945 -0.3048)
			(end -0.67945 0.3048)
			(stroke
				(width 0.1)
				(type default)
			)
			(layer "B.Fab")
		)
		(fp_line
			(start -0.12065 -0.3048)
			(end -0.67945 -0.3048)
			(stroke
				(width 0.1)
				(type default)
			)
			(layer "B.Fab")
		)
		(fp_line
			(start 0.12065 -0.305054)
			(end 0.12065 -0.2794)
			(stroke
				(width 0.1)
				(type default)
			)
			(layer "B.Fab")
		)
		(fp_line
			(start 0.67945 -0.305054)
			(end 0.12065 -0.305054)
			(stroke
				(width 0.1)
				(type default)
			)
			(layer "B.Fab")
		)
		(pad "1" smd circle
			(at 0.40005 0 90)
			(size 0 0)
			(layers "B.Cu" "B.Mask" "B.Paste")
			(net "P3V3_AUX")
		)
		(pad "2" smd circle
			(at -0.40005 0 90)
			(size 0 0)
			(layers "B.Cu" "B.Mask" "B.Paste")
			(net "TMC75_A2")
		)
	)
	(footprint ""
		(layer "B.Cu")
		(at 66.4972 -62.0268 -90)
		(property "Reference" "R129"
			(at 0 0 90)
			(layer "B.SilkS")
			(hide yes)
			(effects
				(font
					(size 1.27 1.27)
				)
				(justify mirror)
			)
		)
		(property "Value" ""
			(at 0 0 90)
			(layer "B.Fab")
			(effects
				(font
					(size 1.27 1.27)
				)
				(justify mirror)
			)
		)
		(duplicate_pad_numbers_are_jumpers no)
		(fp_line
			(start -0.7874 0.4064)
			(end 0.7874 0.4064)
			(stroke
				(width 0.1524)
				(type default)
			)
			(layer "B.SilkS")
		)
		(fp_line
			(start 0.7874 0.4064)
			(end 0.7874 -0.4064)
			(stroke
				(width 0.1524)
				(type default)
			)
			(layer "B.SilkS")
		)
		(fp_line
			(start -0.7874 -0.4064)
			(end -0.7874 0.4064)
			(stroke
				(width 0.1524)
				(type default)
			)
			(layer "B.SilkS")
		)
		(fp_line
			(start 0.7874 -0.4064)
			(end -0.7874 -0.4064)
			(stroke
				(width 0.1524)
				(type default)
			)
			(layer "B.SilkS")
		)
		(fp_line
			(start -0.67945 0.3048)
			(end -0.120396 0.3048)
			(stroke
				(width 0.1)
				(type default)
			)
			(layer "B.Fab")
		)
		(fp_line
			(start -0.120396 0.3048)
			(end -0.120396 0.2794)
			(stroke
				(width 0.1)
				(type default)
			)
			(layer "B.Fab")
		)
		(fp_line
			(start 0.12065 0.3048)
			(end 0.67945 0.3048)
			(stroke
				(width 0.1)
				(type default)
			)
			(layer "B.Fab")
		)
		(fp_line
			(start 0.67945 0.3048)
			(end 0.67945 -0.305054)
			(stroke
				(width 0.1)
				(type default)
			)
			(layer "B.Fab")
		)
		(fp_line
			(start -0.120396 0.2794)
			(end 0.12065 0.2794)
			(stroke
				(width 0.1)
				(type default)
			)
			(layer "B.Fab")
		)
		(fp_line
			(start 0.12065 0.2794)
			(end 0.12065 0.3048)
			(stroke
				(width 0.1)
				(type default)
			)
			(layer "B.Fab")
		)
		(fp_line
			(start -0.12065 -0.2794)
			(end -0.12065 -0.3048)
			(stroke
				(width 0.1)
				(type default)
			)
			(layer "B.Fab")
		)
		(fp_line
			(start 0.12065 -0.2794)
			(end -0.12065 -0.2794)
			(stroke
				(width 0.1)
				(type default)
			)
			(layer "B.Fab")
		)
		(fp_line
			(start -0.67945 -0.3048)
			(end -0.67945 0.3048)
			(stroke
				(width 0.1)
				(type default)
			)
			(layer "B.Fab")
		)
		(fp_line
			(start -0.12065 -0.3048)
			(end -0.67945 -0.3048)
			(stroke
				(width 0.1)
				(type default)
			)
			(layer "B.Fab")
		)
		(fp_line
			(start 0.12065 -0.305054)
			(end 0.12065 -0.2794)
			(stroke
				(width 0.1)
				(type default)
			)
			(layer "B.Fab")
		)
		(fp_line
			(start 0.67945 -0.305054)
			(end 0.12065 -0.305054)
			(stroke
				(width 0.1)
				(type default)
			)
			(layer "B.Fab")
		)
		(pad "1" smd circle
			(at 0.40005 0 90)
			(size 0 0)
			(layers "B.Cu" "B.Mask" "B.Paste")
			(net "ESPI_LPC_D1_IO1")
		)
		(pad "2" smd circle
			(at -0.40005 0 90)
			(size 0 0)
			(layers "B.Cu" "B.Mask" "B.Paste")
			(net "ESPI_LPC_LAD1_IO1")
		)
	)
	(footprint ""
		(layer "B.Cu")
		(at 23.573486 -106.50982 -90)
		(property "Reference" "R40"
			(at 0 0 90)
			(layer "B.SilkS")
			(hide yes)
			(effects
				(font
					(size 1.27 1.27)
				)
				(justify mirror)
			)
		)
		(property "Value" ""
			(at 0 0 90)
			(layer "B.Fab")
			(effects
				(font
					(size 1.27 1.27)
				)
				(justify mirror)
			)
		)
		(duplicate_pad_numbers_are_jumpers no)
		(fp_line
			(start -0.7874 0.4064)
			(end 0.7874 0.4064)
			(stroke
				(width 0.1524)
				(type default)
			)
			(layer "B.SilkS")
		)
		(fp_line
			(start 0.7874 0.4064)
			(end 0.7874 -0.4064)
			(stroke
				(width 0.1524)
				(type default)
			)
			(layer "B.SilkS")
		)
		(fp_line
			(start -0.7874 -0.4064)
			(end -0.7874 0.4064)
			(stroke
				(width 0.1524)
				(type default)
			)
			(layer "B.SilkS")
		)
		(fp_line
			(start 0.7874 -0.4064)
			(end -0.7874 -0.4064)
			(stroke
				(width 0.1524)
				(type default)
			)
			(layer "B.SilkS")
		)
		(fp_line
			(start -0.67945 0.3048)
			(end -0.120396 0.3048)
			(stroke
				(width 0.1)
				(type default)
			)
			(layer "B.Fab")
		)
		(fp_line
			(start -0.120396 0.3048)
			(end -0.120396 0.2794)
			(stroke
				(width 0.1)
				(type default)
			)
			(layer "B.Fab")
		)
		(fp_line
			(start 0.12065 0.3048)
			(end 0.67945 0.3048)
			(stroke
				(width 0.1)
				(type default)
			)
			(layer "B.Fab")
		)
		(fp_line
			(start 0.67945 0.3048)
			(end 0.67945 -0.305054)
			(stroke
				(width 0.1)
				(type default)
			)
			(layer "B.Fab")
		)
		(fp_line
			(start -0.120396 0.2794)
			(end 0.12065 0.2794)
			(stroke
				(width 0.1)
				(type default)
			)
			(layer "B.Fab")
		)
		(fp_line
			(start 0.12065 0.2794)
			(end 0.12065 0.3048)
			(stroke
				(width 0.1)
				(type default)
			)
			(layer "B.Fab")
		)
		(fp_line
			(start -0.12065 -0.2794)
			(end -0.12065 -0.3048)
			(stroke
				(width 0.1)
				(type default)
			)
			(layer "B.Fab")
		)
		(fp_line
			(start 0.12065 -0.2794)
			(end -0.12065 -0.2794)
			(stroke
				(width 0.1)
				(type default)
			)
			(layer "B.Fab")
		)
		(fp_line
			(start -0.67945 -0.3048)
			(end -0.67945 0.3048)
			(stroke
				(width 0.1)
				(type default)
			)
			(layer "B.Fab")
		)
		(fp_line
			(start -0.12065 -0.3048)
			(end -0.67945 -0.3048)
			(stroke
				(width 0.1)
				(type default)
			)
			(layer "B.Fab")
		)
		(fp_line
			(start 0.12065 -0.305054)
			(end 0.12065 -0.2794)
			(stroke
				(width 0.1)
				(type default)
			)
			(layer "B.Fab")
		)
		(fp_line
			(start 0.67945 -0.305054)
			(end 0.12065 -0.305054)
			(stroke
				(width 0.1)
				(type default)
			)
			(layer "B.Fab")
		)
		(pad "1" smd circle
			(at 0.40005 0 90)
			(size 0 0)
			(layers "B.Cu" "B.Mask" "B.Paste")
			(net "GND")
		)
		(pad "2" smd circle
			(at -0.40005 0 90)
			(size 0 0)
			(layers "B.Cu" "B.Mask" "B.Paste")
			(net "PWRGD_SYS_PWROK")
		)
	)
	(footprint ""
		(layer "B.Cu")
		(at 59.055 -18.034)
		(property "Reference" "R730"
			(at 0 0 0)
			(layer "B.SilkS")
			(hide yes)
			(effects
				(font
					(size 1.27 1.27)
				)
				(justify mirror)
			)
		)
		(property "Value" ""
			(at 0 0 0)
			(layer "B.Fab")
			(effects
				(font
					(size 1.27 1.27)
				)
				(justify mirror)
			)
		)
		(duplicate_pad_numbers_are_jumpers no)
		(fp_line
			(start -0.7874 -0.4064)
			(end -0.7874 0.4064)
			(stroke
				(width 0.1524)
				(type default)
			)
			(layer "B.SilkS")
		)
		(fp_line
			(start -0.7874 0.4064)
			(end 0.7874 0.4064)
			(stroke
				(width 0.1524)
				(type default)
			)
			(layer "B.SilkS")
		)
		(fp_line
			(start 0.7874 -0.4064)
			(end -0.7874 -0.4064)
			(stroke
				(width 0.1524)
				(type default)
			)
			(layer "B.SilkS")
		)
		(fp_line
			(start 0.7874 0.4064)
			(end 0.7874 -0.4064)
			(stroke
				(width 0.1524)
				(type default)
			)
			(layer "B.SilkS")
		)
		(fp_line
			(start -0.67945 -0.3048)
			(end -0.67945 0.3048)
			(stroke
				(width 0.1)
				(type default)
			)
			(layer "B.Fab")
		)
		(fp_line
			(start -0.67945 0.3048)
			(end -0.120396 0.3048)
			(stroke
				(width 0.1)
				(type default)
			)
			(layer "B.Fab")
		)
		(fp_line
			(start -0.12065 -0.3048)
			(end -0.67945 -0.3048)
			(stroke
				(width 0.1)
				(type default)
			)
			(layer "B.Fab")
		)
		(fp_line
			(start -0.12065 -0.2794)
			(end -0.12065 -0.3048)
			(stroke
				(width 0.1)
				(type default)
			)
			(layer "B.Fab")
		)
		(fp_line
			(start -0.120396 0.2794)
			(end 0.12065 0.2794)
			(stroke
				(width 0.1)
				(type default)
			)
			(layer "B.Fab")
		)
		(fp_line
			(start -0.120396 0.3048)
			(end -0.120396 0.2794)
			(stroke
				(width 0.1)
				(type default)
			)
			(layer "B.Fab")
		)
		(fp_line
			(start 0.12065 -0.305054)
			(end 0.12065 -0.2794)
			(stroke
				(width 0.1)
				(type default)
			)
			(layer "B.Fab")
		)
		(fp_line
			(start 0.12065 -0.2794)
			(end -0.12065 -0.2794)
			(stroke
				(width 0.1)
				(type default)
			)
			(layer "B.Fab")
		)
		(fp_line
			(start 0.12065 0.2794)
			(end 0.12065 0.3048)
			(stroke
				(width 0.1)
				(type default)
			)
			(layer "B.Fab")
		)
		(fp_line
			(start 0.12065 0.3048)
			(end 0.67945 0.3048)
			(stroke
				(width 0.1)
				(type default)
			)
			(layer "B.Fab")
		)
		(fp_line
			(start 0.67945 -0.305054)
			(end 0.12065 -0.305054)
			(stroke
				(width 0.1)
				(type default)
			)
			(layer "B.Fab")
		)
		(fp_line
			(start 0.67945 0.3048)
			(end 0.67945 -0.305054)
			(stroke
				(width 0.1)
				(type default)
			)
			(layer "B.Fab")
		)
		(pad "1" smd circle
			(at 0.40005 0 180)
			(size 0 0)
			(layers "B.Cu" "B.Mask" "B.Paste")
			(net "P3V3_AUX")
		)
		(pad "2" smd circle
			(at -0.40005 0 180)
			(size 0 0)
			(layers "B.Cu" "B.Mask" "B.Paste")
			(net "FM_DEBUG_PORT_R_PRSNT_N")
		)
	)
	(footprint ""
		(layer "B.Cu")
		(at 54.917848 -49.255934 180)
		(property "Reference" "C84"
			(at 0 0 0)
			(layer "B.SilkS")
			(hide yes)
			(effects
				(font
					(size 1.27 1.27)
				)
				(justify mirror)
			)
		)
		(property "Value" ""
			(at 0 0 0)
			(layer "B.Fab")
			(effects
				(font
					(size 1.27 1.27)
				)
				(justify mirror)
			)
		)
		(duplicate_pad_numbers_are_jumpers no)
		(fp_line
			(start 0.7874 0.4064)
			(end 0.7874 -0.4064)
			(stroke
				(width 0.1524)
				(type default)
			)
			(layer "B.SilkS")
		)
		(fp_line
			(start 0.7874 -0.4064)
			(end -0.7874 -0.4064)
			(stroke
				(width 0.1524)
				(type default)
			)
			(layer "B.SilkS")
		)
		(fp_line
			(start -0.7874 0.4064)
			(end 0.7874 0.4064)
			(stroke
				(width 0.1524)
				(type default)
			)
			(layer "B.SilkS")
		)
		(fp_line
			(start -0.7874 -0.4064)
			(end -0.7874 0.4064)
			(stroke
				(width 0.1524)
				(type default)
			)
			(layer "B.SilkS")
		)
		(fp_line
			(start 0.67945 0.3048)
			(end 0.67945 -0.305054)
			(stroke
				(width 0.1)
				(type default)
			)
			(layer "B.Fab")
		)
		(fp_line
			(start 0.67945 -0.305054)
			(end 0.12065 -0.305054)
			(stroke
				(width 0.1)
				(type default)
			)
			(layer "B.Fab")
		)
		(fp_line
			(start 0.12065 0.3048)
			(end 0.67945 0.3048)
			(stroke
				(width 0.1)
				(type default)
			)
			(layer "B.Fab")
		)
		(fp_line
			(start 0.12065 0.2794)
			(end 0.12065 0.3048)
			(stroke
				(width 0.1)
				(type default)
			)
			(layer "B.Fab")
		)
		(fp_line
			(start 0.12065 -0.2794)
			(end -0.12065 -0.2794)
			(stroke
				(width 0.1)
				(type default)
			)
			(layer "B.Fab")
		)
		(fp_line
			(start 0.12065 -0.305054)
			(end 0.12065 -0.2794)
			(stroke
				(width 0.1)
				(type default)
			)
			(layer "B.Fab")
		)
		(fp_line
			(start -0.120396 0.3048)
			(end -0.120396 0.2794)
			(stroke
				(width 0.1)
				(type default)
			)
			(layer "B.Fab")
		)
		(fp_line
			(start -0.120396 0.2794)
			(end 0.12065 0.2794)
			(stroke
				(width 0.1)
				(type default)
			)
			(layer "B.Fab")
		)
		(fp_line
			(start -0.12065 -0.2794)
			(end -0.12065 -0.3048)
			(stroke
				(width 0.1)
				(type default)
			)
			(layer "B.Fab")
		)
		(fp_line
			(start -0.12065 -0.3048)
			(end -0.67945 -0.3048)
			(stroke
				(width 0.1)
				(type default)
			)
			(layer "B.Fab")
		)
		(fp_line
			(start -0.67945 0.3048)
			(end -0.120396 0.3048)
			(stroke
				(width 0.1)
				(type default)
			)
			(layer "B.Fab")
		)
		(fp_line
			(start -0.67945 -0.3048)
			(end -0.67945 0.3048)
			(stroke
				(width 0.1)
				(type default)
			)
			(layer "B.Fab")
		)
		(pad "1" smd circle
			(at 0.40005 0)
			(size 0 0)
			(layers "B.Cu" "B.Mask" "B.Paste")
			(net "P1V2_AUX")
		)
		(pad "2" smd circle
			(at -0.40005 0)
			(size 0 0)
			(layers "B.Cu" "B.Mask" "B.Paste")
			(net "GND")
		)
	)
	(footprint ""
		(layer "B.Cu")
		(at 68.608448 -26.594562 180)
		(property "Reference" "R421"
			(at 0 0 0)
			(layer "B.SilkS")
			(hide yes)
			(effects
				(font
					(size 1.27 1.27)
				)
				(justify mirror)
			)
		)
		(property "Value" ""
			(at 0 0 0)
			(layer "B.Fab")
			(effects
				(font
					(size 1.27 1.27)
				)
				(justify mirror)
			)
		)
		(duplicate_pad_numbers_are_jumpers no)
		(fp_line
			(start 0.7874 0.4064)
			(end 0.7874 -0.4064)
			(stroke
				(width 0.1524)
				(type default)
			)
			(layer "B.SilkS")
		)
		(fp_line
			(start 0.7874 -0.4064)
			(end -0.7874 -0.4064)
			(stroke
				(width 0.1524)
				(type default)
			)
			(layer "B.SilkS")
		)
		(fp_line
			(start -0.7874 0.4064)
			(end 0.7874 0.4064)
			(stroke
				(width 0.1524)
				(type default)
			)
			(layer "B.SilkS")
		)
		(fp_line
			(start -0.7874 -0.4064)
			(end -0.7874 0.4064)
			(stroke
				(width 0.1524)
				(type default)
			)
			(layer "B.SilkS")
		)
		(fp_line
			(start 0.67945 0.3048)
			(end 0.67945 -0.305054)
			(stroke
				(width 0.1)
				(type default)
			)
			(layer "B.Fab")
		)
		(fp_line
			(start 0.67945 -0.305054)
			(end 0.12065 -0.305054)
			(stroke
				(width 0.1)
				(type default)
			)
			(layer "B.Fab")
		)
		(fp_line
			(start 0.12065 0.3048)
			(end 0.67945 0.3048)
			(stroke
				(width 0.1)
				(type default)
			)
			(layer "B.Fab")
		)
		(fp_line
			(start 0.12065 0.2794)
			(end 0.12065 0.3048)
			(stroke
				(width 0.1)
				(type default)
			)
			(layer "B.Fab")
		)
		(fp_line
			(start 0.12065 -0.2794)
			(end -0.12065 -0.2794)
			(stroke
				(width 0.1)
				(type default)
			)
			(layer "B.Fab")
		)
		(fp_line
			(start 0.12065 -0.305054)
			(end 0.12065 -0.2794)
			(stroke
				(width 0.1)
				(type default)
			)
			(layer "B.Fab")
		)
		(fp_line
			(start -0.120396 0.3048)
			(end -0.120396 0.2794)
			(stroke
				(width 0.1)
				(type default)
			)
			(layer "B.Fab")
		)
		(fp_line
			(start -0.120396 0.2794)
			(end 0.12065 0.2794)
			(stroke
				(width 0.1)
				(type default)
			)
			(layer "B.Fab")
		)
		(fp_line
			(start -0.12065 -0.2794)
			(end -0.12065 -0.3048)
			(stroke
				(width 0.1)
				(type default)
			)
			(layer "B.Fab")
		)
		(fp_line
			(start -0.12065 -0.3048)
			(end -0.67945 -0.3048)
			(stroke
				(width 0.1)
				(type default)
			)
			(layer "B.Fab")
		)
		(fp_line
			(start -0.67945 0.3048)
			(end -0.120396 0.3048)
			(stroke
				(width 0.1)
				(type default)
			)
			(layer "B.Fab")
		)
		(fp_line
			(start -0.67945 -0.3048)
			(end -0.67945 0.3048)
			(stroke
				(width 0.1)
				(type default)
			)
			(layer "B.Fab")
		)
		(pad "1" smd circle
			(at 0.40005 0)
			(size 0 0)
			(layers "B.Cu" "B.Mask" "B.Paste")
			(net "SMB_BMC_MM16_R2_SDA")
		)
		(pad "2" smd circle
			(at -0.40005 0)
			(size 0 0)
			(layers "B.Cu" "B.Mask" "B.Paste")
			(net "SMB_BMC_MM16_SDA")
		)
	)
	(footprint ""
		(layer "B.Cu")
		(at 34.163 -67.437 -90)
		(property "Reference" "U20"
			(at -1.905 -1.87833 270)
			(unlocked yes)
			(layer "B.SilkS")
			(effects
				(font
					(size 0.7874 0.5842)
					(thickness 0.1524)
				)
				(justify mirror)
			)
		)
		(property "Value" ""
			(at 0 0 90)
			(layer "B.Fab")
			(effects
				(font
					(size 1.27 1.27)
				)
				(justify mirror)
			)
		)
		(duplicate_pad_numbers_are_jumpers no)
		(fp_line
			(start -1.7272 1.1176)
			(end 1.7272 1.1176)
			(stroke
				(width 0.1524)
				(type default)
			)
			(layer "B.SilkS")
		)
		(fp_line
			(start 1.7272 1.1176)
			(end 1.7272 -1.1176)
			(stroke
				(width 0.1524)
				(type default)
			)
			(layer "B.SilkS")
		)
		(fp_line
			(start 0 -0.7366)
			(end 0.254 -1.1176)
			(stroke
				(width 0.1524)
				(type default)
			)
			(layer "B.SilkS")
		)
		(fp_line
			(start -1.7272 -1.1176)
			(end -1.7272 1.1176)
			(stroke
				(width 0.1524)
				(type default)
			)
			(layer "B.SilkS")
		)
		(fp_line
			(start -1.7272 -1.1176)
			(end -0.254 -1.1176)
			(stroke
				(width 0.1524)
				(type default)
			)
			(layer "B.SilkS")
		)
		(fp_line
			(start -0.254 -1.1176)
			(end 0 -0.7366)
			(stroke
				(width 0.1524)
				(type default)
			)
			(layer "B.SilkS")
		)
		(fp_line
			(start 0.254 -1.1176)
			(end 1.7272 -1.1176)
			(stroke
				(width 0.1524)
				(type default)
			)
			(layer "B.SilkS")
		)
		(fp_poly
			(pts
				(xy 2.280412 -1.158748) (xy 3.08864 -1.427988) (xy 2.549906 -1.966976)
			)
			(stroke
				(width 0)
				(type default)
			)
			(fill yes)
			(layer "B.SilkS")
		)
		(fp_line
			(start -1.5748 1.1176)
			(end -1.5748 -1.1176)
			(stroke
				(width 0.1)
				(type default)
			)
			(layer "B.Fab")
		)
		(fp_line
			(start 1.5748 1.1176)
			(end -1.5748 1.1176)
			(stroke
				(width 0.1)
				(type default)
			)
			(layer "B.Fab")
		)
		(fp_line
			(start -1.5748 -1.1176)
			(end 1.5748 -1.1176)
			(stroke
				(width 0.1)
				(type default)
			)
			(layer "B.Fab")
		)
		(fp_line
			(start 1.5748 -1.1176)
			(end 1.5748 1.1176)
			(stroke
				(width 0.1)
				(type default)
			)
			(layer "B.Fab")
		)
		(fp_poly
			(pts
				(xy 1.9558 -0.649986) (xy 2.7178 -0.268986) (xy 2.7178 -1.030986)
			)
			(stroke
				(width 0)
				(type default)
			)
			(fill yes)
			(layer "B.Fab")
		)
		(pad "1" smd rect
			(at 0.999998 -0.649986 180)
			(size 0.3556 1.1176)
			(layers "B.Cu" "B.Mask" "B.Paste")
			(net "SPA_SIN_SW_DBG_R")
		)
		(pad "2" smd rect
			(at 0.999998 0 180)
			(size 0.3556 1.1176)
			(layers "B.Cu" "B.Mask" "B.Paste")
			(net "GND")
		)
		(pad "3" smd rect
			(at 0.999998 0.649986 180)
			(size 0.3556 1.1176)
			(layers "B.Cu" "B.Mask" "B.Paste")
			(net "UART_SYS_DBG_RX_R")
		)
		(pad "4" smd rect
			(at -0.999998 0.649986 180)
			(size 0.3556 1.1176)
			(layers "B.Cu" "B.Mask" "B.Paste")
			(net "SPA_SIN_SW_BUF_R")
		)
		(pad "5" smd rect
			(at -0.999998 0 180)
			(size 0.3556 1.1176)
			(layers "B.Cu" "B.Mask" "B.Paste")
			(net "P3V3_AUX")
		)
		(pad "6" smd rect
			(at -0.999998 -0.649986 180)
			(size 0.3556 1.1176)
			(layers "B.Cu" "B.Mask" "B.Paste")
			(net "FM_DBG_SW_N")
		)
	)
	(footprint ""
		(layer "B.Cu")
		(at 79.739744 -35.540188 -90)
		(property "Reference" "R346"
			(at 0 0 90)
			(layer "B.SilkS")
			(hide yes)
			(effects
				(font
					(size 1.27 1.27)
				)
				(justify mirror)
			)
		)
		(property "Value" ""
			(at 0 0 90)
			(layer "B.Fab")
			(effects
				(font
					(size 1.27 1.27)
				)
				(justify mirror)
			)
		)
		(duplicate_pad_numbers_are_jumpers no)
		(fp_line
			(start -0.7874 0.4064)
			(end 0.7874 0.4064)
			(stroke
				(width 0.1524)
				(type default)
			)
			(layer "B.SilkS")
		)
		(fp_line
			(start 0.7874 0.4064)
			(end 0.7874 -0.4064)
			(stroke
				(width 0.1524)
				(type default)
			)
			(layer "B.SilkS")
		)
		(fp_line
			(start -0.7874 -0.4064)
			(end -0.7874 0.4064)
			(stroke
				(width 0.1524)
				(type default)
			)
			(layer "B.SilkS")
		)
		(fp_line
			(start 0.7874 -0.4064)
			(end -0.7874 -0.4064)
			(stroke
				(width 0.1524)
				(type default)
			)
			(layer "B.SilkS")
		)
		(fp_line
			(start -0.67945 0.3048)
			(end -0.120396 0.3048)
			(stroke
				(width 0.1)
				(type default)
			)
			(layer "B.Fab")
		)
		(fp_line
			(start -0.120396 0.3048)
			(end -0.120396 0.2794)
			(stroke
				(width 0.1)
				(type default)
			)
			(layer "B.Fab")
		)
		(fp_line
			(start 0.12065 0.3048)
			(end 0.67945 0.3048)
			(stroke
				(width 0.1)
				(type default)
			)
			(layer "B.Fab")
		)
		(fp_line
			(start 0.67945 0.3048)
			(end 0.67945 -0.305054)
			(stroke
				(width 0.1)
				(type default)
			)
			(layer "B.Fab")
		)
		(fp_line
			(start -0.120396 0.2794)
			(end 0.12065 0.2794)
			(stroke
				(width 0.1)
				(type default)
			)
			(layer "B.Fab")
		)
		(fp_line
			(start 0.12065 0.2794)
			(end 0.12065 0.3048)
			(stroke
				(width 0.1)
				(type default)
			)
			(layer "B.Fab")
		)
		(fp_line
			(start -0.12065 -0.2794)
			(end -0.12065 -0.3048)
			(stroke
				(width 0.1)
				(type default)
			)
			(layer "B.Fab")
		)
		(fp_line
			(start 0.12065 -0.2794)
			(end -0.12065 -0.2794)
			(stroke
				(width 0.1)
				(type default)
			)
			(layer "B.Fab")
		)
		(fp_line
			(start -0.67945 -0.3048)
			(end -0.67945 0.3048)
			(stroke
				(width 0.1)
				(type default)
			)
			(layer "B.Fab")
		)
		(fp_line
			(start -0.12065 -0.3048)
			(end -0.67945 -0.3048)
			(stroke
				(width 0.1)
				(type default)
			)
			(layer "B.Fab")
		)
		(fp_line
			(start 0.12065 -0.305054)
			(end 0.12065 -0.2794)
			(stroke
				(width 0.1)
				(type default)
			)
			(layer "B.Fab")
		)
		(fp_line
			(start 0.67945 -0.305054)
			(end 0.12065 -0.305054)
			(stroke
				(width 0.1)
				(type default)
			)
			(layer "B.Fab")
		)
		(pad "1" smd circle
			(at 0.40005 0 90)
			(size 0 0)
			(layers "B.Cu" "B.Mask" "B.Paste")
			(net "GND")
		)
		(pad "2" smd circle
			(at -0.40005 0 90)
			(size 0 0)
			(layers "B.Cu" "B.Mask" "B.Paste")
			(net "M_BMC_DDR4_MBA0")
		)
	)
	(footprint ""
		(layer "B.Cu")
		(at 54.93131 -46.073314 90)
		(property "Reference" "C89"
			(at 0 0 90)
			(layer "B.SilkS")
			(hide yes)
			(effects
				(font
					(size 1.27 1.27)
				)
				(justify mirror)
			)
		)
		(property "Value" ""
			(at 0 0 90)
			(layer "B.Fab")
			(effects
				(font
					(size 1.27 1.27)
				)
				(justify mirror)
			)
		)
		(duplicate_pad_numbers_are_jumpers no)
		(fp_line
			(start 0.7874 -0.4064)
			(end -0.7874 -0.4064)
			(stroke
				(width 0.1524)
				(type default)
			)
			(layer "B.SilkS")
		)
		(fp_line
			(start -0.7874 -0.4064)
			(end -0.7874 0.4064)
			(stroke
				(width 0.1524)
				(type default)
			)
			(layer "B.SilkS")
		)
		(fp_line
			(start 0.7874 0.4064)
			(end 0.7874 -0.4064)
			(stroke
				(width 0.1524)
				(type default)
			)
			(layer "B.SilkS")
		)
		(fp_line
			(start -0.7874 0.4064)
			(end 0.7874 0.4064)
			(stroke
				(width 0.1524)
				(type default)
			)
			(layer "B.SilkS")
		)
		(fp_line
			(start 0.67945 -0.305054)
			(end 0.12065 -0.305054)
			(stroke
				(width 0.1)
				(type default)
			)
			(layer "B.Fab")
		)
		(fp_line
			(start 0.12065 -0.305054)
			(end 0.12065 -0.2794)
			(stroke
				(width 0.1)
				(type default)
			)
			(layer "B.Fab")
		)
		(fp_line
			(start -0.12065 -0.3048)
			(end -0.67945 -0.3048)
			(stroke
				(width 0.1)
				(type default)
			)
			(layer "B.Fab")
		)
		(fp_line
			(start -0.67945 -0.3048)
			(end -0.67945 0.3048)
			(stroke
				(width 0.1)
				(type default)
			)
			(layer "B.Fab")
		)
		(fp_line
			(start 0.12065 -0.2794)
			(end -0.12065 -0.2794)
			(stroke
				(width 0.1)
				(type default)
			)
			(layer "B.Fab")
		)
		(fp_line
			(start -0.12065 -0.2794)
			(end -0.12065 -0.3048)
			(stroke
				(width 0.1)
				(type default)
			)
			(layer "B.Fab")
		)
		(fp_line
			(start 0.12065 0.2794)
			(end 0.12065 0.3048)
			(stroke
				(width 0.1)
				(type default)
			)
			(layer "B.Fab")
		)
		(fp_line
			(start -0.120396 0.2794)
			(end 0.12065 0.2794)
			(stroke
				(width 0.1)
				(type default)
			)
			(layer "B.Fab")
		)
		(fp_line
			(start 0.67945 0.3048)
			(end 0.67945 -0.305054)
			(stroke
				(width 0.1)
				(type default)
			)
			(layer "B.Fab")
		)
		(fp_line
			(start 0.12065 0.3048)
			(end 0.67945 0.3048)
			(stroke
				(width 0.1)
				(type default)
			)
			(layer "B.Fab")
		)
		(fp_line
			(start -0.120396 0.3048)
			(end -0.120396 0.2794)
			(stroke
				(width 0.1)
				(type default)
			)
			(layer "B.Fab")
		)
		(fp_line
			(start -0.67945 0.3048)
			(end -0.120396 0.3048)
			(stroke
				(width 0.1)
				(type default)
			)
			(layer "B.Fab")
		)
		(pad "1" smd circle
			(at 0.40005 0 270)
			(size 0 0)
			(layers "B.Cu" "B.Mask" "B.Paste")
			(net "P1V8_AUX")
		)
		(pad "2" smd circle
			(at -0.40005 0 270)
			(size 0 0)
			(layers "B.Cu" "B.Mask" "B.Paste")
			(net "GND")
		)
	)
	(footprint ""
		(layer "B.Cu")
		(at 79.739744 -37.559488 90)
		(property "Reference" "R371"
			(at 0 0 90)
			(layer "B.SilkS")
			(hide yes)
			(effects
				(font
					(size 1.27 1.27)
				)
				(justify mirror)
			)
		)
		(property "Value" ""
			(at 0 0 90)
			(layer "B.Fab")
			(effects
				(font
					(size 1.27 1.27)
				)
				(justify mirror)
			)
		)
		(duplicate_pad_numbers_are_jumpers no)
		(fp_line
			(start 0.7874 -0.4064)
			(end -0.7874 -0.4064)
			(stroke
				(width 0.1524)
				(type default)
			)
			(layer "B.SilkS")
		)
		(fp_line
			(start -0.7874 -0.4064)
			(end -0.7874 0.4064)
			(stroke
				(width 0.1524)
				(type default)
			)
			(layer "B.SilkS")
		)
		(fp_line
			(start 0.7874 0.4064)
			(end 0.7874 -0.4064)
			(stroke
				(width 0.1524)
				(type default)
			)
			(layer "B.SilkS")
		)
		(fp_line
			(start -0.7874 0.4064)
			(end 0.7874 0.4064)
			(stroke
				(width 0.1524)
				(type default)
			)
			(layer "B.SilkS")
		)
		(fp_line
			(start 0.67945 -0.305054)
			(end 0.12065 -0.305054)
			(stroke
				(width 0.1)
				(type default)
			)
			(layer "B.Fab")
		)
		(fp_line
			(start 0.12065 -0.305054)
			(end 0.12065 -0.2794)
			(stroke
				(width 0.1)
				(type default)
			)
			(layer "B.Fab")
		)
		(fp_line
			(start -0.12065 -0.3048)
			(end -0.67945 -0.3048)
			(stroke
				(width 0.1)
				(type default)
			)
			(layer "B.Fab")
		)
		(fp_line
			(start -0.67945 -0.3048)
			(end -0.67945 0.3048)
			(stroke
				(width 0.1)
				(type default)
			)
			(layer "B.Fab")
		)
		(fp_line
			(start 0.12065 -0.2794)
			(end -0.12065 -0.2794)
			(stroke
				(width 0.1)
				(type default)
			)
			(layer "B.Fab")
		)
		(fp_line
			(start -0.12065 -0.2794)
			(end -0.12065 -0.3048)
			(stroke
				(width 0.1)
				(type default)
			)
			(layer "B.Fab")
		)
		(fp_line
			(start 0.12065 0.2794)
			(end 0.12065 0.3048)
			(stroke
				(width 0.1)
				(type default)
			)
			(layer "B.Fab")
		)
		(fp_line
			(start -0.120396 0.2794)
			(end 0.12065 0.2794)
			(stroke
				(width 0.1)
				(type default)
			)
			(layer "B.Fab")
		)
		(fp_line
			(start 0.67945 0.3048)
			(end 0.67945 -0.305054)
			(stroke
				(width 0.1)
				(type default)
			)
			(layer "B.Fab")
		)
		(fp_line
			(start 0.12065 0.3048)
			(end 0.67945 0.3048)
			(stroke
				(width 0.1)
				(type default)
			)
			(layer "B.Fab")
		)
		(fp_line
			(start -0.120396 0.3048)
			(end -0.120396 0.2794)
			(stroke
				(width 0.1)
				(type default)
			)
			(layer "B.Fab")
		)
		(fp_line
			(start -0.67945 0.3048)
			(end -0.120396 0.3048)
			(stroke
				(width 0.1)
				(type default)
			)
			(layer "B.Fab")
		)
		(pad "1" smd circle
			(at 0.40005 0 270)
			(size 0 0)
			(layers "B.Cu" "B.Mask" "B.Paste")
			(net "M_BMC_DDR4_MBA0")
		)
		(pad "2" smd circle
			(at -0.40005 0 270)
			(size 0 0)
			(layers "B.Cu" "B.Mask" "B.Paste")
			(net "P1V2_AUX")
		)
	)
	(footprint ""
		(layer "B.Cu")
		(at 29.8196 -106.2482 -90)
		(property "Reference" "R77"
			(at 0 0 90)
			(layer "B.SilkS")
			(hide yes)
			(effects
				(font
					(size 1.27 1.27)
				)
				(justify mirror)
			)
		)
		(property "Value" ""
			(at 0 0 90)
			(layer "B.Fab")
			(effects
				(font
					(size 1.27 1.27)
				)
				(justify mirror)
			)
		)
		(duplicate_pad_numbers_are_jumpers no)
		(fp_line
			(start -0.7874 0.4064)
			(end 0.7874 0.4064)
			(stroke
				(width 0.1524)
				(type default)
			)
			(layer "B.SilkS")
		)
		(fp_line
			(start 0.7874 0.4064)
			(end 0.7874 -0.4064)
			(stroke
				(width 0.1524)
				(type default)
			)
			(layer "B.SilkS")
		)
		(fp_line
			(start -0.7874 -0.4064)
			(end -0.7874 0.4064)
			(stroke
				(width 0.1524)
				(type default)
			)
			(layer "B.SilkS")
		)
		(fp_line
			(start 0.7874 -0.4064)
			(end -0.7874 -0.4064)
			(stroke
				(width 0.1524)
				(type default)
			)
			(layer "B.SilkS")
		)
		(fp_line
			(start -0.67945 0.3048)
			(end -0.120396 0.3048)
			(stroke
				(width 0.1)
				(type default)
			)
			(layer "B.Fab")
		)
		(fp_line
			(start -0.120396 0.3048)
			(end -0.120396 0.2794)
			(stroke
				(width 0.1)
				(type default)
			)
			(layer "B.Fab")
		)
		(fp_line
			(start 0.12065 0.3048)
			(end 0.67945 0.3048)
			(stroke
				(width 0.1)
				(type default)
			)
			(layer "B.Fab")
		)
		(fp_line
			(start 0.67945 0.3048)
			(end 0.67945 -0.305054)
			(stroke
				(width 0.1)
				(type default)
			)
			(layer "B.Fab")
		)
		(fp_line
			(start -0.120396 0.2794)
			(end 0.12065 0.2794)
			(stroke
				(width 0.1)
				(type default)
			)
			(layer "B.Fab")
		)
		(fp_line
			(start 0.12065 0.2794)
			(end 0.12065 0.3048)
			(stroke
				(width 0.1)
				(type default)
			)
			(layer "B.Fab")
		)
		(fp_line
			(start -0.12065 -0.2794)
			(end -0.12065 -0.3048)
			(stroke
				(width 0.1)
				(type default)
			)
			(layer "B.Fab")
		)
		(fp_line
			(start 0.12065 -0.2794)
			(end -0.12065 -0.2794)
			(stroke
				(width 0.1)
				(type default)
			)
			(layer "B.Fab")
		)
		(fp_line
			(start -0.67945 -0.3048)
			(end -0.67945 0.3048)
			(stroke
				(width 0.1)
				(type default)
			)
			(layer "B.Fab")
		)
		(fp_line
			(start -0.12065 -0.3048)
			(end -0.67945 -0.3048)
			(stroke
				(width 0.1)
				(type default)
			)
			(layer "B.Fab")
		)
		(fp_line
			(start 0.12065 -0.305054)
			(end 0.12065 -0.2794)
			(stroke
				(width 0.1)
				(type default)
			)
			(layer "B.Fab")
		)
		(fp_line
			(start 0.67945 -0.305054)
			(end 0.12065 -0.305054)
			(stroke
				(width 0.1)
				(type default)
			)
			(layer "B.Fab")
		)
		(pad "1" smd circle
			(at 0.40005 0 90)
			(size 0 0)
			(layers "B.Cu" "B.Mask" "B.Paste")
			(net "P3V3_AUX")
		)
		(pad "2" smd circle
			(at -0.40005 0 90)
			(size 0 0)
			(layers "B.Cu" "B.Mask" "B.Paste")
			(net "SGPIO_LD_0")
		)
	)
	(footprint ""
		(layer "B.Cu")
		(at 22.5298 -83.693 -90)
		(property "Reference" "R807"
			(at 0 0 90)
			(layer "B.SilkS")
			(hide yes)
			(effects
				(font
					(size 1.27 1.27)
				)
				(justify mirror)
			)
		)
		(property "Value" ""
			(at 0 0 90)
			(layer "B.Fab")
			(effects
				(font
					(size 1.27 1.27)
				)
				(justify mirror)
			)
		)
		(duplicate_pad_numbers_are_jumpers no)
		(fp_line
			(start -0.7874 0.4064)
			(end 0.7874 0.4064)
			(stroke
				(width 0.1524)
				(type default)
			)
			(layer "B.SilkS")
		)
		(fp_line
			(start 0.7874 0.4064)
			(end 0.7874 -0.4064)
			(stroke
				(width 0.1524)
				(type default)
			)
			(layer "B.SilkS")
		)
		(fp_line
			(start -0.7874 -0.4064)
			(end -0.7874 0.4064)
			(stroke
				(width 0.1524)
				(type default)
			)
			(layer "B.SilkS")
		)
		(fp_line
			(start 0.7874 -0.4064)
			(end -0.7874 -0.4064)
			(stroke
				(width 0.1524)
				(type default)
			)
			(layer "B.SilkS")
		)
		(fp_line
			(start -0.67945 0.3048)
			(end -0.120396 0.3048)
			(stroke
				(width 0.1)
				(type default)
			)
			(layer "B.Fab")
		)
		(fp_line
			(start -0.120396 0.3048)
			(end -0.120396 0.2794)
			(stroke
				(width 0.1)
				(type default)
			)
			(layer "B.Fab")
		)
		(fp_line
			(start 0.12065 0.3048)
			(end 0.67945 0.3048)
			(stroke
				(width 0.1)
				(type default)
			)
			(layer "B.Fab")
		)
		(fp_line
			(start 0.67945 0.3048)
			(end 0.67945 -0.305054)
			(stroke
				(width 0.1)
				(type default)
			)
			(layer "B.Fab")
		)
		(fp_line
			(start -0.120396 0.2794)
			(end 0.12065 0.2794)
			(stroke
				(width 0.1)
				(type default)
			)
			(layer "B.Fab")
		)
		(fp_line
			(start 0.12065 0.2794)
			(end 0.12065 0.3048)
			(stroke
				(width 0.1)
				(type default)
			)
			(layer "B.Fab")
		)
		(fp_line
			(start -0.12065 -0.2794)
			(end -0.12065 -0.3048)
			(stroke
				(width 0.1)
				(type default)
			)
			(layer "B.Fab")
		)
		(fp_line
			(start 0.12065 -0.2794)
			(end -0.12065 -0.2794)
			(stroke
				(width 0.1)
				(type default)
			)
			(layer "B.Fab")
		)
		(fp_line
			(start -0.67945 -0.3048)
			(end -0.67945 0.3048)
			(stroke
				(width 0.1)
				(type default)
			)
			(layer "B.Fab")
		)
		(fp_line
			(start -0.12065 -0.3048)
			(end -0.67945 -0.3048)
			(stroke
				(width 0.1)
				(type default)
			)
			(layer "B.Fab")
		)
		(fp_line
			(start 0.12065 -0.305054)
			(end 0.12065 -0.2794)
			(stroke
				(width 0.1)
				(type default)
			)
			(layer "B.Fab")
		)
		(fp_line
			(start 0.67945 -0.305054)
			(end 0.12065 -0.305054)
			(stroke
				(width 0.1)
				(type default)
			)
			(layer "B.Fab")
		)
		(pad "1" smd circle
			(at 0.40005 0 90)
			(size 0 0)
			(layers "B.Cu" "B.Mask" "B.Paste")
			(net "CLK_25M_OSC_FPGA_R")
		)
		(pad "2" smd circle
			(at -0.40005 0 90)
			(size 0 0)
			(layers "B.Cu" "B.Mask" "B.Paste")
			(net "CLK_25M_OSC_FPGA")
		)
	)
	(footprint ""
		(layer "B.Cu")
		(at 43.8912 -88.4936 90)
		(property "Reference" "R694"
			(at 0 0 90)
			(layer "B.SilkS")
			(hide yes)
			(effects
				(font
					(size 1.27 1.27)
				)
				(justify mirror)
			)
		)
		(property "Value" ""
			(at 0 0 90)
			(layer "B.Fab")
			(effects
				(font
					(size 1.27 1.27)
				)
				(justify mirror)
			)
		)
		(duplicate_pad_numbers_are_jumpers no)
		(fp_line
			(start 0.7874 -0.4064)
			(end -0.7874 -0.4064)
			(stroke
				(width 0.1524)
				(type default)
			)
			(layer "B.SilkS")
		)
		(fp_line
			(start -0.7874 -0.4064)
			(end -0.7874 0.4064)
			(stroke
				(width 0.1524)
				(type default)
			)
			(layer "B.SilkS")
		)
		(fp_line
			(start 0.7874 0.4064)
			(end 0.7874 -0.4064)
			(stroke
				(width 0.1524)
				(type default)
			)
			(layer "B.SilkS")
		)
		(fp_line
			(start -0.7874 0.4064)
			(end 0.7874 0.4064)
			(stroke
				(width 0.1524)
				(type default)
			)
			(layer "B.SilkS")
		)
		(fp_line
			(start 0.67945 -0.305054)
			(end 0.12065 -0.305054)
			(stroke
				(width 0.1)
				(type default)
			)
			(layer "B.Fab")
		)
		(fp_line
			(start 0.12065 -0.305054)
			(end 0.12065 -0.2794)
			(stroke
				(width 0.1)
				(type default)
			)
			(layer "B.Fab")
		)
		(fp_line
			(start -0.12065 -0.3048)
			(end -0.67945 -0.3048)
			(stroke
				(width 0.1)
				(type default)
			)
			(layer "B.Fab")
		)
		(fp_line
			(start -0.67945 -0.3048)
			(end -0.67945 0.3048)
			(stroke
				(width 0.1)
				(type default)
			)
			(layer "B.Fab")
		)
		(fp_line
			(start 0.12065 -0.2794)
			(end -0.12065 -0.2794)
			(stroke
				(width 0.1)
				(type default)
			)
			(layer "B.Fab")
		)
		(fp_line
			(start -0.12065 -0.2794)
			(end -0.12065 -0.3048)
			(stroke
				(width 0.1)
				(type default)
			)
			(layer "B.Fab")
		)
		(fp_line
			(start 0.12065 0.2794)
			(end 0.12065 0.3048)
			(stroke
				(width 0.1)
				(type default)
			)
			(layer "B.Fab")
		)
		(fp_line
			(start -0.120396 0.2794)
			(end 0.12065 0.2794)
			(stroke
				(width 0.1)
				(type default)
			)
			(layer "B.Fab")
		)
		(fp_line
			(start 0.67945 0.3048)
			(end 0.67945 -0.305054)
			(stroke
				(width 0.1)
				(type default)
			)
			(layer "B.Fab")
		)
		(fp_line
			(start 0.12065 0.3048)
			(end 0.67945 0.3048)
			(stroke
				(width 0.1)
				(type default)
			)
			(layer "B.Fab")
		)
		(fp_line
			(start -0.120396 0.3048)
			(end -0.120396 0.2794)
			(stroke
				(width 0.1)
				(type default)
			)
			(layer "B.Fab")
		)
		(fp_line
			(start -0.67945 0.3048)
			(end -0.120396 0.3048)
			(stroke
				(width 0.1)
				(type default)
			)
			(layer "B.Fab")
		)
		(pad "1" smd circle
			(at 0.40005 0 270)
			(size 0 0)
			(layers "B.Cu" "B.Mask" "B.Paste")
			(net "USB3_MUX_PD")
		)
		(pad "2" smd circle
			(at -0.40005 0 270)
			(size 0 0)
			(layers "B.Cu" "B.Mask" "B.Paste")
			(net "GND")
		)
	)
	(footprint ""
		(layer "B.Cu")
		(at 20.955 -101.981 -90)
		(property "Reference" "R749"
			(at 0 0 90)
			(layer "B.SilkS")
			(hide yes)
			(effects
				(font
					(size 1.27 1.27)
				)
				(justify mirror)
			)
		)
		(property "Value" ""
			(at 0 0 90)
			(layer "B.Fab")
			(effects
				(font
					(size 1.27 1.27)
				)
				(justify mirror)
			)
		)
		(duplicate_pad_numbers_are_jumpers no)
		(fp_line
			(start -0.7874 0.4064)
			(end 0.7874 0.4064)
			(stroke
				(width 0.1524)
				(type default)
			)
			(layer "B.SilkS")
		)
		(fp_line
			(start 0.7874 0.4064)
			(end 0.7874 -0.4064)
			(stroke
				(width 0.1524)
				(type default)
			)
			(layer "B.SilkS")
		)
		(fp_line
			(start -0.7874 -0.4064)
			(end -0.7874 0.4064)
			(stroke
				(width 0.1524)
				(type default)
			)
			(layer "B.SilkS")
		)
		(fp_line
			(start 0.7874 -0.4064)
			(end -0.7874 -0.4064)
			(stroke
				(width 0.1524)
				(type default)
			)
			(layer "B.SilkS")
		)
		(fp_line
			(start -0.67945 0.3048)
			(end -0.120396 0.3048)
			(stroke
				(width 0.1)
				(type default)
			)
			(layer "B.Fab")
		)
		(fp_line
			(start -0.120396 0.3048)
			(end -0.120396 0.2794)
			(stroke
				(width 0.1)
				(type default)
			)
			(layer "B.Fab")
		)
		(fp_line
			(start 0.12065 0.3048)
			(end 0.67945 0.3048)
			(stroke
				(width 0.1)
				(type default)
			)
			(layer "B.Fab")
		)
		(fp_line
			(start 0.67945 0.3048)
			(end 0.67945 -0.305054)
			(stroke
				(width 0.1)
				(type default)
			)
			(layer "B.Fab")
		)
		(fp_line
			(start -0.120396 0.2794)
			(end 0.12065 0.2794)
			(stroke
				(width 0.1)
				(type default)
			)
			(layer "B.Fab")
		)
		(fp_line
			(start 0.12065 0.2794)
			(end 0.12065 0.3048)
			(stroke
				(width 0.1)
				(type default)
			)
			(layer "B.Fab")
		)
		(fp_line
			(start -0.12065 -0.2794)
			(end -0.12065 -0.3048)
			(stroke
				(width 0.1)
				(type default)
			)
			(layer "B.Fab")
		)
		(fp_line
			(start 0.12065 -0.2794)
			(end -0.12065 -0.2794)
			(stroke
				(width 0.1)
				(type default)
			)
			(layer "B.Fab")
		)
		(fp_line
			(start -0.67945 -0.3048)
			(end -0.67945 0.3048)
			(stroke
				(width 0.1)
				(type default)
			)
			(layer "B.Fab")
		)
		(fp_line
			(start -0.12065 -0.3048)
			(end -0.67945 -0.3048)
			(stroke
				(width 0.1)
				(type default)
			)
			(layer "B.Fab")
		)
		(fp_line
			(start 0.12065 -0.305054)
			(end 0.12065 -0.2794)
			(stroke
				(width 0.1)
				(type default)
			)
			(layer "B.Fab")
		)
		(fp_line
			(start 0.67945 -0.305054)
			(end 0.12065 -0.305054)
			(stroke
				(width 0.1)
				(type default)
			)
			(layer "B.Fab")
		)
		(pad "1" smd circle
			(at 0.40005 0 90)
			(size 0 0)
			(layers "B.Cu" "B.Mask" "B.Paste")
			(net "P3V3_AUX")
		)
		(pad "2" smd circle
			(at -0.40005 0 90)
			(size 0 0)
			(layers "B.Cu" "B.Mask" "B.Paste")
			(net "FM_BMC_CRASHLOG_TRIG_N")
		)
	)
	(footprint ""
		(layer "B.Cu")
		(at 78.02372 -51.000406 180)
		(property "Reference" "R3"
			(at 0 0 0)
			(layer "B.SilkS")
			(hide yes)
			(effects
				(font
					(size 1.27 1.27)
				)
				(justify mirror)
			)
		)
		(property "Value" ""
			(at 0 0 0)
			(layer "B.Fab")
			(effects
				(font
					(size 1.27 1.27)
				)
				(justify mirror)
			)
		)
		(duplicate_pad_numbers_are_jumpers no)
		(fp_line
			(start 0.7874 0.4064)
			(end 0.7874 -0.4064)
			(stroke
				(width 0.1524)
				(type default)
			)
			(layer "B.SilkS")
		)
		(fp_line
			(start 0.7874 -0.4064)
			(end -0.7874 -0.4064)
			(stroke
				(width 0.1524)
				(type default)
			)
			(layer "B.SilkS")
		)
		(fp_line
			(start -0.7874 0.4064)
			(end 0.7874 0.4064)
			(stroke
				(width 0.1524)
				(type default)
			)
			(layer "B.SilkS")
		)
		(fp_line
			(start -0.7874 -0.4064)
			(end -0.7874 0.4064)
			(stroke
				(width 0.1524)
				(type default)
			)
			(layer "B.SilkS")
		)
		(fp_line
			(start 0.67945 0.3048)
			(end 0.67945 -0.305054)
			(stroke
				(width 0.1)
				(type default)
			)
			(layer "B.Fab")
		)
		(fp_line
			(start 0.67945 -0.305054)
			(end 0.12065 -0.305054)
			(stroke
				(width 0.1)
				(type default)
			)
			(layer "B.Fab")
		)
		(fp_line
			(start 0.12065 0.3048)
			(end 0.67945 0.3048)
			(stroke
				(width 0.1)
				(type default)
			)
			(layer "B.Fab")
		)
		(fp_line
			(start 0.12065 0.2794)
			(end 0.12065 0.3048)
			(stroke
				(width 0.1)
				(type default)
			)
			(layer "B.Fab")
		)
		(fp_line
			(start 0.12065 -0.2794)
			(end -0.12065 -0.2794)
			(stroke
				(width 0.1)
				(type default)
			)
			(layer "B.Fab")
		)
		(fp_line
			(start 0.12065 -0.305054)
			(end 0.12065 -0.2794)
			(stroke
				(width 0.1)
				(type default)
			)
			(layer "B.Fab")
		)
		(fp_line
			(start -0.120396 0.3048)
			(end -0.120396 0.2794)
			(stroke
				(width 0.1)
				(type default)
			)
			(layer "B.Fab")
		)
		(fp_line
			(start -0.120396 0.2794)
			(end 0.12065 0.2794)
			(stroke
				(width 0.1)
				(type default)
			)
			(layer "B.Fab")
		)
		(fp_line
			(start -0.12065 -0.2794)
			(end -0.12065 -0.3048)
			(stroke
				(width 0.1)
				(type default)
			)
			(layer "B.Fab")
		)
		(fp_line
			(start -0.12065 -0.3048)
			(end -0.67945 -0.3048)
			(stroke
				(width 0.1)
				(type default)
			)
			(layer "B.Fab")
		)
		(fp_line
			(start -0.67945 0.3048)
			(end -0.120396 0.3048)
			(stroke
				(width 0.1)
				(type default)
			)
			(layer "B.Fab")
		)
		(fp_line
			(start -0.67945 -0.3048)
			(end -0.67945 0.3048)
			(stroke
				(width 0.1)
				(type default)
			)
			(layer "B.Fab")
		)
		(pad "1" smd circle
			(at 0.40005 0)
			(size 0 0)
			(layers "B.Cu" "B.Mask" "B.Paste")
			(net "M_BMC_DDR4_ZQU")
		)
		(pad "2" smd circle
			(at -0.40005 0)
			(size 0 0)
			(layers "B.Cu" "B.Mask" "B.Paste")
			(net "GND")
		)
	)
	(footprint ""
		(layer "B.Cu")
		(at 59.7154 -64.3382 -90)
		(property "Reference" "R176"
			(at 0 0 90)
			(layer "B.SilkS")
			(hide yes)
			(effects
				(font
					(size 1.27 1.27)
				)
				(justify mirror)
			)
		)
		(property "Value" ""
			(at 0 0 90)
			(layer "B.Fab")
			(effects
				(font
					(size 1.27 1.27)
				)
				(justify mirror)
			)
		)
		(duplicate_pad_numbers_are_jumpers no)
		(fp_line
			(start -0.7874 0.4064)
			(end 0.7874 0.4064)
			(stroke
				(width 0.1524)
				(type default)
			)
			(layer "B.SilkS")
		)
		(fp_line
			(start 0.7874 0.4064)
			(end 0.7874 -0.4064)
			(stroke
				(width 0.1524)
				(type default)
			)
			(layer "B.SilkS")
		)
		(fp_line
			(start -0.7874 -0.4064)
			(end -0.7874 0.4064)
			(stroke
				(width 0.1524)
				(type default)
			)
			(layer "B.SilkS")
		)
		(fp_line
			(start 0.7874 -0.4064)
			(end -0.7874 -0.4064)
			(stroke
				(width 0.1524)
				(type default)
			)
			(layer "B.SilkS")
		)
		(fp_line
			(start -0.67945 0.3048)
			(end -0.120396 0.3048)
			(stroke
				(width 0.1)
				(type default)
			)
			(layer "B.Fab")
		)
		(fp_line
			(start -0.120396 0.3048)
			(end -0.120396 0.2794)
			(stroke
				(width 0.1)
				(type default)
			)
			(layer "B.Fab")
		)
		(fp_line
			(start 0.12065 0.3048)
			(end 0.67945 0.3048)
			(stroke
				(width 0.1)
				(type default)
			)
			(layer "B.Fab")
		)
		(fp_line
			(start 0.67945 0.3048)
			(end 0.67945 -0.305054)
			(stroke
				(width 0.1)
				(type default)
			)
			(layer "B.Fab")
		)
		(fp_line
			(start -0.120396 0.2794)
			(end 0.12065 0.2794)
			(stroke
				(width 0.1)
				(type default)
			)
			(layer "B.Fab")
		)
		(fp_line
			(start 0.12065 0.2794)
			(end 0.12065 0.3048)
			(stroke
				(width 0.1)
				(type default)
			)
			(layer "B.Fab")
		)
		(fp_line
			(start -0.12065 -0.2794)
			(end -0.12065 -0.3048)
			(stroke
				(width 0.1)
				(type default)
			)
			(layer "B.Fab")
		)
		(fp_line
			(start 0.12065 -0.2794)
			(end -0.12065 -0.2794)
			(stroke
				(width 0.1)
				(type default)
			)
			(layer "B.Fab")
		)
		(fp_line
			(start -0.67945 -0.3048)
			(end -0.67945 0.3048)
			(stroke
				(width 0.1)
				(type default)
			)
			(layer "B.Fab")
		)
		(fp_line
			(start -0.12065 -0.3048)
			(end -0.67945 -0.3048)
			(stroke
				(width 0.1)
				(type default)
			)
			(layer "B.Fab")
		)
		(fp_line
			(start 0.12065 -0.305054)
			(end 0.12065 -0.2794)
			(stroke
				(width 0.1)
				(type default)
			)
			(layer "B.Fab")
		)
		(fp_line
			(start 0.67945 -0.305054)
			(end 0.12065 -0.305054)
			(stroke
				(width 0.1)
				(type default)
			)
			(layer "B.Fab")
		)
		(pad "1" smd circle
			(at 0.40005 0 90)
			(size 0 0)
			(layers "B.Cu" "B.Mask" "B.Paste")
			(net "SPI_BMC_BIOS_ROM_MISO")
		)
		(pad "2" smd circle
			(at -0.40005 0 90)
			(size 0 0)
			(layers "B.Cu" "B.Mask" "B.Paste")
			(net "SPI_BMC_BIOS_ROM_R_MISO")
		)
	)
	(footprint ""
		(layer "B.Cu")
		(at 77.2795 -99.911408)
		(property "Reference" "R713"
			(at 0 0 0)
			(layer "B.SilkS")
			(hide yes)
			(effects
				(font
					(size 1.27 1.27)
				)
				(justify mirror)
			)
		)
		(property "Value" ""
			(at 0 0 0)
			(layer "B.Fab")
			(effects
				(font
					(size 1.27 1.27)
				)
				(justify mirror)
			)
		)
		(duplicate_pad_numbers_are_jumpers no)
		(fp_line
			(start -0.7874 -0.4064)
			(end -0.7874 0.4064)
			(stroke
				(width 0.1524)
				(type default)
			)
			(layer "B.SilkS")
		)
		(fp_line
			(start -0.7874 0.4064)
			(end 0.7874 0.4064)
			(stroke
				(width 0.1524)
				(type default)
			)
			(layer "B.SilkS")
		)
		(fp_line
			(start 0.7874 -0.4064)
			(end -0.7874 -0.4064)
			(stroke
				(width 0.1524)
				(type default)
			)
			(layer "B.SilkS")
		)
		(fp_line
			(start 0.7874 0.4064)
			(end 0.7874 -0.4064)
			(stroke
				(width 0.1524)
				(type default)
			)
			(layer "B.SilkS")
		)
		(fp_line
			(start -0.67945 -0.3048)
			(end -0.67945 0.3048)
			(stroke
				(width 0.1)
				(type default)
			)
			(layer "B.Fab")
		)
		(fp_line
			(start -0.67945 0.3048)
			(end -0.120396 0.3048)
			(stroke
				(width 0.1)
				(type default)
			)
			(layer "B.Fab")
		)
		(fp_line
			(start -0.12065 -0.3048)
			(end -0.67945 -0.3048)
			(stroke
				(width 0.1)
				(type default)
			)
			(layer "B.Fab")
		)
		(fp_line
			(start -0.12065 -0.2794)
			(end -0.12065 -0.3048)
			(stroke
				(width 0.1)
				(type default)
			)
			(layer "B.Fab")
		)
		(fp_line
			(start -0.120396 0.2794)
			(end 0.12065 0.2794)
			(stroke
				(width 0.1)
				(type default)
			)
			(layer "B.Fab")
		)
		(fp_line
			(start -0.120396 0.3048)
			(end -0.120396 0.2794)
			(stroke
				(width 0.1)
				(type default)
			)
			(layer "B.Fab")
		)
		(fp_line
			(start 0.12065 -0.305054)
			(end 0.12065 -0.2794)
			(stroke
				(width 0.1)
				(type default)
			)
			(layer "B.Fab")
		)
		(fp_line
			(start 0.12065 -0.2794)
			(end -0.12065 -0.2794)
			(stroke
				(width 0.1)
				(type default)
			)
			(layer "B.Fab")
		)
		(fp_line
			(start 0.12065 0.2794)
			(end 0.12065 0.3048)
			(stroke
				(width 0.1)
				(type default)
			)
			(layer "B.Fab")
		)
		(fp_line
			(start 0.12065 0.3048)
			(end 0.67945 0.3048)
			(stroke
				(width 0.1)
				(type default)
			)
			(layer "B.Fab")
		)
		(fp_line
			(start 0.67945 -0.305054)
			(end 0.12065 -0.305054)
			(stroke
				(width 0.1)
				(type default)
			)
			(layer "B.Fab")
		)
		(fp_line
			(start 0.67945 0.3048)
			(end 0.67945 -0.305054)
			(stroke
				(width 0.1)
				(type default)
			)
			(layer "B.Fab")
		)
		(pad "1" smd circle
			(at 0.40005 0 180)
			(size 0 0)
			(layers "B.Cu" "B.Mask" "B.Paste")
			(net "LPC_ESPI_SEL_R")
		)
		(pad "2" smd circle
			(at -0.40005 0 180)
			(size 0 0)
			(layers "B.Cu" "B.Mask" "B.Paste")
			(net "LPC_ESPI_SEL")
		)
	)
	(footprint ""
		(layer "B.Cu")
		(at 55.705502 -30.867604 -90)
		(property "Reference" "R258"
			(at 0 0 90)
			(layer "B.SilkS")
			(hide yes)
			(effects
				(font
					(size 1.27 1.27)
				)
				(justify mirror)
			)
		)
		(property "Value" ""
			(at 0 0 90)
			(layer "B.Fab")
			(effects
				(font
					(size 1.27 1.27)
				)
				(justify mirror)
			)
		)
		(duplicate_pad_numbers_are_jumpers no)
		(fp_line
			(start -0.7874 0.4064)
			(end 0.7874 0.4064)
			(stroke
				(width 0.1524)
				(type default)
			)
			(layer "B.SilkS")
		)
		(fp_line
			(start 0.7874 0.4064)
			(end 0.7874 -0.4064)
			(stroke
				(width 0.1524)
				(type default)
			)
			(layer "B.SilkS")
		)
		(fp_line
			(start -0.7874 -0.4064)
			(end -0.7874 0.4064)
			(stroke
				(width 0.1524)
				(type default)
			)
			(layer "B.SilkS")
		)
		(fp_line
			(start 0.7874 -0.4064)
			(end -0.7874 -0.4064)
			(stroke
				(width 0.1524)
				(type default)
			)
			(layer "B.SilkS")
		)
		(fp_line
			(start -0.67945 0.3048)
			(end -0.120396 0.3048)
			(stroke
				(width 0.1)
				(type default)
			)
			(layer "B.Fab")
		)
		(fp_line
			(start -0.120396 0.3048)
			(end -0.120396 0.2794)
			(stroke
				(width 0.1)
				(type default)
			)
			(layer "B.Fab")
		)
		(fp_line
			(start 0.12065 0.3048)
			(end 0.67945 0.3048)
			(stroke
				(width 0.1)
				(type default)
			)
			(layer "B.Fab")
		)
		(fp_line
			(start 0.67945 0.3048)
			(end 0.67945 -0.305054)
			(stroke
				(width 0.1)
				(type default)
			)
			(layer "B.Fab")
		)
		(fp_line
			(start -0.120396 0.2794)
			(end 0.12065 0.2794)
			(stroke
				(width 0.1)
				(type default)
			)
			(layer "B.Fab")
		)
		(fp_line
			(start 0.12065 0.2794)
			(end 0.12065 0.3048)
			(stroke
				(width 0.1)
				(type default)
			)
			(layer "B.Fab")
		)
		(fp_line
			(start -0.12065 -0.2794)
			(end -0.12065 -0.3048)
			(stroke
				(width 0.1)
				(type default)
			)
			(layer "B.Fab")
		)
		(fp_line
			(start 0.12065 -0.2794)
			(end -0.12065 -0.2794)
			(stroke
				(width 0.1)
				(type default)
			)
			(layer "B.Fab")
		)
		(fp_line
			(start -0.67945 -0.3048)
			(end -0.67945 0.3048)
			(stroke
				(width 0.1)
				(type default)
			)
			(layer "B.Fab")
		)
		(fp_line
			(start -0.12065 -0.3048)
			(end -0.67945 -0.3048)
			(stroke
				(width 0.1)
				(type default)
			)
			(layer "B.Fab")
		)
		(fp_line
			(start 0.12065 -0.305054)
			(end 0.12065 -0.2794)
			(stroke
				(width 0.1)
				(type default)
			)
			(layer "B.Fab")
		)
		(fp_line
			(start 0.67945 -0.305054)
			(end 0.12065 -0.305054)
			(stroke
				(width 0.1)
				(type default)
			)
			(layer "B.Fab")
		)
		(pad "1" smd circle
			(at 0.40005 0 90)
			(size 0 0)
			(layers "B.Cu" "B.Mask" "B.Paste")
			(net "P3V3_AUX")
		)
		(pad "2" smd circle
			(at -0.40005 0 90)
			(size 0 0)
			(layers "B.Cu" "B.Mask" "B.Paste")
			(net "SMB_BMC_MM8_SCL")
		)
	)
	(footprint ""
		(layer "B.Cu")
		(at 37.6047 -92.2528 -90)
		(property "Reference" "C236"
			(at 0 0 90)
			(layer "B.SilkS")
			(hide yes)
			(effects
				(font
					(size 1.27 1.27)
				)
				(justify mirror)
			)
		)
		(property "Value" ""
			(at 0 0 90)
			(layer "B.Fab")
			(effects
				(font
					(size 1.27 1.27)
				)
				(justify mirror)
			)
		)
		(duplicate_pad_numbers_are_jumpers no)
		(fp_line
			(start -0.7874 0.4064)
			(end 0.7874 0.4064)
			(stroke
				(width 0.1524)
				(type default)
			)
			(layer "B.SilkS")
		)
		(fp_line
			(start 0.7874 0.4064)
			(end 0.7874 -0.4064)
			(stroke
				(width 0.1524)
				(type default)
			)
			(layer "B.SilkS")
		)
		(fp_line
			(start -0.7874 -0.4064)
			(end -0.7874 0.4064)
			(stroke
				(width 0.1524)
				(type default)
			)
			(layer "B.SilkS")
		)
		(fp_line
			(start 0.7874 -0.4064)
			(end -0.7874 -0.4064)
			(stroke
				(width 0.1524)
				(type default)
			)
			(layer "B.SilkS")
		)
		(fp_line
			(start -0.67945 0.3048)
			(end -0.120396 0.3048)
			(stroke
				(width 0.1)
				(type default)
			)
			(layer "B.Fab")
		)
		(fp_line
			(start -0.120396 0.3048)
			(end -0.120396 0.2794)
			(stroke
				(width 0.1)
				(type default)
			)
			(layer "B.Fab")
		)
		(fp_line
			(start 0.12065 0.3048)
			(end 0.67945 0.3048)
			(stroke
				(width 0.1)
				(type default)
			)
			(layer "B.Fab")
		)
		(fp_line
			(start 0.67945 0.3048)
			(end 0.67945 -0.305054)
			(stroke
				(width 0.1)
				(type default)
			)
			(layer "B.Fab")
		)
		(fp_line
			(start -0.120396 0.2794)
			(end 0.12065 0.2794)
			(stroke
				(width 0.1)
				(type default)
			)
			(layer "B.Fab")
		)
		(fp_line
			(start 0.12065 0.2794)
			(end 0.12065 0.3048)
			(stroke
				(width 0.1)
				(type default)
			)
			(layer "B.Fab")
		)
		(fp_line
			(start -0.12065 -0.2794)
			(end -0.12065 -0.3048)
			(stroke
				(width 0.1)
				(type default)
			)
			(layer "B.Fab")
		)
		(fp_line
			(start 0.12065 -0.2794)
			(end -0.12065 -0.2794)
			(stroke
				(width 0.1)
				(type default)
			)
			(layer "B.Fab")
		)
		(fp_line
			(start -0.67945 -0.3048)
			(end -0.67945 0.3048)
			(stroke
				(width 0.1)
				(type default)
			)
			(layer "B.Fab")
		)
		(fp_line
			(start -0.12065 -0.3048)
			(end -0.67945 -0.3048)
			(stroke
				(width 0.1)
				(type default)
			)
			(layer "B.Fab")
		)
		(fp_line
			(start 0.12065 -0.305054)
			(end 0.12065 -0.2794)
			(stroke
				(width 0.1)
				(type default)
			)
			(layer "B.Fab")
		)
		(fp_line
			(start 0.67945 -0.305054)
			(end 0.12065 -0.305054)
			(stroke
				(width 0.1)
				(type default)
			)
			(layer "B.Fab")
		)
		(pad "1" smd circle
			(at 0.40005 0 90)
			(size 0 0)
			(layers "B.Cu" "B.Mask" "B.Paste")
			(net "P3V3_AUX")
		)
		(pad "2" smd circle
			(at -0.40005 0 90)
			(size 0 0)
			(layers "B.Cu" "B.Mask" "B.Paste")
			(net "GND")
		)
	)
	(footprint ""
		(layer "B.Cu")
		(at 83.058 -101.473 90)
		(property "Reference" "C330"
			(at 0 0 90)
			(layer "B.SilkS")
			(hide yes)
			(effects
				(font
					(size 1.27 1.27)
				)
				(justify mirror)
			)
		)
		(property "Value" ""
			(at 0 0 90)
			(layer "B.Fab")
			(effects
				(font
					(size 1.27 1.27)
				)
				(justify mirror)
			)
		)
		(duplicate_pad_numbers_are_jumpers no)
		(fp_line
			(start 1.524 -0.762)
			(end -1.524 -0.762)
			(stroke
				(width 0.1524)
				(type default)
			)
			(layer "B.SilkS")
		)
		(fp_line
			(start -1.524 -0.762)
			(end -1.524 0.762)
			(stroke
				(width 0.1524)
				(type default)
			)
			(layer "B.SilkS")
		)
		(fp_line
			(start 1.524 0.762)
			(end 1.524 -0.762)
			(stroke
				(width 0.1524)
				(type default)
			)
			(layer "B.SilkS")
		)
		(fp_line
			(start -1.524 0.762)
			(end 1.524 0.762)
			(stroke
				(width 0.1524)
				(type default)
			)
			(layer "B.SilkS")
		)
		(fp_line
			(start 1.1049 -0.724916)
			(end 1.1049 0.724916)
			(stroke
				(width 0.1)
				(type default)
			)
			(layer "B.Fab")
		)
		(fp_line
			(start -1.1049 -0.724916)
			(end 1.1049 -0.724916)
			(stroke
				(width 0.1)
				(type default)
			)
			(layer "B.Fab")
		)
		(fp_line
			(start 1.1049 0.724916)
			(end -1.1049 0.724916)
			(stroke
				(width 0.1)
				(type default)
			)
			(layer "B.Fab")
		)
		(fp_line
			(start -1.1049 0.724916)
			(end -1.1049 -0.724916)
			(stroke
				(width 0.1)
				(type default)
			)
			(layer "B.Fab")
		)
		(pad "1" smd rect
			(at 0.889 0 90)
			(size 1.016 1.27)
			(layers "B.Cu" "B.Mask" "B.Paste")
			(net "P12V_AUX")
		)
		(pad "2" smd rect
			(at -0.889 0 90)
			(size 1.016 1.27)
			(layers "B.Cu" "B.Mask" "B.Paste")
			(net "GND")
		)
	)
	(footprint ""
		(layer "B.Cu")
		(at 51.2445 -88.7095 180)
		(property "Reference" "R703"
			(at 0 0 0)
			(layer "B.SilkS")
			(hide yes)
			(effects
				(font
					(size 1.27 1.27)
				)
				(justify mirror)
			)
		)
		(property "Value" ""
			(at 0 0 0)
			(layer "B.Fab")
			(effects
				(font
					(size 1.27 1.27)
				)
				(justify mirror)
			)
		)
		(duplicate_pad_numbers_are_jumpers no)
		(fp_line
			(start 0.7874 0.4064)
			(end 0.7874 -0.4064)
			(stroke
				(width 0.1524)
				(type default)
			)
			(layer "B.SilkS")
		)
		(fp_line
			(start 0.7874 -0.4064)
			(end -0.7874 -0.4064)
			(stroke
				(width 0.1524)
				(type default)
			)
			(layer "B.SilkS")
		)
		(fp_line
			(start -0.7874 0.4064)
			(end 0.7874 0.4064)
			(stroke
				(width 0.1524)
				(type default)
			)
			(layer "B.SilkS")
		)
		(fp_line
			(start -0.7874 -0.4064)
			(end -0.7874 0.4064)
			(stroke
				(width 0.1524)
				(type default)
			)
			(layer "B.SilkS")
		)
		(fp_line
			(start 0.67945 0.3048)
			(end 0.67945 -0.305054)
			(stroke
				(width 0.1)
				(type default)
			)
			(layer "B.Fab")
		)
		(fp_line
			(start 0.67945 -0.305054)
			(end 0.12065 -0.305054)
			(stroke
				(width 0.1)
				(type default)
			)
			(layer "B.Fab")
		)
		(fp_line
			(start 0.12065 0.3048)
			(end 0.67945 0.3048)
			(stroke
				(width 0.1)
				(type default)
			)
			(layer "B.Fab")
		)
		(fp_line
			(start 0.12065 0.2794)
			(end 0.12065 0.3048)
			(stroke
				(width 0.1)
				(type default)
			)
			(layer "B.Fab")
		)
		(fp_line
			(start 0.12065 -0.2794)
			(end -0.12065 -0.2794)
			(stroke
				(width 0.1)
				(type default)
			)
			(layer "B.Fab")
		)
		(fp_line
			(start 0.12065 -0.305054)
			(end 0.12065 -0.2794)
			(stroke
				(width 0.1)
				(type default)
			)
			(layer "B.Fab")
		)
		(fp_line
			(start -0.120396 0.3048)
			(end -0.120396 0.2794)
			(stroke
				(width 0.1)
				(type default)
			)
			(layer "B.Fab")
		)
		(fp_line
			(start -0.120396 0.2794)
			(end 0.12065 0.2794)
			(stroke
				(width 0.1)
				(type default)
			)
			(layer "B.Fab")
		)
		(fp_line
			(start -0.12065 -0.2794)
			(end -0.12065 -0.3048)
			(stroke
				(width 0.1)
				(type default)
			)
			(layer "B.Fab")
		)
		(fp_line
			(start -0.12065 -0.3048)
			(end -0.67945 -0.3048)
			(stroke
				(width 0.1)
				(type default)
			)
			(layer "B.Fab")
		)
		(fp_line
			(start -0.67945 0.3048)
			(end -0.120396 0.3048)
			(stroke
				(width 0.1)
				(type default)
			)
			(layer "B.Fab")
		)
		(fp_line
			(start -0.67945 -0.3048)
			(end -0.67945 0.3048)
			(stroke
				(width 0.1)
				(type default)
			)
			(layer "B.Fab")
		)
		(pad "1" smd circle
			(at 0.40005 0)
			(size 0 0)
			(layers "B.Cu" "B.Mask" "B.Paste")
			(net "PWRGD_DSW_PWROK")
		)
		(pad "2" smd circle
			(at -0.40005 0)
			(size 0 0)
			(layers "B.Cu" "B.Mask" "B.Paste")
			(net "PWRGD_DSW_PWROK_R3")
		)
	)
	(footprint ""
		(layer "B.Cu")
		(at 47.51578 -66.27114 90)
		(property "Reference" "R843"
			(at 0 0 90)
			(layer "B.SilkS")
			(hide yes)
			(effects
				(font
					(size 1.27 1.27)
				)
				(justify mirror)
			)
		)
		(property "Value" ""
			(at 0 0 90)
			(layer "B.Fab")
			(effects
				(font
					(size 1.27 1.27)
				)
				(justify mirror)
			)
		)
		(duplicate_pad_numbers_are_jumpers no)
		(fp_line
			(start 0.7874 -0.4064)
			(end -0.7874 -0.4064)
			(stroke
				(width 0.1524)
				(type default)
			)
			(layer "B.SilkS")
		)
		(fp_line
			(start -0.7874 -0.4064)
			(end -0.7874 0.4064)
			(stroke
				(width 0.1524)
				(type default)
			)
			(layer "B.SilkS")
		)
		(fp_line
			(start 0.7874 0.4064)
			(end 0.7874 -0.4064)
			(stroke
				(width 0.1524)
				(type default)
			)
			(layer "B.SilkS")
		)
		(fp_line
			(start -0.7874 0.4064)
			(end 0.7874 0.4064)
			(stroke
				(width 0.1524)
				(type default)
			)
			(layer "B.SilkS")
		)
		(fp_line
			(start 0.67945 -0.305054)
			(end 0.12065 -0.305054)
			(stroke
				(width 0.1)
				(type default)
			)
			(layer "B.Fab")
		)
		(fp_line
			(start 0.12065 -0.305054)
			(end 0.12065 -0.2794)
			(stroke
				(width 0.1)
				(type default)
			)
			(layer "B.Fab")
		)
		(fp_line
			(start -0.12065 -0.3048)
			(end -0.67945 -0.3048)
			(stroke
				(width 0.1)
				(type default)
			)
			(layer "B.Fab")
		)
		(fp_line
			(start -0.67945 -0.3048)
			(end -0.67945 0.3048)
			(stroke
				(width 0.1)
				(type default)
			)
			(layer "B.Fab")
		)
		(fp_line
			(start 0.12065 -0.2794)
			(end -0.12065 -0.2794)
			(stroke
				(width 0.1)
				(type default)
			)
			(layer "B.Fab")
		)
		(fp_line
			(start -0.12065 -0.2794)
			(end -0.12065 -0.3048)
			(stroke
				(width 0.1)
				(type default)
			)
			(layer "B.Fab")
		)
		(fp_line
			(start 0.12065 0.2794)
			(end 0.12065 0.3048)
			(stroke
				(width 0.1)
				(type default)
			)
			(layer "B.Fab")
		)
		(fp_line
			(start -0.120396 0.2794)
			(end 0.12065 0.2794)
			(stroke
				(width 0.1)
				(type default)
			)
			(layer "B.Fab")
		)
		(fp_line
			(start 0.67945 0.3048)
			(end 0.67945 -0.305054)
			(stroke
				(width 0.1)
				(type default)
			)
			(layer "B.Fab")
		)
		(fp_line
			(start 0.12065 0.3048)
			(end 0.67945 0.3048)
			(stroke
				(width 0.1)
				(type default)
			)
			(layer "B.Fab")
		)
		(fp_line
			(start -0.120396 0.3048)
			(end -0.120396 0.2794)
			(stroke
				(width 0.1)
				(type default)
			)
			(layer "B.Fab")
		)
		(fp_line
			(start -0.67945 0.3048)
			(end -0.120396 0.3048)
			(stroke
				(width 0.1)
				(type default)
			)
			(layer "B.Fab")
		)
		(pad "1" smd circle
			(at 0.40005 0 270)
			(size 0 0)
			(layers "B.Cu" "B.Mask" "B.Paste")
			(net "P3V3_AUX")
		)
		(pad "2" smd circle
			(at -0.40005 0 270)
			(size 0 0)
			(layers "B.Cu" "B.Mask" "B.Paste")
			(net "SMB_BMC_ALERT10_N")
		)
	)
	(footprint ""
		(layer "B.Cu")
		(at 38.3286 -4.1148 -90)
		(property "Reference" "U33"
			(at 0.924052 1.4986 0)
			(unlocked yes)
			(layer "B.SilkS")
			(effects
				(font
					(size 0.7874 0.5842)
					(thickness 0.1524)
				)
				(justify left mirror)
			)
		)
		(property "Value" ""
			(at 0 0 90)
			(layer "B.Fab")
			(effects
				(font
					(size 1.27 1.27)
				)
				(justify mirror)
			)
		)
		(duplicate_pad_numbers_are_jumpers no)
		(fp_line
			(start -1.3462 1.1938)
			(end -1.3462 -1.1938)
			(stroke
				(width 0.1524)
				(type default)
			)
			(layer "B.SilkS")
		)
		(fp_line
			(start 1.3462 1.1938)
			(end -1.3462 1.1938)
			(stroke
				(width 0.1524)
				(type default)
			)
			(layer "B.SilkS")
		)
		(fp_line
			(start -1.3462 -1.1938)
			(end 1.3462 -1.1938)
			(stroke
				(width 0.1524)
				(type default)
			)
			(layer "B.SilkS")
		)
		(fp_line
			(start 1.3462 -1.1938)
			(end 1.3462 1.1684)
			(stroke
				(width 0.1524)
				(type default)
			)
			(layer "B.SilkS")
		)
		(fp_poly
			(pts
				(xy 1.447038 -0.760476) (xy 2.052066 -0.457962) (xy 2.052066 -1.06299)
			)
			(stroke
				(width 0)
				(type default)
			)
			(fill yes)
			(layer "B.SilkS")
		)
		(fp_line
			(start -0.674878 1.124966)
			(end -0.674878 -1.124966)
			(stroke
				(width 0.1)
				(type default)
			)
			(layer "B.Fab")
		)
		(fp_line
			(start 0.674878 1.124966)
			(end -0.674878 1.124966)
			(stroke
				(width 0.1)
				(type default)
			)
			(layer "B.Fab")
		)
		(fp_line
			(start -0.674878 -1.124966)
			(end 0.674878 -1.124966)
			(stroke
				(width 0.1)
				(type default)
			)
			(layer "B.Fab")
		)
		(fp_line
			(start 0.674878 -1.124966)
			(end 0.674878 1.124966)
			(stroke
				(width 0.1)
				(type default)
			)
			(layer "B.Fab")
		)
		(fp_poly
			(pts
				(xy 1.447038 -0.760476) (xy 2.052066 -0.457962) (xy 2.052066 -1.06299)
			)
			(stroke
				(width 0)
				(type default)
			)
			(fill yes)
			(layer "B.Fab")
		)
		(pad "1" smd rect
			(at 0.899922 -0.750062 90)
			(size 0.6096 0.6096)
			(layers "B.Cu" "B.Mask" "B.Paste")
			(net "BMC_DDC_BUF_EN")
		)
		(pad "2" smd rect
			(at 0.899922 0)
			(size 0.4064 0.6096)
			(layers "B.Cu" "B.Mask" "B.Paste")
			(net "V_VGAHS")
		)
		(pad "3" smd rect
			(at 0.899922 0.750062 90)
			(size 0.6096 0.6096)
			(layers "B.Cu" "B.Mask" "B.Paste")
			(net "GND")
		)
		(pad "4" smd rect
			(at -0.899922 0.750062 90)
			(size 0.6096 0.6096)
			(layers "B.Cu" "B.Mask" "B.Paste")
			(net "V_VGAHS_BUF_R")
		)
		(pad "5" smd rect
			(at -0.899922 -0.750062 90)
			(size 0.6096 0.6096)
			(layers "B.Cu" "B.Mask" "B.Paste")
			(net "BMC_DDC_BUF_PWR")
		)
	)
	(footprint ""
		(layer "B.Cu")
		(at 38.47084 -35.828224)
		(property "Reference" "R208"
			(at 0 0 0)
			(layer "B.SilkS")
			(hide yes)
			(effects
				(font
					(size 1.27 1.27)
				)
				(justify mirror)
			)
		)
		(property "Value" ""
			(at 0 0 0)
			(layer "B.Fab")
			(effects
				(font
					(size 1.27 1.27)
				)
				(justify mirror)
			)
		)
		(duplicate_pad_numbers_are_jumpers no)
		(fp_line
			(start -0.7874 -0.4064)
			(end -0.7874 0.4064)
			(stroke
				(width 0.1524)
				(type default)
			)
			(layer "B.SilkS")
		)
		(fp_line
			(start -0.7874 0.4064)
			(end 0.7874 0.4064)
			(stroke
				(width 0.1524)
				(type default)
			)
			(layer "B.SilkS")
		)
		(fp_line
			(start 0.7874 -0.4064)
			(end -0.7874 -0.4064)
			(stroke
				(width 0.1524)
				(type default)
			)
			(layer "B.SilkS")
		)
		(fp_line
			(start 0.7874 0.4064)
			(end 0.7874 -0.4064)
			(stroke
				(width 0.1524)
				(type default)
			)
			(layer "B.SilkS")
		)
		(fp_line
			(start -0.67945 -0.3048)
			(end -0.67945 0.3048)
			(stroke
				(width 0.1)
				(type default)
			)
			(layer "B.Fab")
		)
		(fp_line
			(start -0.67945 0.3048)
			(end -0.120396 0.3048)
			(stroke
				(width 0.1)
				(type default)
			)
			(layer "B.Fab")
		)
		(fp_line
			(start -0.12065 -0.3048)
			(end -0.67945 -0.3048)
			(stroke
				(width 0.1)
				(type default)
			)
			(layer "B.Fab")
		)
		(fp_line
			(start -0.12065 -0.2794)
			(end -0.12065 -0.3048)
			(stroke
				(width 0.1)
				(type default)
			)
			(layer "B.Fab")
		)
		(fp_line
			(start -0.120396 0.2794)
			(end 0.12065 0.2794)
			(stroke
				(width 0.1)
				(type default)
			)
			(layer "B.Fab")
		)
		(fp_line
			(start -0.120396 0.3048)
			(end -0.120396 0.2794)
			(stroke
				(width 0.1)
				(type default)
			)
			(layer "B.Fab")
		)
		(fp_line
			(start 0.12065 -0.305054)
			(end 0.12065 -0.2794)
			(stroke
				(width 0.1)
				(type default)
			)
			(layer "B.Fab")
		)
		(fp_line
			(start 0.12065 -0.2794)
			(end -0.12065 -0.2794)
			(stroke
				(width 0.1)
				(type default)
			)
			(layer "B.Fab")
		)
		(fp_line
			(start 0.12065 0.2794)
			(end 0.12065 0.3048)
			(stroke
				(width 0.1)
				(type default)
			)
			(layer "B.Fab")
		)
		(fp_line
			(start 0.12065 0.3048)
			(end 0.67945 0.3048)
			(stroke
				(width 0.1)
				(type default)
			)
			(layer "B.Fab")
		)
		(fp_line
			(start 0.67945 -0.305054)
			(end 0.12065 -0.305054)
			(stroke
				(width 0.1)
				(type default)
			)
			(layer "B.Fab")
		)
		(fp_line
			(start 0.67945 0.3048)
			(end 0.67945 -0.305054)
			(stroke
				(width 0.1)
				(type default)
			)
			(layer "B.Fab")
		)
		(pad "1" smd circle
			(at 0.40005 0 180)
			(size 0 0)
			(layers "B.Cu" "B.Mask" "B.Paste")
			(net "P1V8_AUX")
		)
		(pad "2" smd circle
			(at -0.40005 0 180)
			(size 0 0)
			(layers "B.Cu" "B.Mask" "B.Paste")
			(net "P3V3_P1V8_SD1VDD")
		)
	)
	(footprint ""
		(layer "B.Cu")
		(at 41.918128 -60.573666)
		(property "Reference" "R225"
			(at 0 0 0)
			(layer "B.SilkS")
			(hide yes)
			(effects
				(font
					(size 1.27 1.27)
				)
				(justify mirror)
			)
		)
		(property "Value" ""
			(at 0 0 0)
			(layer "B.Fab")
			(effects
				(font
					(size 1.27 1.27)
				)
				(justify mirror)
			)
		)
		(duplicate_pad_numbers_are_jumpers no)
		(fp_line
			(start -0.7874 -0.4064)
			(end -0.7874 0.4064)
			(stroke
				(width 0.1524)
				(type default)
			)
			(layer "B.SilkS")
		)
		(fp_line
			(start -0.7874 0.4064)
			(end 0.7874 0.4064)
			(stroke
				(width 0.1524)
				(type default)
			)
			(layer "B.SilkS")
		)
		(fp_line
			(start 0.7874 -0.4064)
			(end -0.7874 -0.4064)
			(stroke
				(width 0.1524)
				(type default)
			)
			(layer "B.SilkS")
		)
		(fp_line
			(start 0.7874 0.4064)
			(end 0.7874 -0.4064)
			(stroke
				(width 0.1524)
				(type default)
			)
			(layer "B.SilkS")
		)
		(fp_line
			(start -0.67945 -0.3048)
			(end -0.67945 0.3048)
			(stroke
				(width 0.1)
				(type default)
			)
			(layer "B.Fab")
		)
		(fp_line
			(start -0.67945 0.3048)
			(end -0.120396 0.3048)
			(stroke
				(width 0.1)
				(type default)
			)
			(layer "B.Fab")
		)
		(fp_line
			(start -0.12065 -0.3048)
			(end -0.67945 -0.3048)
			(stroke
				(width 0.1)
				(type default)
			)
			(layer "B.Fab")
		)
		(fp_line
			(start -0.12065 -0.2794)
			(end -0.12065 -0.3048)
			(stroke
				(width 0.1)
				(type default)
			)
			(layer "B.Fab")
		)
		(fp_line
			(start -0.120396 0.2794)
			(end 0.12065 0.2794)
			(stroke
				(width 0.1)
				(type default)
			)
			(layer "B.Fab")
		)
		(fp_line
			(start -0.120396 0.3048)
			(end -0.120396 0.2794)
			(stroke
				(width 0.1)
				(type default)
			)
			(layer "B.Fab")
		)
		(fp_line
			(start 0.12065 -0.305054)
			(end 0.12065 -0.2794)
			(stroke
				(width 0.1)
				(type default)
			)
			(layer "B.Fab")
		)
		(fp_line
			(start 0.12065 -0.2794)
			(end -0.12065 -0.2794)
			(stroke
				(width 0.1)
				(type default)
			)
			(layer "B.Fab")
		)
		(fp_line
			(start 0.12065 0.2794)
			(end 0.12065 0.3048)
			(stroke
				(width 0.1)
				(type default)
			)
			(layer "B.Fab")
		)
		(fp_line
			(start 0.12065 0.3048)
			(end 0.67945 0.3048)
			(stroke
				(width 0.1)
				(type default)
			)
			(layer "B.Fab")
		)
		(fp_line
			(start 0.67945 -0.305054)
			(end 0.12065 -0.305054)
			(stroke
				(width 0.1)
				(type default)
			)
			(layer "B.Fab")
		)
		(fp_line
			(start 0.67945 0.3048)
			(end 0.67945 -0.305054)
			(stroke
				(width 0.1)
				(type default)
			)
			(layer "B.Fab")
		)
		(pad "1" smd circle
			(at 0.40005 0 180)
			(size 0 0)
			(layers "B.Cu" "B.Mask" "B.Paste")
			(net "FM_PWR_BTN")
		)
		(pad "2" smd circle
			(at -0.40005 0 180)
			(size 0 0)
			(layers "B.Cu" "B.Mask" "B.Paste")
			(net "PWR_BTN_BMC_N")
		)
	)
	(footprint ""
		(layer "B.Cu")
		(at 32.96793 -38.8747 90)
		(property "Reference" "R27"
			(at 0 0 90)
			(layer "B.SilkS")
			(hide yes)
			(effects
				(font
					(size 1.27 1.27)
				)
				(justify mirror)
			)
		)
		(property "Value" ""
			(at 0 0 90)
			(layer "B.Fab")
			(effects
				(font
					(size 1.27 1.27)
				)
				(justify mirror)
			)
		)
		(duplicate_pad_numbers_are_jumpers no)
		(fp_line
			(start 1.2954 -0.5842)
			(end -1.2954 -0.5842)
			(stroke
				(width 0.1524)
				(type default)
			)
			(layer "B.SilkS")
		)
		(fp_line
			(start -1.2954 -0.5842)
			(end -1.2954 0.5842)
			(stroke
				(width 0.1524)
				(type default)
			)
			(layer "B.SilkS")
		)
		(fp_line
			(start 1.2954 0.5842)
			(end 1.2954 -0.5842)
			(stroke
				(width 0.1524)
				(type default)
			)
			(layer "B.SilkS")
		)
		(fp_line
			(start -1.2954 0.5842)
			(end 1.2954 0.5842)
			(stroke
				(width 0.1524)
				(type default)
			)
			(layer "B.SilkS")
		)
		(fp_line
			(start 0.8636 -0.4572)
			(end -0.8636 -0.4572)
			(stroke
				(width 0.1)
				(type default)
			)
			(layer "B.Fab")
		)
		(fp_line
			(start -0.8636 -0.4572)
			(end -0.8636 -0.406654)
			(stroke
				(width 0.1)
				(type default)
			)
			(layer "B.Fab")
		)
		(fp_line
			(start 1.1938 -0.406654)
			(end 0.8636 -0.406654)
			(stroke
				(width 0.1)
				(type default)
			)
			(layer "B.Fab")
		)
		(fp_line
			(start 0.8636 -0.406654)
			(end 0.8636 -0.4572)
			(stroke
				(width 0.1)
				(type default)
			)
			(layer "B.Fab")
		)
		(fp_line
			(start -0.8636 -0.406654)
			(end -1.1938 -0.406654)
			(stroke
				(width 0.1)
				(type default)
			)
			(layer "B.Fab")
		)
		(fp_line
			(start -1.1938 -0.406654)
			(end -1.1938 0.4064)
			(stroke
				(width 0.1)
				(type default)
			)
			(layer "B.Fab")
		)
		(fp_line
			(start 1.1938 0.4064)
			(end 1.1938 -0.406654)
			(stroke
				(width 0.1)
				(type default)
			)
			(layer "B.Fab")
		)
		(fp_line
			(start 0.8636 0.4064)
			(end 1.1938 0.4064)
			(stroke
				(width 0.1)
				(type default)
			)
			(layer "B.Fab")
		)
		(fp_line
			(start -0.8636 0.4064)
			(end -0.8636 0.4572)
			(stroke
				(width 0.1)
				(type default)
			)
			(layer "B.Fab")
		)
		(fp_line
			(start -1.1938 0.4064)
			(end -0.8636 0.4064)
			(stroke
				(width 0.1)
				(type default)
			)
			(layer "B.Fab")
		)
		(fp_line
			(start 0.8636 0.4318)
			(end 0.8636 0.4064)
			(stroke
				(width 0.1)
				(type default)
			)
			(layer "B.Fab")
		)
		(fp_line
			(start 0.8636 0.4572)
			(end 0.8636 0.4318)
			(stroke
				(width 0.1)
				(type default)
			)
			(layer "B.Fab")
		)
		(fp_line
			(start -0.8636 0.4572)
			(end 0.8636 0.4572)
			(stroke
				(width 0.1)
				(type default)
			)
			(layer "B.Fab")
		)
		(pad "1" smd rect
			(at 0.7366 0)
			(size 0.7112 0.8128)
			(layers "B.Cu" "B.Mask" "B.Paste")
			(net "P5V_AUX")
		)
		(pad "2" smd rect
			(at -0.7366 0)
			(size 0.7112 0.8128)
			(layers "B.Cu" "B.Mask" "B.Paste")
			(net "CRT_VCC5")
		)
	)
	(footprint ""
		(layer "B.Cu")
		(at 112.014 54.61 90)
		(property "Reference" "X14"
			(at 1.73863 3.2385 0)
			(unlocked yes)
			(layer "B.SilkS")
			(effects
				(font
					(size 0.7874 0.5842)
					(thickness 0.1524)
				)
				(justify left mirror)
			)
		)
		(property "Value" ""
			(at 0 0 90)
			(layer "B.Fab")
			(effects
				(font
					(size 1.27 1.27)
				)
				(justify mirror)
			)
		)
		(property "Device Type" "TP_TDR_4P_FTS_TH-TP_TDR_4P_DIPA"
			(at -1.30175 1.27 0)
			(unlocked yes)
			(layer "B.Fab")
			(hide yes)
			(effects
				(font
					(size 0.635 0.4064)
					(thickness 0.1524)
				)
				(justify mirror)
			)
		)
		(property "User Part Number" "N_A"
			(at -1.30175 1.27 0)
			(unlocked yes)
			(layer "Cmts.User")
			(hide yes)
			(effects
				(font
					(size 0.635 0.4064)
					(thickness 0.1524)
				)
				(justify mirror)
			)
		)
		(duplicate_pad_numbers_are_jumpers no)
		(fp_line
			(start 0 -1.27)
			(end 0 -0.635)
			(stroke
				(width 0.1524)
				(type default)
			)
			(layer "B.SilkS")
		)
		(fp_line
			(start -2.54 -1.27)
			(end 0 -1.27)
			(stroke
				(width 0.1524)
				(type default)
			)
			(layer "B.SilkS")
		)
		(fp_line
			(start -2.54 -1.1303)
			(end -2.54 -1.27)
			(stroke
				(width 0.1524)
				(type default)
			)
			(layer "B.SilkS")
		)
		(fp_line
			(start 0 0.635)
			(end 0 1.905)
			(stroke
				(width 0.1524)
				(type default)
			)
			(layer "B.SilkS")
		)
		(fp_line
			(start -2.54 1.4097)
			(end -2.54 1.1303)
			(stroke
				(width 0.1524)
				(type default)
			)
			(layer "B.SilkS")
		)
		(fp_line
			(start 0 3.175)
			(end 0 3.81)
			(stroke
				(width 0.1524)
				(type default)
			)
			(layer "B.SilkS")
		)
		(fp_line
			(start 0 3.81)
			(end -2.54 3.81)
			(stroke
				(width 0.1524)
				(type default)
			)
			(layer "B.SilkS")
		)
		(fp_line
			(start -2.54 3.81)
			(end -2.54 3.6703)
			(stroke
				(width 0.1524)
				(type default)
			)
			(layer "B.SilkS")
		)
		(fp_poly
			(pts
				(xy 0.761746 0) (xy 2.285746 -0.762) (xy 2.285746 0.762)
			)
			(stroke
				(width 0)
				(type default)
			)
			(fill yes)
			(layer "B.SilkS")
		)
		(fp_line
			(start 0 -1.27)
			(end 0 3.81)
			(stroke
				(width 0.1)
				(type default)
			)
			(layer "B.Fab")
		)
		(fp_line
			(start -2.54 -1.27)
			(end 0 -1.27)
			(stroke
				(width 0.1)
				(type default)
			)
			(layer "B.Fab")
		)
		(fp_line
			(start 0 3.81)
			(end -2.54 3.81)
			(stroke
				(width 0.1)
				(type default)
			)
			(layer "B.Fab")
		)
		(fp_line
			(start -2.54 3.81)
			(end -2.54 -1.27)
			(stroke
				(width 0.1)
				(type default)
			)
			(layer "B.Fab")
		)
		(fp_poly
			(pts
				(xy 0.761746 0) (xy 2.285746 -0.762) (xy 2.285746 0.762)
			)
			(stroke
				(width 0)
				(type default)
			)
			(fill yes)
			(layer "B.Fab")
		)
		(pad "1" thru_hole circle
			(at 0 0 270)
			(size 1.0033 1.0033)
			(drill 0.249936)
			(layers "*.Cu" "*.Mask")
			(remove_unused_layers no)
			(net "TDR_DIFF_100_IN1_DP")
			(clearance 0.10795)
			(padstack
				(mode front_inner_back)
				(layer "Inner"
					(shape circle)
					(size 0.8001 0.8001)
					(clearance 0.1524)
				)
				(layer "B.Cu"
					(shape circle)
					(size 1.0033 1.0033)
					(thermal_gap 0.10795)
					(clearance 0.10795)
				)
			)
		)
		(pad "2" thru_hole circle
			(at -2.54 0 270)
			(size 1.9939 1.9939)
			(drill 0.249936)
			(layers "*.Cu" "*.Mask")
			(remove_unused_layers no)
			(net "GND_P1")
			(clearance 0.10795)
			(padstack
				(mode front_inner_back)
				(layer "Inner"
					(shape circle)
					(size 0.8001 0.8001)
					(clearance 0.1524)
				)
				(layer "B.Cu"
					(shape circle)
					(size 1.9939 1.9939)
					(thermal_gap 0.10795)
					(clearance 0.10795)
				)
			)
		)
		(pad "3" thru_hole circle
			(at -2.54 2.54 270)
			(size 1.9939 1.9939)
			(drill 0.249936)
			(layers "*.Cu" "*.Mask")
			(remove_unused_layers no)
			(net "GND_P1")
			(clearance 0.10795)
			(padstack
				(mode front_inner_back)
				(layer "Inner"
					(shape circle)
					(size 0.8001 0.8001)
					(clearance 0.1524)
				)
				(layer "B.Cu"
					(shape circle)
					(size 1.9939 1.9939)
					(thermal_gap 0.10795)
					(clearance 0.10795)
				)
			)
		)
		(pad "4" thru_hole circle
			(at 0 2.54 270)
			(size 1.0033 1.0033)
			(drill 0.249936)
			(layers "*.Cu" "*.Mask")
			(remove_unused_layers no)
			(net "TDR_DIFF_100_IN1_DN")
			(clearance 0.10795)
			(padstack
				(mode front_inner_back)
				(layer "Inner"
					(shape circle)
					(size 0.8001 0.8001)
					(clearance 0.1524)
				)
				(layer "B.Cu"
					(shape circle)
					(size 1.0033 1.0033)
					(thermal_gap 0.10795)
					(clearance 0.10795)
				)
			)
		)
	)
	(footprint ""
		(layer "B.Cu")
		(at 17.2974 -83.693 90)
		(property "Reference" "R397"
			(at 0 0 90)
			(layer "B.SilkS")
			(hide yes)
			(effects
				(font
					(size 1.27 1.27)
				)
				(justify mirror)
			)
		)
		(property "Value" ""
			(at 0 0 90)
			(layer "B.Fab")
			(effects
				(font
					(size 1.27 1.27)
				)
				(justify mirror)
			)
		)
		(duplicate_pad_numbers_are_jumpers no)
		(fp_line
			(start 0.7874 -0.4064)
			(end -0.7874 -0.4064)
			(stroke
				(width 0.1524)
				(type default)
			)
			(layer "B.SilkS")
		)
		(fp_line
			(start -0.7874 -0.4064)
			(end -0.7874 0.4064)
			(stroke
				(width 0.1524)
				(type default)
			)
			(layer "B.SilkS")
		)
		(fp_line
			(start 0.7874 0.4064)
			(end 0.7874 -0.4064)
			(stroke
				(width 0.1524)
				(type default)
			)
			(layer "B.SilkS")
		)
		(fp_line
			(start -0.7874 0.4064)
			(end 0.7874 0.4064)
			(stroke
				(width 0.1524)
				(type default)
			)
			(layer "B.SilkS")
		)
		(fp_line
			(start 0.67945 -0.305054)
			(end 0.12065 -0.305054)
			(stroke
				(width 0.1)
				(type default)
			)
			(layer "B.Fab")
		)
		(fp_line
			(start 0.12065 -0.305054)
			(end 0.12065 -0.2794)
			(stroke
				(width 0.1)
				(type default)
			)
			(layer "B.Fab")
		)
		(fp_line
			(start -0.12065 -0.3048)
			(end -0.67945 -0.3048)
			(stroke
				(width 0.1)
				(type default)
			)
			(layer "B.Fab")
		)
		(fp_line
			(start -0.67945 -0.3048)
			(end -0.67945 0.3048)
			(stroke
				(width 0.1)
				(type default)
			)
			(layer "B.Fab")
		)
		(fp_line
			(start 0.12065 -0.2794)
			(end -0.12065 -0.2794)
			(stroke
				(width 0.1)
				(type default)
			)
			(layer "B.Fab")
		)
		(fp_line
			(start -0.12065 -0.2794)
			(end -0.12065 -0.3048)
			(stroke
				(width 0.1)
				(type default)
			)
			(layer "B.Fab")
		)
		(fp_line
			(start 0.12065 0.2794)
			(end 0.12065 0.3048)
			(stroke
				(width 0.1)
				(type default)
			)
			(layer "B.Fab")
		)
		(fp_line
			(start -0.120396 0.2794)
			(end 0.12065 0.2794)
			(stroke
				(width 0.1)
				(type default)
			)
			(layer "B.Fab")
		)
		(fp_line
			(start 0.67945 0.3048)
			(end 0.67945 -0.305054)
			(stroke
				(width 0.1)
				(type default)
			)
			(layer "B.Fab")
		)
		(fp_line
			(start 0.12065 0.3048)
			(end 0.67945 0.3048)
			(stroke
				(width 0.1)
				(type default)
			)
			(layer "B.Fab")
		)
		(fp_line
			(start -0.120396 0.3048)
			(end -0.120396 0.2794)
			(stroke
				(width 0.1)
				(type default)
			)
			(layer "B.Fab")
		)
		(fp_line
			(start -0.67945 0.3048)
			(end -0.120396 0.3048)
			(stroke
				(width 0.1)
				(type default)
			)
			(layer "B.Fab")
		)
		(pad "1" smd circle
			(at 0.40005 0 270)
			(size 0 0)
			(layers "B.Cu" "B.Mask" "B.Paste")
			(net "JTAG_SCM_PLD_R_JTAGEN")
		)
		(pad "2" smd circle
			(at -0.40005 0 270)
			(size 0 0)
			(layers "B.Cu" "B.Mask" "B.Paste")
			(net "JTAG_SCM_PLD_JTAGEN")
		)
	)
	(footprint ""
		(layer "B.Cu")
		(at 57.63768 -89.72042)
		(property "Reference" "U40"
			(at 0.97282 4.66979 0)
			(unlocked yes)
			(layer "B.SilkS")
			(effects
				(font
					(size 0.7874 0.5842)
					(thickness 0.1524)
				)
				(justify left mirror)
			)
		)
		(property "Value" ""
			(at 0 0 0)
			(layer "B.Fab")
			(effects
				(font
					(size 1.27 1.27)
				)
				(justify mirror)
			)
		)
		(duplicate_pad_numbers_are_jumpers no)
		(fp_line
			(start -2.0066 -3.9624)
			(end -2.0066 3.9624)
			(stroke
				(width 0.1524)
				(type default)
			)
			(layer "B.SilkS")
		)
		(fp_line
			(start -2.0066 3.9624)
			(end 2.0066 3.9624)
			(stroke
				(width 0.1524)
				(type default)
			)
			(layer "B.SilkS")
		)
		(fp_line
			(start -0.5842 -3.9624)
			(end -2.0066 -3.9624)
			(stroke
				(width 0.1524)
				(type default)
			)
			(layer "B.SilkS")
		)
		(fp_line
			(start 0 -3.3782)
			(end -0.5842 -3.9624)
			(stroke
				(width 0.1524)
				(type default)
			)
			(layer "B.SilkS")
		)
		(fp_line
			(start 0.5842 -3.9624)
			(end 0 -3.3782)
			(stroke
				(width 0.1524)
				(type default)
			)
			(layer "B.SilkS")
		)
		(fp_line
			(start 2.0066 -3.9624)
			(end 0.5842 -3.9624)
			(stroke
				(width 0.1524)
				(type default)
			)
			(layer "B.SilkS")
		)
		(fp_line
			(start 2.0066 3.9624)
			(end 2.0066 -3.9624)
			(stroke
				(width 0.1524)
				(type default)
			)
			(layer "B.SilkS")
		)
		(fp_poly
			(pts
				(xy 3.502914 -3.90906) (xy 3.883914 -4.67106) (xy 3.121914 -4.67106)
			)
			(stroke
				(width 0)
				(type default)
			)
			(fill yes)
			(layer "B.SilkS")
		)
		(fp_line
			(start -3.7211 -3.80365)
			(end -2.2479 -3.80365)
			(stroke
				(width 0.1)
				(type default)
			)
			(layer "B.Fab")
		)
		(fp_line
			(start -3.7211 3.80365)
			(end -3.7211 -3.80365)
			(stroke
				(width 0.1)
				(type default)
			)
			(layer "B.Fab")
		)
		(fp_line
			(start -2.2479 -3.974846)
			(end 2.2479 -3.974846)
			(stroke
				(width 0.1)
				(type default)
			)
			(layer "B.Fab")
		)
		(fp_line
			(start -2.2479 -3.80365)
			(end -2.2479 -3.974846)
			(stroke
				(width 0.1)
				(type default)
			)
			(layer "B.Fab")
		)
		(fp_line
			(start -2.2479 3.80365)
			(end -3.7211 3.80365)
			(stroke
				(width 0.1)
				(type default)
			)
			(layer "B.Fab")
		)
		(fp_line
			(start -2.2479 3.9624)
			(end -2.2479 3.80365)
			(stroke
				(width 0.1)
				(type default)
			)
			(layer "B.Fab")
		)
		(fp_line
			(start 2.2479 -3.974846)
			(end 2.2479 -3.80365)
			(stroke
				(width 0.1)
				(type default)
			)
			(layer "B.Fab")
		)
		(fp_line
			(start 2.2479 -3.80365)
			(end 3.724402 -3.80365)
			(stroke
				(width 0.1)
				(type default)
			)
			(layer "B.Fab")
		)
		(fp_line
			(start 2.2479 3.80365)
			(end 2.2479 3.9624)
			(stroke
				(width 0.1)
				(type default)
			)
			(layer "B.Fab")
		)
		(fp_line
			(start 2.2479 3.9624)
			(end -2.2479 3.9624)
			(stroke
				(width 0.1)
				(type default)
			)
			(layer "B.Fab")
		)
		(fp_line
			(start 3.7211 -3.34645)
			(end 3.7211 -3.80365)
			(stroke
				(width 0.1)
				(type default)
			)
			(layer "B.Fab")
		)
		(fp_line
			(start 3.724402 -3.80365)
			(end 3.724402 3.80365)
			(stroke
				(width 0.1)
				(type default)
			)
			(layer "B.Fab")
		)
		(fp_line
			(start 3.724402 3.80365)
			(end 2.2479 3.80365)
			(stroke
				(width 0.1)
				(type default)
			)
			(layer "B.Fab")
		)
		(fp_poly
			(pts
				(xy 3.8862 -3.570986) (xy 4.6482 -3.189986) (xy 4.6482 -3.951986)
			)
			(stroke
				(width 0)
				(type default)
			)
			(fill yes)
			(layer "B.Fab")
		)
		(pad "1" smd rect
			(at 2.921 -3.57505 270)
			(size 0.3556 1.4986)
			(layers "B.Cu" "B.Mask" "B.Paste")
			(net "LED_POSTCODE_INT")
		)
		(pad "2" smd rect
			(at 2.921 -2.925064 270)
			(size 0.3556 1.4986)
			(layers "B.Cu" "B.Mask" "B.Paste")
			(net "LED_POSTCODE_A1")
		)
		(pad "3" smd rect
			(at 2.921 -2.275078 270)
			(size 0.3556 1.4986)
			(layers "B.Cu" "B.Mask" "B.Paste")
			(net "LED_POSTCODE_A2")
		)
		(pad "4" smd rect
			(at 2.921 -1.625092 270)
			(size 0.3556 1.4986)
			(layers "B.Cu" "B.Mask" "B.Paste")
			(net "LED_POSTCODE_0_R1")
		)
		(pad "5" smd rect
			(at 2.921 -0.975106 270)
			(size 0.3556 1.4986)
			(layers "B.Cu" "B.Mask" "B.Paste")
			(net "LED_POSTCODE_1_R1")
		)
		(pad "6" smd rect
			(at 2.921 -0.32512 270)
			(size 0.3556 1.4986)
			(layers "B.Cu" "B.Mask" "B.Paste")
			(net "LED_POSTCODE_2_R1")
		)
		(pad "7" smd rect
			(at 2.921 0.32512 270)
			(size 0.3556 1.4986)
			(layers "B.Cu" "B.Mask" "B.Paste")
			(net "LED_POSTCODE_3_R1")
		)
		(pad "8" smd rect
			(at 2.921 0.975106 270)
			(size 0.3556 1.4986)
			(layers "B.Cu" "B.Mask" "B.Paste")
			(net "LED_POSTCODE_4_R1")
		)
		(pad "9" smd rect
			(at 2.921 1.625092 270)
			(size 0.3556 1.4986)
			(layers "B.Cu" "B.Mask" "B.Paste")
			(net "LED_POSTCODE_5_R1")
		)
		(pad "10" smd rect
			(at 2.921 2.275078 270)
			(size 0.3556 1.4986)
			(layers "B.Cu" "B.Mask" "B.Paste")
			(net "LED_POSTCODE_6_R1")
		)
		(pad "11" smd rect
			(at 2.921 2.925064 270)
			(size 0.3556 1.4986)
			(layers "B.Cu" "B.Mask" "B.Paste")
			(net "LED_POSTCODE_7_R1")
		)
		(pad "12" smd rect
			(at 2.921 3.57505 270)
			(size 0.3556 1.4986)
			(layers "B.Cu" "B.Mask" "B.Paste")
			(net "GND")
		)
		(pad "13" smd rect
			(at -2.921 3.57505 270)
			(size 0.3556 1.4986)
			(layers "B.Cu" "B.Mask" "B.Paste")
			(net "FM_DEBUG_RST_BTN_N")
		)
		(pad "14" smd rect
			(at -2.921 2.925064 270)
			(size 0.3556 1.4986)
			(layers "B.Cu" "B.Mask" "B.Paste")
			(net "FM_DEBUG_PWR_BTN_N")
		)
		(pad "15" smd rect
			(at -2.921 2.275078 270)
			(size 0.3556 1.4986)
			(layers "B.Cu" "B.Mask" "B.Paste")
			(net "PWRGD_SYS_PWROK_R1")
		)
		(pad "16" smd rect
			(at -2.921 1.625092 270)
			(size 0.3556 1.4986)
			(layers "B.Cu" "B.Mask" "B.Paste")
			(net "RST_PLTRST_R2_N")
		)
		(pad "17" smd rect
			(at -2.921 0.975106 270)
			(size 0.3556 1.4986)
			(layers "B.Cu" "B.Mask" "B.Paste")
			(net "PWRGD_DSW_PWROK_R3")
		)
		(pad "18" smd rect
			(at -2.921 0.32512 270)
			(size 0.3556 1.4986)
			(layers "B.Cu" "B.Mask" "B.Paste")
			(net "FM_CPU_MSMI_CATERR_LVT3_R3_N")
		)
		(pad "19" smd rect
			(at -2.921 -0.32512 270)
			(size 0.3556 1.4986)
			(layers "B.Cu" "B.Mask" "B.Paste")
			(net "FM_SLPS3_GF_R2_N")
		)
		(pad "20" smd rect
			(at -2.921 -0.975106 270)
			(size 0.3556 1.4986)
			(layers "B.Cu" "B.Mask" "B.Paste")
			(net "FM_UART_SWITCH_N")
		)
		(pad "21" smd rect
			(at -2.921 -1.625092 270)
			(size 0.3556 1.4986)
			(layers "B.Cu" "B.Mask" "B.Paste")
			(net "LED_POSTCODE_A0")
		)
		(pad "22" smd rect
			(at -2.921 -2.275078 270)
			(size 0.3556 1.4986)
			(layers "B.Cu" "B.Mask" "B.Paste")
			(net "SMB_DEBUG_AUX_LVC3_USB_R3_SCL")
		)
		(pad "23" smd rect
			(at -2.921 -2.925064 270)
			(size 0.3556 1.4986)
			(layers "B.Cu" "B.Mask" "B.Paste")
			(net "SMB_DEBUG_AUX_LVC3_USB_R3_SDA")
		)
		(pad "24" smd rect
			(at -2.921 -3.57505 270)
			(size 0.3556 1.4986)
			(layers "B.Cu" "B.Mask" "B.Paste")
			(net "P3V3_AUX")
		)
	)
	(footprint ""
		(layer "B.Cu")
		(at 55.14848 -74.242676 -90)
		(property "Reference" "R795"
			(at 0 0 90)
			(layer "B.SilkS")
			(hide yes)
			(effects
				(font
					(size 1.27 1.27)
				)
				(justify mirror)
			)
		)
		(property "Value" ""
			(at 0 0 90)
			(layer "B.Fab")
			(effects
				(font
					(size 1.27 1.27)
				)
				(justify mirror)
			)
		)
		(duplicate_pad_numbers_are_jumpers no)
		(fp_line
			(start -0.7874 0.4064)
			(end 0.7874 0.4064)
			(stroke
				(width 0.1524)
				(type default)
			)
			(layer "B.SilkS")
		)
		(fp_line
			(start 0.7874 0.4064)
			(end 0.7874 -0.4064)
			(stroke
				(width 0.1524)
				(type default)
			)
			(layer "B.SilkS")
		)
		(fp_line
			(start -0.7874 -0.4064)
			(end -0.7874 0.4064)
			(stroke
				(width 0.1524)
				(type default)
			)
			(layer "B.SilkS")
		)
		(fp_line
			(start 0.7874 -0.4064)
			(end -0.7874 -0.4064)
			(stroke
				(width 0.1524)
				(type default)
			)
			(layer "B.SilkS")
		)
		(fp_line
			(start -0.67945 0.3048)
			(end -0.120396 0.3048)
			(stroke
				(width 0.1)
				(type default)
			)
			(layer "B.Fab")
		)
		(fp_line
			(start -0.120396 0.3048)
			(end -0.120396 0.2794)
			(stroke
				(width 0.1)
				(type default)
			)
			(layer "B.Fab")
		)
		(fp_line
			(start 0.12065 0.3048)
			(end 0.67945 0.3048)
			(stroke
				(width 0.1)
				(type default)
			)
			(layer "B.Fab")
		)
		(fp_line
			(start 0.67945 0.3048)
			(end 0.67945 -0.305054)
			(stroke
				(width 0.1)
				(type default)
			)
			(layer "B.Fab")
		)
		(fp_line
			(start -0.120396 0.2794)
			(end 0.12065 0.2794)
			(stroke
				(width 0.1)
				(type default)
			)
			(layer "B.Fab")
		)
		(fp_line
			(start 0.12065 0.2794)
			(end 0.12065 0.3048)
			(stroke
				(width 0.1)
				(type default)
			)
			(layer "B.Fab")
		)
		(fp_line
			(start -0.12065 -0.2794)
			(end -0.12065 -0.3048)
			(stroke
				(width 0.1)
				(type default)
			)
			(layer "B.Fab")
		)
		(fp_line
			(start 0.12065 -0.2794)
			(end -0.12065 -0.2794)
			(stroke
				(width 0.1)
				(type default)
			)
			(layer "B.Fab")
		)
		(fp_line
			(start -0.67945 -0.3048)
			(end -0.67945 0.3048)
			(stroke
				(width 0.1)
				(type default)
			)
			(layer "B.Fab")
		)
		(fp_line
			(start -0.12065 -0.3048)
			(end -0.67945 -0.3048)
			(stroke
				(width 0.1)
				(type default)
			)
			(layer "B.Fab")
		)
		(fp_line
			(start 0.12065 -0.305054)
			(end 0.12065 -0.2794)
			(stroke
				(width 0.1)
				(type default)
			)
			(layer "B.Fab")
		)
		(fp_line
			(start 0.67945 -0.305054)
			(end 0.12065 -0.305054)
			(stroke
				(width 0.1)
				(type default)
			)
			(layer "B.Fab")
		)
		(pad "1" smd circle
			(at 0.40005 0 90)
			(size 0 0)
			(layers "B.Cu" "B.Mask" "B.Paste")
			(net "P1V2_AUX")
		)
		(pad "2" smd circle
			(at -0.40005 0 90)
			(size 0 0)
			(layers "B.Cu" "B.Mask" "B.Paste")
			(net "P1V2_SENSOR")
		)
	)
	(footprint ""
		(layer "B.Cu")
		(at 74.803 -32.131 180)
		(property "Reference" "R669"
			(at 0 0 0)
			(layer "B.SilkS")
			(hide yes)
			(effects
				(font
					(size 1.27 1.27)
				)
				(justify mirror)
			)
		)
		(property "Value" ""
			(at 0 0 0)
			(layer "B.Fab")
			(effects
				(font
					(size 1.27 1.27)
				)
				(justify mirror)
			)
		)
		(duplicate_pad_numbers_are_jumpers no)
		(fp_line
			(start 0.7874 0.4064)
			(end 0.7874 -0.4064)
			(stroke
				(width 0.1524)
				(type default)
			)
			(layer "B.SilkS")
		)
		(fp_line
			(start 0.7874 -0.4064)
			(end -0.7874 -0.4064)
			(stroke
				(width 0.1524)
				(type default)
			)
			(layer "B.SilkS")
		)
		(fp_line
			(start -0.7874 0.4064)
			(end 0.7874 0.4064)
			(stroke
				(width 0.1524)
				(type default)
			)
			(layer "B.SilkS")
		)
		(fp_line
			(start -0.7874 -0.4064)
			(end -0.7874 0.4064)
			(stroke
				(width 0.1524)
				(type default)
			)
			(layer "B.SilkS")
		)
		(fp_line
			(start 0.67945 0.3048)
			(end 0.67945 -0.305054)
			(stroke
				(width 0.1)
				(type default)
			)
			(layer "B.Fab")
		)
		(fp_line
			(start 0.67945 -0.305054)
			(end 0.12065 -0.305054)
			(stroke
				(width 0.1)
				(type default)
			)
			(layer "B.Fab")
		)
		(fp_line
			(start 0.12065 0.3048)
			(end 0.67945 0.3048)
			(stroke
				(width 0.1)
				(type default)
			)
			(layer "B.Fab")
		)
		(fp_line
			(start 0.12065 0.2794)
			(end 0.12065 0.3048)
			(stroke
				(width 0.1)
				(type default)
			)
			(layer "B.Fab")
		)
		(fp_line
			(start 0.12065 -0.2794)
			(end -0.12065 -0.2794)
			(stroke
				(width 0.1)
				(type default)
			)
			(layer "B.Fab")
		)
		(fp_line
			(start 0.12065 -0.305054)
			(end 0.12065 -0.2794)
			(stroke
				(width 0.1)
				(type default)
			)
			(layer "B.Fab")
		)
		(fp_line
			(start -0.120396 0.3048)
			(end -0.120396 0.2794)
			(stroke
				(width 0.1)
				(type default)
			)
			(layer "B.Fab")
		)
		(fp_line
			(start -0.120396 0.2794)
			(end 0.12065 0.2794)
			(stroke
				(width 0.1)
				(type default)
			)
			(layer "B.Fab")
		)
		(fp_line
			(start -0.12065 -0.2794)
			(end -0.12065 -0.3048)
			(stroke
				(width 0.1)
				(type default)
			)
			(layer "B.Fab")
		)
		(fp_line
			(start -0.12065 -0.3048)
			(end -0.67945 -0.3048)
			(stroke
				(width 0.1)
				(type default)
			)
			(layer "B.Fab")
		)
		(fp_line
			(start -0.67945 0.3048)
			(end -0.120396 0.3048)
			(stroke
				(width 0.1)
				(type default)
			)
			(layer "B.Fab")
		)
		(fp_line
			(start -0.67945 -0.3048)
			(end -0.67945 0.3048)
			(stroke
				(width 0.1)
				(type default)
			)
			(layer "B.Fab")
		)
		(pad "1" smd circle
			(at 0.40005 0)
			(size 0 0)
			(layers "B.Cu" "B.Mask" "B.Paste")
			(net "LED_POSTCODE_7")
		)
		(pad "2" smd circle
			(at -0.40005 0)
			(size 0 0)
			(layers "B.Cu" "B.Mask" "B.Paste")
			(net "LED_POSTCODE_7_R1")
		)
	)
	(footprint ""
		(layer "B.Cu")
		(at 31.9532 -60.5282)
		(property "Reference" "C290"
			(at 0 0 0)
			(layer "B.SilkS")
			(hide yes)
			(effects
				(font
					(size 1.27 1.27)
				)
				(justify mirror)
			)
		)
		(property "Value" ""
			(at 0 0 0)
			(layer "B.Fab")
			(effects
				(font
					(size 1.27 1.27)
				)
				(justify mirror)
			)
		)
		(duplicate_pad_numbers_are_jumpers no)
		(fp_line
			(start -0.7874 -0.4064)
			(end -0.7874 0.4064)
			(stroke
				(width 0.1524)
				(type default)
			)
			(layer "B.SilkS")
		)
		(fp_line
			(start -0.7874 0.4064)
			(end 0.7874 0.4064)
			(stroke
				(width 0.1524)
				(type default)
			)
			(layer "B.SilkS")
		)
		(fp_line
			(start 0.7874 -0.4064)
			(end -0.7874 -0.4064)
			(stroke
				(width 0.1524)
				(type default)
			)
			(layer "B.SilkS")
		)
		(fp_line
			(start 0.7874 0.4064)
			(end 0.7874 -0.4064)
			(stroke
				(width 0.1524)
				(type default)
			)
			(layer "B.SilkS")
		)
		(fp_line
			(start -0.67945 -0.3048)
			(end -0.67945 0.3048)
			(stroke
				(width 0.1)
				(type default)
			)
			(layer "B.Fab")
		)
		(fp_line
			(start -0.67945 0.3048)
			(end -0.120396 0.3048)
			(stroke
				(width 0.1)
				(type default)
			)
			(layer "B.Fab")
		)
		(fp_line
			(start -0.12065 -0.3048)
			(end -0.67945 -0.3048)
			(stroke
				(width 0.1)
				(type default)
			)
			(layer "B.Fab")
		)
		(fp_line
			(start -0.12065 -0.2794)
			(end -0.12065 -0.3048)
			(stroke
				(width 0.1)
				(type default)
			)
			(layer "B.Fab")
		)
		(fp_line
			(start -0.120396 0.2794)
			(end 0.12065 0.2794)
			(stroke
				(width 0.1)
				(type default)
			)
			(layer "B.Fab")
		)
		(fp_line
			(start -0.120396 0.3048)
			(end -0.120396 0.2794)
			(stroke
				(width 0.1)
				(type default)
			)
			(layer "B.Fab")
		)
		(fp_line
			(start 0.12065 -0.305054)
			(end 0.12065 -0.2794)
			(stroke
				(width 0.1)
				(type default)
			)
			(layer "B.Fab")
		)
		(fp_line
			(start 0.12065 -0.2794)
			(end -0.12065 -0.2794)
			(stroke
				(width 0.1)
				(type default)
			)
			(layer "B.Fab")
		)
		(fp_line
			(start 0.12065 0.2794)
			(end 0.12065 0.3048)
			(stroke
				(width 0.1)
				(type default)
			)
			(layer "B.Fab")
		)
		(fp_line
			(start 0.12065 0.3048)
			(end 0.67945 0.3048)
			(stroke
				(width 0.1)
				(type default)
			)
			(layer "B.Fab")
		)
		(fp_line
			(start 0.67945 -0.305054)
			(end 0.12065 -0.305054)
			(stroke
				(width 0.1)
				(type default)
			)
			(layer "B.Fab")
		)
		(fp_line
			(start 0.67945 0.3048)
			(end 0.67945 -0.305054)
			(stroke
				(width 0.1)
				(type default)
			)
			(layer "B.Fab")
		)
		(pad "1" smd circle
			(at 0.40005 0 180)
			(size 0 0)
			(layers "B.Cu" "B.Mask" "B.Paste")
			(net "P12V_SENSOR")
		)
		(pad "2" smd circle
			(at -0.40005 0 180)
			(size 0 0)
			(layers "B.Cu" "B.Mask" "B.Paste")
			(net "GND")
		)
	)
	(footprint ""
		(layer "B.Cu")
		(at 14.478 -21.844 180)
		(property "Reference" "R812"
			(at 0 0 0)
			(layer "B.SilkS")
			(hide yes)
			(effects
				(font
					(size 1.27 1.27)
				)
				(justify mirror)
			)
		)
		(property "Value" ""
			(at 0 0 0)
			(layer "B.Fab")
			(effects
				(font
					(size 1.27 1.27)
				)
				(justify mirror)
			)
		)
		(duplicate_pad_numbers_are_jumpers no)
		(fp_line
			(start 0.7874 0.4064)
			(end 0.7874 -0.4064)
			(stroke
				(width 0.1524)
				(type default)
			)
			(layer "B.SilkS")
		)
		(fp_line
			(start 0.7874 -0.4064)
			(end -0.7874 -0.4064)
			(stroke
				(width 0.1524)
				(type default)
			)
			(layer "B.SilkS")
		)
		(fp_line
			(start -0.7874 0.4064)
			(end 0.7874 0.4064)
			(stroke
				(width 0.1524)
				(type default)
			)
			(layer "B.SilkS")
		)
		(fp_line
			(start -0.7874 -0.4064)
			(end -0.7874 0.4064)
			(stroke
				(width 0.1524)
				(type default)
			)
			(layer "B.SilkS")
		)
		(fp_line
			(start 0.67945 0.3048)
			(end 0.67945 -0.305054)
			(stroke
				(width 0.1)
				(type default)
			)
			(layer "B.Fab")
		)
		(fp_line
			(start 0.67945 -0.305054)
			(end 0.12065 -0.305054)
			(stroke
				(width 0.1)
				(type default)
			)
			(layer "B.Fab")
		)
		(fp_line
			(start 0.12065 0.3048)
			(end 0.67945 0.3048)
			(stroke
				(width 0.1)
				(type default)
			)
			(layer "B.Fab")
		)
		(fp_line
			(start 0.12065 0.2794)
			(end 0.12065 0.3048)
			(stroke
				(width 0.1)
				(type default)
			)
			(layer "B.Fab")
		)
		(fp_line
			(start 0.12065 -0.2794)
			(end -0.12065 -0.2794)
			(stroke
				(width 0.1)
				(type default)
			)
			(layer "B.Fab")
		)
		(fp_line
			(start 0.12065 -0.305054)
			(end 0.12065 -0.2794)
			(stroke
				(width 0.1)
				(type default)
			)
			(layer "B.Fab")
		)
		(fp_line
			(start -0.120396 0.3048)
			(end -0.120396 0.2794)
			(stroke
				(width 0.1)
				(type default)
			)
			(layer "B.Fab")
		)
		(fp_line
			(start -0.120396 0.2794)
			(end 0.12065 0.2794)
			(stroke
				(width 0.1)
				(type default)
			)
			(layer "B.Fab")
		)
		(fp_line
			(start -0.12065 -0.2794)
			(end -0.12065 -0.3048)
			(stroke
				(width 0.1)
				(type default)
			)
			(layer "B.Fab")
		)
		(fp_line
			(start -0.12065 -0.3048)
			(end -0.67945 -0.3048)
			(stroke
				(width 0.1)
				(type default)
			)
			(layer "B.Fab")
		)
		(fp_line
			(start -0.67945 0.3048)
			(end -0.120396 0.3048)
			(stroke
				(width 0.1)
				(type default)
			)
			(layer "B.Fab")
		)
		(fp_line
			(start -0.67945 -0.3048)
			(end -0.67945 0.3048)
			(stroke
				(width 0.1)
				(type default)
			)
			(layer "B.Fab")
		)
		(pad "1" smd circle
			(at 0.40005 0)
			(size 0 0)
			(layers "B.Cu" "B.Mask" "B.Paste")
			(net "PWR_LED_BUF_N")
		)
		(pad "2" smd circle
			(at -0.40005 0)
			(size 0 0)
			(layers "B.Cu" "B.Mask" "B.Paste")
			(net "PWR_LED_BUF_N_R")
		)
	)
	(footprint ""
		(layer "B.Cu")
		(at 80.755744 -35.540188 -90)
		(property "Reference" "R326"
			(at 0 0 90)
			(layer "B.SilkS")
			(hide yes)
			(effects
				(font
					(size 1.27 1.27)
				)
				(justify mirror)
			)
		)
		(property "Value" ""
			(at 0 0 90)
			(layer "B.Fab")
			(effects
				(font
					(size 1.27 1.27)
				)
				(justify mirror)
			)
		)
		(duplicate_pad_numbers_are_jumpers no)
		(fp_line
			(start -0.7874 0.4064)
			(end 0.7874 0.4064)
			(stroke
				(width 0.1524)
				(type default)
			)
			(layer "B.SilkS")
		)
		(fp_line
			(start 0.7874 0.4064)
			(end 0.7874 -0.4064)
			(stroke
				(width 0.1524)
				(type default)
			)
			(layer "B.SilkS")
		)
		(fp_line
			(start -0.7874 -0.4064)
			(end -0.7874 0.4064)
			(stroke
				(width 0.1524)
				(type default)
			)
			(layer "B.SilkS")
		)
		(fp_line
			(start 0.7874 -0.4064)
			(end -0.7874 -0.4064)
			(stroke
				(width 0.1524)
				(type default)
			)
			(layer "B.SilkS")
		)
		(fp_line
			(start -0.67945 0.3048)
			(end -0.120396 0.3048)
			(stroke
				(width 0.1)
				(type default)
			)
			(layer "B.Fab")
		)
		(fp_line
			(start -0.120396 0.3048)
			(end -0.120396 0.2794)
			(stroke
				(width 0.1)
				(type default)
			)
			(layer "B.Fab")
		)
		(fp_line
			(start 0.12065 0.3048)
			(end 0.67945 0.3048)
			(stroke
				(width 0.1)
				(type default)
			)
			(layer "B.Fab")
		)
		(fp_line
			(start 0.67945 0.3048)
			(end 0.67945 -0.305054)
			(stroke
				(width 0.1)
				(type default)
			)
			(layer "B.Fab")
		)
		(fp_line
			(start -0.120396 0.2794)
			(end 0.12065 0.2794)
			(stroke
				(width 0.1)
				(type default)
			)
			(layer "B.Fab")
		)
		(fp_line
			(start 0.12065 0.2794)
			(end 0.12065 0.3048)
			(stroke
				(width 0.1)
				(type default)
			)
			(layer "B.Fab")
		)
		(fp_line
			(start -0.12065 -0.2794)
			(end -0.12065 -0.3048)
			(stroke
				(width 0.1)
				(type default)
			)
			(layer "B.Fab")
		)
		(fp_line
			(start 0.12065 -0.2794)
			(end -0.12065 -0.2794)
			(stroke
				(width 0.1)
				(type default)
			)
			(layer "B.Fab")
		)
		(fp_line
			(start -0.67945 -0.3048)
			(end -0.67945 0.3048)
			(stroke
				(width 0.1)
				(type default)
			)
			(layer "B.Fab")
		)
		(fp_line
			(start -0.12065 -0.3048)
			(end -0.67945 -0.3048)
			(stroke
				(width 0.1)
				(type default)
			)
			(layer "B.Fab")
		)
		(fp_line
			(start 0.12065 -0.305054)
			(end 0.12065 -0.2794)
			(stroke
				(width 0.1)
				(type default)
			)
			(layer "B.Fab")
		)
		(fp_line
			(start 0.67945 -0.305054)
			(end 0.12065 -0.305054)
			(stroke
				(width 0.1)
				(type default)
			)
			(layer "B.Fab")
		)
		(pad "1" smd circle
			(at 0.40005 0 90)
			(size 0 0)
			(layers "B.Cu" "B.Mask" "B.Paste")
			(net "GND")
		)
		(pad "2" smd circle
			(at -0.40005 0 90)
			(size 0 0)
			(layers "B.Cu" "B.Mask" "B.Paste")
			(net "M_BMC_DDR4_MA<0>")
		)
	)
	(footprint ""
		(layer "B.Cu")
		(at 50.292 -66.7131 -90)
		(property "Reference" "R796"
			(at 0 0 90)
			(layer "B.SilkS")
			(hide yes)
			(effects
				(font
					(size 1.27 1.27)
				)
				(justify mirror)
			)
		)
		(property "Value" ""
			(at 0 0 90)
			(layer "B.Fab")
			(effects
				(font
					(size 1.27 1.27)
				)
				(justify mirror)
			)
		)
		(duplicate_pad_numbers_are_jumpers no)
		(fp_line
			(start -0.7874 0.4064)
			(end 0.7874 0.4064)
			(stroke
				(width 0.1524)
				(type default)
			)
			(layer "B.SilkS")
		)
		(fp_line
			(start 0.7874 0.4064)
			(end 0.7874 -0.4064)
			(stroke
				(width 0.1524)
				(type default)
			)
			(layer "B.SilkS")
		)
		(fp_line
			(start -0.7874 -0.4064)
			(end -0.7874 0.4064)
			(stroke
				(width 0.1524)
				(type default)
			)
			(layer "B.SilkS")
		)
		(fp_line
			(start 0.7874 -0.4064)
			(end -0.7874 -0.4064)
			(stroke
				(width 0.1524)
				(type default)
			)
			(layer "B.SilkS")
		)
		(fp_line
			(start -0.67945 0.3048)
			(end -0.120396 0.3048)
			(stroke
				(width 0.1)
				(type default)
			)
			(layer "B.Fab")
		)
		(fp_line
			(start -0.120396 0.3048)
			(end -0.120396 0.2794)
			(stroke
				(width 0.1)
				(type default)
			)
			(layer "B.Fab")
		)
		(fp_line
			(start 0.12065 0.3048)
			(end 0.67945 0.3048)
			(stroke
				(width 0.1)
				(type default)
			)
			(layer "B.Fab")
		)
		(fp_line
			(start 0.67945 0.3048)
			(end 0.67945 -0.305054)
			(stroke
				(width 0.1)
				(type default)
			)
			(layer "B.Fab")
		)
		(fp_line
			(start -0.120396 0.2794)
			(end 0.12065 0.2794)
			(stroke
				(width 0.1)
				(type default)
			)
			(layer "B.Fab")
		)
		(fp_line
			(start 0.12065 0.2794)
			(end 0.12065 0.3048)
			(stroke
				(width 0.1)
				(type default)
			)
			(layer "B.Fab")
		)
		(fp_line
			(start -0.12065 -0.2794)
			(end -0.12065 -0.3048)
			(stroke
				(width 0.1)
				(type default)
			)
			(layer "B.Fab")
		)
		(fp_line
			(start 0.12065 -0.2794)
			(end -0.12065 -0.2794)
			(stroke
				(width 0.1)
				(type default)
			)
			(layer "B.Fab")
		)
		(fp_line
			(start -0.67945 -0.3048)
			(end -0.67945 0.3048)
			(stroke
				(width 0.1)
				(type default)
			)
			(layer "B.Fab")
		)
		(fp_line
			(start -0.12065 -0.3048)
			(end -0.67945 -0.3048)
			(stroke
				(width 0.1)
				(type default)
			)
			(layer "B.Fab")
		)
		(fp_line
			(start 0.12065 -0.305054)
			(end 0.12065 -0.2794)
			(stroke
				(width 0.1)
				(type default)
			)
			(layer "B.Fab")
		)
		(fp_line
			(start 0.67945 -0.305054)
			(end 0.12065 -0.305054)
			(stroke
				(width 0.1)
				(type default)
			)
			(layer "B.Fab")
		)
		(pad "1" smd circle
			(at 0.40005 0 90)
			(size 0 0)
			(layers "B.Cu" "B.Mask" "B.Paste")
			(net "P1V0_AUX")
		)
		(pad "2" smd circle
			(at -0.40005 0 90)
			(size 0 0)
			(layers "B.Cu" "B.Mask" "B.Paste")
			(net "P1V0_SENSOR")
		)
	)
	(footprint ""
		(layer "B.Cu")
		(at 53.424582 -55.13197 -90)
		(property "Reference" "C96"
			(at 0 0 90)
			(layer "B.SilkS")
			(hide yes)
			(effects
				(font
					(size 1.27 1.27)
				)
				(justify mirror)
			)
		)
		(property "Value" ""
			(at 0 0 90)
			(layer "B.Fab")
			(effects
				(font
					(size 1.27 1.27)
				)
				(justify mirror)
			)
		)
		(duplicate_pad_numbers_are_jumpers no)
		(fp_line
			(start -0.7874 0.4064)
			(end 0.7874 0.4064)
			(stroke
				(width 0.1524)
				(type default)
			)
			(layer "B.SilkS")
		)
		(fp_line
			(start 0.7874 0.4064)
			(end 0.7874 -0.4064)
			(stroke
				(width 0.1524)
				(type default)
			)
			(layer "B.SilkS")
		)
		(fp_line
			(start -0.7874 -0.4064)
			(end -0.7874 0.4064)
			(stroke
				(width 0.1524)
				(type default)
			)
			(layer "B.SilkS")
		)
		(fp_line
			(start 0.7874 -0.4064)
			(end -0.7874 -0.4064)
			(stroke
				(width 0.1524)
				(type default)
			)
			(layer "B.SilkS")
		)
		(fp_line
			(start -0.67945 0.3048)
			(end -0.120396 0.3048)
			(stroke
				(width 0.1)
				(type default)
			)
			(layer "B.Fab")
		)
		(fp_line
			(start -0.120396 0.3048)
			(end -0.120396 0.2794)
			(stroke
				(width 0.1)
				(type default)
			)
			(layer "B.Fab")
		)
		(fp_line
			(start 0.12065 0.3048)
			(end 0.67945 0.3048)
			(stroke
				(width 0.1)
				(type default)
			)
			(layer "B.Fab")
		)
		(fp_line
			(start 0.67945 0.3048)
			(end 0.67945 -0.305054)
			(stroke
				(width 0.1)
				(type default)
			)
			(layer "B.Fab")
		)
		(fp_line
			(start -0.120396 0.2794)
			(end 0.12065 0.2794)
			(stroke
				(width 0.1)
				(type default)
			)
			(layer "B.Fab")
		)
		(fp_line
			(start 0.12065 0.2794)
			(end 0.12065 0.3048)
			(stroke
				(width 0.1)
				(type default)
			)
			(layer "B.Fab")
		)
		(fp_line
			(start -0.12065 -0.2794)
			(end -0.12065 -0.3048)
			(stroke
				(width 0.1)
				(type default)
			)
			(layer "B.Fab")
		)
		(fp_line
			(start 0.12065 -0.2794)
			(end -0.12065 -0.2794)
			(stroke
				(width 0.1)
				(type default)
			)
			(layer "B.Fab")
		)
		(fp_line
			(start -0.67945 -0.3048)
			(end -0.67945 0.3048)
			(stroke
				(width 0.1)
				(type default)
			)
			(layer "B.Fab")
		)
		(fp_line
			(start -0.12065 -0.3048)
			(end -0.67945 -0.3048)
			(stroke
				(width 0.1)
				(type default)
			)
			(layer "B.Fab")
		)
		(fp_line
			(start 0.12065 -0.305054)
			(end 0.12065 -0.2794)
			(stroke
				(width 0.1)
				(type default)
			)
			(layer "B.Fab")
		)
		(fp_line
			(start 0.67945 -0.305054)
			(end 0.12065 -0.305054)
			(stroke
				(width 0.1)
				(type default)
			)
			(layer "B.Fab")
		)
		(pad "1" smd circle
			(at 0.40005 0 90)
			(size 0 0)
			(layers "B.Cu" "B.Mask" "B.Paste")
			(net "PGPPA_BMC_AUX")
		)
		(pad "2" smd circle
			(at -0.40005 0 90)
			(size 0 0)
			(layers "B.Cu" "B.Mask" "B.Paste")
			(net "GND")
		)
	)
	(footprint ""
		(layer "B.Cu")
		(at 11.9126 -26.9748)
		(property "Reference" "R741"
			(at 0 0 0)
			(layer "B.SilkS")
			(hide yes)
			(effects
				(font
					(size 1.27 1.27)
				)
				(justify mirror)
			)
		)
		(property "Value" ""
			(at 0 0 0)
			(layer "B.Fab")
			(effects
				(font
					(size 1.27 1.27)
				)
				(justify mirror)
			)
		)
		(duplicate_pad_numbers_are_jumpers no)
		(fp_line
			(start -0.7874 -0.4064)
			(end -0.7874 0.4064)
			(stroke
				(width 0.1524)
				(type default)
			)
			(layer "B.SilkS")
		)
		(fp_line
			(start -0.7874 0.4064)
			(end 0.7874 0.4064)
			(stroke
				(width 0.1524)
				(type default)
			)
			(layer "B.SilkS")
		)
		(fp_line
			(start 0.7874 -0.4064)
			(end -0.7874 -0.4064)
			(stroke
				(width 0.1524)
				(type default)
			)
			(layer "B.SilkS")
		)
		(fp_line
			(start 0.7874 0.4064)
			(end 0.7874 -0.4064)
			(stroke
				(width 0.1524)
				(type default)
			)
			(layer "B.SilkS")
		)
		(fp_line
			(start -0.67945 -0.3048)
			(end -0.67945 0.3048)
			(stroke
				(width 0.1)
				(type default)
			)
			(layer "B.Fab")
		)
		(fp_line
			(start -0.67945 0.3048)
			(end -0.120396 0.3048)
			(stroke
				(width 0.1)
				(type default)
			)
			(layer "B.Fab")
		)
		(fp_line
			(start -0.12065 -0.3048)
			(end -0.67945 -0.3048)
			(stroke
				(width 0.1)
				(type default)
			)
			(layer "B.Fab")
		)
		(fp_line
			(start -0.12065 -0.2794)
			(end -0.12065 -0.3048)
			(stroke
				(width 0.1)
				(type default)
			)
			(layer "B.Fab")
		)
		(fp_line
			(start -0.120396 0.2794)
			(end 0.12065 0.2794)
			(stroke
				(width 0.1)
				(type default)
			)
			(layer "B.Fab")
		)
		(fp_line
			(start -0.120396 0.3048)
			(end -0.120396 0.2794)
			(stroke
				(width 0.1)
				(type default)
			)
			(layer "B.Fab")
		)
		(fp_line
			(start 0.12065 -0.305054)
			(end 0.12065 -0.2794)
			(stroke
				(width 0.1)
				(type default)
			)
			(layer "B.Fab")
		)
		(fp_line
			(start 0.12065 -0.2794)
			(end -0.12065 -0.2794)
			(stroke
				(width 0.1)
				(type default)
			)
			(layer "B.Fab")
		)
		(fp_line
			(start 0.12065 0.2794)
			(end 0.12065 0.3048)
			(stroke
				(width 0.1)
				(type default)
			)
			(layer "B.Fab")
		)
		(fp_line
			(start 0.12065 0.3048)
			(end 0.67945 0.3048)
			(stroke
				(width 0.1)
				(type default)
			)
			(layer "B.Fab")
		)
		(fp_line
			(start 0.67945 -0.305054)
			(end 0.12065 -0.305054)
			(stroke
				(width 0.1)
				(type default)
			)
			(layer "B.Fab")
		)
		(fp_line
			(start 0.67945 0.3048)
			(end 0.67945 -0.305054)
			(stroke
				(width 0.1)
				(type default)
			)
			(layer "B.Fab")
		)
		(pad "1" smd circle
			(at 0.40005 0 180)
			(size 0 0)
			(layers "B.Cu" "B.Mask" "B.Paste")
			(net "P3V3_AUX")
		)
		(pad "2" smd circle
			(at -0.40005 0 180)
			(size 0 0)
			(layers "B.Cu" "B.Mask" "B.Paste")
			(net "UART_BMC_5_RXD_BUF")
		)
	)
	(footprint ""
		(layer "B.Cu")
		(at 19.459448 -92.787216 -90)
		(property "Reference" "C164"
			(at 0 0 90)
			(layer "B.SilkS")
			(hide yes)
			(effects
				(font
					(size 1.27 1.27)
				)
				(justify mirror)
			)
		)
		(property "Value" ""
			(at 0 0 90)
			(layer "B.Fab")
			(effects
				(font
					(size 1.27 1.27)
				)
				(justify mirror)
			)
		)
		(duplicate_pad_numbers_are_jumpers no)
		(fp_line
			(start -0.69215 0.2921)
			(end 0.69215 0.2921)
			(stroke
				(width 0.1524)
				(type default)
			)
			(layer "B.SilkS")
		)
		(fp_line
			(start 0.69215 0.2921)
			(end 0.69215 -0.2921)
			(stroke
				(width 0.1524)
				(type default)
			)
			(layer "B.SilkS")
		)
		(fp_line
			(start -0.69215 -0.2921)
			(end -0.69215 0.2921)
			(stroke
				(width 0.1524)
				(type default)
			)
			(layer "B.SilkS")
		)
		(fp_line
			(start 0.69215 -0.2921)
			(end -0.69215 -0.2921)
			(stroke
				(width 0.1524)
				(type default)
			)
			(layer "B.SilkS")
		)
		(fp_line
			(start -0.51435 0.2794)
			(end 0.51435 0.2794)
			(stroke
				(width 0.1)
				(type default)
			)
			(layer "B.Fab")
		)
		(fp_line
			(start 0.51435 0.2794)
			(end 0.51435 -0.2794)
			(stroke
				(width 0.1)
				(type default)
			)
			(layer "B.Fab")
		)
		(fp_line
			(start -0.51435 -0.2794)
			(end -0.51435 0.2794)
			(stroke
				(width 0.1)
				(type default)
			)
			(layer "B.Fab")
		)
		(fp_line
			(start 0.51435 -0.2794)
			(end -0.51435 -0.2794)
			(stroke
				(width 0.1)
				(type default)
			)
			(layer "B.Fab")
		)
		(pad "1" smd circle
			(at 0.40005 0 90)
			(size 0 0)
			(layers "B.Cu" "B.Mask" "B.Paste")
			(net "VCCIO1")
		)
		(pad "2" smd circle
			(at -0.40005 0 90)
			(size 0 0)
			(layers "B.Cu" "B.Mask" "B.Paste")
			(net "GND")
		)
		(zone
			(layer "B.Cu")
			(hatch none 0.5)
			(connect_pads
				(clearance 0)
			)
			(min_thickness 0.25)
			(keepout
				(tracks not_allowed)
				(vias allowed)
				(pads allowed)
				(copperpour not_allowed)
				(footprints allowed)
			)
			(placement
				(enabled no)
				(sheetname "")
			)
			(fill
				(thermal_gap 0.5)
				(thermal_bridge_width 0.5)
				(island_removal_mode 0)
			)
			(polygon
				(pts
					(xy 19.371818 -92.596716) (xy 19.313652 -92.688156) (xy 19.313652 -92.887546) (xy 19.371818 -92.977716)
					(xy 19.547078 -92.977716) (xy 19.605498 -92.887546) (xy 19.605498 -92.688156) (xy 19.547332 -92.596716)
				)
			)
		)
	)
	(footprint ""
		(layer "B.Cu")
		(at 41.966134 -46.16069)
		(property "Reference" "R144"
			(at 0 0 0)
			(layer "B.SilkS")
			(hide yes)
			(effects
				(font
					(size 1.27 1.27)
				)
				(justify mirror)
			)
		)
		(property "Value" ""
			(at 0 0 0)
			(layer "B.Fab")
			(effects
				(font
					(size 1.27 1.27)
				)
				(justify mirror)
			)
		)
		(duplicate_pad_numbers_are_jumpers no)
		(fp_line
			(start -0.7874 -0.4064)
			(end -0.7874 0.4064)
			(stroke
				(width 0.1524)
				(type default)
			)
			(layer "B.SilkS")
		)
		(fp_line
			(start -0.7874 0.4064)
			(end 0.7874 0.4064)
			(stroke
				(width 0.1524)
				(type default)
			)
			(layer "B.SilkS")
		)
		(fp_line
			(start 0.7874 -0.4064)
			(end -0.7874 -0.4064)
			(stroke
				(width 0.1524)
				(type default)
			)
			(layer "B.SilkS")
		)
		(fp_line
			(start 0.7874 0.4064)
			(end 0.7874 -0.4064)
			(stroke
				(width 0.1524)
				(type default)
			)
			(layer "B.SilkS")
		)
		(fp_line
			(start -0.67945 -0.3048)
			(end -0.67945 0.3048)
			(stroke
				(width 0.1)
				(type default)
			)
			(layer "B.Fab")
		)
		(fp_line
			(start -0.67945 0.3048)
			(end -0.120396 0.3048)
			(stroke
				(width 0.1)
				(type default)
			)
			(layer "B.Fab")
		)
		(fp_line
			(start -0.12065 -0.3048)
			(end -0.67945 -0.3048)
			(stroke
				(width 0.1)
				(type default)
			)
			(layer "B.Fab")
		)
		(fp_line
			(start -0.12065 -0.2794)
			(end -0.12065 -0.3048)
			(stroke
				(width 0.1)
				(type default)
			)
			(layer "B.Fab")
		)
		(fp_line
			(start -0.120396 0.2794)
			(end 0.12065 0.2794)
			(stroke
				(width 0.1)
				(type default)
			)
			(layer "B.Fab")
		)
		(fp_line
			(start -0.120396 0.3048)
			(end -0.120396 0.2794)
			(stroke
				(width 0.1)
				(type default)
			)
			(layer "B.Fab")
		)
		(fp_line
			(start 0.12065 -0.305054)
			(end 0.12065 -0.2794)
			(stroke
				(width 0.1)
				(type default)
			)
			(layer "B.Fab")
		)
		(fp_line
			(start 0.12065 -0.2794)
			(end -0.12065 -0.2794)
			(stroke
				(width 0.1)
				(type default)
			)
			(layer "B.Fab")
		)
		(fp_line
			(start 0.12065 0.2794)
			(end 0.12065 0.3048)
			(stroke
				(width 0.1)
				(type default)
			)
			(layer "B.Fab")
		)
		(fp_line
			(start 0.12065 0.3048)
			(end 0.67945 0.3048)
			(stroke
				(width 0.1)
				(type default)
			)
			(layer "B.Fab")
		)
		(fp_line
			(start 0.67945 -0.305054)
			(end 0.12065 -0.305054)
			(stroke
				(width 0.1)
				(type default)
			)
			(layer "B.Fab")
		)
		(fp_line
			(start 0.67945 0.3048)
			(end 0.67945 -0.305054)
			(stroke
				(width 0.1)
				(type default)
			)
			(layer "B.Fab")
		)
		(pad "1" smd circle
			(at 0.40005 0 180)
			(size 0 0)
			(layers "B.Cu" "B.Mask" "B.Paste")
			(net "SMB_BMC_MM12_R_SDA")
		)
		(pad "2" smd circle
			(at -0.40005 0 180)
			(size 0 0)
			(layers "B.Cu" "B.Mask" "B.Paste")
			(net "SMB_BMC_MM12_SDA")
		)
	)
	(footprint ""
		(layer "B.Cu")
		(at 4.7244 -26.797)
		(property "Reference" "C175"
			(at 0 0 0)
			(layer "B.SilkS")
			(hide yes)
			(effects
				(font
					(size 1.27 1.27)
				)
				(justify mirror)
			)
		)
		(property "Value" ""
			(at 0 0 0)
			(layer "B.Fab")
			(effects
				(font
					(size 1.27 1.27)
				)
				(justify mirror)
			)
		)
		(duplicate_pad_numbers_are_jumpers no)
		(fp_line
			(start -0.7874 -0.4064)
			(end -0.7874 0.4064)
			(stroke
				(width 0.1524)
				(type default)
			)
			(layer "B.SilkS")
		)
		(fp_line
			(start -0.7874 0.4064)
			(end 0.7874 0.4064)
			(stroke
				(width 0.1524)
				(type default)
			)
			(layer "B.SilkS")
		)
		(fp_line
			(start 0.7874 -0.4064)
			(end -0.7874 -0.4064)
			(stroke
				(width 0.1524)
				(type default)
			)
			(layer "B.SilkS")
		)
		(fp_line
			(start 0.7874 0.4064)
			(end 0.7874 -0.4064)
			(stroke
				(width 0.1524)
				(type default)
			)
			(layer "B.SilkS")
		)
		(fp_line
			(start -0.67945 -0.3048)
			(end -0.67945 0.3048)
			(stroke
				(width 0.1)
				(type default)
			)
			(layer "B.Fab")
		)
		(fp_line
			(start -0.67945 0.3048)
			(end -0.120396 0.3048)
			(stroke
				(width 0.1)
				(type default)
			)
			(layer "B.Fab")
		)
		(fp_line
			(start -0.12065 -0.3048)
			(end -0.67945 -0.3048)
			(stroke
				(width 0.1)
				(type default)
			)
			(layer "B.Fab")
		)
		(fp_line
			(start -0.12065 -0.2794)
			(end -0.12065 -0.3048)
			(stroke
				(width 0.1)
				(type default)
			)
			(layer "B.Fab")
		)
		(fp_line
			(start -0.120396 0.2794)
			(end 0.12065 0.2794)
			(stroke
				(width 0.1)
				(type default)
			)
			(layer "B.Fab")
		)
		(fp_line
			(start -0.120396 0.3048)
			(end -0.120396 0.2794)
			(stroke
				(width 0.1)
				(type default)
			)
			(layer "B.Fab")
		)
		(fp_line
			(start 0.12065 -0.305054)
			(end 0.12065 -0.2794)
			(stroke
				(width 0.1)
				(type default)
			)
			(layer "B.Fab")
		)
		(fp_line
			(start 0.12065 -0.2794)
			(end -0.12065 -0.2794)
			(stroke
				(width 0.1)
				(type default)
			)
			(layer "B.Fab")
		)
		(fp_line
			(start 0.12065 0.2794)
			(end 0.12065 0.3048)
			(stroke
				(width 0.1)
				(type default)
			)
			(layer "B.Fab")
		)
		(fp_line
			(start 0.12065 0.3048)
			(end 0.67945 0.3048)
			(stroke
				(width 0.1)
				(type default)
			)
			(layer "B.Fab")
		)
		(fp_line
			(start 0.67945 -0.305054)
			(end 0.12065 -0.305054)
			(stroke
				(width 0.1)
				(type default)
			)
			(layer "B.Fab")
		)
		(fp_line
			(start 0.67945 0.3048)
			(end 0.67945 -0.305054)
			(stroke
				(width 0.1)
				(type default)
			)
			(layer "B.Fab")
		)
		(pad "1" smd circle
			(at 0.40005 0 180)
			(size 0 0)
			(layers "B.Cu" "B.Mask" "B.Paste")
			(net "P3V3_AUX")
		)
		(pad "2" smd circle
			(at -0.40005 0 180)
			(size 0 0)
			(layers "B.Cu" "B.Mask" "B.Paste")
			(net "GND")
		)
	)
	(footprint ""
		(layer "B.Cu")
		(at 20.955 -17.907 -90)
		(property "Reference" "R54"
			(at 0 0 90)
			(layer "B.SilkS")
			(hide yes)
			(effects
				(font
					(size 1.27 1.27)
				)
				(justify mirror)
			)
		)
		(property "Value" ""
			(at 0 0 90)
			(layer "B.Fab")
			(effects
				(font
					(size 1.27 1.27)
				)
				(justify mirror)
			)
		)
		(duplicate_pad_numbers_are_jumpers no)
		(fp_line
			(start -0.7874 0.4064)
			(end 0.7874 0.4064)
			(stroke
				(width 0.1524)
				(type default)
			)
			(layer "B.SilkS")
		)
		(fp_line
			(start 0.7874 0.4064)
			(end 0.7874 -0.4064)
			(stroke
				(width 0.1524)
				(type default)
			)
			(layer "B.SilkS")
		)
		(fp_line
			(start -0.7874 -0.4064)
			(end -0.7874 0.4064)
			(stroke
				(width 0.1524)
				(type default)
			)
			(layer "B.SilkS")
		)
		(fp_line
			(start 0.7874 -0.4064)
			(end -0.7874 -0.4064)
			(stroke
				(width 0.1524)
				(type default)
			)
			(layer "B.SilkS")
		)
		(fp_line
			(start -0.67945 0.3048)
			(end -0.120396 0.3048)
			(stroke
				(width 0.1)
				(type default)
			)
			(layer "B.Fab")
		)
		(fp_line
			(start -0.120396 0.3048)
			(end -0.120396 0.2794)
			(stroke
				(width 0.1)
				(type default)
			)
			(layer "B.Fab")
		)
		(fp_line
			(start 0.12065 0.3048)
			(end 0.67945 0.3048)
			(stroke
				(width 0.1)
				(type default)
			)
			(layer "B.Fab")
		)
		(fp_line
			(start 0.67945 0.3048)
			(end 0.67945 -0.305054)
			(stroke
				(width 0.1)
				(type default)
			)
			(layer "B.Fab")
		)
		(fp_line
			(start -0.120396 0.2794)
			(end 0.12065 0.2794)
			(stroke
				(width 0.1)
				(type default)
			)
			(layer "B.Fab")
		)
		(fp_line
			(start 0.12065 0.2794)
			(end 0.12065 0.3048)
			(stroke
				(width 0.1)
				(type default)
			)
			(layer "B.Fab")
		)
		(fp_line
			(start -0.12065 -0.2794)
			(end -0.12065 -0.3048)
			(stroke
				(width 0.1)
				(type default)
			)
			(layer "B.Fab")
		)
		(fp_line
			(start 0.12065 -0.2794)
			(end -0.12065 -0.2794)
			(stroke
				(width 0.1)
				(type default)
			)
			(layer "B.Fab")
		)
		(fp_line
			(start -0.67945 -0.3048)
			(end -0.67945 0.3048)
			(stroke
				(width 0.1)
				(type default)
			)
			(layer "B.Fab")
		)
		(fp_line
			(start -0.12065 -0.3048)
			(end -0.67945 -0.3048)
			(stroke
				(width 0.1)
				(type default)
			)
			(layer "B.Fab")
		)
		(fp_line
			(start 0.12065 -0.305054)
			(end 0.12065 -0.2794)
			(stroke
				(width 0.1)
				(type default)
			)
			(layer "B.Fab")
		)
		(fp_line
			(start 0.67945 -0.305054)
			(end 0.12065 -0.305054)
			(stroke
				(width 0.1)
				(type default)
			)
			(layer "B.Fab")
		)
		(pad "1" smd circle
			(at 0.40005 0 90)
			(size 0 0)
			(layers "B.Cu" "B.Mask" "B.Paste")
			(net "SMB_BMC_ALERT16_R_N")
		)
		(pad "2" smd circle
			(at -0.40005 0 90)
			(size 0 0)
			(layers "B.Cu" "B.Mask" "B.Paste")
			(net "SMB_BMC_ALERT16_N")
		)
	)
	(footprint ""
		(layer "B.Cu")
		(at 51.3715 -86.0425 180)
		(property "Reference" "R701"
			(at 0 0 0)
			(layer "B.SilkS")
			(hide yes)
			(effects
				(font
					(size 1.27 1.27)
				)
				(justify mirror)
			)
		)
		(property "Value" ""
			(at 0 0 0)
			(layer "B.Fab")
			(effects
				(font
					(size 1.27 1.27)
				)
				(justify mirror)
			)
		)
		(duplicate_pad_numbers_are_jumpers no)
		(fp_line
			(start 0.7874 0.4064)
			(end 0.7874 -0.4064)
			(stroke
				(width 0.1524)
				(type default)
			)
			(layer "B.SilkS")
		)
		(fp_line
			(start 0.7874 -0.4064)
			(end -0.7874 -0.4064)
			(stroke
				(width 0.1524)
				(type default)
			)
			(layer "B.SilkS")
		)
		(fp_line
			(start -0.7874 0.4064)
			(end 0.7874 0.4064)
			(stroke
				(width 0.1524)
				(type default)
			)
			(layer "B.SilkS")
		)
		(fp_line
			(start -0.7874 -0.4064)
			(end -0.7874 0.4064)
			(stroke
				(width 0.1524)
				(type default)
			)
			(layer "B.SilkS")
		)
		(fp_line
			(start 0.67945 0.3048)
			(end 0.67945 -0.305054)
			(stroke
				(width 0.1)
				(type default)
			)
			(layer "B.Fab")
		)
		(fp_line
			(start 0.67945 -0.305054)
			(end 0.12065 -0.305054)
			(stroke
				(width 0.1)
				(type default)
			)
			(layer "B.Fab")
		)
		(fp_line
			(start 0.12065 0.3048)
			(end 0.67945 0.3048)
			(stroke
				(width 0.1)
				(type default)
			)
			(layer "B.Fab")
		)
		(fp_line
			(start 0.12065 0.2794)
			(end 0.12065 0.3048)
			(stroke
				(width 0.1)
				(type default)
			)
			(layer "B.Fab")
		)
		(fp_line
			(start 0.12065 -0.2794)
			(end -0.12065 -0.2794)
			(stroke
				(width 0.1)
				(type default)
			)
			(layer "B.Fab")
		)
		(fp_line
			(start 0.12065 -0.305054)
			(end 0.12065 -0.2794)
			(stroke
				(width 0.1)
				(type default)
			)
			(layer "B.Fab")
		)
		(fp_line
			(start -0.120396 0.3048)
			(end -0.120396 0.2794)
			(stroke
				(width 0.1)
				(type default)
			)
			(layer "B.Fab")
		)
		(fp_line
			(start -0.120396 0.2794)
			(end 0.12065 0.2794)
			(stroke
				(width 0.1)
				(type default)
			)
			(layer "B.Fab")
		)
		(fp_line
			(start -0.12065 -0.2794)
			(end -0.12065 -0.3048)
			(stroke
				(width 0.1)
				(type default)
			)
			(layer "B.Fab")
		)
		(fp_line
			(start -0.12065 -0.3048)
			(end -0.67945 -0.3048)
			(stroke
				(width 0.1)
				(type default)
			)
			(layer "B.Fab")
		)
		(fp_line
			(start -0.67945 0.3048)
			(end -0.120396 0.3048)
			(stroke
				(width 0.1)
				(type default)
			)
			(layer "B.Fab")
		)
		(fp_line
			(start -0.67945 -0.3048)
			(end -0.67945 0.3048)
			(stroke
				(width 0.1)
				(type default)
			)
			(layer "B.Fab")
		)
		(pad "1" smd circle
			(at 0.40005 0)
			(size 0 0)
			(layers "B.Cu" "B.Mask" "B.Paste")
			(net "PWRGD_SYS_PWROK")
		)
		(pad "2" smd circle
			(at -0.40005 0)
			(size 0 0)
			(layers "B.Cu" "B.Mask" "B.Paste")
			(net "PWRGD_SYS_PWROK_R1")
		)
	)
	(footprint ""
		(layer "B.Cu")
		(at 17.864328 -96.782128 -90)
		(property "Reference" "C254"
			(at 0 0 90)
			(layer "B.SilkS")
			(hide yes)
			(effects
				(font
					(size 1.27 1.27)
				)
				(justify mirror)
			)
		)
		(property "Value" ""
			(at 0 0 90)
			(layer "B.Fab")
			(effects
				(font
					(size 1.27 1.27)
				)
				(justify mirror)
			)
		)
		(duplicate_pad_numbers_are_jumpers no)
		(fp_line
			(start -0.69215 0.2921)
			(end 0.69215 0.2921)
			(stroke
				(width 0.1524)
				(type default)
			)
			(layer "B.SilkS")
		)
		(fp_line
			(start 0.69215 0.2921)
			(end 0.69215 -0.2921)
			(stroke
				(width 0.1524)
				(type default)
			)
			(layer "B.SilkS")
		)
		(fp_line
			(start -0.69215 -0.2921)
			(end -0.69215 0.2921)
			(stroke
				(width 0.1524)
				(type default)
			)
			(layer "B.SilkS")
		)
		(fp_line
			(start 0.69215 -0.2921)
			(end -0.69215 -0.2921)
			(stroke
				(width 0.1524)
				(type default)
			)
			(layer "B.SilkS")
		)
		(fp_line
			(start -0.51435 0.2794)
			(end 0.51435 0.2794)
			(stroke
				(width 0.1)
				(type default)
			)
			(layer "B.Fab")
		)
		(fp_line
			(start 0.51435 0.2794)
			(end 0.51435 -0.2794)
			(stroke
				(width 0.1)
				(type default)
			)
			(layer "B.Fab")
		)
		(fp_line
			(start -0.51435 -0.2794)
			(end -0.51435 0.2794)
			(stroke
				(width 0.1)
				(type default)
			)
			(layer "B.Fab")
		)
		(fp_line
			(start 0.51435 -0.2794)
			(end -0.51435 -0.2794)
			(stroke
				(width 0.1)
				(type default)
			)
			(layer "B.Fab")
		)
		(pad "1" smd circle
			(at 0.40005 0 90)
			(size 0 0)
			(layers "B.Cu" "B.Mask" "B.Paste")
			(net "VCCIO1")
		)
		(pad "2" smd circle
			(at -0.40005 0 90)
			(size 0 0)
			(layers "B.Cu" "B.Mask" "B.Paste")
			(net "GND")
		)
		(zone
			(layer "B.Cu")
			(hatch none 0.5)
			(connect_pads
				(clearance 0)
			)
			(min_thickness 0.25)
			(keepout
				(tracks not_allowed)
				(vias allowed)
				(pads allowed)
				(copperpour not_allowed)
				(footprints allowed)
			)
			(placement
				(enabled no)
				(sheetname "")
			)
			(fill
				(thermal_gap 0.5)
				(thermal_bridge_width 0.5)
				(island_removal_mode 0)
			)
			(polygon
				(pts
					(xy 17.776698 -96.591628) (xy 17.718532 -96.683068) (xy 17.718532 -96.882458) (xy 17.776698 -96.972628)
					(xy 17.951958 -96.972628) (xy 18.010378 -96.882458) (xy 18.010378 -96.683068) (xy 17.952212 -96.591628)
				)
			)
		)
	)
	(footprint ""
		(layer "B.Cu")
		(at 39.8526 -30.2768 180)
		(property "Reference" "R761"
			(at 0 0 0)
			(layer "B.SilkS")
			(hide yes)
			(effects
				(font
					(size 1.27 1.27)
				)
				(justify mirror)
			)
		)
		(property "Value" ""
			(at 0 0 0)
			(layer "B.Fab")
			(effects
				(font
					(size 1.27 1.27)
				)
				(justify mirror)
			)
		)
		(duplicate_pad_numbers_are_jumpers no)
		(fp_line
			(start 0.7874 0.4064)
			(end 0.7874 -0.4064)
			(stroke
				(width 0.1524)
				(type default)
			)
			(layer "B.SilkS")
		)
		(fp_line
			(start 0.7874 -0.4064)
			(end -0.7874 -0.4064)
			(stroke
				(width 0.1524)
				(type default)
			)
			(layer "B.SilkS")
		)
		(fp_line
			(start -0.7874 0.4064)
			(end 0.7874 0.4064)
			(stroke
				(width 0.1524)
				(type default)
			)
			(layer "B.SilkS")
		)
		(fp_line
			(start -0.7874 -0.4064)
			(end -0.7874 0.4064)
			(stroke
				(width 0.1524)
				(type default)
			)
			(layer "B.SilkS")
		)
		(fp_line
			(start 0.67945 0.3048)
			(end 0.67945 -0.305054)
			(stroke
				(width 0.1)
				(type default)
			)
			(layer "B.Fab")
		)
		(fp_line
			(start 0.67945 -0.305054)
			(end 0.12065 -0.305054)
			(stroke
				(width 0.1)
				(type default)
			)
			(layer "B.Fab")
		)
		(fp_line
			(start 0.12065 0.3048)
			(end 0.67945 0.3048)
			(stroke
				(width 0.1)
				(type default)
			)
			(layer "B.Fab")
		)
		(fp_line
			(start 0.12065 0.2794)
			(end 0.12065 0.3048)
			(stroke
				(width 0.1)
				(type default)
			)
			(layer "B.Fab")
		)
		(fp_line
			(start 0.12065 -0.2794)
			(end -0.12065 -0.2794)
			(stroke
				(width 0.1)
				(type default)
			)
			(layer "B.Fab")
		)
		(fp_line
			(start 0.12065 -0.305054)
			(end 0.12065 -0.2794)
			(stroke
				(width 0.1)
				(type default)
			)
			(layer "B.Fab")
		)
		(fp_line
			(start -0.120396 0.3048)
			(end -0.120396 0.2794)
			(stroke
				(width 0.1)
				(type default)
			)
			(layer "B.Fab")
		)
		(fp_line
			(start -0.120396 0.2794)
			(end 0.12065 0.2794)
			(stroke
				(width 0.1)
				(type default)
			)
			(layer "B.Fab")
		)
		(fp_line
			(start -0.12065 -0.2794)
			(end -0.12065 -0.3048)
			(stroke
				(width 0.1)
				(type default)
			)
			(layer "B.Fab")
		)
		(fp_line
			(start -0.12065 -0.3048)
			(end -0.67945 -0.3048)
			(stroke
				(width 0.1)
				(type default)
			)
			(layer "B.Fab")
		)
		(fp_line
			(start -0.67945 0.3048)
			(end -0.120396 0.3048)
			(stroke
				(width 0.1)
				(type default)
			)
			(layer "B.Fab")
		)
		(fp_line
			(start -0.67945 -0.3048)
			(end -0.67945 0.3048)
			(stroke
				(width 0.1)
				(type default)
			)
			(layer "B.Fab")
		)
		(pad "1" smd circle
			(at 0.40005 0)
			(size 0 0)
			(layers "B.Cu" "B.Mask" "B.Paste")
			(net "UART_6_BMC_TXD")
		)
		(pad "2" smd circle
			(at -0.40005 0)
			(size 0 0)
			(layers "B.Cu" "B.Mask" "B.Paste")
			(net "UART_6_BMC_R_TXD")
		)
	)
	(footprint ""
		(layer "B.Cu")
		(at 46.9646 -70.9168 180)
		(property "Reference" "R679"
			(at 0 0 0)
			(layer "B.SilkS")
			(hide yes)
			(effects
				(font
					(size 1.27 1.27)
				)
				(justify mirror)
			)
		)
		(property "Value" ""
			(at 0 0 0)
			(layer "B.Fab")
			(effects
				(font
					(size 1.27 1.27)
				)
				(justify mirror)
			)
		)
		(duplicate_pad_numbers_are_jumpers no)
		(fp_line
			(start 0.7874 0.4064)
			(end 0.7874 -0.4064)
			(stroke
				(width 0.1524)
				(type default)
			)
			(layer "B.SilkS")
		)
		(fp_line
			(start 0.7874 -0.4064)
			(end -0.7874 -0.4064)
			(stroke
				(width 0.1524)
				(type default)
			)
			(layer "B.SilkS")
		)
		(fp_line
			(start -0.7874 0.4064)
			(end 0.7874 0.4064)
			(stroke
				(width 0.1524)
				(type default)
			)
			(layer "B.SilkS")
		)
		(fp_line
			(start -0.7874 -0.4064)
			(end -0.7874 0.4064)
			(stroke
				(width 0.1524)
				(type default)
			)
			(layer "B.SilkS")
		)
		(fp_line
			(start 0.67945 0.3048)
			(end 0.67945 -0.305054)
			(stroke
				(width 0.1)
				(type default)
			)
			(layer "B.Fab")
		)
		(fp_line
			(start 0.67945 -0.305054)
			(end 0.12065 -0.305054)
			(stroke
				(width 0.1)
				(type default)
			)
			(layer "B.Fab")
		)
		(fp_line
			(start 0.12065 0.3048)
			(end 0.67945 0.3048)
			(stroke
				(width 0.1)
				(type default)
			)
			(layer "B.Fab")
		)
		(fp_line
			(start 0.12065 0.2794)
			(end 0.12065 0.3048)
			(stroke
				(width 0.1)
				(type default)
			)
			(layer "B.Fab")
		)
		(fp_line
			(start 0.12065 -0.2794)
			(end -0.12065 -0.2794)
			(stroke
				(width 0.1)
				(type default)
			)
			(layer "B.Fab")
		)
		(fp_line
			(start 0.12065 -0.305054)
			(end 0.12065 -0.2794)
			(stroke
				(width 0.1)
				(type default)
			)
			(layer "B.Fab")
		)
		(fp_line
			(start -0.120396 0.3048)
			(end -0.120396 0.2794)
			(stroke
				(width 0.1)
				(type default)
			)
			(layer "B.Fab")
		)
		(fp_line
			(start -0.120396 0.2794)
			(end 0.12065 0.2794)
			(stroke
				(width 0.1)
				(type default)
			)
			(layer "B.Fab")
		)
		(fp_line
			(start -0.12065 -0.2794)
			(end -0.12065 -0.3048)
			(stroke
				(width 0.1)
				(type default)
			)
			(layer "B.Fab")
		)
		(fp_line
			(start -0.12065 -0.3048)
			(end -0.67945 -0.3048)
			(stroke
				(width 0.1)
				(type default)
			)
			(layer "B.Fab")
		)
		(fp_line
			(start -0.67945 0.3048)
			(end -0.120396 0.3048)
			(stroke
				(width 0.1)
				(type default)
			)
			(layer "B.Fab")
		)
		(fp_line
			(start -0.67945 -0.3048)
			(end -0.67945 0.3048)
			(stroke
				(width 0.1)
				(type default)
			)
			(layer "B.Fab")
		)
		(pad "1" smd circle
			(at 0.40005 0)
			(size 0 0)
			(layers "B.Cu" "B.Mask" "B.Paste")
			(net "SPI_BMC_MOSI_IO0_R")
		)
		(pad "2" smd circle
			(at -0.40005 0)
			(size 0 0)
			(layers "B.Cu" "B.Mask" "B.Paste")
			(net "QSPI_2_PLD_IO0")
		)
	)
	(footprint ""
		(layer "B.Cu")
		(at 4.2672 -28.1686 -90)
		(property "Reference" "R102"
			(at 0 0 90)
			(layer "B.SilkS")
			(hide yes)
			(effects
				(font
					(size 1.27 1.27)
				)
				(justify mirror)
			)
		)
		(property "Value" ""
			(at 0 0 90)
			(layer "B.Fab")
			(effects
				(font
					(size 1.27 1.27)
				)
				(justify mirror)
			)
		)
		(duplicate_pad_numbers_are_jumpers no)
		(fp_line
			(start -0.7874 0.4064)
			(end 0.7874 0.4064)
			(stroke
				(width 0.1524)
				(type default)
			)
			(layer "B.SilkS")
		)
		(fp_line
			(start 0.7874 0.4064)
			(end 0.7874 -0.4064)
			(stroke
				(width 0.1524)
				(type default)
			)
			(layer "B.SilkS")
		)
		(fp_line
			(start -0.7874 -0.4064)
			(end -0.7874 0.4064)
			(stroke
				(width 0.1524)
				(type default)
			)
			(layer "B.SilkS")
		)
		(fp_line
			(start 0.7874 -0.4064)
			(end -0.7874 -0.4064)
			(stroke
				(width 0.1524)
				(type default)
			)
			(layer "B.SilkS")
		)
		(fp_line
			(start -0.67945 0.3048)
			(end -0.120396 0.3048)
			(stroke
				(width 0.1)
				(type default)
			)
			(layer "B.Fab")
		)
		(fp_line
			(start -0.120396 0.3048)
			(end -0.120396 0.2794)
			(stroke
				(width 0.1)
				(type default)
			)
			(layer "B.Fab")
		)
		(fp_line
			(start 0.12065 0.3048)
			(end 0.67945 0.3048)
			(stroke
				(width 0.1)
				(type default)
			)
			(layer "B.Fab")
		)
		(fp_line
			(start 0.67945 0.3048)
			(end 0.67945 -0.305054)
			(stroke
				(width 0.1)
				(type default)
			)
			(layer "B.Fab")
		)
		(fp_line
			(start -0.120396 0.2794)
			(end 0.12065 0.2794)
			(stroke
				(width 0.1)
				(type default)
			)
			(layer "B.Fab")
		)
		(fp_line
			(start 0.12065 0.2794)
			(end 0.12065 0.3048)
			(stroke
				(width 0.1)
				(type default)
			)
			(layer "B.Fab")
		)
		(fp_line
			(start -0.12065 -0.2794)
			(end -0.12065 -0.3048)
			(stroke
				(width 0.1)
				(type default)
			)
			(layer "B.Fab")
		)
		(fp_line
			(start 0.12065 -0.2794)
			(end -0.12065 -0.2794)
			(stroke
				(width 0.1)
				(type default)
			)
			(layer "B.Fab")
		)
		(fp_line
			(start -0.67945 -0.3048)
			(end -0.67945 0.3048)
			(stroke
				(width 0.1)
				(type default)
			)
			(layer "B.Fab")
		)
		(fp_line
			(start -0.12065 -0.3048)
			(end -0.67945 -0.3048)
			(stroke
				(width 0.1)
				(type default)
			)
			(layer "B.Fab")
		)
		(fp_line
			(start 0.12065 -0.305054)
			(end 0.12065 -0.2794)
			(stroke
				(width 0.1)
				(type default)
			)
			(layer "B.Fab")
		)
		(fp_line
			(start 0.67945 -0.305054)
			(end 0.12065 -0.305054)
			(stroke
				(width 0.1)
				(type default)
			)
			(layer "B.Fab")
		)
		(pad "1" smd circle
			(at 0.40005 0 90)
			(size 0 0)
			(layers "B.Cu" "B.Mask" "B.Paste")
			(net "UART_BMC_5_TXD_BUF")
		)
		(pad "2" smd circle
			(at -0.40005 0 90)
			(size 0 0)
			(layers "B.Cu" "B.Mask" "B.Paste")
			(net "UART_BMC_5_TXD_BUF_R")
		)
	)
	(footprint ""
		(layer "B.Cu")
		(at 39.497 -6.731 -90)
		(property "Reference" "R85"
			(at 0 0 90)
			(layer "B.SilkS")
			(hide yes)
			(effects
				(font
					(size 1.27 1.27)
				)
				(justify mirror)
			)
		)
		(property "Value" ""
			(at 0 0 90)
			(layer "B.Fab")
			(effects
				(font
					(size 1.27 1.27)
				)
				(justify mirror)
			)
		)
		(duplicate_pad_numbers_are_jumpers no)
		(fp_line
			(start -0.7874 0.4064)
			(end 0.7874 0.4064)
			(stroke
				(width 0.1524)
				(type default)
			)
			(layer "B.SilkS")
		)
		(fp_line
			(start 0.7874 0.4064)
			(end 0.7874 -0.4064)
			(stroke
				(width 0.1524)
				(type default)
			)
			(layer "B.SilkS")
		)
		(fp_line
			(start -0.7874 -0.4064)
			(end -0.7874 0.4064)
			(stroke
				(width 0.1524)
				(type default)
			)
			(layer "B.SilkS")
		)
		(fp_line
			(start 0.7874 -0.4064)
			(end -0.7874 -0.4064)
			(stroke
				(width 0.1524)
				(type default)
			)
			(layer "B.SilkS")
		)
		(fp_line
			(start -0.67945 0.3048)
			(end -0.120396 0.3048)
			(stroke
				(width 0.1)
				(type default)
			)
			(layer "B.Fab")
		)
		(fp_line
			(start -0.120396 0.3048)
			(end -0.120396 0.2794)
			(stroke
				(width 0.1)
				(type default)
			)
			(layer "B.Fab")
		)
		(fp_line
			(start 0.12065 0.3048)
			(end 0.67945 0.3048)
			(stroke
				(width 0.1)
				(type default)
			)
			(layer "B.Fab")
		)
		(fp_line
			(start 0.67945 0.3048)
			(end 0.67945 -0.305054)
			(stroke
				(width 0.1)
				(type default)
			)
			(layer "B.Fab")
		)
		(fp_line
			(start -0.120396 0.2794)
			(end 0.12065 0.2794)
			(stroke
				(width 0.1)
				(type default)
			)
			(layer "B.Fab")
		)
		(fp_line
			(start 0.12065 0.2794)
			(end 0.12065 0.3048)
			(stroke
				(width 0.1)
				(type default)
			)
			(layer "B.Fab")
		)
		(fp_line
			(start -0.12065 -0.2794)
			(end -0.12065 -0.3048)
			(stroke
				(width 0.1)
				(type default)
			)
			(layer "B.Fab")
		)
		(fp_line
			(start 0.12065 -0.2794)
			(end -0.12065 -0.2794)
			(stroke
				(width 0.1)
				(type default)
			)
			(layer "B.Fab")
		)
		(fp_line
			(start -0.67945 -0.3048)
			(end -0.67945 0.3048)
			(stroke
				(width 0.1)
				(type default)
			)
			(layer "B.Fab")
		)
		(fp_line
			(start -0.12065 -0.3048)
			(end -0.67945 -0.3048)
			(stroke
				(width 0.1)
				(type default)
			)
			(layer "B.Fab")
		)
		(fp_line
			(start 0.12065 -0.305054)
			(end 0.12065 -0.2794)
			(stroke
				(width 0.1)
				(type default)
			)
			(layer "B.Fab")
		)
		(fp_line
			(start 0.67945 -0.305054)
			(end 0.12065 -0.305054)
			(stroke
				(width 0.1)
				(type default)
			)
			(layer "B.Fab")
		)
		(pad "1" smd circle
			(at 0.40005 0 90)
			(size 0 0)
			(layers "B.Cu" "B.Mask" "B.Paste")
			(net "V_VGAHS_BUF_R")
		)
		(pad "2" smd circle
			(at -0.40005 0 90)
			(size 0 0)
			(layers "B.Cu" "B.Mask" "B.Paste")
			(net "V_VGAHS_BUF")
		)
	)
	(footprint ""
		(layer "B.Cu")
		(at 51.2445 -89.5985 180)
		(property "Reference" "R720"
			(at 0 0 0)
			(layer "B.SilkS")
			(hide yes)
			(effects
				(font
					(size 1.27 1.27)
				)
				(justify mirror)
			)
		)
		(property "Value" ""
			(at 0 0 0)
			(layer "B.Fab")
			(effects
				(font
					(size 1.27 1.27)
				)
				(justify mirror)
			)
		)
		(duplicate_pad_numbers_are_jumpers no)
		(fp_line
			(start 0.7874 0.4064)
			(end 0.7874 -0.4064)
			(stroke
				(width 0.1524)
				(type default)
			)
			(layer "B.SilkS")
		)
		(fp_line
			(start 0.7874 -0.4064)
			(end -0.7874 -0.4064)
			(stroke
				(width 0.1524)
				(type default)
			)
			(layer "B.SilkS")
		)
		(fp_line
			(start -0.7874 0.4064)
			(end 0.7874 0.4064)
			(stroke
				(width 0.1524)
				(type default)
			)
			(layer "B.SilkS")
		)
		(fp_line
			(start -0.7874 -0.4064)
			(end -0.7874 0.4064)
			(stroke
				(width 0.1524)
				(type default)
			)
			(layer "B.SilkS")
		)
		(fp_line
			(start 0.67945 0.3048)
			(end 0.67945 -0.305054)
			(stroke
				(width 0.1)
				(type default)
			)
			(layer "B.Fab")
		)
		(fp_line
			(start 0.67945 -0.305054)
			(end 0.12065 -0.305054)
			(stroke
				(width 0.1)
				(type default)
			)
			(layer "B.Fab")
		)
		(fp_line
			(start 0.12065 0.3048)
			(end 0.67945 0.3048)
			(stroke
				(width 0.1)
				(type default)
			)
			(layer "B.Fab")
		)
		(fp_line
			(start 0.12065 0.2794)
			(end 0.12065 0.3048)
			(stroke
				(width 0.1)
				(type default)
			)
			(layer "B.Fab")
		)
		(fp_line
			(start 0.12065 -0.2794)
			(end -0.12065 -0.2794)
			(stroke
				(width 0.1)
				(type default)
			)
			(layer "B.Fab")
		)
		(fp_line
			(start 0.12065 -0.305054)
			(end 0.12065 -0.2794)
			(stroke
				(width 0.1)
				(type default)
			)
			(layer "B.Fab")
		)
		(fp_line
			(start -0.120396 0.3048)
			(end -0.120396 0.2794)
			(stroke
				(width 0.1)
				(type default)
			)
			(layer "B.Fab")
		)
		(fp_line
			(start -0.120396 0.2794)
			(end 0.12065 0.2794)
			(stroke
				(width 0.1)
				(type default)
			)
			(layer "B.Fab")
		)
		(fp_line
			(start -0.12065 -0.2794)
			(end -0.12065 -0.3048)
			(stroke
				(width 0.1)
				(type default)
			)
			(layer "B.Fab")
		)
		(fp_line
			(start -0.12065 -0.3048)
			(end -0.67945 -0.3048)
			(stroke
				(width 0.1)
				(type default)
			)
			(layer "B.Fab")
		)
		(fp_line
			(start -0.67945 0.3048)
			(end -0.120396 0.3048)
			(stroke
				(width 0.1)
				(type default)
			)
			(layer "B.Fab")
		)
		(fp_line
			(start -0.67945 -0.3048)
			(end -0.67945 0.3048)
			(stroke
				(width 0.1)
				(type default)
			)
			(layer "B.Fab")
		)
		(pad "1" smd circle
			(at 0.40005 0)
			(size 0 0)
			(layers "B.Cu" "B.Mask" "B.Paste")
			(net "FM_CPU_MSMI_CATERR_LVT3_N")
		)
		(pad "2" smd circle
			(at -0.40005 0)
			(size 0 0)
			(layers "B.Cu" "B.Mask" "B.Paste")
			(net "FM_CPU_MSMI_CATERR_LVT3_R3_N")
		)
	)
	(footprint ""
		(layer "B.Cu")
		(at 25.459436 -89.18702 180)
		(property "Reference" "C261"
			(at 0 0 0)
			(layer "B.SilkS")
			(hide yes)
			(effects
				(font
					(size 1.27 1.27)
				)
				(justify mirror)
			)
		)
		(property "Value" ""
			(at 0 0 0)
			(layer "B.Fab")
			(effects
				(font
					(size 1.27 1.27)
				)
				(justify mirror)
			)
		)
		(duplicate_pad_numbers_are_jumpers no)
		(fp_line
			(start 0.69215 0.2921)
			(end 0.69215 -0.2921)
			(stroke
				(width 0.1524)
				(type default)
			)
			(layer "B.SilkS")
		)
		(fp_line
			(start 0.69215 -0.2921)
			(end -0.69215 -0.2921)
			(stroke
				(width 0.1524)
				(type default)
			)
			(layer "B.SilkS")
		)
		(fp_line
			(start -0.69215 0.2921)
			(end 0.69215 0.2921)
			(stroke
				(width 0.1524)
				(type default)
			)
			(layer "B.SilkS")
		)
		(fp_line
			(start -0.69215 -0.2921)
			(end -0.69215 0.2921)
			(stroke
				(width 0.1524)
				(type default)
			)
			(layer "B.SilkS")
		)
		(fp_line
			(start 0.51435 0.2794)
			(end 0.51435 -0.2794)
			(stroke
				(width 0.1)
				(type default)
			)
			(layer "B.Fab")
		)
		(fp_line
			(start 0.51435 -0.2794)
			(end -0.51435 -0.2794)
			(stroke
				(width 0.1)
				(type default)
			)
			(layer "B.Fab")
		)
		(fp_line
			(start -0.51435 0.2794)
			(end 0.51435 0.2794)
			(stroke
				(width 0.1)
				(type default)
			)
			(layer "B.Fab")
		)
		(fp_line
			(start -0.51435 -0.2794)
			(end -0.51435 0.2794)
			(stroke
				(width 0.1)
				(type default)
			)
			(layer "B.Fab")
		)
		(pad "1" smd circle
			(at 0.40005 0)
			(size 0 0)
			(layers "B.Cu" "B.Mask" "B.Paste")
			(net "VCCIO0")
		)
		(pad "2" smd circle
			(at -0.40005 0)
			(size 0 0)
			(layers "B.Cu" "B.Mask" "B.Paste")
			(net "GND")
		)
		(zone
			(layer "B.Cu")
			(hatch none 0.5)
			(connect_pads
				(clearance 0)
			)
			(min_thickness 0.25)
			(keepout
				(tracks not_allowed)
				(vias allowed)
				(pads allowed)
				(copperpour not_allowed)
				(footprints allowed)
			)
			(placement
				(enabled no)
				(sheetname "")
			)
			(fill
				(thermal_gap 0.5)
				(thermal_bridge_width 0.5)
				(island_removal_mode 0)
			)
			(polygon
				(pts
					(xy 25.268936 -89.27465) (xy 25.360376 -89.332816) (xy 25.559766 -89.332816) (xy 25.649936 -89.27465)
					(xy 25.649936 -89.09939) (xy 25.559766 -89.04097) (xy 25.360376 -89.04097) (xy 25.268936 -89.099136)
				)
			)
		)
	)
	(footprint ""
		(layer "B.Cu")
		(at 61.57722 -61.985906 -90)
		(property "Reference" "C25"
			(at 0 0 90)
			(layer "B.SilkS")
			(hide yes)
			(effects
				(font
					(size 1.27 1.27)
				)
				(justify mirror)
			)
		)
		(property "Value" ""
			(at 0 0 90)
			(layer "B.Fab")
			(effects
				(font
					(size 1.27 1.27)
				)
				(justify mirror)
			)
		)
		(duplicate_pad_numbers_are_jumpers no)
		(fp_line
			(start -0.7874 0.4064)
			(end 0.7874 0.4064)
			(stroke
				(width 0.1524)
				(type default)
			)
			(layer "B.SilkS")
		)
		(fp_line
			(start 0.7874 0.4064)
			(end 0.7874 -0.10414)
			(stroke
				(width 0.1524)
				(type default)
			)
			(layer "B.SilkS")
		)
		(fp_line
			(start -0.7874 -0.15494)
			(end -0.7874 0.4064)
			(stroke
				(width 0.1524)
				(type default)
			)
			(layer "B.SilkS")
		)
		(fp_line
			(start 0.489966 -0.4064)
			(end -0.480314 -0.4064)
			(stroke
				(width 0.1524)
				(type default)
			)
			(layer "B.SilkS")
		)
		(fp_line
			(start -0.67945 0.3048)
			(end -0.120396 0.3048)
			(stroke
				(width 0.1)
				(type default)
			)
			(layer "B.Fab")
		)
		(fp_line
			(start -0.120396 0.3048)
			(end -0.120396 0.2794)
			(stroke
				(width 0.1)
				(type default)
			)
			(layer "B.Fab")
		)
		(fp_line
			(start 0.12065 0.3048)
			(end 0.67945 0.3048)
			(stroke
				(width 0.1)
				(type default)
			)
			(layer "B.Fab")
		)
		(fp_line
			(start 0.67945 0.3048)
			(end 0.67945 -0.305054)
			(stroke
				(width 0.1)
				(type default)
			)
			(layer "B.Fab")
		)
		(fp_line
			(start -0.120396 0.2794)
			(end 0.12065 0.2794)
			(stroke
				(width 0.1)
				(type default)
			)
			(layer "B.Fab")
		)
		(fp_line
			(start 0.12065 0.2794)
			(end 0.12065 0.3048)
			(stroke
				(width 0.1)
				(type default)
			)
			(layer "B.Fab")
		)
		(fp_line
			(start -0.12065 -0.2794)
			(end -0.12065 -0.3048)
			(stroke
				(width 0.1)
				(type default)
			)
			(layer "B.Fab")
		)
		(fp_line
			(start 0.12065 -0.2794)
			(end -0.12065 -0.2794)
			(stroke
				(width 0.1)
				(type default)
			)
			(layer "B.Fab")
		)
		(fp_line
			(start -0.67945 -0.3048)
			(end -0.67945 0.3048)
			(stroke
				(width 0.1)
				(type default)
			)
			(layer "B.Fab")
		)
		(fp_line
			(start -0.12065 -0.3048)
			(end -0.67945 -0.3048)
			(stroke
				(width 0.1)
				(type default)
			)
			(layer "B.Fab")
		)
		(fp_line
			(start 0.12065 -0.305054)
			(end 0.12065 -0.2794)
			(stroke
				(width 0.1)
				(type default)
			)
			(layer "B.Fab")
		)
		(fp_line
			(start 0.67945 -0.305054)
			(end 0.12065 -0.305054)
			(stroke
				(width 0.1)
				(type default)
			)
			(layer "B.Fab")
		)
		(pad "1" smd circle
			(at 0.40005 0 90)
			(size 0 0)
			(layers "B.Cu" "B.Mask" "B.Paste")
			(net "P2E_PCH_TX_DN")
		)
		(pad "2" smd circle
			(at -0.40005 0 90)
			(size 0 0)
			(layers "B.Cu" "B.Mask" "B.Paste")
			(net "P2E_PCH_TX_C_DN")
		)
	)
	(footprint ""
		(layer "B.Cu")
		(at 30.988 -67.437 -90)
		(property "Reference" "U7"
			(at 1.0922 1.77927 270)
			(unlocked yes)
			(layer "B.SilkS")
			(effects
				(font
					(size 0.7874 0.5842)
					(thickness 0.1524)
				)
				(justify mirror)
			)
		)
		(property "Value" ""
			(at 0 0 90)
			(layer "B.Fab")
			(effects
				(font
					(size 1.27 1.27)
				)
				(justify mirror)
			)
		)
		(duplicate_pad_numbers_are_jumpers no)
		(fp_line
			(start -1.7272 1.1176)
			(end 1.7272 1.1176)
			(stroke
				(width 0.1524)
				(type default)
			)
			(layer "B.SilkS")
		)
		(fp_line
			(start 1.7272 1.1176)
			(end 1.7272 -1.1176)
			(stroke
				(width 0.1524)
				(type default)
			)
			(layer "B.SilkS")
		)
		(fp_line
			(start 0 -0.7366)
			(end 0.254 -1.1176)
			(stroke
				(width 0.1524)
				(type default)
			)
			(layer "B.SilkS")
		)
		(fp_line
			(start -1.7272 -1.1176)
			(end -1.7272 1.1176)
			(stroke
				(width 0.1524)
				(type default)
			)
			(layer "B.SilkS")
		)
		(fp_line
			(start -1.7272 -1.1176)
			(end -0.254 -1.1176)
			(stroke
				(width 0.1524)
				(type default)
			)
			(layer "B.SilkS")
		)
		(fp_line
			(start -0.254 -1.1176)
			(end 0 -0.7366)
			(stroke
				(width 0.1524)
				(type default)
			)
			(layer "B.SilkS")
		)
		(fp_line
			(start 0.254 -1.1176)
			(end 1.7272 -1.1176)
			(stroke
				(width 0.1524)
				(type default)
			)
			(layer "B.SilkS")
		)
		(fp_poly
			(pts
				(xy 2.9718 -0.395986) (xy 3.7338 -0.014986) (xy 3.7338 -0.776986)
			)
			(stroke
				(width 0)
				(type default)
			)
			(fill yes)
			(layer "B.SilkS")
		)
		(fp_line
			(start -1.5748 1.1176)
			(end -1.5748 -1.1176)
			(stroke
				(width 0.1)
				(type default)
			)
			(layer "B.Fab")
		)
		(fp_line
			(start 1.5748 1.1176)
			(end -1.5748 1.1176)
			(stroke
				(width 0.1)
				(type default)
			)
			(layer "B.Fab")
		)
		(fp_line
			(start -1.5748 -1.1176)
			(end 1.5748 -1.1176)
			(stroke
				(width 0.1)
				(type default)
			)
			(layer "B.Fab")
		)
		(fp_line
			(start 1.5748 -1.1176)
			(end 1.5748 1.1176)
			(stroke
				(width 0.1)
				(type default)
			)
			(layer "B.Fab")
		)
		(fp_poly
			(pts
				(xy 1.9558 -0.649986) (xy 2.7178 -0.268986) (xy 2.7178 -1.030986)
			)
			(stroke
				(width 0)
				(type default)
			)
			(fill yes)
			(layer "B.Fab")
		)
		(pad "1" smd rect
			(at 0.999998 -0.649986 180)
			(size 0.3556 1.1176)
			(layers "B.Cu" "B.Mask" "B.Paste")
			(net "SPA_SOUT_SW_DBG_R")
		)
		(pad "2" smd rect
			(at 0.999998 0 180)
			(size 0.3556 1.1176)
			(layers "B.Cu" "B.Mask" "B.Paste")
			(net "GND")
		)
		(pad "3" smd rect
			(at 0.999998 0.649986 180)
			(size 0.3556 1.1176)
			(layers "B.Cu" "B.Mask" "B.Paste")
			(net "UART_SYS_DBG_TX_R")
		)
		(pad "4" smd rect
			(at -0.999998 0.649986 180)
			(size 0.3556 1.1176)
			(layers "B.Cu" "B.Mask" "B.Paste")
			(net "SPA_SOUT_SW_BUF_R")
		)
		(pad "5" smd rect
			(at -0.999998 0 180)
			(size 0.3556 1.1176)
			(layers "B.Cu" "B.Mask" "B.Paste")
			(net "P3V3_AUX")
		)
		(pad "6" smd rect
			(at -0.999998 -0.649986 180)
			(size 0.3556 1.1176)
			(layers "B.Cu" "B.Mask" "B.Paste")
			(net "FM_DBG_SW_N")
		)
	)
	(footprint ""
		(layer "B.Cu")
		(at 56.727852 -30.867604 -90)
		(property "Reference" "R259"
			(at 0 0 90)
			(layer "B.SilkS")
			(hide yes)
			(effects
				(font
					(size 1.27 1.27)
				)
				(justify mirror)
			)
		)
		(property "Value" ""
			(at 0 0 90)
			(layer "B.Fab")
			(effects
				(font
					(size 1.27 1.27)
				)
				(justify mirror)
			)
		)
		(duplicate_pad_numbers_are_jumpers no)
		(fp_line
			(start -0.7874 0.4064)
			(end 0.7874 0.4064)
			(stroke
				(width 0.1524)
				(type default)
			)
			(layer "B.SilkS")
		)
		(fp_line
			(start 0.7874 0.4064)
			(end 0.7874 -0.4064)
			(stroke
				(width 0.1524)
				(type default)
			)
			(layer "B.SilkS")
		)
		(fp_line
			(start -0.7874 -0.4064)
			(end -0.7874 0.4064)
			(stroke
				(width 0.1524)
				(type default)
			)
			(layer "B.SilkS")
		)
		(fp_line
			(start 0.7874 -0.4064)
			(end -0.7874 -0.4064)
			(stroke
				(width 0.1524)
				(type default)
			)
			(layer "B.SilkS")
		)
		(fp_line
			(start -0.67945 0.3048)
			(end -0.120396 0.3048)
			(stroke
				(width 0.1)
				(type default)
			)
			(layer "B.Fab")
		)
		(fp_line
			(start -0.120396 0.3048)
			(end -0.120396 0.2794)
			(stroke
				(width 0.1)
				(type default)
			)
			(layer "B.Fab")
		)
		(fp_line
			(start 0.12065 0.3048)
			(end 0.67945 0.3048)
			(stroke
				(width 0.1)
				(type default)
			)
			(layer "B.Fab")
		)
		(fp_line
			(start 0.67945 0.3048)
			(end 0.67945 -0.305054)
			(stroke
				(width 0.1)
				(type default)
			)
			(layer "B.Fab")
		)
		(fp_line
			(start -0.120396 0.2794)
			(end 0.12065 0.2794)
			(stroke
				(width 0.1)
				(type default)
			)
			(layer "B.Fab")
		)
		(fp_line
			(start 0.12065 0.2794)
			(end 0.12065 0.3048)
			(stroke
				(width 0.1)
				(type default)
			)
			(layer "B.Fab")
		)
		(fp_line
			(start -0.12065 -0.2794)
			(end -0.12065 -0.3048)
			(stroke
				(width 0.1)
				(type default)
			)
			(layer "B.Fab")
		)
		(fp_line
			(start 0.12065 -0.2794)
			(end -0.12065 -0.2794)
			(stroke
				(width 0.1)
				(type default)
			)
			(layer "B.Fab")
		)
		(fp_line
			(start -0.67945 -0.3048)
			(end -0.67945 0.3048)
			(stroke
				(width 0.1)
				(type default)
			)
			(layer "B.Fab")
		)
		(fp_line
			(start -0.12065 -0.3048)
			(end -0.67945 -0.3048)
			(stroke
				(width 0.1)
				(type default)
			)
			(layer "B.Fab")
		)
		(fp_line
			(start 0.12065 -0.305054)
			(end 0.12065 -0.2794)
			(stroke
				(width 0.1)
				(type default)
			)
			(layer "B.Fab")
		)
		(fp_line
			(start 0.67945 -0.305054)
			(end 0.12065 -0.305054)
			(stroke
				(width 0.1)
				(type default)
			)
			(layer "B.Fab")
		)
		(pad "1" smd circle
			(at 0.40005 0 90)
			(size 0 0)
			(layers "B.Cu" "B.Mask" "B.Paste")
			(net "P3V3_AUX")
		)
		(pad "2" smd circle
			(at -0.40005 0 90)
			(size 0 0)
			(layers "B.Cu" "B.Mask" "B.Paste")
			(net "SMB_BMC_MM8_SDA")
		)
	)
	(footprint ""
		(layer "B.Cu")
		(at 101.2825 18.001488 -90)
		(property "Reference" "J27"
			(at 1.048512 2.88417 270)
			(unlocked yes)
			(layer "B.SilkS")
			(effects
				(font
					(size 0.7874 0.5842)
					(thickness 0.1524)
				)
				(justify left mirror)
			)
		)
		(property "Value" ""
			(at 0 0 90)
			(layer "B.Fab")
			(effects
				(font
					(size 1.27 1.27)
				)
				(justify mirror)
			)
		)
		(duplicate_pad_numbers_are_jumpers no)
		(fp_line
			(start -1.2192 2.1082)
			(end 1.2192 2.1082)
			(stroke
				(width 0.1524)
				(type default)
			)
			(layer "B.SilkS")
		)
		(fp_line
			(start 1.2192 2.1082)
			(end 1.2192 -2.1082)
			(stroke
				(width 0.1524)
				(type default)
			)
			(layer "B.SilkS")
		)
		(fp_line
			(start -1.2192 0.465582)
			(end -1.2192 2.1082)
			(stroke
				(width 0.1524)
				(type default)
			)
			(layer "B.SilkS")
		)
		(fp_line
			(start -1.2192 -2.1082)
			(end -1.2192 -0.45085)
			(stroke
				(width 0.1524)
				(type default)
			)
			(layer "B.SilkS")
		)
		(fp_line
			(start 1.2192 -2.1082)
			(end -1.2192 -2.1082)
			(stroke
				(width 0.1524)
				(type default)
			)
			(layer "B.SilkS")
		)
		(pad "" np_thru_hole circle
			(at -3.4671 -1.27 180)
			(size 1.0414 1.0414)
			(drill 1.0414)
			(layers "*.Cu" "*.Mask")
			(clearance 0.381)
			(thermal_gap 0.381)
		)
		(pad "" np_thru_hole circle
			(at -3.4671 1.27 180)
			(size 1.0414 1.0414)
			(drill 1.0414)
			(layers "*.Cu" "*.Mask")
			(clearance 0.381)
			(thermal_gap 0.381)
		)
		(pad "" np_thru_hole circle
			(at 2.8829 -1.27 180)
			(size 1.0414 1.0414)
			(drill 1.0414)
			(layers "*.Cu" "*.Mask")
			(clearance 0.381)
			(thermal_gap 0.381)
		)
		(pad "" np_thru_hole circle
			(at 2.8829 1.27 180)
			(size 1.0414 1.0414)
			(drill 1.0414)
			(layers "*.Cu" "*.Mask")
			(clearance 0.381)
			(thermal_gap 0.381)
		)
		(pad "1" smd rect
			(at -0.8255 -0.249936 180)
			(size 0.3048 0.508)
			(layers "B.Cu" "B.Mask" "B.Paste")
			(net "85_10INCH_BOT_DN")
		)
		(pad "2" smd rect
			(at -0.8255 0.249936 180)
			(size 0.3048 0.508)
			(layers "B.Cu" "B.Mask" "B.Paste")
			(net "85_10INCH_BOT_DP")
		)
		(pad "3" smd circle
			(at 0 0 90)
			(size 0 0)
			(layers "B.Cu" "B.Mask" "B.Paste")
			(net "GND_P1")
		)
		(zone
			(layers "F.Cu" "B.Cu" "In1.Cu" "In2.Cu" "In3.Cu" "In4.Cu" "In5.Cu" "In6.Cu"
				"In7.Cu" "In8.Cu" "In9.Cu" "In10.Cu"
			)
			(hatch none 0.5)
			(connect_pads
				(clearance 0)
			)
			(min_thickness 0.25)
			(keepout
				(tracks not_allowed)
				(vias allowed)
				(pads allowed)
				(copperpour not_allowed)
				(footprints allowed)
			)
			(placement
				(enabled no)
				(sheetname "")
			)
			(fill
				(thermal_gap 0.5)
				(thermal_bridge_width 0.5)
				(island_removal_mode 0)
			)
			(polygon
				(pts
					(arc
						(start 100.9396 14.534388)
						(mid 99.0854 14.534388)
						(end 100.9396 14.534388)
					)
				)
			)
		)
		(zone
			(layers "F.Cu" "B.Cu" "In1.Cu" "In2.Cu" "In3.Cu" "In4.Cu" "In5.Cu" "In6.Cu"
				"In7.Cu" "In8.Cu" "In9.Cu" "In10.Cu"
			)
			(hatch none 0.5)
			(connect_pads
				(clearance 0)
			)
			(min_thickness 0.25)
			(keepout
				(tracks not_allowed)
				(vias allowed)
				(pads allowed)
				(copperpour not_allowed)
				(footprints allowed)
			)
			(placement
				(enabled no)
				(sheetname "")
			)
			(fill
				(thermal_gap 0.5)
				(thermal_bridge_width 0.5)
				(island_removal_mode 0)
			)
			(polygon
				(pts
					(arc
						(start 100.9396 20.884388)
						(mid 99.0854 20.884388)
						(end 100.9396 20.884388)
					)
				)
			)
		)
		(zone
			(layers "F.Cu" "B.Cu" "In1.Cu" "In2.Cu" "In3.Cu" "In4.Cu" "In5.Cu" "In6.Cu"
				"In7.Cu" "In8.Cu" "In9.Cu" "In10.Cu"
			)
			(hatch none 0.5)
			(connect_pads
				(clearance 0)
			)
			(min_thickness 0.25)
			(keepout
				(tracks not_allowed)
				(vias allowed)
				(pads allowed)
				(copperpour not_allowed)
				(footprints allowed)
			)
			(placement
				(enabled no)
				(sheetname "")
			)
			(fill
				(thermal_gap 0.5)
				(thermal_bridge_width 0.5)
				(island_removal_mode 0)
			)
			(polygon
				(pts
					(arc
						(start 103.4796 14.534388)
						(mid 101.6254 14.534388)
						(end 103.4796 14.534388)
					)
				)
			)
		)
		(zone
			(layers "F.Cu" "B.Cu" "In1.Cu" "In2.Cu" "In3.Cu" "In4.Cu" "In5.Cu" "In6.Cu"
				"In7.Cu" "In8.Cu" "In9.Cu" "In10.Cu"
			)
			(hatch none 0.5)
			(connect_pads
				(clearance 0)
			)
			(min_thickness 0.25)
			(keepout
				(tracks not_allowed)
				(vias allowed)
				(pads allowed)
				(copperpour not_allowed)
				(footprints allowed)
			)
			(placement
				(enabled no)
				(sheetname "")
			)
			(fill
				(thermal_gap 0.5)
				(thermal_bridge_width 0.5)
				(island_removal_mode 0)
			)
			(polygon
				(pts
					(arc
						(start 103.4796 20.884388)
						(mid 101.6254 20.884388)
						(end 103.4796 20.884388)
					)
				)
			)
		)
		(zone
			(layer "B.Cu")
			(hatch none 0.5)
			(connect_pads
				(clearance 0)
			)
			(min_thickness 0.25)
			(keepout
				(tracks not_allowed)
				(vias allowed)
				(pads allowed)
				(copperpour not_allowed)
				(footprints allowed)
			)
			(placement
				(enabled no)
				(sheetname "")
			)
			(fill
				(thermal_gap 0.5)
				(thermal_bridge_width 0.5)
				(island_removal_mode 0)
			)
			(polygon
				(pts
					(xy 101.83114 16.883888) (xy 101.735636 16.883888) (xy 101.735636 17.480788) (xy 101.329236 17.480788)
					(xy 101.329236 16.883888) (xy 101.235764 16.883888) (xy 101.235764 17.480788) (xy 100.829364 17.480788)
					(xy 100.829364 16.883888) (xy 100.73386 16.883888) (xy 100.73386 17.582388) (xy 101.83114 17.582388)
				)
			)
		)
	)
	(footprint ""
		(layer "B.Cu")
		(at 70.869556 -55.53202)
		(property "Reference" "L6"
			(at 0 0 0)
			(layer "B.SilkS")
			(hide yes)
			(effects
				(font
					(size 1.27 1.27)
				)
				(justify mirror)
			)
		)
		(property "Value" ""
			(at 0 0 0)
			(layer "B.Fab")
			(effects
				(font
					(size 1.27 1.27)
				)
				(justify mirror)
			)
		)
		(duplicate_pad_numbers_are_jumpers no)
		(fp_line
			(start -1.27 0.5842)
			(end -1.27 -0.5842)
			(stroke
				(width 0.1524)
				(type default)
			)
			(layer "B.SilkS")
		)
		(fp_line
			(start -1.27 0.5842)
			(end 1.27 0.5842)
			(stroke
				(width 0.1524)
				(type default)
			)
			(layer "B.SilkS")
		)
		(fp_line
			(start -0.127 0.5842)
			(end -0.127 -0.5842)
			(stroke
				(width 0.1524)
				(type default)
			)
			(layer "B.SilkS")
		)
		(fp_line
			(start 0.127 0.5842)
			(end 0.127 -0.5842)
			(stroke
				(width 0.1524)
				(type default)
			)
			(layer "B.SilkS")
		)
		(fp_line
			(start 1.27 -0.5842)
			(end -1.27 -0.5842)
			(stroke
				(width 0.1524)
				(type default)
			)
			(layer "B.SilkS")
		)
		(fp_line
			(start 1.27 -0.5588)
			(end 1.27 -0.5842)
			(stroke
				(width 0.1524)
				(type default)
			)
			(layer "B.SilkS")
		)
		(fp_line
			(start 1.27 0.5842)
			(end 1.27 -0.5842)
			(stroke
				(width 0.1524)
				(type default)
			)
			(layer "B.SilkS")
		)
		(fp_line
			(start -1.1938 -0.406654)
			(end -1.1938 0.4064)
			(stroke
				(width 0.1)
				(type default)
			)
			(layer "B.Fab")
		)
		(fp_line
			(start -1.1938 0.4064)
			(end -0.9144 0.4064)
			(stroke
				(width 0.1)
				(type default)
			)
			(layer "B.Fab")
		)
		(fp_line
			(start -0.9144 -0.508)
			(end -0.9144 -0.406654)
			(stroke
				(width 0.1)
				(type default)
			)
			(layer "B.Fab")
		)
		(fp_line
			(start -0.9144 -0.406654)
			(end -1.1938 -0.406654)
			(stroke
				(width 0.1)
				(type default)
			)
			(layer "B.Fab")
		)
		(fp_line
			(start -0.9144 0.4064)
			(end -0.9144 0.508)
			(stroke
				(width 0.1)
				(type default)
			)
			(layer "B.Fab")
		)
		(fp_line
			(start -0.9144 0.508)
			(end 0.9144 0.508)
			(stroke
				(width 0.1)
				(type default)
			)
			(layer "B.Fab")
		)
		(fp_line
			(start 0.9144 -0.508)
			(end -0.9144 -0.508)
			(stroke
				(width 0.1)
				(type default)
			)
			(layer "B.Fab")
		)
		(fp_line
			(start 0.9144 -0.406654)
			(end 0.9144 -0.508)
			(stroke
				(width 0.1)
				(type default)
			)
			(layer "B.Fab")
		)
		(fp_line
			(start 0.9144 0.406654)
			(end 1.194308 0.406654)
			(stroke
				(width 0.1)
				(type default)
			)
			(layer "B.Fab")
		)
		(fp_line
			(start 0.9144 0.508)
			(end 0.9144 0.406654)
			(stroke
				(width 0.1)
				(type default)
			)
			(layer "B.Fab")
		)
		(fp_line
			(start 1.194308 -0.406654)
			(end 0.9144 -0.406654)
			(stroke
				(width 0.1)
				(type default)
			)
			(layer "B.Fab")
		)
		(fp_line
			(start 1.194308 0.406654)
			(end 1.194308 -0.406654)
			(stroke
				(width 0.1)
				(type default)
			)
			(layer "B.Fab")
		)
		(pad "1" smd rect
			(at 0.7366 0 270)
			(size 0.7112 0.8128)
			(layers "B.Cu" "B.Mask" "B.Paste")
			(net "P1V0_AUX")
		)
		(pad "2" smd rect
			(at -0.7366 0 270)
			(size 0.7112 0.8128)
			(layers "B.Cu" "B.Mask" "B.Paste")
			(net "P1V0_STBY_RC_VCC10A")
		)
	)
	(footprint ""
		(layer "B.Cu")
		(at 8.001 -112.649)
		(property "Reference" ""
			(at 0 0 0)
			(layer "B.SilkS")
			(hide yes)
			(effects
				(font
					(size 1.27 1.27)
				)
				(justify mirror)
			)
		)
		(property "Value" ""
			(at 0 0 0)
			(layer "B.Fab")
			(effects
				(font
					(size 1.27 1.27)
				)
				(justify mirror)
			)
		)
		(duplicate_pad_numbers_are_jumpers no)
		(pad "1" smd circle
			(at 0 0 180)
			(size 0.9906 0.9906)
			(layers "B.Cu" "B.Mask" "B.Paste")
			(net "Net_598")
		)
		(zone
			(layer "B.Cu")
			(hatch none 0.5)
			(connect_pads
				(clearance 0)
			)
			(min_thickness 0.25)
			(keepout
				(tracks not_allowed)
				(vias allowed)
				(pads allowed)
				(copperpour not_allowed)
				(footprints allowed)
			)
			(placement
				(enabled no)
				(sheetname "")
			)
			(fill
				(thermal_gap 0.5)
				(thermal_bridge_width 0.5)
				(island_removal_mode 0)
			)
			(polygon
				(pts
					(arc
						(start 9.6266 -112.649)
						(mid 6.3754 -112.649)
						(end 9.6266 -112.649)
					)
				)
			)
		)
	)
	(footprint ""
		(layer "B.Cu")
		(at 70.543674 -37.05479 90)
		(property "Reference" "C126"
			(at 0 0 90)
			(layer "B.SilkS")
			(hide yes)
			(effects
				(font
					(size 1.27 1.27)
				)
				(justify mirror)
			)
		)
		(property "Value" ""
			(at 0 0 90)
			(layer "B.Fab")
			(effects
				(font
					(size 1.27 1.27)
				)
				(justify mirror)
			)
		)
		(duplicate_pad_numbers_are_jumpers no)
		(fp_line
			(start 1.2954 -0.5842)
			(end -1.2954 -0.5842)
			(stroke
				(width 0.1524)
				(type default)
			)
			(layer "B.SilkS")
		)
		(fp_line
			(start 0 -0.5842)
			(end 0 0.5842)
			(stroke
				(width 0.1524)
				(type default)
			)
			(layer "B.SilkS")
		)
		(fp_line
			(start -1.2954 -0.5842)
			(end -1.2954 0.5842)
			(stroke
				(width 0.1524)
				(type default)
			)
			(layer "B.SilkS")
		)
		(fp_line
			(start 1.2954 0.5842)
			(end 1.2954 -0.5842)
			(stroke
				(width 0.1524)
				(type default)
			)
			(layer "B.SilkS")
		)
		(fp_line
			(start -1.2954 0.5842)
			(end 1.2954 0.5842)
			(stroke
				(width 0.1524)
				(type default)
			)
			(layer "B.SilkS")
		)
		(fp_line
			(start 0.8636 -0.4572)
			(end -0.8636 -0.4572)
			(stroke
				(width 0.1)
				(type default)
			)
			(layer "B.Fab")
		)
		(fp_line
			(start -0.8636 -0.4572)
			(end -0.8636 -0.4064)
			(stroke
				(width 0.1)
				(type default)
			)
			(layer "B.Fab")
		)
		(fp_line
			(start 1.1938 -0.4064)
			(end 0.8636 -0.4064)
			(stroke
				(width 0.1)
				(type default)
			)
			(layer "B.Fab")
		)
		(fp_line
			(start 0.8636 -0.4064)
			(end 0.8636 -0.4572)
			(stroke
				(width 0.1)
				(type default)
			)
			(layer "B.Fab")
		)
		(fp_line
			(start -0.8636 -0.4064)
			(end -1.1938 -0.4064)
			(stroke
				(width 0.1)
				(type default)
			)
			(layer "B.Fab")
		)
		(fp_line
			(start -1.1938 -0.4064)
			(end -1.1938 0.4064)
			(stroke
				(width 0.1)
				(type default)
			)
			(layer "B.Fab")
		)
		(fp_line
			(start 1.1938 0.4064)
			(end 1.1938 -0.4064)
			(stroke
				(width 0.1)
				(type default)
			)
			(layer "B.Fab")
		)
		(fp_line
			(start 0.8636 0.4064)
			(end 1.1938 0.4064)
			(stroke
				(width 0.1)
				(type default)
			)
			(layer "B.Fab")
		)
		(fp_line
			(start -0.8636 0.4064)
			(end -0.8636 0.4572)
			(stroke
				(width 0.1)
				(type default)
			)
			(layer "B.Fab")
		)
		(fp_line
			(start -1.1938 0.4064)
			(end -0.8636 0.4064)
			(stroke
				(width 0.1)
				(type default)
			)
			(layer "B.Fab")
		)
		(fp_line
			(start 0.8636 0.4572)
			(end 0.8636 0.4064)
			(stroke
				(width 0.1)
				(type default)
			)
			(layer "B.Fab")
		)
		(fp_line
			(start -0.8636 0.4572)
			(end 0.8636 0.4572)
			(stroke
				(width 0.1)
				(type default)
			)
			(layer "B.Fab")
		)
		(pad "1" smd rect
			(at 0.7366 0)
			(size 0.7112 0.8128)
			(layers "B.Cu" "B.Mask" "B.Paste")
			(net "P1V8_AUX")
		)
		(pad "2" smd rect
			(at -0.7366 0)
			(size 0.7112 0.8128)
			(layers "B.Cu" "B.Mask" "B.Paste")
			(net "GND")
		)
	)
	(footprint ""
		(layer "B.Cu")
		(at 60.722256 -53.533548 -90)
		(property "Reference" "C21"
			(at 0 0 90)
			(layer "B.SilkS")
			(hide yes)
			(effects
				(font
					(size 1.27 1.27)
				)
				(justify mirror)
			)
		)
		(property "Value" ""
			(at 0 0 90)
			(layer "B.Fab")
			(effects
				(font
					(size 1.27 1.27)
				)
				(justify mirror)
			)
		)
		(duplicate_pad_numbers_are_jumpers no)
		(fp_line
			(start -0.7874 0.4064)
			(end 0.7874 0.4064)
			(stroke
				(width 0.1524)
				(type default)
			)
			(layer "B.SilkS")
		)
		(fp_line
			(start 0.7874 0.4064)
			(end 0.7874 -0.4064)
			(stroke
				(width 0.1524)
				(type default)
			)
			(layer "B.SilkS")
		)
		(fp_line
			(start -0.7874 -0.4064)
			(end -0.7874 0.4064)
			(stroke
				(width 0.1524)
				(type default)
			)
			(layer "B.SilkS")
		)
		(fp_line
			(start 0.7874 -0.4064)
			(end -0.7874 -0.4064)
			(stroke
				(width 0.1524)
				(type default)
			)
			(layer "B.SilkS")
		)
		(fp_line
			(start -0.67945 0.3048)
			(end -0.120396 0.3048)
			(stroke
				(width 0.1)
				(type default)
			)
			(layer "B.Fab")
		)
		(fp_line
			(start -0.120396 0.3048)
			(end -0.120396 0.2794)
			(stroke
				(width 0.1)
				(type default)
			)
			(layer "B.Fab")
		)
		(fp_line
			(start 0.12065 0.3048)
			(end 0.67945 0.3048)
			(stroke
				(width 0.1)
				(type default)
			)
			(layer "B.Fab")
		)
		(fp_line
			(start 0.67945 0.3048)
			(end 0.67945 -0.305054)
			(stroke
				(width 0.1)
				(type default)
			)
			(layer "B.Fab")
		)
		(fp_line
			(start -0.120396 0.2794)
			(end 0.12065 0.2794)
			(stroke
				(width 0.1)
				(type default)
			)
			(layer "B.Fab")
		)
		(fp_line
			(start 0.12065 0.2794)
			(end 0.12065 0.3048)
			(stroke
				(width 0.1)
				(type default)
			)
			(layer "B.Fab")
		)
		(fp_line
			(start -0.12065 -0.2794)
			(end -0.12065 -0.3048)
			(stroke
				(width 0.1)
				(type default)
			)
			(layer "B.Fab")
		)
		(fp_line
			(start 0.12065 -0.2794)
			(end -0.12065 -0.2794)
			(stroke
				(width 0.1)
				(type default)
			)
			(layer "B.Fab")
		)
		(fp_line
			(start -0.67945 -0.3048)
			(end -0.67945 0.3048)
			(stroke
				(width 0.1)
				(type default)
			)
			(layer "B.Fab")
		)
		(fp_line
			(start -0.12065 -0.3048)
			(end -0.67945 -0.3048)
			(stroke
				(width 0.1)
				(type default)
			)
			(layer "B.Fab")
		)
		(fp_line
			(start 0.12065 -0.305054)
			(end 0.12065 -0.2794)
			(stroke
				(width 0.1)
				(type default)
			)
			(layer "B.Fab")
		)
		(fp_line
			(start 0.67945 -0.305054)
			(end 0.12065 -0.305054)
			(stroke
				(width 0.1)
				(type default)
			)
			(layer "B.Fab")
		)
		(pad "1" smd circle
			(at 0.40005 0 90)
			(size 0 0)
			(layers "B.Cu" "B.Mask" "B.Paste")
			(net "P0V6_DDR_VREF_AUX")
		)
		(pad "2" smd circle
			(at -0.40005 0 90)
			(size 0 0)
			(layers "B.Cu" "B.Mask" "B.Paste")
			(net "GND")
		)
	)
	(footprint ""
		(layer "B.Cu")
		(at 69.997828 -30.8356 180)
		(property "Reference" "C240"
			(at 0 0 0)
			(layer "B.SilkS")
			(hide yes)
			(effects
				(font
					(size 1.27 1.27)
				)
				(justify mirror)
			)
		)
		(property "Value" ""
			(at 0 0 0)
			(layer "B.Fab")
			(effects
				(font
					(size 1.27 1.27)
				)
				(justify mirror)
			)
		)
		(duplicate_pad_numbers_are_jumpers no)
		(fp_line
			(start 0.7874 0.4064)
			(end 0.7874 -0.4064)
			(stroke
				(width 0.1524)
				(type default)
			)
			(layer "B.SilkS")
		)
		(fp_line
			(start 0.7874 -0.4064)
			(end -0.7874 -0.4064)
			(stroke
				(width 0.1524)
				(type default)
			)
			(layer "B.SilkS")
		)
		(fp_line
			(start -0.7874 0.4064)
			(end 0.7874 0.4064)
			(stroke
				(width 0.1524)
				(type default)
			)
			(layer "B.SilkS")
		)
		(fp_line
			(start -0.7874 -0.4064)
			(end -0.7874 0.4064)
			(stroke
				(width 0.1524)
				(type default)
			)
			(layer "B.SilkS")
		)
		(fp_line
			(start 0.67945 0.3048)
			(end 0.67945 -0.305054)
			(stroke
				(width 0.1)
				(type default)
			)
			(layer "B.Fab")
		)
		(fp_line
			(start 0.67945 -0.305054)
			(end 0.12065 -0.305054)
			(stroke
				(width 0.1)
				(type default)
			)
			(layer "B.Fab")
		)
		(fp_line
			(start 0.12065 0.3048)
			(end 0.67945 0.3048)
			(stroke
				(width 0.1)
				(type default)
			)
			(layer "B.Fab")
		)
		(fp_line
			(start 0.12065 0.2794)
			(end 0.12065 0.3048)
			(stroke
				(width 0.1)
				(type default)
			)
			(layer "B.Fab")
		)
		(fp_line
			(start 0.12065 -0.2794)
			(end -0.12065 -0.2794)
			(stroke
				(width 0.1)
				(type default)
			)
			(layer "B.Fab")
		)
		(fp_line
			(start 0.12065 -0.305054)
			(end 0.12065 -0.2794)
			(stroke
				(width 0.1)
				(type default)
			)
			(layer "B.Fab")
		)
		(fp_line
			(start -0.120396 0.3048)
			(end -0.120396 0.2794)
			(stroke
				(width 0.1)
				(type default)
			)
			(layer "B.Fab")
		)
		(fp_line
			(start -0.120396 0.2794)
			(end 0.12065 0.2794)
			(stroke
				(width 0.1)
				(type default)
			)
			(layer "B.Fab")
		)
		(fp_line
			(start -0.12065 -0.2794)
			(end -0.12065 -0.3048)
			(stroke
				(width 0.1)
				(type default)
			)
			(layer "B.Fab")
		)
		(fp_line
			(start -0.12065 -0.3048)
			(end -0.67945 -0.3048)
			(stroke
				(width 0.1)
				(type default)
			)
			(layer "B.Fab")
		)
		(fp_line
			(start -0.67945 0.3048)
			(end -0.120396 0.3048)
			(stroke
				(width 0.1)
				(type default)
			)
			(layer "B.Fab")
		)
		(fp_line
			(start -0.67945 -0.3048)
			(end -0.67945 0.3048)
			(stroke
				(width 0.1)
				(type default)
			)
			(layer "B.Fab")
		)
		(pad "1" smd circle
			(at 0.40005 0)
			(size 0 0)
			(layers "B.Cu" "B.Mask" "B.Paste")
			(net "P3V3_AUX")
		)
		(pad "2" smd circle
			(at -0.40005 0)
			(size 0 0)
			(layers "B.Cu" "B.Mask" "B.Paste")
			(net "GND")
		)
	)
	(footprint ""
		(layer "B.Cu")
		(at 47.879 -52.1462 -90)
		(property "Reference" "R61"
			(at 0 0 90)
			(layer "B.SilkS")
			(hide yes)
			(effects
				(font
					(size 1.27 1.27)
				)
				(justify mirror)
			)
		)
		(property "Value" ""
			(at 0 0 90)
			(layer "B.Fab")
			(effects
				(font
					(size 1.27 1.27)
				)
				(justify mirror)
			)
		)
		(duplicate_pad_numbers_are_jumpers no)
		(fp_line
			(start -0.7874 0.4064)
			(end 0.7874 0.4064)
			(stroke
				(width 0.1524)
				(type default)
			)
			(layer "B.SilkS")
		)
		(fp_line
			(start 0.7874 0.4064)
			(end 0.7874 -0.4064)
			(stroke
				(width 0.1524)
				(type default)
			)
			(layer "B.SilkS")
		)
		(fp_line
			(start -0.7874 -0.4064)
			(end -0.7874 0.4064)
			(stroke
				(width 0.1524)
				(type default)
			)
			(layer "B.SilkS")
		)
		(fp_line
			(start 0.7874 -0.4064)
			(end -0.7874 -0.4064)
			(stroke
				(width 0.1524)
				(type default)
			)
			(layer "B.SilkS")
		)
		(fp_line
			(start -0.67945 0.3048)
			(end -0.120396 0.3048)
			(stroke
				(width 0.1)
				(type default)
			)
			(layer "B.Fab")
		)
		(fp_line
			(start -0.120396 0.3048)
			(end -0.120396 0.2794)
			(stroke
				(width 0.1)
				(type default)
			)
			(layer "B.Fab")
		)
		(fp_line
			(start 0.12065 0.3048)
			(end 0.67945 0.3048)
			(stroke
				(width 0.1)
				(type default)
			)
			(layer "B.Fab")
		)
		(fp_line
			(start 0.67945 0.3048)
			(end 0.67945 -0.305054)
			(stroke
				(width 0.1)
				(type default)
			)
			(layer "B.Fab")
		)
		(fp_line
			(start -0.120396 0.2794)
			(end 0.12065 0.2794)
			(stroke
				(width 0.1)
				(type default)
			)
			(layer "B.Fab")
		)
		(fp_line
			(start 0.12065 0.2794)
			(end 0.12065 0.3048)
			(stroke
				(width 0.1)
				(type default)
			)
			(layer "B.Fab")
		)
		(fp_line
			(start -0.12065 -0.2794)
			(end -0.12065 -0.3048)
			(stroke
				(width 0.1)
				(type default)
			)
			(layer "B.Fab")
		)
		(fp_line
			(start 0.12065 -0.2794)
			(end -0.12065 -0.2794)
			(stroke
				(width 0.1)
				(type default)
			)
			(layer "B.Fab")
		)
		(fp_line
			(start -0.67945 -0.3048)
			(end -0.67945 0.3048)
			(stroke
				(width 0.1)
				(type default)
			)
			(layer "B.Fab")
		)
		(fp_line
			(start -0.12065 -0.3048)
			(end -0.67945 -0.3048)
			(stroke
				(width 0.1)
				(type default)
			)
			(layer "B.Fab")
		)
		(fp_line
			(start 0.12065 -0.305054)
			(end 0.12065 -0.2794)
			(stroke
				(width 0.1)
				(type default)
			)
			(layer "B.Fab")
		)
		(fp_line
			(start 0.67945 -0.305054)
			(end 0.12065 -0.305054)
			(stroke
				(width 0.1)
				(type default)
			)
			(layer "B.Fab")
		)
		(pad "1" smd circle
			(at 0.40005 0 90)
			(size 0 0)
			(layers "B.Cu" "B.Mask" "B.Paste")
			(net "P3V3_AUX")
		)
		(pad "2" smd circle
			(at -0.40005 0 90)
			(size 0 0)
			(layers "B.Cu" "B.Mask" "B.Paste")
			(net "IRQ_BMC_PCH_NMI_N")
		)
	)
	(footprint ""
		(layer "B.Cu")
		(at 47.879 -63.9445 90)
		(property "Reference" "R449"
			(at 0 0 90)
			(layer "B.SilkS")
			(hide yes)
			(effects
				(font
					(size 1.27 1.27)
				)
				(justify mirror)
			)
		)
		(property "Value" ""
			(at 0 0 90)
			(layer "B.Fab")
			(effects
				(font
					(size 1.27 1.27)
				)
				(justify mirror)
			)
		)
		(duplicate_pad_numbers_are_jumpers no)
		(fp_line
			(start 0.7874 -0.4064)
			(end -0.7874 -0.4064)
			(stroke
				(width 0.1524)
				(type default)
			)
			(layer "B.SilkS")
		)
		(fp_line
			(start -0.7874 -0.4064)
			(end -0.7874 0.4064)
			(stroke
				(width 0.1524)
				(type default)
			)
			(layer "B.SilkS")
		)
		(fp_line
			(start 0.7874 0.4064)
			(end 0.7874 -0.4064)
			(stroke
				(width 0.1524)
				(type default)
			)
			(layer "B.SilkS")
		)
		(fp_line
			(start -0.7874 0.4064)
			(end 0.7874 0.4064)
			(stroke
				(width 0.1524)
				(type default)
			)
			(layer "B.SilkS")
		)
		(fp_line
			(start 0.67945 -0.305054)
			(end 0.12065 -0.305054)
			(stroke
				(width 0.1)
				(type default)
			)
			(layer "B.Fab")
		)
		(fp_line
			(start 0.12065 -0.305054)
			(end 0.12065 -0.2794)
			(stroke
				(width 0.1)
				(type default)
			)
			(layer "B.Fab")
		)
		(fp_line
			(start -0.12065 -0.3048)
			(end -0.67945 -0.3048)
			(stroke
				(width 0.1)
				(type default)
			)
			(layer "B.Fab")
		)
		(fp_line
			(start -0.67945 -0.3048)
			(end -0.67945 0.3048)
			(stroke
				(width 0.1)
				(type default)
			)
			(layer "B.Fab")
		)
		(fp_line
			(start 0.12065 -0.2794)
			(end -0.12065 -0.2794)
			(stroke
				(width 0.1)
				(type default)
			)
			(layer "B.Fab")
		)
		(fp_line
			(start -0.12065 -0.2794)
			(end -0.12065 -0.3048)
			(stroke
				(width 0.1)
				(type default)
			)
			(layer "B.Fab")
		)
		(fp_line
			(start 0.12065 0.2794)
			(end 0.12065 0.3048)
			(stroke
				(width 0.1)
				(type default)
			)
			(layer "B.Fab")
		)
		(fp_line
			(start -0.120396 0.2794)
			(end 0.12065 0.2794)
			(stroke
				(width 0.1)
				(type default)
			)
			(layer "B.Fab")
		)
		(fp_line
			(start 0.67945 0.3048)
			(end 0.67945 -0.305054)
			(stroke
				(width 0.1)
				(type default)
			)
			(layer "B.Fab")
		)
		(fp_line
			(start 0.12065 0.3048)
			(end 0.67945 0.3048)
			(stroke
				(width 0.1)
				(type default)
			)
			(layer "B.Fab")
		)
		(fp_line
			(start -0.120396 0.3048)
			(end -0.120396 0.2794)
			(stroke
				(width 0.1)
				(type default)
			)
			(layer "B.Fab")
		)
		(fp_line
			(start -0.67945 0.3048)
			(end -0.120396 0.3048)
			(stroke
				(width 0.1)
				(type default)
			)
			(layer "B.Fab")
		)
		(pad "1" smd circle
			(at 0.40005 0 270)
			(size 0 0)
			(layers "B.Cu" "B.Mask" "B.Paste")
			(net "SMB_BMC_ALERT10_N")
		)
		(pad "2" smd circle
			(at -0.40005 0 270)
			(size 0 0)
			(layers "B.Cu" "B.Mask" "B.Paste")
			(net "SMB_BMC_ALERT10_R_N")
		)
	)
	(footprint ""
		(layer "B.Cu")
		(at 18.259298 -94.786958 180)
		(property "Reference" "C141"
			(at 0 0 0)
			(layer "B.SilkS")
			(hide yes)
			(effects
				(font
					(size 1.27 1.27)
				)
				(justify mirror)
			)
		)
		(property "Value" ""
			(at 0 0 0)
			(layer "B.Fab")
			(effects
				(font
					(size 1.27 1.27)
				)
				(justify mirror)
			)
		)
		(duplicate_pad_numbers_are_jumpers no)
		(fp_line
			(start 0.69215 0.2921)
			(end 0.69215 -0.2921)
			(stroke
				(width 0.1524)
				(type default)
			)
			(layer "B.SilkS")
		)
		(fp_line
			(start 0.69215 -0.2921)
			(end -0.69215 -0.2921)
			(stroke
				(width 0.1524)
				(type default)
			)
			(layer "B.SilkS")
		)
		(fp_line
			(start -0.69215 0.2921)
			(end 0.69215 0.2921)
			(stroke
				(width 0.1524)
				(type default)
			)
			(layer "B.SilkS")
		)
		(fp_line
			(start -0.69215 -0.2921)
			(end -0.69215 0.2921)
			(stroke
				(width 0.1524)
				(type default)
			)
			(layer "B.SilkS")
		)
		(fp_line
			(start 0.51435 0.2794)
			(end 0.51435 -0.2794)
			(stroke
				(width 0.1)
				(type default)
			)
			(layer "B.Fab")
		)
		(fp_line
			(start 0.51435 -0.2794)
			(end -0.51435 -0.2794)
			(stroke
				(width 0.1)
				(type default)
			)
			(layer "B.Fab")
		)
		(fp_line
			(start -0.51435 0.2794)
			(end 0.51435 0.2794)
			(stroke
				(width 0.1)
				(type default)
			)
			(layer "B.Fab")
		)
		(fp_line
			(start -0.51435 -0.2794)
			(end -0.51435 0.2794)
			(stroke
				(width 0.1)
				(type default)
			)
			(layer "B.Fab")
		)
		(pad "1" smd circle
			(at 0.40005 0)
			(size 0 0)
			(layers "B.Cu" "B.Mask" "B.Paste")
			(net "VCCIO1")
		)
		(pad "2" smd circle
			(at -0.40005 0)
			(size 0 0)
			(layers "B.Cu" "B.Mask" "B.Paste")
			(net "GND")
		)
		(zone
			(layer "B.Cu")
			(hatch none 0.5)
			(connect_pads
				(clearance 0)
			)
			(min_thickness 0.25)
			(keepout
				(tracks not_allowed)
				(vias allowed)
				(pads allowed)
				(copperpour not_allowed)
				(footprints allowed)
			)
			(placement
				(enabled no)
				(sheetname "")
			)
			(fill
				(thermal_gap 0.5)
				(thermal_bridge_width 0.5)
				(island_removal_mode 0)
			)
			(polygon
				(pts
					(xy 18.068798 -94.874588) (xy 18.160238 -94.932754) (xy 18.359628 -94.932754) (xy 18.449798 -94.874588)
					(xy 18.449798 -94.699328) (xy 18.359628 -94.640908) (xy 18.160238 -94.640908) (xy 18.068798 -94.699074)
				)
			)
		)
	)
	(footprint ""
		(layer "B.Cu")
		(at 35.433 -36.195 -90)
		(property "Reference" "R159"
			(at 0 0 90)
			(layer "B.SilkS")
			(hide yes)
			(effects
				(font
					(size 1.27 1.27)
				)
				(justify mirror)
			)
		)
		(property "Value" ""
			(at 0 0 90)
			(layer "B.Fab")
			(effects
				(font
					(size 1.27 1.27)
				)
				(justify mirror)
			)
		)
		(duplicate_pad_numbers_are_jumpers no)
		(fp_line
			(start -0.7874 0.4064)
			(end 0.7874 0.4064)
			(stroke
				(width 0.1524)
				(type default)
			)
			(layer "B.SilkS")
		)
		(fp_line
			(start 0.7874 0.4064)
			(end 0.7874 -0.4064)
			(stroke
				(width 0.1524)
				(type default)
			)
			(layer "B.SilkS")
		)
		(fp_line
			(start -0.7874 -0.4064)
			(end -0.7874 0.4064)
			(stroke
				(width 0.1524)
				(type default)
			)
			(layer "B.SilkS")
		)
		(fp_line
			(start 0.7874 -0.4064)
			(end -0.7874 -0.4064)
			(stroke
				(width 0.1524)
				(type default)
			)
			(layer "B.SilkS")
		)
		(fp_line
			(start -0.67945 0.3048)
			(end -0.120396 0.3048)
			(stroke
				(width 0.1)
				(type default)
			)
			(layer "B.Fab")
		)
		(fp_line
			(start -0.120396 0.3048)
			(end -0.120396 0.2794)
			(stroke
				(width 0.1)
				(type default)
			)
			(layer "B.Fab")
		)
		(fp_line
			(start 0.12065 0.3048)
			(end 0.67945 0.3048)
			(stroke
				(width 0.1)
				(type default)
			)
			(layer "B.Fab")
		)
		(fp_line
			(start 0.67945 0.3048)
			(end 0.67945 -0.305054)
			(stroke
				(width 0.1)
				(type default)
			)
			(layer "B.Fab")
		)
		(fp_line
			(start -0.120396 0.2794)
			(end 0.12065 0.2794)
			(stroke
				(width 0.1)
				(type default)
			)
			(layer "B.Fab")
		)
		(fp_line
			(start 0.12065 0.2794)
			(end 0.12065 0.3048)
			(stroke
				(width 0.1)
				(type default)
			)
			(layer "B.Fab")
		)
		(fp_line
			(start -0.12065 -0.2794)
			(end -0.12065 -0.3048)
			(stroke
				(width 0.1)
				(type default)
			)
			(layer "B.Fab")
		)
		(fp_line
			(start 0.12065 -0.2794)
			(end -0.12065 -0.2794)
			(stroke
				(width 0.1)
				(type default)
			)
			(layer "B.Fab")
		)
		(fp_line
			(start -0.67945 -0.3048)
			(end -0.67945 0.3048)
			(stroke
				(width 0.1)
				(type default)
			)
			(layer "B.Fab")
		)
		(fp_line
			(start -0.12065 -0.3048)
			(end -0.67945 -0.3048)
			(stroke
				(width 0.1)
				(type default)
			)
			(layer "B.Fab")
		)
		(fp_line
			(start 0.12065 -0.305054)
			(end 0.12065 -0.2794)
			(stroke
				(width 0.1)
				(type default)
			)
			(layer "B.Fab")
		)
		(fp_line
			(start 0.67945 -0.305054)
			(end 0.12065 -0.305054)
			(stroke
				(width 0.1)
				(type default)
			)
			(layer "B.Fab")
		)
		(pad "1" smd circle
			(at 0.40005 0 90)
			(size 0 0)
			(layers "B.Cu" "B.Mask" "B.Paste")
			(net "FM_JTAG_TCK_MUX_BMC_SEL")
		)
		(pad "2" smd circle
			(at -0.40005 0 90)
			(size 0 0)
			(layers "B.Cu" "B.Mask" "B.Paste")
			(net "FM_JTAG_TCK_MUX_BMC_SEL_R1")
		)
	)
	(footprint ""
		(layer "B.Cu")
		(at 28.3464 -30.35935 -90)
		(property "Reference" "C206"
			(at 0 0 90)
			(layer "B.SilkS")
			(hide yes)
			(effects
				(font
					(size 1.27 1.27)
				)
				(justify mirror)
			)
		)
		(property "Value" ""
			(at 0 0 90)
			(layer "B.Fab")
			(effects
				(font
					(size 1.27 1.27)
				)
				(justify mirror)
			)
		)
		(duplicate_pad_numbers_are_jumpers no)
		(fp_line
			(start -0.7874 0.4064)
			(end 0.7874 0.4064)
			(stroke
				(width 0.1524)
				(type default)
			)
			(layer "B.SilkS")
		)
		(fp_line
			(start 0.7874 0.4064)
			(end 0.7874 -0.4064)
			(stroke
				(width 0.1524)
				(type default)
			)
			(layer "B.SilkS")
		)
		(fp_line
			(start -0.7874 -0.4064)
			(end -0.7874 0.4064)
			(stroke
				(width 0.1524)
				(type default)
			)
			(layer "B.SilkS")
		)
		(fp_line
			(start 0.7874 -0.4064)
			(end -0.7874 -0.4064)
			(stroke
				(width 0.1524)
				(type default)
			)
			(layer "B.SilkS")
		)
		(fp_line
			(start -0.67945 0.3048)
			(end -0.120396 0.3048)
			(stroke
				(width 0.1)
				(type default)
			)
			(layer "B.Fab")
		)
		(fp_line
			(start -0.120396 0.3048)
			(end -0.120396 0.2794)
			(stroke
				(width 0.1)
				(type default)
			)
			(layer "B.Fab")
		)
		(fp_line
			(start 0.12065 0.3048)
			(end 0.67945 0.3048)
			(stroke
				(width 0.1)
				(type default)
			)
			(layer "B.Fab")
		)
		(fp_line
			(start 0.67945 0.3048)
			(end 0.67945 -0.305054)
			(stroke
				(width 0.1)
				(type default)
			)
			(layer "B.Fab")
		)
		(fp_line
			(start -0.120396 0.2794)
			(end 0.12065 0.2794)
			(stroke
				(width 0.1)
				(type default)
			)
			(layer "B.Fab")
		)
		(fp_line
			(start 0.12065 0.2794)
			(end 0.12065 0.3048)
			(stroke
				(width 0.1)
				(type default)
			)
			(layer "B.Fab")
		)
		(fp_line
			(start -0.12065 -0.2794)
			(end -0.12065 -0.3048)
			(stroke
				(width 0.1)
				(type default)
			)
			(layer "B.Fab")
		)
		(fp_line
			(start 0.12065 -0.2794)
			(end -0.12065 -0.2794)
			(stroke
				(width 0.1)
				(type default)
			)
			(layer "B.Fab")
		)
		(fp_line
			(start -0.67945 -0.3048)
			(end -0.67945 0.3048)
			(stroke
				(width 0.1)
				(type default)
			)
			(layer "B.Fab")
		)
		(fp_line
			(start -0.12065 -0.3048)
			(end -0.67945 -0.3048)
			(stroke
				(width 0.1)
				(type default)
			)
			(layer "B.Fab")
		)
		(fp_line
			(start 0.12065 -0.305054)
			(end 0.12065 -0.2794)
			(stroke
				(width 0.1)
				(type default)
			)
			(layer "B.Fab")
		)
		(fp_line
			(start 0.67945 -0.305054)
			(end 0.12065 -0.305054)
			(stroke
				(width 0.1)
				(type default)
			)
			(layer "B.Fab")
		)
		(pad "1" smd circle
			(at 0.40005 0 90)
			(size 0 0)
			(layers "B.Cu" "B.Mask" "B.Paste")
			(net "V_DACG")
		)
		(pad "2" smd circle
			(at -0.40005 0 90)
			(size 0 0)
			(layers "B.Cu" "B.Mask" "B.Paste")
			(net "GND")
		)
	)
	(footprint ""
		(layer "B.Cu")
		(at 53.4924 -77.9018 -90)
		(property "Reference" "C255"
			(at 0 0 90)
			(layer "B.SilkS")
			(hide yes)
			(effects
				(font
					(size 1.27 1.27)
				)
				(justify mirror)
			)
		)
		(property "Value" ""
			(at 0 0 90)
			(layer "B.Fab")
			(effects
				(font
					(size 1.27 1.27)
				)
				(justify mirror)
			)
		)
		(duplicate_pad_numbers_are_jumpers no)
		(fp_line
			(start -0.7874 0.4064)
			(end 0.7874 0.4064)
			(stroke
				(width 0.1524)
				(type default)
			)
			(layer "B.SilkS")
		)
		(fp_line
			(start 0.7874 0.4064)
			(end 0.7874 -0.4064)
			(stroke
				(width 0.1524)
				(type default)
			)
			(layer "B.SilkS")
		)
		(fp_line
			(start -0.7874 -0.4064)
			(end -0.7874 0.4064)
			(stroke
				(width 0.1524)
				(type default)
			)
			(layer "B.SilkS")
		)
		(fp_line
			(start 0.7874 -0.4064)
			(end -0.7874 -0.4064)
			(stroke
				(width 0.1524)
				(type default)
			)
			(layer "B.SilkS")
		)
		(fp_line
			(start -0.67945 0.3048)
			(end -0.120396 0.3048)
			(stroke
				(width 0.1)
				(type default)
			)
			(layer "B.Fab")
		)
		(fp_line
			(start -0.120396 0.3048)
			(end -0.120396 0.2794)
			(stroke
				(width 0.1)
				(type default)
			)
			(layer "B.Fab")
		)
		(fp_line
			(start 0.12065 0.3048)
			(end 0.67945 0.3048)
			(stroke
				(width 0.1)
				(type default)
			)
			(layer "B.Fab")
		)
		(fp_line
			(start 0.67945 0.3048)
			(end 0.67945 -0.305054)
			(stroke
				(width 0.1)
				(type default)
			)
			(layer "B.Fab")
		)
		(fp_line
			(start -0.120396 0.2794)
			(end 0.12065 0.2794)
			(stroke
				(width 0.1)
				(type default)
			)
			(layer "B.Fab")
		)
		(fp_line
			(start 0.12065 0.2794)
			(end 0.12065 0.3048)
			(stroke
				(width 0.1)
				(type default)
			)
			(layer "B.Fab")
		)
		(fp_line
			(start -0.12065 -0.2794)
			(end -0.12065 -0.3048)
			(stroke
				(width 0.1)
				(type default)
			)
			(layer "B.Fab")
		)
		(fp_line
			(start 0.12065 -0.2794)
			(end -0.12065 -0.2794)
			(stroke
				(width 0.1)
				(type default)
			)
			(layer "B.Fab")
		)
		(fp_line
			(start -0.67945 -0.3048)
			(end -0.67945 0.3048)
			(stroke
				(width 0.1)
				(type default)
			)
			(layer "B.Fab")
		)
		(fp_line
			(start -0.12065 -0.3048)
			(end -0.67945 -0.3048)
			(stroke
				(width 0.1)
				(type default)
			)
			(layer "B.Fab")
		)
		(fp_line
			(start 0.12065 -0.305054)
			(end 0.12065 -0.2794)
			(stroke
				(width 0.1)
				(type default)
			)
			(layer "B.Fab")
		)
		(fp_line
			(start 0.67945 -0.305054)
			(end 0.12065 -0.305054)
			(stroke
				(width 0.1)
				(type default)
			)
			(layer "B.Fab")
		)
		(pad "1" smd circle
			(at 0.40005 0 90)
			(size 0 0)
			(layers "B.Cu" "B.Mask" "B.Paste")
			(net "P3V3_AUX")
		)
		(pad "2" smd circle
			(at -0.40005 0 90)
			(size 0 0)
			(layers "B.Cu" "B.Mask" "B.Paste")
			(net "GND")
		)
	)
	(footprint ""
		(layer "B.Cu")
		(at 20.4724 -65.1256 90)
		(property "Reference" "R726"
			(at 0 0 90)
			(layer "B.SilkS")
			(hide yes)
			(effects
				(font
					(size 1.27 1.27)
				)
				(justify mirror)
			)
		)
		(property "Value" ""
			(at 0 0 90)
			(layer "B.Fab")
			(effects
				(font
					(size 1.27 1.27)
				)
				(justify mirror)
			)
		)
		(duplicate_pad_numbers_are_jumpers no)
		(fp_line
			(start 0.7874 -0.4064)
			(end -0.7874 -0.4064)
			(stroke
				(width 0.1524)
				(type default)
			)
			(layer "B.SilkS")
		)
		(fp_line
			(start -0.7874 -0.4064)
			(end -0.7874 0.4064)
			(stroke
				(width 0.1524)
				(type default)
			)
			(layer "B.SilkS")
		)
		(fp_line
			(start 0.7874 0.4064)
			(end 0.7874 -0.4064)
			(stroke
				(width 0.1524)
				(type default)
			)
			(layer "B.SilkS")
		)
		(fp_line
			(start -0.7874 0.4064)
			(end 0.7874 0.4064)
			(stroke
				(width 0.1524)
				(type default)
			)
			(layer "B.SilkS")
		)
		(fp_line
			(start 0.67945 -0.305054)
			(end 0.12065 -0.305054)
			(stroke
				(width 0.1)
				(type default)
			)
			(layer "B.Fab")
		)
		(fp_line
			(start 0.12065 -0.305054)
			(end 0.12065 -0.2794)
			(stroke
				(width 0.1)
				(type default)
			)
			(layer "B.Fab")
		)
		(fp_line
			(start -0.12065 -0.3048)
			(end -0.67945 -0.3048)
			(stroke
				(width 0.1)
				(type default)
			)
			(layer "B.Fab")
		)
		(fp_line
			(start -0.67945 -0.3048)
			(end -0.67945 0.3048)
			(stroke
				(width 0.1)
				(type default)
			)
			(layer "B.Fab")
		)
		(fp_line
			(start 0.12065 -0.2794)
			(end -0.12065 -0.2794)
			(stroke
				(width 0.1)
				(type default)
			)
			(layer "B.Fab")
		)
		(fp_line
			(start -0.12065 -0.2794)
			(end -0.12065 -0.3048)
			(stroke
				(width 0.1)
				(type default)
			)
			(layer "B.Fab")
		)
		(fp_line
			(start 0.12065 0.2794)
			(end 0.12065 0.3048)
			(stroke
				(width 0.1)
				(type default)
			)
			(layer "B.Fab")
		)
		(fp_line
			(start -0.120396 0.2794)
			(end 0.12065 0.2794)
			(stroke
				(width 0.1)
				(type default)
			)
			(layer "B.Fab")
		)
		(fp_line
			(start 0.67945 0.3048)
			(end 0.67945 -0.305054)
			(stroke
				(width 0.1)
				(type default)
			)
			(layer "B.Fab")
		)
		(fp_line
			(start 0.12065 0.3048)
			(end 0.67945 0.3048)
			(stroke
				(width 0.1)
				(type default)
			)
			(layer "B.Fab")
		)
		(fp_line
			(start -0.120396 0.3048)
			(end -0.120396 0.2794)
			(stroke
				(width 0.1)
				(type default)
			)
			(layer "B.Fab")
		)
		(fp_line
			(start -0.67945 0.3048)
			(end -0.120396 0.3048)
			(stroke
				(width 0.1)
				(type default)
			)
			(layer "B.Fab")
		)
		(pad "1" smd circle
			(at 0.40005 0 270)
			(size 0 0)
			(layers "B.Cu" "B.Mask" "B.Paste")
			(net "SPA_SIN_SW_BUF_R")
		)
		(pad "2" smd circle
			(at -0.40005 0 270)
			(size 0 0)
			(layers "B.Cu" "B.Mask" "B.Paste")
			(net "SPA_SIN_SW_BUF")
		)
	)
	(footprint ""
		(layer "B.Cu")
		(at 60.663328 -52.136294)
		(property "Reference" "C23"
			(at 0 0 0)
			(layer "B.SilkS")
			(hide yes)
			(effects
				(font
					(size 1.27 1.27)
				)
				(justify mirror)
			)
		)
		(property "Value" ""
			(at 0 0 0)
			(layer "B.Fab")
			(effects
				(font
					(size 1.27 1.27)
				)
				(justify mirror)
			)
		)
		(duplicate_pad_numbers_are_jumpers no)
		(fp_line
			(start -0.7874 -0.4064)
			(end -0.7874 0.4064)
			(stroke
				(width 0.1524)
				(type default)
			)
			(layer "B.SilkS")
		)
		(fp_line
			(start -0.7874 0.4064)
			(end 0.7874 0.4064)
			(stroke
				(width 0.1524)
				(type default)
			)
			(layer "B.SilkS")
		)
		(fp_line
			(start 0.7874 -0.4064)
			(end -0.7874 -0.4064)
			(stroke
				(width 0.1524)
				(type default)
			)
			(layer "B.SilkS")
		)
		(fp_line
			(start 0.7874 0.4064)
			(end 0.7874 -0.4064)
			(stroke
				(width 0.1524)
				(type default)
			)
			(layer "B.SilkS")
		)
		(fp_line
			(start -0.67945 -0.3048)
			(end -0.67945 0.3048)
			(stroke
				(width 0.1)
				(type default)
			)
			(layer "B.Fab")
		)
		(fp_line
			(start -0.67945 0.3048)
			(end -0.120396 0.3048)
			(stroke
				(width 0.1)
				(type default)
			)
			(layer "B.Fab")
		)
		(fp_line
			(start -0.12065 -0.3048)
			(end -0.67945 -0.3048)
			(stroke
				(width 0.1)
				(type default)
			)
			(layer "B.Fab")
		)
		(fp_line
			(start -0.12065 -0.2794)
			(end -0.12065 -0.3048)
			(stroke
				(width 0.1)
				(type default)
			)
			(layer "B.Fab")
		)
		(fp_line
			(start -0.120396 0.2794)
			(end 0.12065 0.2794)
			(stroke
				(width 0.1)
				(type default)
			)
			(layer "B.Fab")
		)
		(fp_line
			(start -0.120396 0.3048)
			(end -0.120396 0.2794)
			(stroke
				(width 0.1)
				(type default)
			)
			(layer "B.Fab")
		)
		(fp_line
			(start 0.12065 -0.305054)
			(end 0.12065 -0.2794)
			(stroke
				(width 0.1)
				(type default)
			)
			(layer "B.Fab")
		)
		(fp_line
			(start 0.12065 -0.2794)
			(end -0.12065 -0.2794)
			(stroke
				(width 0.1)
				(type default)
			)
			(layer "B.Fab")
		)
		(fp_line
			(start 0.12065 0.2794)
			(end 0.12065 0.3048)
			(stroke
				(width 0.1)
				(type default)
			)
			(layer "B.Fab")
		)
		(fp_line
			(start 0.12065 0.3048)
			(end 0.67945 0.3048)
			(stroke
				(width 0.1)
				(type default)
			)
			(layer "B.Fab")
		)
		(fp_line
			(start 0.67945 -0.305054)
			(end 0.12065 -0.305054)
			(stroke
				(width 0.1)
				(type default)
			)
			(layer "B.Fab")
		)
		(fp_line
			(start 0.67945 0.3048)
			(end 0.67945 -0.305054)
			(stroke
				(width 0.1)
				(type default)
			)
			(layer "B.Fab")
		)
		(pad "1" smd circle
			(at 0.40005 0 180)
			(size 0 0)
			(layers "B.Cu" "B.Mask" "B.Paste")
			(net "P0V6_DDR_VREF_AUX")
		)
		(pad "2" smd circle
			(at -0.40005 0 180)
			(size 0 0)
			(layers "B.Cu" "B.Mask" "B.Paste")
			(net "GND")
		)
	)
	(footprint ""
		(layer "B.Cu")
		(at 61.8744 -18.2626)
		(property "Reference" "R274"
			(at 0 0 0)
			(layer "B.SilkS")
			(hide yes)
			(effects
				(font
					(size 1.27 1.27)
				)
				(justify mirror)
			)
		)
		(property "Value" ""
			(at 0 0 0)
			(layer "B.Fab")
			(effects
				(font
					(size 1.27 1.27)
				)
				(justify mirror)
			)
		)
		(duplicate_pad_numbers_are_jumpers no)
		(fp_line
			(start -0.7874 -0.4064)
			(end -0.7874 0.4064)
			(stroke
				(width 0.1524)
				(type default)
			)
			(layer "B.SilkS")
		)
		(fp_line
			(start -0.7874 0.4064)
			(end 0.7874 0.4064)
			(stroke
				(width 0.1524)
				(type default)
			)
			(layer "B.SilkS")
		)
		(fp_line
			(start 0.7874 -0.4064)
			(end -0.7874 -0.4064)
			(stroke
				(width 0.1524)
				(type default)
			)
			(layer "B.SilkS")
		)
		(fp_line
			(start 0.7874 0.4064)
			(end 0.7874 -0.4064)
			(stroke
				(width 0.1524)
				(type default)
			)
			(layer "B.SilkS")
		)
		(fp_line
			(start -0.67945 -0.3048)
			(end -0.67945 0.3048)
			(stroke
				(width 0.1)
				(type default)
			)
			(layer "B.Fab")
		)
		(fp_line
			(start -0.67945 0.3048)
			(end -0.120396 0.3048)
			(stroke
				(width 0.1)
				(type default)
			)
			(layer "B.Fab")
		)
		(fp_line
			(start -0.12065 -0.3048)
			(end -0.67945 -0.3048)
			(stroke
				(width 0.1)
				(type default)
			)
			(layer "B.Fab")
		)
		(fp_line
			(start -0.12065 -0.2794)
			(end -0.12065 -0.3048)
			(stroke
				(width 0.1)
				(type default)
			)
			(layer "B.Fab")
		)
		(fp_line
			(start -0.120396 0.2794)
			(end 0.12065 0.2794)
			(stroke
				(width 0.1)
				(type default)
			)
			(layer "B.Fab")
		)
		(fp_line
			(start -0.120396 0.3048)
			(end -0.120396 0.2794)
			(stroke
				(width 0.1)
				(type default)
			)
			(layer "B.Fab")
		)
		(fp_line
			(start 0.12065 -0.305054)
			(end 0.12065 -0.2794)
			(stroke
				(width 0.1)
				(type default)
			)
			(layer "B.Fab")
		)
		(fp_line
			(start 0.12065 -0.2794)
			(end -0.12065 -0.2794)
			(stroke
				(width 0.1)
				(type default)
			)
			(layer "B.Fab")
		)
		(fp_line
			(start 0.12065 0.2794)
			(end 0.12065 0.3048)
			(stroke
				(width 0.1)
				(type default)
			)
			(layer "B.Fab")
		)
		(fp_line
			(start 0.12065 0.3048)
			(end 0.67945 0.3048)
			(stroke
				(width 0.1)
				(type default)
			)
			(layer "B.Fab")
		)
		(fp_line
			(start 0.67945 -0.305054)
			(end 0.12065 -0.305054)
			(stroke
				(width 0.1)
				(type default)
			)
			(layer "B.Fab")
		)
		(fp_line
			(start 0.67945 0.3048)
			(end 0.67945 -0.305054)
			(stroke
				(width 0.1)
				(type default)
			)
			(layer "B.Fab")
		)
		(pad "1" smd circle
			(at 0.40005 0 180)
			(size 0 0)
			(layers "B.Cu" "B.Mask" "B.Paste")
			(net "P3V3_AUX")
		)
		(pad "2" smd circle
			(at -0.40005 0 180)
			(size 0 0)
			(layers "B.Cu" "B.Mask" "B.Paste")
			(net "DEBUG_PORT_UART_RX")
		)
	)
	(footprint ""
		(layer "B.Cu")
		(at 52.7812 -30.861 -90)
		(property "Reference" "R816"
			(at 0 0 90)
			(layer "B.SilkS")
			(hide yes)
			(effects
				(font
					(size 1.27 1.27)
				)
				(justify mirror)
			)
		)
		(property "Value" ""
			(at 0 0 90)
			(layer "B.Fab")
			(effects
				(font
					(size 1.27 1.27)
				)
				(justify mirror)
			)
		)
		(duplicate_pad_numbers_are_jumpers no)
		(fp_line
			(start -0.7874 0.4064)
			(end 0.7874 0.4064)
			(stroke
				(width 0.1524)
				(type default)
			)
			(layer "B.SilkS")
		)
		(fp_line
			(start 0.7874 0.4064)
			(end 0.7874 -0.4064)
			(stroke
				(width 0.1524)
				(type default)
			)
			(layer "B.SilkS")
		)
		(fp_line
			(start -0.7874 -0.4064)
			(end -0.7874 0.4064)
			(stroke
				(width 0.1524)
				(type default)
			)
			(layer "B.SilkS")
		)
		(fp_line
			(start 0.7874 -0.4064)
			(end -0.7874 -0.4064)
			(stroke
				(width 0.1524)
				(type default)
			)
			(layer "B.SilkS")
		)
		(fp_line
			(start -0.67945 0.3048)
			(end -0.120396 0.3048)
			(stroke
				(width 0.1)
				(type default)
			)
			(layer "B.Fab")
		)
		(fp_line
			(start -0.120396 0.3048)
			(end -0.120396 0.2794)
			(stroke
				(width 0.1)
				(type default)
			)
			(layer "B.Fab")
		)
		(fp_line
			(start 0.12065 0.3048)
			(end 0.67945 0.3048)
			(stroke
				(width 0.1)
				(type default)
			)
			(layer "B.Fab")
		)
		(fp_line
			(start 0.67945 0.3048)
			(end 0.67945 -0.305054)
			(stroke
				(width 0.1)
				(type default)
			)
			(layer "B.Fab")
		)
		(fp_line
			(start -0.120396 0.2794)
			(end 0.12065 0.2794)
			(stroke
				(width 0.1)
				(type default)
			)
			(layer "B.Fab")
		)
		(fp_line
			(start 0.12065 0.2794)
			(end 0.12065 0.3048)
			(stroke
				(width 0.1)
				(type default)
			)
			(layer "B.Fab")
		)
		(fp_line
			(start -0.12065 -0.2794)
			(end -0.12065 -0.3048)
			(stroke
				(width 0.1)
				(type default)
			)
			(layer "B.Fab")
		)
		(fp_line
			(start 0.12065 -0.2794)
			(end -0.12065 -0.2794)
			(stroke
				(width 0.1)
				(type default)
			)
			(layer "B.Fab")
		)
		(fp_line
			(start -0.67945 -0.3048)
			(end -0.67945 0.3048)
			(stroke
				(width 0.1)
				(type default)
			)
			(layer "B.Fab")
		)
		(fp_line
			(start -0.12065 -0.3048)
			(end -0.67945 -0.3048)
			(stroke
				(width 0.1)
				(type default)
			)
			(layer "B.Fab")
		)
		(fp_line
			(start 0.12065 -0.305054)
			(end 0.12065 -0.2794)
			(stroke
				(width 0.1)
				(type default)
			)
			(layer "B.Fab")
		)
		(fp_line
			(start 0.67945 -0.305054)
			(end 0.12065 -0.305054)
			(stroke
				(width 0.1)
				(type default)
			)
			(layer "B.Fab")
		)
		(pad "1" smd circle
			(at 0.40005 0 90)
			(size 0 0)
			(layers "B.Cu" "B.Mask" "B.Paste")
			(net "P3V3_AUX")
		)
		(pad "2" smd circle
			(at -0.40005 0 90)
			(size 0 0)
			(layers "B.Cu" "B.Mask" "B.Paste")
			(net "IRQ_PCH_SCI_WHEA_N")
		)
	)
	(footprint ""
		(layer "B.Cu")
		(at 12.319 -95.504)
		(property "Reference" "R608"
			(at 0 0 0)
			(layer "B.SilkS")
			(hide yes)
			(effects
				(font
					(size 1.27 1.27)
				)
				(justify mirror)
			)
		)
		(property "Value" ""
			(at 0 0 0)
			(layer "B.Fab")
			(effects
				(font
					(size 1.27 1.27)
				)
				(justify mirror)
			)
		)
		(duplicate_pad_numbers_are_jumpers no)
		(fp_line
			(start -0.7874 -0.4064)
			(end -0.7874 0.4064)
			(stroke
				(width 0.1524)
				(type default)
			)
			(layer "B.SilkS")
		)
		(fp_line
			(start -0.7874 0.4064)
			(end 0.7874 0.4064)
			(stroke
				(width 0.1524)
				(type default)
			)
			(layer "B.SilkS")
		)
		(fp_line
			(start 0.7874 -0.4064)
			(end -0.7874 -0.4064)
			(stroke
				(width 0.1524)
				(type default)
			)
			(layer "B.SilkS")
		)
		(fp_line
			(start 0.7874 0.4064)
			(end 0.7874 -0.4064)
			(stroke
				(width 0.1524)
				(type default)
			)
			(layer "B.SilkS")
		)
		(fp_line
			(start -0.67945 -0.3048)
			(end -0.67945 0.3048)
			(stroke
				(width 0.1)
				(type default)
			)
			(layer "B.Fab")
		)
		(fp_line
			(start -0.67945 0.3048)
			(end -0.120396 0.3048)
			(stroke
				(width 0.1)
				(type default)
			)
			(layer "B.Fab")
		)
		(fp_line
			(start -0.12065 -0.3048)
			(end -0.67945 -0.3048)
			(stroke
				(width 0.1)
				(type default)
			)
			(layer "B.Fab")
		)
		(fp_line
			(start -0.12065 -0.2794)
			(end -0.12065 -0.3048)
			(stroke
				(width 0.1)
				(type default)
			)
			(layer "B.Fab")
		)
		(fp_line
			(start -0.120396 0.2794)
			(end 0.12065 0.2794)
			(stroke
				(width 0.1)
				(type default)
			)
			(layer "B.Fab")
		)
		(fp_line
			(start -0.120396 0.3048)
			(end -0.120396 0.2794)
			(stroke
				(width 0.1)
				(type default)
			)
			(layer "B.Fab")
		)
		(fp_line
			(start 0.12065 -0.305054)
			(end 0.12065 -0.2794)
			(stroke
				(width 0.1)
				(type default)
			)
			(layer "B.Fab")
		)
		(fp_line
			(start 0.12065 -0.2794)
			(end -0.12065 -0.2794)
			(stroke
				(width 0.1)
				(type default)
			)
			(layer "B.Fab")
		)
		(fp_line
			(start 0.12065 0.2794)
			(end 0.12065 0.3048)
			(stroke
				(width 0.1)
				(type default)
			)
			(layer "B.Fab")
		)
		(fp_line
			(start 0.12065 0.3048)
			(end 0.67945 0.3048)
			(stroke
				(width 0.1)
				(type default)
			)
			(layer "B.Fab")
		)
		(fp_line
			(start 0.67945 -0.305054)
			(end 0.12065 -0.305054)
			(stroke
				(width 0.1)
				(type default)
			)
			(layer "B.Fab")
		)
		(fp_line
			(start 0.67945 0.3048)
			(end 0.67945 -0.305054)
			(stroke
				(width 0.1)
				(type default)
			)
			(layer "B.Fab")
		)
		(pad "1" smd circle
			(at 0.40005 0 180)
			(size 0 0)
			(layers "B.Cu" "B.Mask" "B.Paste")
			(net "P3V3_AUX")
		)
		(pad "2" smd circle
			(at -0.40005 0 180)
			(size 0 0)
			(layers "B.Cu" "B.Mask" "B.Paste")
			(net "BMC_CPLD_GPIO_13")
		)
	)
	(footprint ""
		(layer "B.Cu")
		(at 55.5752 -64.02324 -90)
		(property "Reference" "R637"
			(at 0 0 90)
			(layer "B.SilkS")
			(hide yes)
			(effects
				(font
					(size 1.27 1.27)
				)
				(justify mirror)
			)
		)
		(property "Value" ""
			(at 0 0 90)
			(layer "B.Fab")
			(effects
				(font
					(size 1.27 1.27)
				)
				(justify mirror)
			)
		)
		(duplicate_pad_numbers_are_jumpers no)
		(fp_line
			(start -0.7874 0.4064)
			(end 0.7874 0.4064)
			(stroke
				(width 0.1524)
				(type default)
			)
			(layer "B.SilkS")
		)
		(fp_line
			(start 0.7874 0.4064)
			(end 0.7874 -0.4064)
			(stroke
				(width 0.1524)
				(type default)
			)
			(layer "B.SilkS")
		)
		(fp_line
			(start -0.7874 -0.4064)
			(end -0.7874 0.4064)
			(stroke
				(width 0.1524)
				(type default)
			)
			(layer "B.SilkS")
		)
		(fp_line
			(start 0.7874 -0.4064)
			(end -0.7874 -0.4064)
			(stroke
				(width 0.1524)
				(type default)
			)
			(layer "B.SilkS")
		)
		(fp_line
			(start -0.67945 0.3048)
			(end -0.120396 0.3048)
			(stroke
				(width 0.1)
				(type default)
			)
			(layer "B.Fab")
		)
		(fp_line
			(start -0.120396 0.3048)
			(end -0.120396 0.2794)
			(stroke
				(width 0.1)
				(type default)
			)
			(layer "B.Fab")
		)
		(fp_line
			(start 0.12065 0.3048)
			(end 0.67945 0.3048)
			(stroke
				(width 0.1)
				(type default)
			)
			(layer "B.Fab")
		)
		(fp_line
			(start 0.67945 0.3048)
			(end 0.67945 -0.305054)
			(stroke
				(width 0.1)
				(type default)
			)
			(layer "B.Fab")
		)
		(fp_line
			(start -0.120396 0.2794)
			(end 0.12065 0.2794)
			(stroke
				(width 0.1)
				(type default)
			)
			(layer "B.Fab")
		)
		(fp_line
			(start 0.12065 0.2794)
			(end 0.12065 0.3048)
			(stroke
				(width 0.1)
				(type default)
			)
			(layer "B.Fab")
		)
		(fp_line
			(start -0.12065 -0.2794)
			(end -0.12065 -0.3048)
			(stroke
				(width 0.1)
				(type default)
			)
			(layer "B.Fab")
		)
		(fp_line
			(start 0.12065 -0.2794)
			(end -0.12065 -0.2794)
			(stroke
				(width 0.1)
				(type default)
			)
			(layer "B.Fab")
		)
		(fp_line
			(start -0.67945 -0.3048)
			(end -0.67945 0.3048)
			(stroke
				(width 0.1)
				(type default)
			)
			(layer "B.Fab")
		)
		(fp_line
			(start -0.12065 -0.3048)
			(end -0.67945 -0.3048)
			(stroke
				(width 0.1)
				(type default)
			)
			(layer "B.Fab")
		)
		(fp_line
			(start 0.12065 -0.305054)
			(end 0.12065 -0.2794)
			(stroke
				(width 0.1)
				(type default)
			)
			(layer "B.Fab")
		)
		(fp_line
			(start 0.67945 -0.305054)
			(end 0.12065 -0.305054)
			(stroke
				(width 0.1)
				(type default)
			)
			(layer "B.Fab")
		)
		(pad "1" smd circle
			(at 0.40005 0 90)
			(size 0 0)
			(layers "B.Cu" "B.Mask" "B.Paste")
			(net "RST_WDTRST_PLD_R1_N")
		)
		(pad "2" smd circle
			(at -0.40005 0 90)
			(size 0 0)
			(layers "B.Cu" "B.Mask" "B.Paste")
			(net "RST_WDTRST_PLD_N")
		)
	)
	(footprint ""
		(layer "B.Cu")
		(at 15.548864 -58.7502 -90)
		(property "Reference" "R294"
			(at 0 0 90)
			(layer "B.SilkS")
			(hide yes)
			(effects
				(font
					(size 1.27 1.27)
				)
				(justify mirror)
			)
		)
		(property "Value" ""
			(at 0 0 90)
			(layer "B.Fab")
			(effects
				(font
					(size 1.27 1.27)
				)
				(justify mirror)
			)
		)
		(duplicate_pad_numbers_are_jumpers no)
		(fp_line
			(start -0.7874 0.4064)
			(end 0.7874 0.4064)
			(stroke
				(width 0.1524)
				(type default)
			)
			(layer "B.SilkS")
		)
		(fp_line
			(start 0.7874 0.4064)
			(end 0.7874 -0.4064)
			(stroke
				(width 0.1524)
				(type default)
			)
			(layer "B.SilkS")
		)
		(fp_line
			(start -0.7874 -0.4064)
			(end -0.7874 0.4064)
			(stroke
				(width 0.1524)
				(type default)
			)
			(layer "B.SilkS")
		)
		(fp_line
			(start 0.7874 -0.4064)
			(end -0.7874 -0.4064)
			(stroke
				(width 0.1524)
				(type default)
			)
			(layer "B.SilkS")
		)
		(fp_line
			(start -0.67945 0.3048)
			(end -0.120396 0.3048)
			(stroke
				(width 0.1)
				(type default)
			)
			(layer "B.Fab")
		)
		(fp_line
			(start -0.120396 0.3048)
			(end -0.120396 0.2794)
			(stroke
				(width 0.1)
				(type default)
			)
			(layer "B.Fab")
		)
		(fp_line
			(start 0.12065 0.3048)
			(end 0.67945 0.3048)
			(stroke
				(width 0.1)
				(type default)
			)
			(layer "B.Fab")
		)
		(fp_line
			(start 0.67945 0.3048)
			(end 0.67945 -0.305054)
			(stroke
				(width 0.1)
				(type default)
			)
			(layer "B.Fab")
		)
		(fp_line
			(start -0.120396 0.2794)
			(end 0.12065 0.2794)
			(stroke
				(width 0.1)
				(type default)
			)
			(layer "B.Fab")
		)
		(fp_line
			(start 0.12065 0.2794)
			(end 0.12065 0.3048)
			(stroke
				(width 0.1)
				(type default)
			)
			(layer "B.Fab")
		)
		(fp_line
			(start -0.12065 -0.2794)
			(end -0.12065 -0.3048)
			(stroke
				(width 0.1)
				(type default)
			)
			(layer "B.Fab")
		)
		(fp_line
			(start 0.12065 -0.2794)
			(end -0.12065 -0.2794)
			(stroke
				(width 0.1)
				(type default)
			)
			(layer "B.Fab")
		)
		(fp_line
			(start -0.67945 -0.3048)
			(end -0.67945 0.3048)
			(stroke
				(width 0.1)
				(type default)
			)
			(layer "B.Fab")
		)
		(fp_line
			(start -0.12065 -0.3048)
			(end -0.67945 -0.3048)
			(stroke
				(width 0.1)
				(type default)
			)
			(layer "B.Fab")
		)
		(fp_line
			(start 0.12065 -0.305054)
			(end 0.12065 -0.2794)
			(stroke
				(width 0.1)
				(type default)
			)
			(layer "B.Fab")
		)
		(fp_line
			(start 0.67945 -0.305054)
			(end 0.12065 -0.305054)
			(stroke
				(width 0.1)
				(type default)
			)
			(layer "B.Fab")
		)
		(pad "1" smd circle
			(at 0.40005 0 90)
			(size 0 0)
			(layers "B.Cu" "B.Mask" "B.Paste")
			(net "SMB_BMC_MM15_SDA")
		)
		(pad "2" smd circle
			(at -0.40005 0 90)
			(size 0 0)
			(layers "B.Cu" "B.Mask" "B.Paste")
			(net "SMB_BMC_MM15_R1_SDA")
		)
	)
	(footprint ""
		(layer "B.Cu")
		(at 47.85487 -71.92137 180)
		(property "Reference" "R778"
			(at 0 0 0)
			(layer "B.SilkS")
			(hide yes)
			(effects
				(font
					(size 1.27 1.27)
				)
				(justify mirror)
			)
		)
		(property "Value" ""
			(at 0 0 0)
			(layer "B.Fab")
			(effects
				(font
					(size 1.27 1.27)
				)
				(justify mirror)
			)
		)
		(duplicate_pad_numbers_are_jumpers no)
		(fp_line
			(start 0.7874 0.4064)
			(end 0.7874 -0.4064)
			(stroke
				(width 0.1524)
				(type default)
			)
			(layer "B.SilkS")
		)
		(fp_line
			(start 0.7874 -0.4064)
			(end -0.7874 -0.4064)
			(stroke
				(width 0.1524)
				(type default)
			)
			(layer "B.SilkS")
		)
		(fp_line
			(start -0.7874 0.4064)
			(end 0.7874 0.4064)
			(stroke
				(width 0.1524)
				(type default)
			)
			(layer "B.SilkS")
		)
		(fp_line
			(start -0.7874 -0.4064)
			(end -0.7874 0.4064)
			(stroke
				(width 0.1524)
				(type default)
			)
			(layer "B.SilkS")
		)
		(fp_line
			(start 0.67945 0.3048)
			(end 0.67945 -0.305054)
			(stroke
				(width 0.1)
				(type default)
			)
			(layer "B.Fab")
		)
		(fp_line
			(start 0.67945 -0.305054)
			(end 0.12065 -0.305054)
			(stroke
				(width 0.1)
				(type default)
			)
			(layer "B.Fab")
		)
		(fp_line
			(start 0.12065 0.3048)
			(end 0.67945 0.3048)
			(stroke
				(width 0.1)
				(type default)
			)
			(layer "B.Fab")
		)
		(fp_line
			(start 0.12065 0.2794)
			(end 0.12065 0.3048)
			(stroke
				(width 0.1)
				(type default)
			)
			(layer "B.Fab")
		)
		(fp_line
			(start 0.12065 -0.2794)
			(end -0.12065 -0.2794)
			(stroke
				(width 0.1)
				(type default)
			)
			(layer "B.Fab")
		)
		(fp_line
			(start 0.12065 -0.305054)
			(end 0.12065 -0.2794)
			(stroke
				(width 0.1)
				(type default)
			)
			(layer "B.Fab")
		)
		(fp_line
			(start -0.120396 0.3048)
			(end -0.120396 0.2794)
			(stroke
				(width 0.1)
				(type default)
			)
			(layer "B.Fab")
		)
		(fp_line
			(start -0.120396 0.2794)
			(end 0.12065 0.2794)
			(stroke
				(width 0.1)
				(type default)
			)
			(layer "B.Fab")
		)
		(fp_line
			(start -0.12065 -0.2794)
			(end -0.12065 -0.3048)
			(stroke
				(width 0.1)
				(type default)
			)
			(layer "B.Fab")
		)
		(fp_line
			(start -0.12065 -0.3048)
			(end -0.67945 -0.3048)
			(stroke
				(width 0.1)
				(type default)
			)
			(layer "B.Fab")
		)
		(fp_line
			(start -0.67945 0.3048)
			(end -0.120396 0.3048)
			(stroke
				(width 0.1)
				(type default)
			)
			(layer "B.Fab")
		)
		(fp_line
			(start -0.67945 -0.3048)
			(end -0.67945 0.3048)
			(stroke
				(width 0.1)
				(type default)
			)
			(layer "B.Fab")
		)
		(pad "1" smd circle
			(at 0.40005 0)
			(size 0 0)
			(layers "B.Cu" "B.Mask" "B.Paste")
			(net "P3V_BAT_SENSOR")
		)
		(pad "2" smd circle
			(at -0.40005 0)
			(size 0 0)
			(layers "B.Cu" "B.Mask" "B.Paste")
			(net "GND")
		)
	)
	(footprint ""
		(layer "B.Cu")
		(at 45.085 -62.0014 -90)
		(property "Reference" "R24"
			(at 0 0 90)
			(layer "B.SilkS")
			(hide yes)
			(effects
				(font
					(size 1.27 1.27)
				)
				(justify mirror)
			)
		)
		(property "Value" ""
			(at 0 0 90)
			(layer "B.Fab")
			(effects
				(font
					(size 1.27 1.27)
				)
				(justify mirror)
			)
		)
		(duplicate_pad_numbers_are_jumpers no)
		(fp_line
			(start -0.7874 0.4064)
			(end 0.7874 0.4064)
			(stroke
				(width 0.1524)
				(type default)
			)
			(layer "B.SilkS")
		)
		(fp_line
			(start 0.7874 0.4064)
			(end 0.7874 -0.4064)
			(stroke
				(width 0.1524)
				(type default)
			)
			(layer "B.SilkS")
		)
		(fp_line
			(start -0.7874 -0.4064)
			(end -0.7874 0.4064)
			(stroke
				(width 0.1524)
				(type default)
			)
			(layer "B.SilkS")
		)
		(fp_line
			(start 0.7874 -0.4064)
			(end -0.7874 -0.4064)
			(stroke
				(width 0.1524)
				(type default)
			)
			(layer "B.SilkS")
		)
		(fp_line
			(start -0.67945 0.3048)
			(end -0.120396 0.3048)
			(stroke
				(width 0.1)
				(type default)
			)
			(layer "B.Fab")
		)
		(fp_line
			(start -0.120396 0.3048)
			(end -0.120396 0.2794)
			(stroke
				(width 0.1)
				(type default)
			)
			(layer "B.Fab")
		)
		(fp_line
			(start 0.12065 0.3048)
			(end 0.67945 0.3048)
			(stroke
				(width 0.1)
				(type default)
			)
			(layer "B.Fab")
		)
		(fp_line
			(start 0.67945 0.3048)
			(end 0.67945 -0.305054)
			(stroke
				(width 0.1)
				(type default)
			)
			(layer "B.Fab")
		)
		(fp_line
			(start -0.120396 0.2794)
			(end 0.12065 0.2794)
			(stroke
				(width 0.1)
				(type default)
			)
			(layer "B.Fab")
		)
		(fp_line
			(start 0.12065 0.2794)
			(end 0.12065 0.3048)
			(stroke
				(width 0.1)
				(type default)
			)
			(layer "B.Fab")
		)
		(fp_line
			(start -0.12065 -0.2794)
			(end -0.12065 -0.3048)
			(stroke
				(width 0.1)
				(type default)
			)
			(layer "B.Fab")
		)
		(fp_line
			(start 0.12065 -0.2794)
			(end -0.12065 -0.2794)
			(stroke
				(width 0.1)
				(type default)
			)
			(layer "B.Fab")
		)
		(fp_line
			(start -0.67945 -0.3048)
			(end -0.67945 0.3048)
			(stroke
				(width 0.1)
				(type default)
			)
			(layer "B.Fab")
		)
		(fp_line
			(start -0.12065 -0.3048)
			(end -0.67945 -0.3048)
			(stroke
				(width 0.1)
				(type default)
			)
			(layer "B.Fab")
		)
		(fp_line
			(start 0.12065 -0.305054)
			(end 0.12065 -0.2794)
			(stroke
				(width 0.1)
				(type default)
			)
			(layer "B.Fab")
		)
		(fp_line
			(start 0.67945 -0.305054)
			(end 0.12065 -0.305054)
			(stroke
				(width 0.1)
				(type default)
			)
			(layer "B.Fab")
		)
		(pad "1" smd circle
			(at 0.40005 0 90)
			(size 0 0)
			(layers "B.Cu" "B.Mask" "B.Paste")
			(net "V_DACB_R")
		)
		(pad "2" smd circle
			(at -0.40005 0 90)
			(size 0 0)
			(layers "B.Cu" "B.Mask" "B.Paste")
			(net "V_DACB")
		)
	)
	(footprint ""
		(layer "B.Cu")
		(at 31.027624 -37.5412 90)
		(property "Reference" "D11"
			(at -3.7592 -3.977894 270)
			(unlocked yes)
			(layer "B.SilkS")
			(effects
				(font
					(size 0.7874 0.5842)
					(thickness 0.1524)
				)
				(justify left mirror)
			)
		)
		(property "Value" ""
			(at 0 0 90)
			(layer "B.Fab")
			(effects
				(font
					(size 1.27 1.27)
				)
				(justify mirror)
			)
		)
		(duplicate_pad_numbers_are_jumpers no)
		(fp_line
			(start 2.262378 -0.899922)
			(end 2.262378 0.899922)
			(stroke
				(width 0.1524)
				(type default)
			)
			(layer "B.SilkS")
		)
		(fp_line
			(start -2.567178 -0.899922)
			(end 2.262378 -0.899922)
			(stroke
				(width 0.1524)
				(type default)
			)
			(layer "B.SilkS")
		)
		(fp_line
			(start 0.3175 -0.508)
			(end 0.3175 0.508)
			(stroke
				(width 0.1524)
				(type default)
			)
			(layer "B.SilkS")
		)
		(fp_line
			(start -0.3175 -0.508)
			(end -0.3175 0.508)
			(stroke
				(width 0.1524)
				(type default)
			)
			(layer "B.SilkS")
		)
		(fp_line
			(start 0.8255 0)
			(end 0.3175 0)
			(stroke
				(width 0.1524)
				(type default)
			)
			(layer "B.SilkS")
		)
		(fp_line
			(start -0.3175 0)
			(end 0.3175 -0.508)
			(stroke
				(width 0.1524)
				(type default)
			)
			(layer "B.SilkS")
		)
		(fp_line
			(start -0.3175 0)
			(end -0.8255 0)
			(stroke
				(width 0.1524)
				(type default)
			)
			(layer "B.SilkS")
		)
		(fp_line
			(start 0.3175 0.508)
			(end -0.3175 0)
			(stroke
				(width 0.1524)
				(type default)
			)
			(layer "B.SilkS")
		)
		(fp_line
			(start 2.262378 0.899922)
			(end -2.567178 0.899922)
			(stroke
				(width 0.1524)
				(type default)
			)
			(layer "B.SilkS")
		)
		(fp_line
			(start -2.567178 0.899922)
			(end -2.567178 -0.899922)
			(stroke
				(width 0.1524)
				(type default)
			)
			(layer "B.SilkS")
		)
		(fp_poly
			(pts
				(xy -2.567178 -0.899922) (xy -2.186178 -0.899922) (xy -2.186178 0.899922) (xy -2.567178 0.899922)
			)
			(stroke
				(width 0)
				(type default)
			)
			(fill yes)
			(layer "B.SilkS")
		)
		(fp_line
			(start 1.400048 -0.899922)
			(end 1.400048 0.899922)
			(stroke
				(width 0.1)
				(type default)
			)
			(layer "B.Fab")
		)
		(fp_line
			(start -1.400048 -0.899922)
			(end 1.400048 -0.899922)
			(stroke
				(width 0.1)
				(type default)
			)
			(layer "B.Fab")
		)
		(fp_line
			(start 1.400048 0.899922)
			(end -1.400048 0.899922)
			(stroke
				(width 0.1)
				(type default)
			)
			(layer "B.Fab")
		)
		(fp_line
			(start -1.400048 0.899922)
			(end -1.400048 -0.899922)
			(stroke
				(width 0.1)
				(type default)
			)
			(layer "B.Fab")
		)
		(fp_text user "+"
			(at 1.938274 -0.618236 270)
			(unlocked yes)
			(layer "B.SilkS")
			(effects
				(font
					(size 1.905 1.4224)
					(thickness 0.1524)
				)
				(justify left mirror)
			)
		)
		(fp_text user "-"
			(at -3.937762 0.241046 270)
			(unlocked yes)
			(layer "B.SilkS")
			(effects
				(font
					(size 1.905 1.4224)
					(thickness 0.1524)
				)
				(justify left mirror)
			)
		)
		(fp_text user "-"
			(at -3.937762 0.241046 270)
			(unlocked yes)
			(layer "B.Fab")
			(effects
				(font
					(size 1.905 1.4224)
					(thickness 0.1524)
				)
				(justify left mirror)
			)
		)
		(fp_text user "+"
			(at 3.29565 0.6858 0)
			(unlocked yes)
			(layer "B.Fab")
			(effects
				(font
					(size 1.905 1.4224)
					(thickness 0.1524)
				)
				(justify left mirror)
			)
		)
		(pad "A" smd rect
			(at 1.640078 0 270)
			(size 0.9906 1.2192)
			(layers "B.Cu" "B.Mask" "B.Paste")
			(net "P5V_AUX")
		)
		(pad "C" smd rect
			(at -1.640078 0 270)
			(size 0.9906 1.2192)
			(layers "B.Cu" "B.Mask" "B.Paste")
			(net "CRT_VCC5")
		)
	)
	(footprint ""
		(layer "B.Cu")
		(at 81.161636 -38.957758 180)
		(property "Reference" "R370"
			(at 0 0 0)
			(layer "B.SilkS")
			(hide yes)
			(effects
				(font
					(size 1.27 1.27)
				)
				(justify mirror)
			)
		)
		(property "Value" ""
			(at 0 0 0)
			(layer "B.Fab")
			(effects
				(font
					(size 1.27 1.27)
				)
				(justify mirror)
			)
		)
		(duplicate_pad_numbers_are_jumpers no)
		(fp_line
			(start 0.7874 0.4064)
			(end 0.7874 -0.4064)
			(stroke
				(width 0.1524)
				(type default)
			)
			(layer "B.SilkS")
		)
		(fp_line
			(start 0.7874 -0.4064)
			(end -0.7874 -0.4064)
			(stroke
				(width 0.1524)
				(type default)
			)
			(layer "B.SilkS")
		)
		(fp_line
			(start -0.7874 0.4064)
			(end 0.7874 0.4064)
			(stroke
				(width 0.1524)
				(type default)
			)
			(layer "B.SilkS")
		)
		(fp_line
			(start -0.7874 -0.4064)
			(end -0.7874 0.4064)
			(stroke
				(width 0.1524)
				(type default)
			)
			(layer "B.SilkS")
		)
		(fp_line
			(start 0.67945 0.3048)
			(end 0.67945 -0.305054)
			(stroke
				(width 0.1)
				(type default)
			)
			(layer "B.Fab")
		)
		(fp_line
			(start 0.67945 -0.305054)
			(end 0.12065 -0.305054)
			(stroke
				(width 0.1)
				(type default)
			)
			(layer "B.Fab")
		)
		(fp_line
			(start 0.12065 0.3048)
			(end 0.67945 0.3048)
			(stroke
				(width 0.1)
				(type default)
			)
			(layer "B.Fab")
		)
		(fp_line
			(start 0.12065 0.2794)
			(end 0.12065 0.3048)
			(stroke
				(width 0.1)
				(type default)
			)
			(layer "B.Fab")
		)
		(fp_line
			(start 0.12065 -0.2794)
			(end -0.12065 -0.2794)
			(stroke
				(width 0.1)
				(type default)
			)
			(layer "B.Fab")
		)
		(fp_line
			(start 0.12065 -0.305054)
			(end 0.12065 -0.2794)
			(stroke
				(width 0.1)
				(type default)
			)
			(layer "B.Fab")
		)
		(fp_line
			(start -0.120396 0.3048)
			(end -0.120396 0.2794)
			(stroke
				(width 0.1)
				(type default)
			)
			(layer "B.Fab")
		)
		(fp_line
			(start -0.120396 0.2794)
			(end 0.12065 0.2794)
			(stroke
				(width 0.1)
				(type default)
			)
			(layer "B.Fab")
		)
		(fp_line
			(start -0.12065 -0.2794)
			(end -0.12065 -0.3048)
			(stroke
				(width 0.1)
				(type default)
			)
			(layer "B.Fab")
		)
		(fp_line
			(start -0.12065 -0.3048)
			(end -0.67945 -0.3048)
			(stroke
				(width 0.1)
				(type default)
			)
			(layer "B.Fab")
		)
		(fp_line
			(start -0.67945 0.3048)
			(end -0.120396 0.3048)
			(stroke
				(width 0.1)
				(type default)
			)
			(layer "B.Fab")
		)
		(fp_line
			(start -0.67945 -0.3048)
			(end -0.67945 0.3048)
			(stroke
				(width 0.1)
				(type default)
			)
			(layer "B.Fab")
		)
		(pad "1" smd circle
			(at 0.40005 0)
			(size 0 0)
			(layers "B.Cu" "B.Mask" "B.Paste")
			(net "M_BMC_DDR4_MBG0")
		)
		(pad "2" smd circle
			(at -0.40005 0)
			(size 0 0)
			(layers "B.Cu" "B.Mask" "B.Paste")
			(net "P1V2_AUX")
		)
	)
	(footprint ""
		(layer "B.Cu")
		(at 54.313582 -68.349368 90)
		(property "Reference" "R792"
			(at 0 0 90)
			(layer "B.SilkS")
			(hide yes)
			(effects
				(font
					(size 1.27 1.27)
				)
				(justify mirror)
			)
		)
		(property "Value" ""
			(at 0 0 90)
			(layer "B.Fab")
			(effects
				(font
					(size 1.27 1.27)
				)
				(justify mirror)
			)
		)
		(duplicate_pad_numbers_are_jumpers no)
		(fp_line
			(start 0.7874 -0.4064)
			(end -0.7874 -0.4064)
			(stroke
				(width 0.1524)
				(type default)
			)
			(layer "B.SilkS")
		)
		(fp_line
			(start -0.7874 -0.4064)
			(end -0.7874 0.4064)
			(stroke
				(width 0.1524)
				(type default)
			)
			(layer "B.SilkS")
		)
		(fp_line
			(start 0.7874 0.4064)
			(end 0.7874 -0.4064)
			(stroke
				(width 0.1524)
				(type default)
			)
			(layer "B.SilkS")
		)
		(fp_line
			(start -0.7874 0.4064)
			(end 0.7874 0.4064)
			(stroke
				(width 0.1524)
				(type default)
			)
			(layer "B.SilkS")
		)
		(fp_line
			(start 0.67945 -0.305054)
			(end 0.12065 -0.305054)
			(stroke
				(width 0.1)
				(type default)
			)
			(layer "B.Fab")
		)
		(fp_line
			(start 0.12065 -0.305054)
			(end 0.12065 -0.2794)
			(stroke
				(width 0.1)
				(type default)
			)
			(layer "B.Fab")
		)
		(fp_line
			(start -0.12065 -0.3048)
			(end -0.67945 -0.3048)
			(stroke
				(width 0.1)
				(type default)
			)
			(layer "B.Fab")
		)
		(fp_line
			(start -0.67945 -0.3048)
			(end -0.67945 0.3048)
			(stroke
				(width 0.1)
				(type default)
			)
			(layer "B.Fab")
		)
		(fp_line
			(start 0.12065 -0.2794)
			(end -0.12065 -0.2794)
			(stroke
				(width 0.1)
				(type default)
			)
			(layer "B.Fab")
		)
		(fp_line
			(start -0.12065 -0.2794)
			(end -0.12065 -0.3048)
			(stroke
				(width 0.1)
				(type default)
			)
			(layer "B.Fab")
		)
		(fp_line
			(start 0.12065 0.2794)
			(end 0.12065 0.3048)
			(stroke
				(width 0.1)
				(type default)
			)
			(layer "B.Fab")
		)
		(fp_line
			(start -0.120396 0.2794)
			(end 0.12065 0.2794)
			(stroke
				(width 0.1)
				(type default)
			)
			(layer "B.Fab")
		)
		(fp_line
			(start 0.67945 0.3048)
			(end 0.67945 -0.305054)
			(stroke
				(width 0.1)
				(type default)
			)
			(layer "B.Fab")
		)
		(fp_line
			(start 0.12065 0.3048)
			(end 0.67945 0.3048)
			(stroke
				(width 0.1)
				(type default)
			)
			(layer "B.Fab")
		)
		(fp_line
			(start -0.120396 0.3048)
			(end -0.120396 0.2794)
			(stroke
				(width 0.1)
				(type default)
			)
			(layer "B.Fab")
		)
		(fp_line
			(start -0.67945 0.3048)
			(end -0.120396 0.3048)
			(stroke
				(width 0.1)
				(type default)
			)
			(layer "B.Fab")
		)
		(pad "1" smd circle
			(at 0.40005 0 270)
			(size 0 0)
			(layers "B.Cu" "B.Mask" "B.Paste")
			(net "P2V5_SENSOR")
		)
		(pad "2" smd circle
			(at -0.40005 0 270)
			(size 0 0)
			(layers "B.Cu" "B.Mask" "B.Paste")
			(net "GND")
		)
	)
	(footprint ""
		(layer "B.Cu")
		(at 72.029066 -60.839096 -90)
		(property "Reference" "C78"
			(at 0 0 90)
			(layer "B.SilkS")
			(hide yes)
			(effects
				(font
					(size 1.27 1.27)
				)
				(justify mirror)
			)
		)
		(property "Value" ""
			(at 0 0 90)
			(layer "B.Fab")
			(effects
				(font
					(size 1.27 1.27)
				)
				(justify mirror)
			)
		)
		(duplicate_pad_numbers_are_jumpers no)
		(fp_line
			(start -0.7874 0.4064)
			(end 0.7874 0.4064)
			(stroke
				(width 0.1524)
				(type default)
			)
			(layer "B.SilkS")
		)
		(fp_line
			(start 0.7874 0.4064)
			(end 0.7874 -0.4064)
			(stroke
				(width 0.1524)
				(type default)
			)
			(layer "B.SilkS")
		)
		(fp_line
			(start -0.7874 -0.4064)
			(end -0.7874 0.4064)
			(stroke
				(width 0.1524)
				(type default)
			)
			(layer "B.SilkS")
		)
		(fp_line
			(start 0.7874 -0.4064)
			(end -0.7874 -0.4064)
			(stroke
				(width 0.1524)
				(type default)
			)
			(layer "B.SilkS")
		)
		(fp_line
			(start -0.67945 0.3048)
			(end -0.120396 0.3048)
			(stroke
				(width 0.1)
				(type default)
			)
			(layer "B.Fab")
		)
		(fp_line
			(start -0.120396 0.3048)
			(end -0.120396 0.2794)
			(stroke
				(width 0.1)
				(type default)
			)
			(layer "B.Fab")
		)
		(fp_line
			(start 0.12065 0.3048)
			(end 0.67945 0.3048)
			(stroke
				(width 0.1)
				(type default)
			)
			(layer "B.Fab")
		)
		(fp_line
			(start 0.67945 0.3048)
			(end 0.67945 -0.305054)
			(stroke
				(width 0.1)
				(type default)
			)
			(layer "B.Fab")
		)
		(fp_line
			(start -0.120396 0.2794)
			(end 0.12065 0.2794)
			(stroke
				(width 0.1)
				(type default)
			)
			(layer "B.Fab")
		)
		(fp_line
			(start 0.12065 0.2794)
			(end 0.12065 0.3048)
			(stroke
				(width 0.1)
				(type default)
			)
			(layer "B.Fab")
		)
		(fp_line
			(start -0.12065 -0.2794)
			(end -0.12065 -0.3048)
			(stroke
				(width 0.1)
				(type default)
			)
			(layer "B.Fab")
		)
		(fp_line
			(start 0.12065 -0.2794)
			(end -0.12065 -0.2794)
			(stroke
				(width 0.1)
				(type default)
			)
			(layer "B.Fab")
		)
		(fp_line
			(start -0.67945 -0.3048)
			(end -0.67945 0.3048)
			(stroke
				(width 0.1)
				(type default)
			)
			(layer "B.Fab")
		)
		(fp_line
			(start -0.12065 -0.3048)
			(end -0.67945 -0.3048)
			(stroke
				(width 0.1)
				(type default)
			)
			(layer "B.Fab")
		)
		(fp_line
			(start 0.12065 -0.305054)
			(end 0.12065 -0.2794)
			(stroke
				(width 0.1)
				(type default)
			)
			(layer "B.Fab")
		)
		(fp_line
			(start 0.67945 -0.305054)
			(end 0.12065 -0.305054)
			(stroke
				(width 0.1)
				(type default)
			)
			(layer "B.Fab")
		)
		(pad "1" smd circle
			(at 0.40005 0 90)
			(size 0 0)
			(layers "B.Cu" "B.Mask" "B.Paste")
			(net "P1V0_STBY_PE_VCC10A")
		)
		(pad "2" smd circle
			(at -0.40005 0 90)
			(size 0 0)
			(layers "B.Cu" "B.Mask" "B.Paste")
			(net "GND")
		)
	)
	(footprint ""
		(layer "B.Cu")
		(at 85.29955 -47.488094)
		(property "Reference" "C13"
			(at 0 0 0)
			(layer "B.SilkS")
			(hide yes)
			(effects
				(font
					(size 1.27 1.27)
				)
				(justify mirror)
			)
		)
		(property "Value" ""
			(at 0 0 0)
			(layer "B.Fab")
			(effects
				(font
					(size 1.27 1.27)
				)
				(justify mirror)
			)
		)
		(duplicate_pad_numbers_are_jumpers no)
		(fp_line
			(start -0.7874 -0.4064)
			(end -0.7874 0.4064)
			(stroke
				(width 0.1524)
				(type default)
			)
			(layer "B.SilkS")
		)
		(fp_line
			(start -0.7874 0.4064)
			(end 0.7874 0.4064)
			(stroke
				(width 0.1524)
				(type default)
			)
			(layer "B.SilkS")
		)
		(fp_line
			(start 0.7874 -0.4064)
			(end -0.7874 -0.4064)
			(stroke
				(width 0.1524)
				(type default)
			)
			(layer "B.SilkS")
		)
		(fp_line
			(start 0.7874 0.4064)
			(end 0.7874 -0.4064)
			(stroke
				(width 0.1524)
				(type default)
			)
			(layer "B.SilkS")
		)
		(fp_line
			(start -0.67945 -0.3048)
			(end -0.67945 0.3048)
			(stroke
				(width 0.1)
				(type default)
			)
			(layer "B.Fab")
		)
		(fp_line
			(start -0.67945 0.3048)
			(end -0.120396 0.3048)
			(stroke
				(width 0.1)
				(type default)
			)
			(layer "B.Fab")
		)
		(fp_line
			(start -0.12065 -0.3048)
			(end -0.67945 -0.3048)
			(stroke
				(width 0.1)
				(type default)
			)
			(layer "B.Fab")
		)
		(fp_line
			(start -0.12065 -0.2794)
			(end -0.12065 -0.3048)
			(stroke
				(width 0.1)
				(type default)
			)
			(layer "B.Fab")
		)
		(fp_line
			(start -0.120396 0.2794)
			(end 0.12065 0.2794)
			(stroke
				(width 0.1)
				(type default)
			)
			(layer "B.Fab")
		)
		(fp_line
			(start -0.120396 0.3048)
			(end -0.120396 0.2794)
			(stroke
				(width 0.1)
				(type default)
			)
			(layer "B.Fab")
		)
		(fp_line
			(start 0.12065 -0.305054)
			(end 0.12065 -0.2794)
			(stroke
				(width 0.1)
				(type default)
			)
			(layer "B.Fab")
		)
		(fp_line
			(start 0.12065 -0.2794)
			(end -0.12065 -0.2794)
			(stroke
				(width 0.1)
				(type default)
			)
			(layer "B.Fab")
		)
		(fp_line
			(start 0.12065 0.2794)
			(end 0.12065 0.3048)
			(stroke
				(width 0.1)
				(type default)
			)
			(layer "B.Fab")
		)
		(fp_line
			(start 0.12065 0.3048)
			(end 0.67945 0.3048)
			(stroke
				(width 0.1)
				(type default)
			)
			(layer "B.Fab")
		)
		(fp_line
			(start 0.67945 -0.305054)
			(end 0.12065 -0.305054)
			(stroke
				(width 0.1)
				(type default)
			)
			(layer "B.Fab")
		)
		(fp_line
			(start 0.67945 0.3048)
			(end 0.67945 -0.305054)
			(stroke
				(width 0.1)
				(type default)
			)
			(layer "B.Fab")
		)
		(pad "1" smd circle
			(at 0.40005 0 180)
			(size 0 0)
			(layers "B.Cu" "B.Mask" "B.Paste")
			(net "P1V2_AUX")
		)
		(pad "2" smd circle
			(at -0.40005 0 180)
			(size 0 0)
			(layers "B.Cu" "B.Mask" "B.Paste")
			(net "GND")
		)
	)
	(footprint ""
		(layer "B.Cu")
		(at 49.5046 -52.3748 180)
		(property "Reference" "C140"
			(at 0 0 0)
			(layer "B.SilkS")
			(hide yes)
			(effects
				(font
					(size 1.27 1.27)
				)
				(justify mirror)
			)
		)
		(property "Value" ""
			(at 0 0 0)
			(layer "B.Fab")
			(effects
				(font
					(size 1.27 1.27)
				)
				(justify mirror)
			)
		)
		(duplicate_pad_numbers_are_jumpers no)
		(fp_line
			(start 0.7874 0.4064)
			(end 0.7874 -0.4064)
			(stroke
				(width 0.1524)
				(type default)
			)
			(layer "B.SilkS")
		)
		(fp_line
			(start 0.7874 -0.4064)
			(end -0.7874 -0.4064)
			(stroke
				(width 0.1524)
				(type default)
			)
			(layer "B.SilkS")
		)
		(fp_line
			(start -0.7874 0.4064)
			(end 0.7874 0.4064)
			(stroke
				(width 0.1524)
				(type default)
			)
			(layer "B.SilkS")
		)
		(fp_line
			(start -0.7874 -0.4064)
			(end -0.7874 0.4064)
			(stroke
				(width 0.1524)
				(type default)
			)
			(layer "B.SilkS")
		)
		(fp_line
			(start 0.67945 0.3048)
			(end 0.67945 -0.305054)
			(stroke
				(width 0.1)
				(type default)
			)
			(layer "B.Fab")
		)
		(fp_line
			(start 0.67945 -0.305054)
			(end 0.12065 -0.305054)
			(stroke
				(width 0.1)
				(type default)
			)
			(layer "B.Fab")
		)
		(fp_line
			(start 0.12065 0.3048)
			(end 0.67945 0.3048)
			(stroke
				(width 0.1)
				(type default)
			)
			(layer "B.Fab")
		)
		(fp_line
			(start 0.12065 0.2794)
			(end 0.12065 0.3048)
			(stroke
				(width 0.1)
				(type default)
			)
			(layer "B.Fab")
		)
		(fp_line
			(start 0.12065 -0.2794)
			(end -0.12065 -0.2794)
			(stroke
				(width 0.1)
				(type default)
			)
			(layer "B.Fab")
		)
		(fp_line
			(start 0.12065 -0.305054)
			(end 0.12065 -0.2794)
			(stroke
				(width 0.1)
				(type default)
			)
			(layer "B.Fab")
		)
		(fp_line
			(start -0.120396 0.3048)
			(end -0.120396 0.2794)
			(stroke
				(width 0.1)
				(type default)
			)
			(layer "B.Fab")
		)
		(fp_line
			(start -0.120396 0.2794)
			(end 0.12065 0.2794)
			(stroke
				(width 0.1)
				(type default)
			)
			(layer "B.Fab")
		)
		(fp_line
			(start -0.12065 -0.2794)
			(end -0.12065 -0.3048)
			(stroke
				(width 0.1)
				(type default)
			)
			(layer "B.Fab")
		)
		(fp_line
			(start -0.12065 -0.3048)
			(end -0.67945 -0.3048)
			(stroke
				(width 0.1)
				(type default)
			)
			(layer "B.Fab")
		)
		(fp_line
			(start -0.67945 0.3048)
			(end -0.120396 0.3048)
			(stroke
				(width 0.1)
				(type default)
			)
			(layer "B.Fab")
		)
		(fp_line
			(start -0.67945 -0.3048)
			(end -0.67945 0.3048)
			(stroke
				(width 0.1)
				(type default)
			)
			(layer "B.Fab")
		)
		(pad "1" smd circle
			(at 0.40005 0)
			(size 0 0)
			(layers "B.Cu" "B.Mask" "B.Paste")
			(net "P1V2_P1V0_I3C_VDDL2")
		)
		(pad "2" smd circle
			(at -0.40005 0)
			(size 0 0)
			(layers "B.Cu" "B.Mask" "B.Paste")
			(net "GND")
		)
	)
	(footprint ""
		(layer "B.Cu")
		(at 33.655 -70.358)
		(property "Reference" "C231"
			(at 0 0 0)
			(layer "B.SilkS")
			(hide yes)
			(effects
				(font
					(size 1.27 1.27)
				)
				(justify mirror)
			)
		)
		(property "Value" ""
			(at 0 0 0)
			(layer "B.Fab")
			(effects
				(font
					(size 1.27 1.27)
				)
				(justify mirror)
			)
		)
		(duplicate_pad_numbers_are_jumpers no)
		(fp_line
			(start -0.7874 -0.4064)
			(end -0.7874 0.4064)
			(stroke
				(width 0.1524)
				(type default)
			)
			(layer "B.SilkS")
		)
		(fp_line
			(start -0.7874 0.4064)
			(end 0.7874 0.4064)
			(stroke
				(width 0.1524)
				(type default)
			)
			(layer "B.SilkS")
		)
		(fp_line
			(start 0.7874 -0.4064)
			(end -0.7874 -0.4064)
			(stroke
				(width 0.1524)
				(type default)
			)
			(layer "B.SilkS")
		)
		(fp_line
			(start 0.7874 0.4064)
			(end 0.7874 -0.4064)
			(stroke
				(width 0.1524)
				(type default)
			)
			(layer "B.SilkS")
		)
		(fp_line
			(start -0.67945 -0.3048)
			(end -0.67945 0.3048)
			(stroke
				(width 0.1)
				(type default)
			)
			(layer "B.Fab")
		)
		(fp_line
			(start -0.67945 0.3048)
			(end -0.120396 0.3048)
			(stroke
				(width 0.1)
				(type default)
			)
			(layer "B.Fab")
		)
		(fp_line
			(start -0.12065 -0.3048)
			(end -0.67945 -0.3048)
			(stroke
				(width 0.1)
				(type default)
			)
			(layer "B.Fab")
		)
		(fp_line
			(start -0.12065 -0.2794)
			(end -0.12065 -0.3048)
			(stroke
				(width 0.1)
				(type default)
			)
			(layer "B.Fab")
		)
		(fp_line
			(start -0.120396 0.2794)
			(end 0.12065 0.2794)
			(stroke
				(width 0.1)
				(type default)
			)
			(layer "B.Fab")
		)
		(fp_line
			(start -0.120396 0.3048)
			(end -0.120396 0.2794)
			(stroke
				(width 0.1)
				(type default)
			)
			(layer "B.Fab")
		)
		(fp_line
			(start 0.12065 -0.305054)
			(end 0.12065 -0.2794)
			(stroke
				(width 0.1)
				(type default)
			)
			(layer "B.Fab")
		)
		(fp_line
			(start 0.12065 -0.2794)
			(end -0.12065 -0.2794)
			(stroke
				(width 0.1)
				(type default)
			)
			(layer "B.Fab")
		)
		(fp_line
			(start 0.12065 0.2794)
			(end 0.12065 0.3048)
			(stroke
				(width 0.1)
				(type default)
			)
			(layer "B.Fab")
		)
		(fp_line
			(start 0.12065 0.3048)
			(end 0.67945 0.3048)
			(stroke
				(width 0.1)
				(type default)
			)
			(layer "B.Fab")
		)
		(fp_line
			(start 0.67945 -0.305054)
			(end 0.12065 -0.305054)
			(stroke
				(width 0.1)
				(type default)
			)
			(layer "B.Fab")
		)
		(fp_line
			(start 0.67945 0.3048)
			(end 0.67945 -0.305054)
			(stroke
				(width 0.1)
				(type default)
			)
			(layer "B.Fab")
		)
		(pad "1" smd circle
			(at 0.40005 0 180)
			(size 0 0)
			(layers "B.Cu" "B.Mask" "B.Paste")
			(net "P3V3_AUX")
		)
		(pad "2" smd circle
			(at -0.40005 0 180)
			(size 0 0)
			(layers "B.Cu" "B.Mask" "B.Paste")
			(net "GND")
		)
	)
	(footprint ""
		(layer "B.Cu")
		(at 66.1035 -94.8182 90)
		(property "Reference" "Q5"
			(at 2.29743 -1.7907 0)
			(unlocked yes)
			(layer "B.SilkS")
			(effects
				(font
					(size 0.7874 0.5842)
					(thickness 0.1524)
				)
				(justify left mirror)
			)
		)
		(property "Value" ""
			(at 0 0 90)
			(layer "B.Fab")
			(effects
				(font
					(size 1.27 1.27)
				)
				(justify mirror)
			)
		)
		(duplicate_pad_numbers_are_jumpers no)
		(fp_line
			(start 1.834896 -1.550162)
			(end 1.834896 1.550162)
			(stroke
				(width 0.1524)
				(type default)
			)
			(layer "B.SilkS")
		)
		(fp_line
			(start 0.494538 -1.550162)
			(end 1.834896 -1.550162)
			(stroke
				(width 0.1524)
				(type default)
			)
			(layer "B.SilkS")
		)
		(fp_line
			(start -0.494538 -1.550162)
			(end 0 -0.94996)
			(stroke
				(width 0.1524)
				(type default)
			)
			(layer "B.SilkS")
		)
		(fp_line
			(start -1.834896 -1.550162)
			(end -0.494538 -1.550162)
			(stroke
				(width 0.1524)
				(type default)
			)
			(layer "B.SilkS")
		)
		(fp_line
			(start 0 -0.94996)
			(end 0.494538 -1.550162)
			(stroke
				(width 0.1524)
				(type default)
			)
			(layer "B.SilkS")
		)
		(fp_line
			(start 1.834896 1.550162)
			(end -1.834896 1.550162)
			(stroke
				(width 0.1524)
				(type default)
			)
			(layer "B.SilkS")
		)
		(fp_line
			(start -1.834896 1.550162)
			(end -1.834896 -1.550162)
			(stroke
				(width 0.1524)
				(type default)
			)
			(layer "B.SilkS")
		)
		(fp_poly
			(pts
				(xy 1.1938 -1.7145) (xy 0.6858 -2.7305) (xy 1.7018 -2.7305)
			)
			(stroke
				(width 0)
				(type default)
			)
			(fill yes)
			(layer "B.SilkS")
		)
		(fp_line
			(start 0.850138 -1.550162)
			(end -0.850138 -1.550162)
			(stroke
				(width 0.1)
				(type default)
			)
			(layer "B.Fab")
		)
		(fp_line
			(start -0.850138 -1.550162)
			(end -0.850138 1.550162)
			(stroke
				(width 0.1)
				(type default)
			)
			(layer "B.Fab")
		)
		(fp_line
			(start 0.850138 1.550162)
			(end 0.850138 -1.550162)
			(stroke
				(width 0.1)
				(type default)
			)
			(layer "B.Fab")
		)
		(fp_line
			(start -0.850138 1.550162)
			(end 0.850138 1.550162)
			(stroke
				(width 0.1)
				(type default)
			)
			(layer "B.Fab")
		)
		(fp_poly
			(pts
				(xy 2.081784 -0.94996) (xy 3.097784 -1.45796) (xy 3.097784 -0.44196)
			)
			(stroke
				(width 0)
				(type default)
			)
			(fill yes)
			(layer "B.Fab")
		)
		(pad "1" smd rect
			(at 1.199896 -0.94996 180)
			(size 0.7112 1.016)
			(layers "B.Cu" "B.Mask" "B.Paste")
			(net "PGPPA_BMC_AUX_L")
		)
		(pad "2" smd rect
			(at 1.199896 0 180)
			(size 0.7112 1.016)
			(layers "B.Cu" "B.Mask" "B.Paste")
			(net "PGPPA_BMC_AUX_L")
		)
		(pad "3" smd rect
			(at 1.199896 0.94996 180)
			(size 0.7112 1.016)
			(layers "B.Cu" "B.Mask" "B.Paste")
			(net "LPC_ESPI_SEL_N")
		)
		(pad "4" smd rect
			(at -1.199896 0.94996 180)
			(size 0.7112 1.016)
			(layers "B.Cu" "B.Mask" "B.Paste")
			(net "P1V8_AUX")
		)
		(pad "5" smd rect
			(at -1.199896 0 180)
			(size 0.7112 1.016)
			(layers "B.Cu" "B.Mask" "B.Paste")
			(net "PGPPA_BMC_AUX_L")
		)
		(pad "6" smd rect
			(at -1.199896 -0.94996 180)
			(size 0.7112 1.016)
			(layers "B.Cu" "B.Mask" "B.Paste")
			(net "PGPPA_BMC_AUX_L")
		)
	)
	(footprint ""
		(layer "B.Cu")
		(at 12.319 -98.552)
		(property "Reference" "R320"
			(at 0 0 0)
			(layer "B.SilkS")
			(hide yes)
			(effects
				(font
					(size 1.27 1.27)
				)
				(justify mirror)
			)
		)
		(property "Value" ""
			(at 0 0 0)
			(layer "B.Fab")
			(effects
				(font
					(size 1.27 1.27)
				)
				(justify mirror)
			)
		)
		(duplicate_pad_numbers_are_jumpers no)
		(fp_line
			(start -0.7874 -0.4064)
			(end -0.7874 0.4064)
			(stroke
				(width 0.1524)
				(type default)
			)
			(layer "B.SilkS")
		)
		(fp_line
			(start -0.7874 0.4064)
			(end 0.7874 0.4064)
			(stroke
				(width 0.1524)
				(type default)
			)
			(layer "B.SilkS")
		)
		(fp_line
			(start 0.7874 -0.4064)
			(end -0.7874 -0.4064)
			(stroke
				(width 0.1524)
				(type default)
			)
			(layer "B.SilkS")
		)
		(fp_line
			(start 0.7874 0.4064)
			(end 0.7874 -0.4064)
			(stroke
				(width 0.1524)
				(type default)
			)
			(layer "B.SilkS")
		)
		(fp_line
			(start -0.67945 -0.3048)
			(end -0.67945 0.3048)
			(stroke
				(width 0.1)
				(type default)
			)
			(layer "B.Fab")
		)
		(fp_line
			(start -0.67945 0.3048)
			(end -0.120396 0.3048)
			(stroke
				(width 0.1)
				(type default)
			)
			(layer "B.Fab")
		)
		(fp_line
			(start -0.12065 -0.3048)
			(end -0.67945 -0.3048)
			(stroke
				(width 0.1)
				(type default)
			)
			(layer "B.Fab")
		)
		(fp_line
			(start -0.12065 -0.2794)
			(end -0.12065 -0.3048)
			(stroke
				(width 0.1)
				(type default)
			)
			(layer "B.Fab")
		)
		(fp_line
			(start -0.120396 0.2794)
			(end 0.12065 0.2794)
			(stroke
				(width 0.1)
				(type default)
			)
			(layer "B.Fab")
		)
		(fp_line
			(start -0.120396 0.3048)
			(end -0.120396 0.2794)
			(stroke
				(width 0.1)
				(type default)
			)
			(layer "B.Fab")
		)
		(fp_line
			(start 0.12065 -0.305054)
			(end 0.12065 -0.2794)
			(stroke
				(width 0.1)
				(type default)
			)
			(layer "B.Fab")
		)
		(fp_line
			(start 0.12065 -0.2794)
			(end -0.12065 -0.2794)
			(stroke
				(width 0.1)
				(type default)
			)
			(layer "B.Fab")
		)
		(fp_line
			(start 0.12065 0.2794)
			(end 0.12065 0.3048)
			(stroke
				(width 0.1)
				(type default)
			)
			(layer "B.Fab")
		)
		(fp_line
			(start 0.12065 0.3048)
			(end 0.67945 0.3048)
			(stroke
				(width 0.1)
				(type default)
			)
			(layer "B.Fab")
		)
		(fp_line
			(start 0.67945 -0.305054)
			(end 0.12065 -0.305054)
			(stroke
				(width 0.1)
				(type default)
			)
			(layer "B.Fab")
		)
		(fp_line
			(start 0.67945 0.3048)
			(end 0.67945 -0.305054)
			(stroke
				(width 0.1)
				(type default)
			)
			(layer "B.Fab")
		)
		(pad "1" smd circle
			(at 0.40005 0 180)
			(size 0 0)
			(layers "B.Cu" "B.Mask" "B.Paste")
			(net "PWRGD_P2V5_AUX_R1")
		)
		(pad "2" smd circle
			(at -0.40005 0 180)
			(size 0 0)
			(layers "B.Cu" "B.Mask" "B.Paste")
			(net "PWRGD_P2V5_AUX")
		)
	)
	(footprint ""
		(layer "B.Cu")
		(at 36.068 -106.3625 -90)
		(property "Reference" "R224"
			(at 0 0 90)
			(layer "B.SilkS")
			(hide yes)
			(effects
				(font
					(size 1.27 1.27)
				)
				(justify mirror)
			)
		)
		(property "Value" ""
			(at 0 0 90)
			(layer "B.Fab")
			(effects
				(font
					(size 1.27 1.27)
				)
				(justify mirror)
			)
		)
		(duplicate_pad_numbers_are_jumpers no)
		(fp_line
			(start -0.7874 0.4064)
			(end 0.7874 0.4064)
			(stroke
				(width 0.1524)
				(type default)
			)
			(layer "B.SilkS")
		)
		(fp_line
			(start 0.7874 0.4064)
			(end 0.7874 -0.4064)
			(stroke
				(width 0.1524)
				(type default)
			)
			(layer "B.SilkS")
		)
		(fp_line
			(start -0.7874 -0.4064)
			(end -0.7874 0.4064)
			(stroke
				(width 0.1524)
				(type default)
			)
			(layer "B.SilkS")
		)
		(fp_line
			(start 0.7874 -0.4064)
			(end -0.7874 -0.4064)
			(stroke
				(width 0.1524)
				(type default)
			)
			(layer "B.SilkS")
		)
		(fp_line
			(start -0.67945 0.3048)
			(end -0.120396 0.3048)
			(stroke
				(width 0.1)
				(type default)
			)
			(layer "B.Fab")
		)
		(fp_line
			(start -0.120396 0.3048)
			(end -0.120396 0.2794)
			(stroke
				(width 0.1)
				(type default)
			)
			(layer "B.Fab")
		)
		(fp_line
			(start 0.12065 0.3048)
			(end 0.67945 0.3048)
			(stroke
				(width 0.1)
				(type default)
			)
			(layer "B.Fab")
		)
		(fp_line
			(start 0.67945 0.3048)
			(end 0.67945 -0.305054)
			(stroke
				(width 0.1)
				(type default)
			)
			(layer "B.Fab")
		)
		(fp_line
			(start -0.120396 0.2794)
			(end 0.12065 0.2794)
			(stroke
				(width 0.1)
				(type default)
			)
			(layer "B.Fab")
		)
		(fp_line
			(start 0.12065 0.2794)
			(end 0.12065 0.3048)
			(stroke
				(width 0.1)
				(type default)
			)
			(layer "B.Fab")
		)
		(fp_line
			(start -0.12065 -0.2794)
			(end -0.12065 -0.3048)
			(stroke
				(width 0.1)
				(type default)
			)
			(layer "B.Fab")
		)
		(fp_line
			(start 0.12065 -0.2794)
			(end -0.12065 -0.2794)
			(stroke
				(width 0.1)
				(type default)
			)
			(layer "B.Fab")
		)
		(fp_line
			(start -0.67945 -0.3048)
			(end -0.67945 0.3048)
			(stroke
				(width 0.1)
				(type default)
			)
			(layer "B.Fab")
		)
		(fp_line
			(start -0.12065 -0.3048)
			(end -0.67945 -0.3048)
			(stroke
				(width 0.1)
				(type default)
			)
			(layer "B.Fab")
		)
		(fp_line
			(start 0.12065 -0.305054)
			(end 0.12065 -0.2794)
			(stroke
				(width 0.1)
				(type default)
			)
			(layer "B.Fab")
		)
		(fp_line
			(start 0.67945 -0.305054)
			(end 0.12065 -0.305054)
			(stroke
				(width 0.1)
				(type default)
			)
			(layer "B.Fab")
		)
		(pad "1" smd circle
			(at 0.40005 0 90)
			(size 0 0)
			(layers "B.Cu" "B.Mask" "B.Paste")
			(net "JTAG_1_BMC_TDO_R")
		)
		(pad "2" smd circle
			(at -0.40005 0 90)
			(size 0 0)
			(layers "B.Cu" "B.Mask" "B.Paste")
			(net "JTAG_MB_TDO")
		)
	)
	(footprint ""
		(layer "B.Cu")
		(at 75.438 -24.7904 180)
		(property "Reference" "R696"
			(at 0 0 0)
			(layer "B.SilkS")
			(hide yes)
			(effects
				(font
					(size 1.27 1.27)
				)
				(justify mirror)
			)
		)
		(property "Value" ""
			(at 0 0 0)
			(layer "B.Fab")
			(effects
				(font
					(size 1.27 1.27)
				)
				(justify mirror)
			)
		)
		(duplicate_pad_numbers_are_jumpers no)
		(fp_line
			(start 0.7874 0.4064)
			(end 0.7874 -0.4064)
			(stroke
				(width 0.1524)
				(type default)
			)
			(layer "B.SilkS")
		)
		(fp_line
			(start 0.7874 -0.4064)
			(end -0.7874 -0.4064)
			(stroke
				(width 0.1524)
				(type default)
			)
			(layer "B.SilkS")
		)
		(fp_line
			(start -0.7874 0.4064)
			(end 0.7874 0.4064)
			(stroke
				(width 0.1524)
				(type default)
			)
			(layer "B.SilkS")
		)
		(fp_line
			(start -0.7874 -0.4064)
			(end -0.7874 0.4064)
			(stroke
				(width 0.1524)
				(type default)
			)
			(layer "B.SilkS")
		)
		(fp_line
			(start 0.67945 0.3048)
			(end 0.67945 -0.305054)
			(stroke
				(width 0.1)
				(type default)
			)
			(layer "B.Fab")
		)
		(fp_line
			(start 0.67945 -0.305054)
			(end 0.12065 -0.305054)
			(stroke
				(width 0.1)
				(type default)
			)
			(layer "B.Fab")
		)
		(fp_line
			(start 0.12065 0.3048)
			(end 0.67945 0.3048)
			(stroke
				(width 0.1)
				(type default)
			)
			(layer "B.Fab")
		)
		(fp_line
			(start 0.12065 0.2794)
			(end 0.12065 0.3048)
			(stroke
				(width 0.1)
				(type default)
			)
			(layer "B.Fab")
		)
		(fp_line
			(start 0.12065 -0.2794)
			(end -0.12065 -0.2794)
			(stroke
				(width 0.1)
				(type default)
			)
			(layer "B.Fab")
		)
		(fp_line
			(start 0.12065 -0.305054)
			(end 0.12065 -0.2794)
			(stroke
				(width 0.1)
				(type default)
			)
			(layer "B.Fab")
		)
		(fp_line
			(start -0.120396 0.3048)
			(end -0.120396 0.2794)
			(stroke
				(width 0.1)
				(type default)
			)
			(layer "B.Fab")
		)
		(fp_line
			(start -0.120396 0.2794)
			(end 0.12065 0.2794)
			(stroke
				(width 0.1)
				(type default)
			)
			(layer "B.Fab")
		)
		(fp_line
			(start -0.12065 -0.2794)
			(end -0.12065 -0.3048)
			(stroke
				(width 0.1)
				(type default)
			)
			(layer "B.Fab")
		)
		(fp_line
			(start -0.12065 -0.3048)
			(end -0.67945 -0.3048)
			(stroke
				(width 0.1)
				(type default)
			)
			(layer "B.Fab")
		)
		(fp_line
			(start -0.67945 0.3048)
			(end -0.120396 0.3048)
			(stroke
				(width 0.1)
				(type default)
			)
			(layer "B.Fab")
		)
		(fp_line
			(start -0.67945 -0.3048)
			(end -0.67945 0.3048)
			(stroke
				(width 0.1)
				(type default)
			)
			(layer "B.Fab")
		)
		(pad "1" smd circle
			(at 0.40005 0)
			(size 0 0)
			(layers "B.Cu" "B.Mask" "B.Paste")
			(net "LED_POSTCODE_3")
		)
		(pad "2" smd circle
			(at -0.40005 0)
			(size 0 0)
			(layers "B.Cu" "B.Mask" "B.Paste")
			(net "LED_POSTCODE_3_R1")
		)
	)
	(footprint ""
		(layer "B.Cu")
		(at 11.557 -43.688)
		(property "Reference" "ME2"
			(at 0 0 0)
			(layer "B.SilkS")
			(hide yes)
			(effects
				(font
					(size 1.27 1.27)
				)
				(justify mirror)
			)
		)
		(property "Value" ""
			(at 0 0 0)
			(layer "B.Fab")
			(effects
				(font
					(size 1.27 1.27)
				)
				(justify mirror)
			)
		)
		(duplicate_pad_numbers_are_jumpers no)
		(fp_poly
			(pts
				(xy -1.32715 -3.4417) (xy -2.01295 -3.4417) (xy -2.01295 -3.2512) (xy -1.32715 -3.2512)
			)
			(stroke
				(width 0)
				(type default)
			)
			(fill yes)
			(layer "B.SilkS")
		)
		(fp_poly
			(pts
				(xy 0 -0.5842) (xy -3.3401 -0.5842) (xy -3.3401 0) (xy 0 0)
			)
			(stroke
				(width 0)
				(type default)
			)
			(fill yes)
			(layer "B.SilkS")
		)
		(fp_poly
			(pts
				(xy 0.070612 -0.681228) (xy 0.197612 -0.820928) (xy -0.852678 -1.91262) (xy -0.728472 -3.29184)
				(xy 0.248412 -4.300728) (xy 0.184912 -4.478528) (xy 0.007112 -4.503928) (xy -0.684022 -3.785616)
				(xy -0.65659 -4.0894) (xy -0.97155 -4.3434) (xy -1.22555 -4.3561) (xy -1.46685 -4.4704) (xy -2.01295 -4.4704)
				(xy -2.15265 -4.4069) (xy -2.44475 -4.191) (xy -2.49555 -4.191) (xy -2.59715 -4.2926) (xy -2.80035 -4.2672)
				(xy -2.88925 -4.1656) (xy -2.88925 -4.029456) (xy -3.345688 -4.503928) (xy -3.523488 -4.478528)
				(xy -3.586988 -4.300728) (xy -2.88925 -3.58013) (xy -2.88925 -3.3147) (xy -2.82575 -3.2385) (xy -2.67335 -3.2385)
				(xy -2.521966 -1.875282) (xy -2.545842 -1.85039)
				(arc
					(start -2.55905 -1.8415)
					(mid -2.648099 -1.766068)
					(end -2.717292 -1.672082)
				)
				(xy -3.536188 -0.820928) (xy -3.409188 -0.681228) (xy -3.244088 -0.693928)
				(arc
					(start -2.737612 -1.216914)
					(mid -2.31728 -0.925553)
					(end -1.86055 -1.1557)
				)
				(xy -0.92075 -1.1557) (xy -0.888492 -1.51384) (xy -0.094488 -0.693928)
			)
			(stroke
				(width 0)
				(type default)
			)
			(fill yes)
			(layer "B.SilkS")
		)
	)
	(footprint ""
		(layer "B.Cu")
		(at 56.331358 -46.200568)
		(property "Reference" "C85"
			(at 0 0 0)
			(layer "B.SilkS")
			(hide yes)
			(effects
				(font
					(size 1.27 1.27)
				)
				(justify mirror)
			)
		)
		(property "Value" ""
			(at 0 0 0)
			(layer "B.Fab")
			(effects
				(font
					(size 1.27 1.27)
				)
				(justify mirror)
			)
		)
		(duplicate_pad_numbers_are_jumpers no)
		(fp_line
			(start -0.7874 -0.4064)
			(end -0.7874 0.4064)
			(stroke
				(width 0.1524)
				(type default)
			)
			(layer "B.SilkS")
		)
		(fp_line
			(start -0.7874 0.4064)
			(end 0.7874 0.4064)
			(stroke
				(width 0.1524)
				(type default)
			)
			(layer "B.SilkS")
		)
		(fp_line
			(start 0.7874 -0.4064)
			(end -0.7874 -0.4064)
			(stroke
				(width 0.1524)
				(type default)
			)
			(layer "B.SilkS")
		)
		(fp_line
			(start 0.7874 0.4064)
			(end 0.7874 -0.4064)
			(stroke
				(width 0.1524)
				(type default)
			)
			(layer "B.SilkS")
		)
		(fp_line
			(start -0.67945 -0.3048)
			(end -0.67945 0.3048)
			(stroke
				(width 0.1)
				(type default)
			)
			(layer "B.Fab")
		)
		(fp_line
			(start -0.67945 0.3048)
			(end -0.120396 0.3048)
			(stroke
				(width 0.1)
				(type default)
			)
			(layer "B.Fab")
		)
		(fp_line
			(start -0.12065 -0.3048)
			(end -0.67945 -0.3048)
			(stroke
				(width 0.1)
				(type default)
			)
			(layer "B.Fab")
		)
		(fp_line
			(start -0.12065 -0.2794)
			(end -0.12065 -0.3048)
			(stroke
				(width 0.1)
				(type default)
			)
			(layer "B.Fab")
		)
		(fp_line
			(start -0.120396 0.2794)
			(end 0.12065 0.2794)
			(stroke
				(width 0.1)
				(type default)
			)
			(layer "B.Fab")
		)
		(fp_line
			(start -0.120396 0.3048)
			(end -0.120396 0.2794)
			(stroke
				(width 0.1)
				(type default)
			)
			(layer "B.Fab")
		)
		(fp_line
			(start 0.12065 -0.305054)
			(end 0.12065 -0.2794)
			(stroke
				(width 0.1)
				(type default)
			)
			(layer "B.Fab")
		)
		(fp_line
			(start 0.12065 -0.2794)
			(end -0.12065 -0.2794)
			(stroke
				(width 0.1)
				(type default)
			)
			(layer "B.Fab")
		)
		(fp_line
			(start 0.12065 0.2794)
			(end 0.12065 0.3048)
			(stroke
				(width 0.1)
				(type default)
			)
			(layer "B.Fab")
		)
		(fp_line
			(start 0.12065 0.3048)
			(end 0.67945 0.3048)
			(stroke
				(width 0.1)
				(type default)
			)
			(layer "B.Fab")
		)
		(fp_line
			(start 0.67945 -0.305054)
			(end 0.12065 -0.305054)
			(stroke
				(width 0.1)
				(type default)
			)
			(layer "B.Fab")
		)
		(fp_line
			(start 0.67945 0.3048)
			(end 0.67945 -0.305054)
			(stroke
				(width 0.1)
				(type default)
			)
			(layer "B.Fab")
		)
		(pad "1" smd circle
			(at 0.40005 0 180)
			(size 0 0)
			(layers "B.Cu" "B.Mask" "B.Paste")
			(net "P3V3_RGM")
		)
		(pad "2" smd circle
			(at -0.40005 0 180)
			(size 0 0)
			(layers "B.Cu" "B.Mask" "B.Paste")
			(net "GND")
		)
	)
	(footprint ""
		(layer "B.Cu")
		(at 44.0944 -62.0014 -90)
		(property "Reference" "R22"
			(at 0 0 90)
			(layer "B.SilkS")
			(hide yes)
			(effects
				(font
					(size 1.27 1.27)
				)
				(justify mirror)
			)
		)
		(property "Value" ""
			(at 0 0 90)
			(layer "B.Fab")
			(effects
				(font
					(size 1.27 1.27)
				)
				(justify mirror)
			)
		)
		(duplicate_pad_numbers_are_jumpers no)
		(fp_line
			(start -0.7874 0.4064)
			(end 0.7874 0.4064)
			(stroke
				(width 0.1524)
				(type default)
			)
			(layer "B.SilkS")
		)
		(fp_line
			(start 0.7874 0.4064)
			(end 0.7874 -0.4064)
			(stroke
				(width 0.1524)
				(type default)
			)
			(layer "B.SilkS")
		)
		(fp_line
			(start -0.7874 -0.4064)
			(end -0.7874 0.4064)
			(stroke
				(width 0.1524)
				(type default)
			)
			(layer "B.SilkS")
		)
		(fp_line
			(start 0.7874 -0.4064)
			(end -0.7874 -0.4064)
			(stroke
				(width 0.1524)
				(type default)
			)
			(layer "B.SilkS")
		)
		(fp_line
			(start -0.67945 0.3048)
			(end -0.120396 0.3048)
			(stroke
				(width 0.1)
				(type default)
			)
			(layer "B.Fab")
		)
		(fp_line
			(start -0.120396 0.3048)
			(end -0.120396 0.2794)
			(stroke
				(width 0.1)
				(type default)
			)
			(layer "B.Fab")
		)
		(fp_line
			(start 0.12065 0.3048)
			(end 0.67945 0.3048)
			(stroke
				(width 0.1)
				(type default)
			)
			(layer "B.Fab")
		)
		(fp_line
			(start 0.67945 0.3048)
			(end 0.67945 -0.305054)
			(stroke
				(width 0.1)
				(type default)
			)
			(layer "B.Fab")
		)
		(fp_line
			(start -0.120396 0.2794)
			(end 0.12065 0.2794)
			(stroke
				(width 0.1)
				(type default)
			)
			(layer "B.Fab")
		)
		(fp_line
			(start 0.12065 0.2794)
			(end 0.12065 0.3048)
			(stroke
				(width 0.1)
				(type default)
			)
			(layer "B.Fab")
		)
		(fp_line
			(start -0.12065 -0.2794)
			(end -0.12065 -0.3048)
			(stroke
				(width 0.1)
				(type default)
			)
			(layer "B.Fab")
		)
		(fp_line
			(start 0.12065 -0.2794)
			(end -0.12065 -0.2794)
			(stroke
				(width 0.1)
				(type default)
			)
			(layer "B.Fab")
		)
		(fp_line
			(start -0.67945 -0.3048)
			(end -0.67945 0.3048)
			(stroke
				(width 0.1)
				(type default)
			)
			(layer "B.Fab")
		)
		(fp_line
			(start -0.12065 -0.3048)
			(end -0.67945 -0.3048)
			(stroke
				(width 0.1)
				(type default)
			)
			(layer "B.Fab")
		)
		(fp_line
			(start 0.12065 -0.305054)
			(end 0.12065 -0.2794)
			(stroke
				(width 0.1)
				(type default)
			)
			(layer "B.Fab")
		)
		(fp_line
			(start 0.67945 -0.305054)
			(end 0.12065 -0.305054)
			(stroke
				(width 0.1)
				(type default)
			)
			(layer "B.Fab")
		)
		(pad "1" smd circle
			(at 0.40005 0 90)
			(size 0 0)
			(layers "B.Cu" "B.Mask" "B.Paste")
			(net "V_DACB_R")
		)
		(pad "2" smd circle
			(at -0.40005 0 90)
			(size 0 0)
			(layers "B.Cu" "B.Mask" "B.Paste")
			(net "GND")
		)
	)
	(footprint ""
		(layer "B.Cu")
		(at 7.838186 -3.639312)
		(property "Reference" ""
			(at 0 0 0)
			(layer "B.SilkS")
			(hide yes)
			(effects
				(font
					(size 1.27 1.27)
				)
				(justify mirror)
			)
		)
		(property "Value" ""
			(at 0 0 0)
			(layer "B.Fab")
			(effects
				(font
					(size 1.27 1.27)
				)
				(justify mirror)
			)
		)
		(duplicate_pad_numbers_are_jumpers no)
		(pad "1" smd circle
			(at 0 0 180)
			(size 0.9906 0.9906)
			(layers "B.Cu" "B.Mask" "B.Paste")
			(net "Net_135")
		)
		(zone
			(layer "B.Cu")
			(hatch none 0.5)
			(connect_pads
				(clearance 0)
			)
			(min_thickness 0.25)
			(keepout
				(tracks not_allowed)
				(vias allowed)
				(pads allowed)
				(copperpour not_allowed)
				(footprints allowed)
			)
			(placement
				(enabled no)
				(sheetname "")
			)
			(fill
				(thermal_gap 0.5)
				(thermal_bridge_width 0.5)
				(island_removal_mode 0)
			)
			(polygon
				(pts
					(arc
						(start 9.463786 -3.639312)
						(mid 6.212586 -3.639312)
						(end 9.463786 -3.639312)
					)
				)
			)
		)
	)
	(footprint ""
		(layer "B.Cu")
		(at 47.85487 -72.954134 180)
		(property "Reference" "C275"
			(at 0 0 0)
			(layer "B.SilkS")
			(hide yes)
			(effects
				(font
					(size 1.27 1.27)
				)
				(justify mirror)
			)
		)
		(property "Value" ""
			(at 0 0 0)
			(layer "B.Fab")
			(effects
				(font
					(size 1.27 1.27)
				)
				(justify mirror)
			)
		)
		(duplicate_pad_numbers_are_jumpers no)
		(fp_line
			(start 0.7874 0.4064)
			(end 0.7874 -0.4064)
			(stroke
				(width 0.1524)
				(type default)
			)
			(layer "B.SilkS")
		)
		(fp_line
			(start 0.7874 -0.4064)
			(end -0.7874 -0.4064)
			(stroke
				(width 0.1524)
				(type default)
			)
			(layer "B.SilkS")
		)
		(fp_line
			(start -0.7874 0.4064)
			(end 0.7874 0.4064)
			(stroke
				(width 0.1524)
				(type default)
			)
			(layer "B.SilkS")
		)
		(fp_line
			(start -0.7874 -0.4064)
			(end -0.7874 0.4064)
			(stroke
				(width 0.1524)
				(type default)
			)
			(layer "B.SilkS")
		)
		(fp_line
			(start 0.67945 0.3048)
			(end 0.67945 -0.305054)
			(stroke
				(width 0.1)
				(type default)
			)
			(layer "B.Fab")
		)
		(fp_line
			(start 0.67945 -0.305054)
			(end 0.12065 -0.305054)
			(stroke
				(width 0.1)
				(type default)
			)
			(layer "B.Fab")
		)
		(fp_line
			(start 0.12065 0.3048)
			(end 0.67945 0.3048)
			(stroke
				(width 0.1)
				(type default)
			)
			(layer "B.Fab")
		)
		(fp_line
			(start 0.12065 0.2794)
			(end 0.12065 0.3048)
			(stroke
				(width 0.1)
				(type default)
			)
			(layer "B.Fab")
		)
		(fp_line
			(start 0.12065 -0.2794)
			(end -0.12065 -0.2794)
			(stroke
				(width 0.1)
				(type default)
			)
			(layer "B.Fab")
		)
		(fp_line
			(start 0.12065 -0.305054)
			(end 0.12065 -0.2794)
			(stroke
				(width 0.1)
				(type default)
			)
			(layer "B.Fab")
		)
		(fp_line
			(start -0.120396 0.3048)
			(end -0.120396 0.2794)
			(stroke
				(width 0.1)
				(type default)
			)
			(layer "B.Fab")
		)
		(fp_line
			(start -0.120396 0.2794)
			(end 0.12065 0.2794)
			(stroke
				(width 0.1)
				(type default)
			)
			(layer "B.Fab")
		)
		(fp_line
			(start -0.12065 -0.2794)
			(end -0.12065 -0.3048)
			(stroke
				(width 0.1)
				(type default)
			)
			(layer "B.Fab")
		)
		(fp_line
			(start -0.12065 -0.3048)
			(end -0.67945 -0.3048)
			(stroke
				(width 0.1)
				(type default)
			)
			(layer "B.Fab")
		)
		(fp_line
			(start -0.67945 0.3048)
			(end -0.120396 0.3048)
			(stroke
				(width 0.1)
				(type default)
			)
			(layer "B.Fab")
		)
		(fp_line
			(start -0.67945 -0.3048)
			(end -0.67945 0.3048)
			(stroke
				(width 0.1)
				(type default)
			)
			(layer "B.Fab")
		)
		(pad "1" smd circle
			(at 0.40005 0)
			(size 0 0)
			(layers "B.Cu" "B.Mask" "B.Paste")
			(net "P3V_BAT_SENSOR")
		)
		(pad "2" smd circle
			(at -0.40005 0)
			(size 0 0)
			(layers "B.Cu" "B.Mask" "B.Paste")
			(net "GND")
		)
	)
	(footprint ""
		(layer "B.Cu")
		(at -14.224 -100.584 180)
		(property "Reference" "DB2"
			(at 1.7018 -5.74167 0)
			(unlocked yes)
			(layer "B.SilkS")
			(effects
				(font
					(size 0.7874 0.5842)
					(thickness 0.1524)
				)
				(justify left mirror)
			)
		)
		(property "Value" ""
			(at 0 0 0)
			(layer "B.Fab")
			(effects
				(font
					(size 1.27 1.27)
				)
				(justify mirror)
			)
		)
		(duplicate_pad_numbers_are_jumpers no)
		(fp_line
			(start 3.330702 -4.771136)
			(end -3.330702 -4.771136)
			(stroke
				(width 0.1524)
				(type default)
			)
			(layer "B.SilkS")
		)
		(fp_line
			(start 0 4.011168)
			(end 3.330702 -4.771136)
			(stroke
				(width 0.1524)
				(type default)
			)
			(layer "B.SilkS")
		)
		(fp_line
			(start -3.330702 -4.771136)
			(end 0 4.011168)
			(stroke
				(width 0.1524)
				(type default)
			)
			(layer "B.SilkS")
		)
		(fp_line
			(start 3.330702 -4.771136)
			(end -3.330702 -4.771136)
			(stroke
				(width 0.1)
				(type default)
			)
			(layer "B.Fab")
		)
		(fp_line
			(start 0 4.011168)
			(end 3.330702 -4.771136)
			(stroke
				(width 0.1)
				(type default)
			)
			(layer "B.Fab")
		)
		(fp_line
			(start -3.330702 -4.771136)
			(end 0 4.011168)
			(stroke
				(width 0.1)
				(type default)
			)
			(layer "B.Fab")
		)
		(pad "1" thru_hole circle
			(at 0 0)
			(size 2.159 2.159)
			(drill 1.7018)
			(layers "*.Cu" "*.Mask")
			(remove_unused_layers no)
			(net "T_GND")
			(clearance 0.0254)
			(thermal_gap 0.0254)
		)
		(pad "2" thru_hole circle
			(at 1.27 -3.348736)
			(size 2.159 2.159)
			(drill 1.7018)
			(layers "*.Cu" "*.Mask")
			(remove_unused_layers no)
			(net "TDR_SE_50_OHM_IN1")
			(clearance 0.0254)
			(thermal_gap 0.0254)
		)
		(pad "3" thru_hole circle
			(at -1.27 -3.348736)
			(size 2.159 2.159)
			(drill 1.7018)
			(layers "*.Cu" "*.Mask")
			(remove_unused_layers no)
			(net "TDR_SE_50_OHM_IN1")
			(clearance 0.0254)
			(thermal_gap 0.0254)
		)
	)
	(footprint ""
		(layer "B.Cu")
		(at 58.547 -21.082 -90)
		(property "Reference" "U29"
			(at 1.2065 1.94437 270)
			(unlocked yes)
			(layer "B.SilkS")
			(effects
				(font
					(size 0.7874 0.5842)
					(thickness 0.1524)
				)
				(justify left mirror)
			)
		)
		(property "Value" ""
			(at 0 0 90)
			(layer "B.Fab")
			(effects
				(font
					(size 1.27 1.27)
				)
				(justify mirror)
			)
		)
		(duplicate_pad_numbers_are_jumpers no)
		(fp_line
			(start -1.3462 1.1938)
			(end -1.3462 -1.1938)
			(stroke
				(width 0.1524)
				(type default)
			)
			(layer "B.SilkS")
		)
		(fp_line
			(start 1.3462 1.1938)
			(end -1.3462 1.1938)
			(stroke
				(width 0.1524)
				(type default)
			)
			(layer "B.SilkS")
		)
		(fp_line
			(start -1.3462 -1.1938)
			(end 1.3462 -1.1938)
			(stroke
				(width 0.1524)
				(type default)
			)
			(layer "B.SilkS")
		)
		(fp_line
			(start 1.3462 -1.1938)
			(end 1.3462 1.1684)
			(stroke
				(width 0.1524)
				(type default)
			)
			(layer "B.SilkS")
		)
		(fp_poly
			(pts
				(xy 1.447038 -0.760476) (xy 2.052066 -0.457962) (xy 2.052066 -1.06299)
			)
			(stroke
				(width 0)
				(type default)
			)
			(fill yes)
			(layer "B.SilkS")
		)
		(fp_line
			(start -0.674878 1.124966)
			(end -0.674878 -1.124966)
			(stroke
				(width 0.1)
				(type default)
			)
			(layer "B.Fab")
		)
		(fp_line
			(start 0.674878 1.124966)
			(end -0.674878 1.124966)
			(stroke
				(width 0.1)
				(type default)
			)
			(layer "B.Fab")
		)
		(fp_line
			(start -0.674878 -1.124966)
			(end 0.674878 -1.124966)
			(stroke
				(width 0.1)
				(type default)
			)
			(layer "B.Fab")
		)
		(fp_line
			(start 0.674878 -1.124966)
			(end 0.674878 1.124966)
			(stroke
				(width 0.1)
				(type default)
			)
			(layer "B.Fab")
		)
		(fp_poly
			(pts
				(xy 1.447038 -0.760476) (xy 2.052066 -0.457962) (xy 2.052066 -1.06299)
			)
			(stroke
				(width 0)
				(type default)
			)
			(fill yes)
			(layer "B.Fab")
		)
		(pad "1" smd rect
			(at 0.899922 -0.750062 90)
			(size 0.6096 0.6096)
			(layers "B.Cu" "B.Mask" "B.Paste")
			(net "DEBUG_PORT_PRSNT")
		)
		(pad "2" smd rect
			(at 0.899922 0)
			(size 0.4064 0.6096)
			(layers "B.Cu" "B.Mask" "B.Paste")
			(net "SPA_SOUT_SW_DBG")
		)
		(pad "3" smd rect
			(at 0.899922 0.750062 90)
			(size 0.6096 0.6096)
			(layers "B.Cu" "B.Mask" "B.Paste")
			(net "GND")
		)
		(pad "4" smd rect
			(at -0.899922 0.750062 90)
			(size 0.6096 0.6096)
			(layers "B.Cu" "B.Mask" "B.Paste")
			(net "DEBUG_PORT_UART_TX")
		)
		(pad "5" smd rect
			(at -0.899922 -0.750062 90)
			(size 0.6096 0.6096)
			(layers "B.Cu" "B.Mask" "B.Paste")
			(net "P3V3_AUX")
		)
	)
	(footprint ""
		(layer "B.Cu")
		(at 65.108582 -30.867604 -90)
		(property "Reference" "R523"
			(at 0 0 90)
			(layer "B.SilkS")
			(hide yes)
			(effects
				(font
					(size 1.27 1.27)
				)
				(justify mirror)
			)
		)
		(property "Value" ""
			(at 0 0 90)
			(layer "B.Fab")
			(effects
				(font
					(size 1.27 1.27)
				)
				(justify mirror)
			)
		)
		(duplicate_pad_numbers_are_jumpers no)
		(fp_line
			(start -0.7874 0.4064)
			(end 0.7874 0.4064)
			(stroke
				(width 0.1524)
				(type default)
			)
			(layer "B.SilkS")
		)
		(fp_line
			(start 0.7874 0.4064)
			(end 0.7874 -0.4064)
			(stroke
				(width 0.1524)
				(type default)
			)
			(layer "B.SilkS")
		)
		(fp_line
			(start -0.7874 -0.4064)
			(end -0.7874 0.4064)
			(stroke
				(width 0.1524)
				(type default)
			)
			(layer "B.SilkS")
		)
		(fp_line
			(start 0.7874 -0.4064)
			(end -0.7874 -0.4064)
			(stroke
				(width 0.1524)
				(type default)
			)
			(layer "B.SilkS")
		)
		(fp_line
			(start -0.67945 0.3048)
			(end -0.120396 0.3048)
			(stroke
				(width 0.1)
				(type default)
			)
			(layer "B.Fab")
		)
		(fp_line
			(start -0.120396 0.3048)
			(end -0.120396 0.2794)
			(stroke
				(width 0.1)
				(type default)
			)
			(layer "B.Fab")
		)
		(fp_line
			(start 0.12065 0.3048)
			(end 0.67945 0.3048)
			(stroke
				(width 0.1)
				(type default)
			)
			(layer "B.Fab")
		)
		(fp_line
			(start 0.67945 0.3048)
			(end 0.67945 -0.305054)
			(stroke
				(width 0.1)
				(type default)
			)
			(layer "B.Fab")
		)
		(fp_line
			(start -0.120396 0.2794)
			(end 0.12065 0.2794)
			(stroke
				(width 0.1)
				(type default)
			)
			(layer "B.Fab")
		)
		(fp_line
			(start 0.12065 0.2794)
			(end 0.12065 0.3048)
			(stroke
				(width 0.1)
				(type default)
			)
			(layer "B.Fab")
		)
		(fp_line
			(start -0.12065 -0.2794)
			(end -0.12065 -0.3048)
			(stroke
				(width 0.1)
				(type default)
			)
			(layer "B.Fab")
		)
		(fp_line
			(start 0.12065 -0.2794)
			(end -0.12065 -0.2794)
			(stroke
				(width 0.1)
				(type default)
			)
			(layer "B.Fab")
		)
		(fp_line
			(start -0.67945 -0.3048)
			(end -0.67945 0.3048)
			(stroke
				(width 0.1)
				(type default)
			)
			(layer "B.Fab")
		)
		(fp_line
			(start -0.12065 -0.3048)
			(end -0.67945 -0.3048)
			(stroke
				(width 0.1)
				(type default)
			)
			(layer "B.Fab")
		)
		(fp_line
			(start 0.12065 -0.305054)
			(end 0.12065 -0.2794)
			(stroke
				(width 0.1)
				(type default)
			)
			(layer "B.Fab")
		)
		(fp_line
			(start 0.67945 -0.305054)
			(end 0.12065 -0.305054)
			(stroke
				(width 0.1)
				(type default)
			)
			(layer "B.Fab")
		)
		(pad "1" smd circle
			(at 0.40005 0 90)
			(size 0 0)
			(layers "B.Cu" "B.Mask" "B.Paste")
			(net "P3V3_RGM")
		)
		(pad "2" smd circle
			(at -0.40005 0 90)
			(size 0 0)
			(layers "B.Cu" "B.Mask" "B.Paste")
			(net "JTAG_SCM_TDO")
		)
	)
	(footprint ""
		(layer "B.Cu")
		(at 66.0908 -34.63798 90)
		(property "Reference" "R759"
			(at 0 0 90)
			(layer "B.SilkS")
			(hide yes)
			(effects
				(font
					(size 1.27 1.27)
				)
				(justify mirror)
			)
		)
		(property "Value" ""
			(at 0 0 90)
			(layer "B.Fab")
			(effects
				(font
					(size 1.27 1.27)
				)
				(justify mirror)
			)
		)
		(duplicate_pad_numbers_are_jumpers no)
		(fp_line
			(start 0.7874 -0.4064)
			(end -0.7874 -0.4064)
			(stroke
				(width 0.1524)
				(type default)
			)
			(layer "B.SilkS")
		)
		(fp_line
			(start -0.7874 -0.4064)
			(end -0.7874 0.4064)
			(stroke
				(width 0.1524)
				(type default)
			)
			(layer "B.SilkS")
		)
		(fp_line
			(start 0.7874 0.4064)
			(end 0.7874 -0.4064)
			(stroke
				(width 0.1524)
				(type default)
			)
			(layer "B.SilkS")
		)
		(fp_line
			(start -0.7874 0.4064)
			(end 0.7874 0.4064)
			(stroke
				(width 0.1524)
				(type default)
			)
			(layer "B.SilkS")
		)
		(fp_line
			(start 0.67945 -0.305054)
			(end 0.12065 -0.305054)
			(stroke
				(width 0.1)
				(type default)
			)
			(layer "B.Fab")
		)
		(fp_line
			(start 0.12065 -0.305054)
			(end 0.12065 -0.2794)
			(stroke
				(width 0.1)
				(type default)
			)
			(layer "B.Fab")
		)
		(fp_line
			(start -0.12065 -0.3048)
			(end -0.67945 -0.3048)
			(stroke
				(width 0.1)
				(type default)
			)
			(layer "B.Fab")
		)
		(fp_line
			(start -0.67945 -0.3048)
			(end -0.67945 0.3048)
			(stroke
				(width 0.1)
				(type default)
			)
			(layer "B.Fab")
		)
		(fp_line
			(start 0.12065 -0.2794)
			(end -0.12065 -0.2794)
			(stroke
				(width 0.1)
				(type default)
			)
			(layer "B.Fab")
		)
		(fp_line
			(start -0.12065 -0.2794)
			(end -0.12065 -0.3048)
			(stroke
				(width 0.1)
				(type default)
			)
			(layer "B.Fab")
		)
		(fp_line
			(start 0.12065 0.2794)
			(end 0.12065 0.3048)
			(stroke
				(width 0.1)
				(type default)
			)
			(layer "B.Fab")
		)
		(fp_line
			(start -0.120396 0.2794)
			(end 0.12065 0.2794)
			(stroke
				(width 0.1)
				(type default)
			)
			(layer "B.Fab")
		)
		(fp_line
			(start 0.67945 0.3048)
			(end 0.67945 -0.305054)
			(stroke
				(width 0.1)
				(type default)
			)
			(layer "B.Fab")
		)
		(fp_line
			(start 0.12065 0.3048)
			(end 0.67945 0.3048)
			(stroke
				(width 0.1)
				(type default)
			)
			(layer "B.Fab")
		)
		(fp_line
			(start -0.120396 0.3048)
			(end -0.120396 0.2794)
			(stroke
				(width 0.1)
				(type default)
			)
			(layer "B.Fab")
		)
		(fp_line
			(start -0.67945 0.3048)
			(end -0.120396 0.3048)
			(stroke
				(width 0.1)
				(type default)
			)
			(layer "B.Fab")
		)
		(pad "1" smd circle
			(at 0.40005 0 270)
			(size 0 0)
			(layers "B.Cu" "B.Mask" "B.Paste")
			(net "UART_BMC_5_RXD")
		)
		(pad "2" smd circle
			(at -0.40005 0 270)
			(size 0 0)
			(layers "B.Cu" "B.Mask" "B.Paste")
			(net "UART_BMC_5_RXD_R")
		)
	)
	(footprint ""
		(layer "B.Cu")
		(at 37.084 -106.3625 -90)
		(property "Reference" "R226"
			(at 0 0 90)
			(layer "B.SilkS")
			(hide yes)
			(effects
				(font
					(size 1.27 1.27)
				)
				(justify mirror)
			)
		)
		(property "Value" ""
			(at 0 0 90)
			(layer "B.Fab")
			(effects
				(font
					(size 1.27 1.27)
				)
				(justify mirror)
			)
		)
		(duplicate_pad_numbers_are_jumpers no)
		(fp_line
			(start -0.7874 0.4064)
			(end 0.7874 0.4064)
			(stroke
				(width 0.1524)
				(type default)
			)
			(layer "B.SilkS")
		)
		(fp_line
			(start 0.7874 0.4064)
			(end 0.7874 -0.4064)
			(stroke
				(width 0.1524)
				(type default)
			)
			(layer "B.SilkS")
		)
		(fp_line
			(start -0.7874 -0.4064)
			(end -0.7874 0.4064)
			(stroke
				(width 0.1524)
				(type default)
			)
			(layer "B.SilkS")
		)
		(fp_line
			(start 0.7874 -0.4064)
			(end -0.7874 -0.4064)
			(stroke
				(width 0.1524)
				(type default)
			)
			(layer "B.SilkS")
		)
		(fp_line
			(start -0.67945 0.3048)
			(end -0.120396 0.3048)
			(stroke
				(width 0.1)
				(type default)
			)
			(layer "B.Fab")
		)
		(fp_line
			(start -0.120396 0.3048)
			(end -0.120396 0.2794)
			(stroke
				(width 0.1)
				(type default)
			)
			(layer "B.Fab")
		)
		(fp_line
			(start 0.12065 0.3048)
			(end 0.67945 0.3048)
			(stroke
				(width 0.1)
				(type default)
			)
			(layer "B.Fab")
		)
		(fp_line
			(start 0.67945 0.3048)
			(end 0.67945 -0.305054)
			(stroke
				(width 0.1)
				(type default)
			)
			(layer "B.Fab")
		)
		(fp_line
			(start -0.120396 0.2794)
			(end 0.12065 0.2794)
			(stroke
				(width 0.1)
				(type default)
			)
			(layer "B.Fab")
		)
		(fp_line
			(start 0.12065 0.2794)
			(end 0.12065 0.3048)
			(stroke
				(width 0.1)
				(type default)
			)
			(layer "B.Fab")
		)
		(fp_line
			(start -0.12065 -0.2794)
			(end -0.12065 -0.3048)
			(stroke
				(width 0.1)
				(type default)
			)
			(layer "B.Fab")
		)
		(fp_line
			(start 0.12065 -0.2794)
			(end -0.12065 -0.2794)
			(stroke
				(width 0.1)
				(type default)
			)
			(layer "B.Fab")
		)
		(fp_line
			(start -0.67945 -0.3048)
			(end -0.67945 0.3048)
			(stroke
				(width 0.1)
				(type default)
			)
			(layer "B.Fab")
		)
		(fp_line
			(start -0.12065 -0.3048)
			(end -0.67945 -0.3048)
			(stroke
				(width 0.1)
				(type default)
			)
			(layer "B.Fab")
		)
		(fp_line
			(start 0.12065 -0.305054)
			(end 0.12065 -0.2794)
			(stroke
				(width 0.1)
				(type default)
			)
			(layer "B.Fab")
		)
		(fp_line
			(start 0.67945 -0.305054)
			(end 0.12065 -0.305054)
			(stroke
				(width 0.1)
				(type default)
			)
			(layer "B.Fab")
		)
		(pad "1" smd circle
			(at 0.40005 0 90)
			(size 0 0)
			(layers "B.Cu" "B.Mask" "B.Paste")
			(net "P3V3_AUX")
		)
		(pad "2" smd circle
			(at -0.40005 0 90)
			(size 0 0)
			(layers "B.Cu" "B.Mask" "B.Paste")
			(net "JTAG_MB_TDI")
		)
	)
	(footprint ""
		(layer "B.Cu")
		(at 83.16722 -43.538394 180)
		(property "Reference" "R9"
			(at 0 0 0)
			(layer "B.SilkS")
			(hide yes)
			(effects
				(font
					(size 1.27 1.27)
				)
				(justify mirror)
			)
		)
		(property "Value" ""
			(at 0 0 0)
			(layer "B.Fab")
			(effects
				(font
					(size 1.27 1.27)
				)
				(justify mirror)
			)
		)
		(duplicate_pad_numbers_are_jumpers no)
		(fp_line
			(start 0.7874 0.4064)
			(end 0.7874 -0.4064)
			(stroke
				(width 0.1524)
				(type default)
			)
			(layer "B.SilkS")
		)
		(fp_line
			(start 0.7874 -0.4064)
			(end -0.7874 -0.4064)
			(stroke
				(width 0.1524)
				(type default)
			)
			(layer "B.SilkS")
		)
		(fp_line
			(start -0.7874 0.4064)
			(end 0.7874 0.4064)
			(stroke
				(width 0.1524)
				(type default)
			)
			(layer "B.SilkS")
		)
		(fp_line
			(start -0.7874 -0.4064)
			(end -0.7874 0.4064)
			(stroke
				(width 0.1524)
				(type default)
			)
			(layer "B.SilkS")
		)
		(fp_line
			(start 0.67945 0.3048)
			(end 0.67945 -0.305054)
			(stroke
				(width 0.1)
				(type default)
			)
			(layer "B.Fab")
		)
		(fp_line
			(start 0.67945 -0.305054)
			(end 0.12065 -0.305054)
			(stroke
				(width 0.1)
				(type default)
			)
			(layer "B.Fab")
		)
		(fp_line
			(start 0.12065 0.3048)
			(end 0.67945 0.3048)
			(stroke
				(width 0.1)
				(type default)
			)
			(layer "B.Fab")
		)
		(fp_line
			(start 0.12065 0.2794)
			(end 0.12065 0.3048)
			(stroke
				(width 0.1)
				(type default)
			)
			(layer "B.Fab")
		)
		(fp_line
			(start 0.12065 -0.2794)
			(end -0.12065 -0.2794)
			(stroke
				(width 0.1)
				(type default)
			)
			(layer "B.Fab")
		)
		(fp_line
			(start 0.12065 -0.305054)
			(end 0.12065 -0.2794)
			(stroke
				(width 0.1)
				(type default)
			)
			(layer "B.Fab")
		)
		(fp_line
			(start -0.120396 0.3048)
			(end -0.120396 0.2794)
			(stroke
				(width 0.1)
				(type default)
			)
			(layer "B.Fab")
		)
		(fp_line
			(start -0.120396 0.2794)
			(end 0.12065 0.2794)
			(stroke
				(width 0.1)
				(type default)
			)
			(layer "B.Fab")
		)
		(fp_line
			(start -0.12065 -0.2794)
			(end -0.12065 -0.3048)
			(stroke
				(width 0.1)
				(type default)
			)
			(layer "B.Fab")
		)
		(fp_line
			(start -0.12065 -0.3048)
			(end -0.67945 -0.3048)
			(stroke
				(width 0.1)
				(type default)
			)
			(layer "B.Fab")
		)
		(fp_line
			(start -0.67945 0.3048)
			(end -0.120396 0.3048)
			(stroke
				(width 0.1)
				(type default)
			)
			(layer "B.Fab")
		)
		(fp_line
			(start -0.67945 -0.3048)
			(end -0.67945 0.3048)
			(stroke
				(width 0.1)
				(type default)
			)
			(layer "B.Fab")
		)
		(pad "1" smd circle
			(at 0.40005 0)
			(size 0 0)
			(layers "B.Cu" "B.Mask" "B.Paste")
			(net "M_BMC_DDR4_ALERT_N")
		)
		(pad "2" smd circle
			(at -0.40005 0)
			(size 0 0)
			(layers "B.Cu" "B.Mask" "B.Paste")
			(net "P1V2_AUX")
		)
	)
	(footprint ""
		(layer "B.Cu")
		(at 48.514 -34.671 -90)
		(property "Reference" "R162"
			(at 0 0 90)
			(layer "B.SilkS")
			(hide yes)
			(effects
				(font
					(size 1.27 1.27)
				)
				(justify mirror)
			)
		)
		(property "Value" ""
			(at 0 0 90)
			(layer "B.Fab")
			(effects
				(font
					(size 1.27 1.27)
				)
				(justify mirror)
			)
		)
		(duplicate_pad_numbers_are_jumpers no)
		(fp_line
			(start -0.7874 0.4064)
			(end 0.7874 0.4064)
			(stroke
				(width 0.1524)
				(type default)
			)
			(layer "B.SilkS")
		)
		(fp_line
			(start 0.7874 0.4064)
			(end 0.7874 -0.4064)
			(stroke
				(width 0.1524)
				(type default)
			)
			(layer "B.SilkS")
		)
		(fp_line
			(start -0.7874 -0.4064)
			(end -0.7874 0.4064)
			(stroke
				(width 0.1524)
				(type default)
			)
			(layer "B.SilkS")
		)
		(fp_line
			(start 0.7874 -0.4064)
			(end -0.7874 -0.4064)
			(stroke
				(width 0.1524)
				(type default)
			)
			(layer "B.SilkS")
		)
		(fp_line
			(start -0.67945 0.3048)
			(end -0.120396 0.3048)
			(stroke
				(width 0.1)
				(type default)
			)
			(layer "B.Fab")
		)
		(fp_line
			(start -0.120396 0.3048)
			(end -0.120396 0.2794)
			(stroke
				(width 0.1)
				(type default)
			)
			(layer "B.Fab")
		)
		(fp_line
			(start 0.12065 0.3048)
			(end 0.67945 0.3048)
			(stroke
				(width 0.1)
				(type default)
			)
			(layer "B.Fab")
		)
		(fp_line
			(start 0.67945 0.3048)
			(end 0.67945 -0.305054)
			(stroke
				(width 0.1)
				(type default)
			)
			(layer "B.Fab")
		)
		(fp_line
			(start -0.120396 0.2794)
			(end 0.12065 0.2794)
			(stroke
				(width 0.1)
				(type default)
			)
			(layer "B.Fab")
		)
		(fp_line
			(start 0.12065 0.2794)
			(end 0.12065 0.3048)
			(stroke
				(width 0.1)
				(type default)
			)
			(layer "B.Fab")
		)
		(fp_line
			(start -0.12065 -0.2794)
			(end -0.12065 -0.3048)
			(stroke
				(width 0.1)
				(type default)
			)
			(layer "B.Fab")
		)
		(fp_line
			(start 0.12065 -0.2794)
			(end -0.12065 -0.2794)
			(stroke
				(width 0.1)
				(type default)
			)
			(layer "B.Fab")
		)
		(fp_line
			(start -0.67945 -0.3048)
			(end -0.67945 0.3048)
			(stroke
				(width 0.1)
				(type default)
			)
			(layer "B.Fab")
		)
		(fp_line
			(start -0.12065 -0.3048)
			(end -0.67945 -0.3048)
			(stroke
				(width 0.1)
				(type default)
			)
			(layer "B.Fab")
		)
		(fp_line
			(start 0.12065 -0.305054)
			(end 0.12065 -0.2794)
			(stroke
				(width 0.1)
				(type default)
			)
			(layer "B.Fab")
		)
		(fp_line
			(start 0.67945 -0.305054)
			(end 0.12065 -0.305054)
			(stroke
				(width 0.1)
				(type default)
			)
			(layer "B.Fab")
		)
		(pad "1" smd circle
			(at 0.40005 0 90)
			(size 0 0)
			(layers "B.Cu" "B.Mask" "B.Paste")
			(net "SMB_BMC_MM15_SCL")
		)
		(pad "2" smd circle
			(at -0.40005 0 90)
			(size 0 0)
			(layers "B.Cu" "B.Mask" "B.Paste")
			(net "SMB_BMC_MM15_R_SCL")
		)
	)
	(footprint ""
		(layer "B.Cu")
		(at 46.355 -96.8248 -90)
		(property "Reference" "R671"
			(at 0 0 90)
			(layer "B.SilkS")
			(hide yes)
			(effects
				(font
					(size 1.27 1.27)
				)
				(justify mirror)
			)
		)
		(property "Value" ""
			(at 0 0 90)
			(layer "B.Fab")
			(effects
				(font
					(size 1.27 1.27)
				)
				(justify mirror)
			)
		)
		(duplicate_pad_numbers_are_jumpers no)
		(fp_line
			(start -0.7874 0.4064)
			(end 0.7874 0.4064)
			(stroke
				(width 0.1524)
				(type default)
			)
			(layer "B.SilkS")
		)
		(fp_line
			(start 0.7874 0.4064)
			(end 0.7874 -0.4064)
			(stroke
				(width 0.1524)
				(type default)
			)
			(layer "B.SilkS")
		)
		(fp_line
			(start -0.7874 -0.4064)
			(end -0.7874 0.4064)
			(stroke
				(width 0.1524)
				(type default)
			)
			(layer "B.SilkS")
		)
		(fp_line
			(start 0.7874 -0.4064)
			(end -0.7874 -0.4064)
			(stroke
				(width 0.1524)
				(type default)
			)
			(layer "B.SilkS")
		)
		(fp_line
			(start -0.67945 0.3048)
			(end -0.120396 0.3048)
			(stroke
				(width 0.1)
				(type default)
			)
			(layer "B.Fab")
		)
		(fp_line
			(start -0.120396 0.3048)
			(end -0.120396 0.2794)
			(stroke
				(width 0.1)
				(type default)
			)
			(layer "B.Fab")
		)
		(fp_line
			(start 0.12065 0.3048)
			(end 0.67945 0.3048)
			(stroke
				(width 0.1)
				(type default)
			)
			(layer "B.Fab")
		)
		(fp_line
			(start 0.67945 0.3048)
			(end 0.67945 -0.305054)
			(stroke
				(width 0.1)
				(type default)
			)
			(layer "B.Fab")
		)
		(fp_line
			(start -0.120396 0.2794)
			(end 0.12065 0.2794)
			(stroke
				(width 0.1)
				(type default)
			)
			(layer "B.Fab")
		)
		(fp_line
			(start 0.12065 0.2794)
			(end 0.12065 0.3048)
			(stroke
				(width 0.1)
				(type default)
			)
			(layer "B.Fab")
		)
		(fp_line
			(start -0.12065 -0.2794)
			(end -0.12065 -0.3048)
			(stroke
				(width 0.1)
				(type default)
			)
			(layer "B.Fab")
		)
		(fp_line
			(start 0.12065 -0.2794)
			(end -0.12065 -0.2794)
			(stroke
				(width 0.1)
				(type default)
			)
			(layer "B.Fab")
		)
		(fp_line
			(start -0.67945 -0.3048)
			(end -0.67945 0.3048)
			(stroke
				(width 0.1)
				(type default)
			)
			(layer "B.Fab")
		)
		(fp_line
			(start -0.12065 -0.3048)
			(end -0.67945 -0.3048)
			(stroke
				(width 0.1)
				(type default)
			)
			(layer "B.Fab")
		)
		(fp_line
			(start 0.12065 -0.305054)
			(end 0.12065 -0.2794)
			(stroke
				(width 0.1)
				(type default)
			)
			(layer "B.Fab")
		)
		(fp_line
			(start 0.67945 -0.305054)
			(end 0.12065 -0.305054)
			(stroke
				(width 0.1)
				(type default)
			)
			(layer "B.Fab")
		)
		(pad "1" smd circle
			(at 0.40005 0 90)
			(size 0 0)
			(layers "B.Cu" "B.Mask" "B.Paste")
			(net "USB3_01_TXP_C")
		)
		(pad "2" smd circle
			(at -0.40005 0 90)
			(size 0 0)
			(layers "B.Cu" "B.Mask" "B.Paste")
			(net "USB3_FPNL_TXP")
		)
	)
	(footprint ""
		(layer "B.Cu")
		(at 37.4015 -102.0445 180)
		(property "Reference" "R870"
			(at 0 0 0)
			(layer "B.SilkS")
			(hide yes)
			(effects
				(font
					(size 1.27 1.27)
				)
				(justify mirror)
			)
		)
		(property "Value" ""
			(at 0 0 0)
			(layer "B.Fab")
			(effects
				(font
					(size 1.27 1.27)
				)
				(justify mirror)
			)
		)
		(duplicate_pad_numbers_are_jumpers no)
		(fp_line
			(start 0.7874 0.4064)
			(end 0.7874 -0.4064)
			(stroke
				(width 0.1524)
				(type default)
			)
			(layer "B.SilkS")
		)
		(fp_line
			(start 0.7874 -0.4064)
			(end -0.7874 -0.4064)
			(stroke
				(width 0.1524)
				(type default)
			)
			(layer "B.SilkS")
		)
		(fp_line
			(start -0.7874 0.4064)
			(end 0.7874 0.4064)
			(stroke
				(width 0.1524)
				(type default)
			)
			(layer "B.SilkS")
		)
		(fp_line
			(start -0.7874 -0.4064)
			(end -0.7874 0.4064)
			(stroke
				(width 0.1524)
				(type default)
			)
			(layer "B.SilkS")
		)
		(fp_line
			(start 0.67945 0.3048)
			(end 0.67945 -0.305054)
			(stroke
				(width 0.1)
				(type default)
			)
			(layer "B.Fab")
		)
		(fp_line
			(start 0.67945 -0.305054)
			(end 0.12065 -0.305054)
			(stroke
				(width 0.1)
				(type default)
			)
			(layer "B.Fab")
		)
		(fp_line
			(start 0.12065 0.3048)
			(end 0.67945 0.3048)
			(stroke
				(width 0.1)
				(type default)
			)
			(layer "B.Fab")
		)
		(fp_line
			(start 0.12065 0.2794)
			(end 0.12065 0.3048)
			(stroke
				(width 0.1)
				(type default)
			)
			(layer "B.Fab")
		)
		(fp_line
			(start 0.12065 -0.2794)
			(end -0.12065 -0.2794)
			(stroke
				(width 0.1)
				(type default)
			)
			(layer "B.Fab")
		)
		(fp_line
			(start 0.12065 -0.305054)
			(end 0.12065 -0.2794)
			(stroke
				(width 0.1)
				(type default)
			)
			(layer "B.Fab")
		)
		(fp_line
			(start -0.120396 0.3048)
			(end -0.120396 0.2794)
			(stroke
				(width 0.1)
				(type default)
			)
			(layer "B.Fab")
		)
		(fp_line
			(start -0.120396 0.2794)
			(end 0.12065 0.2794)
			(stroke
				(width 0.1)
				(type default)
			)
			(layer "B.Fab")
		)
		(fp_line
			(start -0.12065 -0.2794)
			(end -0.12065 -0.3048)
			(stroke
				(width 0.1)
				(type default)
			)
			(layer "B.Fab")
		)
		(fp_line
			(start -0.12065 -0.3048)
			(end -0.67945 -0.3048)
			(stroke
				(width 0.1)
				(type default)
			)
			(layer "B.Fab")
		)
		(fp_line
			(start -0.67945 0.3048)
			(end -0.120396 0.3048)
			(stroke
				(width 0.1)
				(type default)
			)
			(layer "B.Fab")
		)
		(fp_line
			(start -0.67945 -0.3048)
			(end -0.67945 0.3048)
			(stroke
				(width 0.1)
				(type default)
			)
			(layer "B.Fab")
		)
		(pad "1" smd circle
			(at 0.40005 0)
			(size 0 0)
			(layers "B.Cu" "B.Mask" "B.Paste")
			(net "P3V3_AUX")
		)
		(pad "2" smd circle
			(at -0.40005 0)
			(size 0 0)
			(layers "B.Cu" "B.Mask" "B.Paste")
			(net "PD_BIOS_MUX_EN_N")
		)
	)
	(footprint ""
		(layer "B.Cu")
		(at 40.83431 -65.776602 -90)
		(property "Reference" "R188"
			(at 0 0 90)
			(layer "B.SilkS")
			(hide yes)
			(effects
				(font
					(size 1.27 1.27)
				)
				(justify mirror)
			)
		)
		(property "Value" ""
			(at 0 0 90)
			(layer "B.Fab")
			(effects
				(font
					(size 1.27 1.27)
				)
				(justify mirror)
			)
		)
		(duplicate_pad_numbers_are_jumpers no)
		(fp_line
			(start -0.7874 0.4064)
			(end 0.7874 0.4064)
			(stroke
				(width 0.1524)
				(type default)
			)
			(layer "B.SilkS")
		)
		(fp_line
			(start 0.7874 0.4064)
			(end 0.7874 -0.4064)
			(stroke
				(width 0.1524)
				(type default)
			)
			(layer "B.SilkS")
		)
		(fp_line
			(start -0.7874 -0.4064)
			(end -0.7874 0.4064)
			(stroke
				(width 0.1524)
				(type default)
			)
			(layer "B.SilkS")
		)
		(fp_line
			(start 0.7874 -0.4064)
			(end -0.7874 -0.4064)
			(stroke
				(width 0.1524)
				(type default)
			)
			(layer "B.SilkS")
		)
		(fp_line
			(start -0.67945 0.3048)
			(end -0.120396 0.3048)
			(stroke
				(width 0.1)
				(type default)
			)
			(layer "B.Fab")
		)
		(fp_line
			(start -0.120396 0.3048)
			(end -0.120396 0.2794)
			(stroke
				(width 0.1)
				(type default)
			)
			(layer "B.Fab")
		)
		(fp_line
			(start 0.12065 0.3048)
			(end 0.67945 0.3048)
			(stroke
				(width 0.1)
				(type default)
			)
			(layer "B.Fab")
		)
		(fp_line
			(start 0.67945 0.3048)
			(end 0.67945 -0.305054)
			(stroke
				(width 0.1)
				(type default)
			)
			(layer "B.Fab")
		)
		(fp_line
			(start -0.120396 0.2794)
			(end 0.12065 0.2794)
			(stroke
				(width 0.1)
				(type default)
			)
			(layer "B.Fab")
		)
		(fp_line
			(start 0.12065 0.2794)
			(end 0.12065 0.3048)
			(stroke
				(width 0.1)
				(type default)
			)
			(layer "B.Fab")
		)
		(fp_line
			(start -0.12065 -0.2794)
			(end -0.12065 -0.3048)
			(stroke
				(width 0.1)
				(type default)
			)
			(layer "B.Fab")
		)
		(fp_line
			(start 0.12065 -0.2794)
			(end -0.12065 -0.2794)
			(stroke
				(width 0.1)
				(type default)
			)
			(layer "B.Fab")
		)
		(fp_line
			(start -0.67945 -0.3048)
			(end -0.67945 0.3048)
			(stroke
				(width 0.1)
				(type default)
			)
			(layer "B.Fab")
		)
		(fp_line
			(start -0.12065 -0.3048)
			(end -0.67945 -0.3048)
			(stroke
				(width 0.1)
				(type default)
			)
			(layer "B.Fab")
		)
		(fp_line
			(start 0.12065 -0.305054)
			(end 0.12065 -0.2794)
			(stroke
				(width 0.1)
				(type default)
			)
			(layer "B.Fab")
		)
		(fp_line
			(start 0.67945 -0.305054)
			(end 0.12065 -0.305054)
			(stroke
				(width 0.1)
				(type default)
			)
			(layer "B.Fab")
		)
		(pad "1" smd circle
			(at 0.40005 0 90)
			(size 0 0)
			(layers "B.Cu" "B.Mask" "B.Paste")
			(net "P1V2_P1V0_I3C_VDDL1")
		)
		(pad "2" smd circle
			(at -0.40005 0 90)
			(size 0 0)
			(layers "B.Cu" "B.Mask" "B.Paste")
			(net "I3C3_SPD_SCL")
		)
	)
	(footprint ""
		(layer "B.Cu")
		(at 34.417 -36.195 90)
		(property "Reference" "R121"
			(at 0 0 90)
			(layer "B.SilkS")
			(hide yes)
			(effects
				(font
					(size 1.27 1.27)
				)
				(justify mirror)
			)
		)
		(property "Value" ""
			(at 0 0 90)
			(layer "B.Fab")
			(effects
				(font
					(size 1.27 1.27)
				)
				(justify mirror)
			)
		)
		(duplicate_pad_numbers_are_jumpers no)
		(fp_line
			(start 0.7874 -0.4064)
			(end -0.7874 -0.4064)
			(stroke
				(width 0.1524)
				(type default)
			)
			(layer "B.SilkS")
		)
		(fp_line
			(start -0.7874 -0.4064)
			(end -0.7874 0.4064)
			(stroke
				(width 0.1524)
				(type default)
			)
			(layer "B.SilkS")
		)
		(fp_line
			(start 0.7874 0.4064)
			(end 0.7874 -0.4064)
			(stroke
				(width 0.1524)
				(type default)
			)
			(layer "B.SilkS")
		)
		(fp_line
			(start -0.7874 0.4064)
			(end 0.7874 0.4064)
			(stroke
				(width 0.1524)
				(type default)
			)
			(layer "B.SilkS")
		)
		(fp_line
			(start 0.67945 -0.305054)
			(end 0.12065 -0.305054)
			(stroke
				(width 0.1)
				(type default)
			)
			(layer "B.Fab")
		)
		(fp_line
			(start 0.12065 -0.305054)
			(end 0.12065 -0.2794)
			(stroke
				(width 0.1)
				(type default)
			)
			(layer "B.Fab")
		)
		(fp_line
			(start -0.12065 -0.3048)
			(end -0.67945 -0.3048)
			(stroke
				(width 0.1)
				(type default)
			)
			(layer "B.Fab")
		)
		(fp_line
			(start -0.67945 -0.3048)
			(end -0.67945 0.3048)
			(stroke
				(width 0.1)
				(type default)
			)
			(layer "B.Fab")
		)
		(fp_line
			(start 0.12065 -0.2794)
			(end -0.12065 -0.2794)
			(stroke
				(width 0.1)
				(type default)
			)
			(layer "B.Fab")
		)
		(fp_line
			(start -0.12065 -0.2794)
			(end -0.12065 -0.3048)
			(stroke
				(width 0.1)
				(type default)
			)
			(layer "B.Fab")
		)
		(fp_line
			(start 0.12065 0.2794)
			(end 0.12065 0.3048)
			(stroke
				(width 0.1)
				(type default)
			)
			(layer "B.Fab")
		)
		(fp_line
			(start -0.120396 0.2794)
			(end 0.12065 0.2794)
			(stroke
				(width 0.1)
				(type default)
			)
			(layer "B.Fab")
		)
		(fp_line
			(start 0.67945 0.3048)
			(end 0.67945 -0.305054)
			(stroke
				(width 0.1)
				(type default)
			)
			(layer "B.Fab")
		)
		(fp_line
			(start 0.12065 0.3048)
			(end 0.67945 0.3048)
			(stroke
				(width 0.1)
				(type default)
			)
			(layer "B.Fab")
		)
		(fp_line
			(start -0.120396 0.3048)
			(end -0.120396 0.2794)
			(stroke
				(width 0.1)
				(type default)
			)
			(layer "B.Fab")
		)
		(fp_line
			(start -0.67945 0.3048)
			(end -0.120396 0.3048)
			(stroke
				(width 0.1)
				(type default)
			)
			(layer "B.Fab")
		)
		(pad "1" smd circle
			(at 0.40005 0 270)
			(size 0 0)
			(layers "B.Cu" "B.Mask" "B.Paste")
			(net "FM_CPU_RMCA_CATERR_LVT3_R_N")
		)
		(pad "2" smd circle
			(at -0.40005 0 270)
			(size 0 0)
			(layers "B.Cu" "B.Mask" "B.Paste")
			(net "FM_CPU_MSMI_CATERR_LVT3_N")
		)
	)
	(footprint ""
		(layer "B.Cu")
		(at 12.7 -90.043 90)
		(property "Reference" "R641"
			(at 0 0 90)
			(layer "B.SilkS")
			(hide yes)
			(effects
				(font
					(size 1.27 1.27)
				)
				(justify mirror)
			)
		)
		(property "Value" ""
			(at 0 0 90)
			(layer "B.Fab")
			(effects
				(font
					(size 1.27 1.27)
				)
				(justify mirror)
			)
		)
		(duplicate_pad_numbers_are_jumpers no)
		(fp_line
			(start 0.7874 -0.4064)
			(end -0.7874 -0.4064)
			(stroke
				(width 0.1524)
				(type default)
			)
			(layer "B.SilkS")
		)
		(fp_line
			(start -0.7874 -0.4064)
			(end -0.7874 0.4064)
			(stroke
				(width 0.1524)
				(type default)
			)
			(layer "B.SilkS")
		)
		(fp_line
			(start 0.7874 0.4064)
			(end 0.7874 -0.4064)
			(stroke
				(width 0.1524)
				(type default)
			)
			(layer "B.SilkS")
		)
		(fp_line
			(start -0.7874 0.4064)
			(end 0.7874 0.4064)
			(stroke
				(width 0.1524)
				(type default)
			)
			(layer "B.SilkS")
		)
		(fp_line
			(start 0.67945 -0.305054)
			(end 0.12065 -0.305054)
			(stroke
				(width 0.1)
				(type default)
			)
			(layer "B.Fab")
		)
		(fp_line
			(start 0.12065 -0.305054)
			(end 0.12065 -0.2794)
			(stroke
				(width 0.1)
				(type default)
			)
			(layer "B.Fab")
		)
		(fp_line
			(start -0.12065 -0.3048)
			(end -0.67945 -0.3048)
			(stroke
				(width 0.1)
				(type default)
			)
			(layer "B.Fab")
		)
		(fp_line
			(start -0.67945 -0.3048)
			(end -0.67945 0.3048)
			(stroke
				(width 0.1)
				(type default)
			)
			(layer "B.Fab")
		)
		(fp_line
			(start 0.12065 -0.2794)
			(end -0.12065 -0.2794)
			(stroke
				(width 0.1)
				(type default)
			)
			(layer "B.Fab")
		)
		(fp_line
			(start -0.12065 -0.2794)
			(end -0.12065 -0.3048)
			(stroke
				(width 0.1)
				(type default)
			)
			(layer "B.Fab")
		)
		(fp_line
			(start 0.12065 0.2794)
			(end 0.12065 0.3048)
			(stroke
				(width 0.1)
				(type default)
			)
			(layer "B.Fab")
		)
		(fp_line
			(start -0.120396 0.2794)
			(end 0.12065 0.2794)
			(stroke
				(width 0.1)
				(type default)
			)
			(layer "B.Fab")
		)
		(fp_line
			(start 0.67945 0.3048)
			(end 0.67945 -0.305054)
			(stroke
				(width 0.1)
				(type default)
			)
			(layer "B.Fab")
		)
		(fp_line
			(start 0.12065 0.3048)
			(end 0.67945 0.3048)
			(stroke
				(width 0.1)
				(type default)
			)
			(layer "B.Fab")
		)
		(fp_line
			(start -0.120396 0.3048)
			(end -0.120396 0.2794)
			(stroke
				(width 0.1)
				(type default)
			)
			(layer "B.Fab")
		)
		(fp_line
			(start -0.67945 0.3048)
			(end -0.120396 0.3048)
			(stroke
				(width 0.1)
				(type default)
			)
			(layer "B.Fab")
		)
		(pad "1" smd circle
			(at 0.40005 0 270)
			(size 0 0)
			(layers "B.Cu" "B.Mask" "B.Paste")
			(net "P3V3_AUX")
		)
		(pad "2" smd circle
			(at -0.40005 0 270)
			(size 0 0)
			(layers "B.Cu" "B.Mask" "B.Paste")
			(net "RST_BMC_SELF_HW_R2")
		)
	)
	(footprint ""
		(layer "B.Cu")
		(at 32.893 -29.972 -90)
		(property "Reference" "C210"
			(at 0 0 90)
			(layer "B.SilkS")
			(hide yes)
			(effects
				(font
					(size 1.27 1.27)
				)
				(justify mirror)
			)
		)
		(property "Value" ""
			(at 0 0 90)
			(layer "B.Fab")
			(effects
				(font
					(size 1.27 1.27)
				)
				(justify mirror)
			)
		)
		(duplicate_pad_numbers_are_jumpers no)
		(fp_line
			(start -0.7874 0.406146)
			(end 0.7874 0.406146)
			(stroke
				(width 0.1524)
				(type default)
			)
			(layer "B.SilkS")
		)
		(fp_line
			(start 0.7874 0.406146)
			(end 0.7874 -0.406146)
			(stroke
				(width 0.1524)
				(type default)
			)
			(layer "B.SilkS")
		)
		(fp_line
			(start -0.7874 -0.406146)
			(end -0.7874 0.406146)
			(stroke
				(width 0.1524)
				(type default)
			)
			(layer "B.SilkS")
		)
		(fp_line
			(start 0.7874 -0.406146)
			(end -0.7874 -0.406146)
			(stroke
				(width 0.1524)
				(type default)
			)
			(layer "B.SilkS")
		)
		(fp_line
			(start -0.67945 0.3048)
			(end -0.120396 0.3048)
			(stroke
				(width 0.1)
				(type default)
			)
			(layer "B.Fab")
		)
		(fp_line
			(start -0.120396 0.3048)
			(end -0.120396 0.2794)
			(stroke
				(width 0.1)
				(type default)
			)
			(layer "B.Fab")
		)
		(fp_line
			(start 0.120396 0.3048)
			(end 0.67945 0.3048)
			(stroke
				(width 0.1)
				(type default)
			)
			(layer "B.Fab")
		)
		(fp_line
			(start 0.67945 0.3048)
			(end 0.67945 -0.305054)
			(stroke
				(width 0.1)
				(type default)
			)
			(layer "B.Fab")
		)
		(fp_line
			(start -0.120396 0.2794)
			(end 0.12065 0.2794)
			(stroke
				(width 0.1)
				(type default)
			)
			(layer "B.Fab")
		)
		(fp_line
			(start 0.12065 0.2794)
			(end 0.120396 0.3048)
			(stroke
				(width 0.1)
				(type default)
			)
			(layer "B.Fab")
		)
		(fp_line
			(start -0.12065 -0.2794)
			(end -0.120396 -0.3048)
			(stroke
				(width 0.1)
				(type default)
			)
			(layer "B.Fab")
		)
		(fp_line
			(start 0.12065 -0.2794)
			(end -0.12065 -0.2794)
			(stroke
				(width 0.1)
				(type default)
			)
			(layer "B.Fab")
		)
		(fp_line
			(start -0.67945 -0.3048)
			(end -0.67945 0.3048)
			(stroke
				(width 0.1)
				(type default)
			)
			(layer "B.Fab")
		)
		(fp_line
			(start -0.120396 -0.3048)
			(end -0.67945 -0.3048)
			(stroke
				(width 0.1)
				(type default)
			)
			(layer "B.Fab")
		)
		(fp_line
			(start 0.12065 -0.305054)
			(end 0.12065 -0.2794)
			(stroke
				(width 0.1)
				(type default)
			)
			(layer "B.Fab")
		)
		(fp_line
			(start 0.67945 -0.305054)
			(end 0.12065 -0.305054)
			(stroke
				(width 0.1)
				(type default)
			)
			(layer "B.Fab")
		)
		(pad "1" smd circle
			(at 0.40005 0 90)
			(size 0 0)
			(layers "B.Cu" "B.Mask" "B.Paste")
			(net "V_DACB_IO")
		)
		(pad "2" smd circle
			(at -0.40005 0 90)
			(size 0 0)
			(layers "B.Cu" "B.Mask" "B.Paste")
			(net "GND")
		)
	)
	(footprint ""
		(layer "B.Cu")
		(at 58.726832 -52.58816)
		(property "Reference" "C97"
			(at 0 0 0)
			(layer "B.SilkS")
			(hide yes)
			(effects
				(font
					(size 1.27 1.27)
				)
				(justify mirror)
			)
		)
		(property "Value" ""
			(at 0 0 0)
			(layer "B.Fab")
			(effects
				(font
					(size 1.27 1.27)
				)
				(justify mirror)
			)
		)
		(duplicate_pad_numbers_are_jumpers no)
		(fp_line
			(start -0.7874 -0.4064)
			(end -0.7874 0.4064)
			(stroke
				(width 0.1524)
				(type default)
			)
			(layer "B.SilkS")
		)
		(fp_line
			(start -0.7874 0.4064)
			(end 0.7874 0.4064)
			(stroke
				(width 0.1524)
				(type default)
			)
			(layer "B.SilkS")
		)
		(fp_line
			(start 0.7874 -0.4064)
			(end -0.7874 -0.4064)
			(stroke
				(width 0.1524)
				(type default)
			)
			(layer "B.SilkS")
		)
		(fp_line
			(start 0.7874 0.4064)
			(end 0.7874 -0.4064)
			(stroke
				(width 0.1524)
				(type default)
			)
			(layer "B.SilkS")
		)
		(fp_line
			(start -0.67945 -0.3048)
			(end -0.67945 0.3048)
			(stroke
				(width 0.1)
				(type default)
			)
			(layer "B.Fab")
		)
		(fp_line
			(start -0.67945 0.3048)
			(end -0.120396 0.3048)
			(stroke
				(width 0.1)
				(type default)
			)
			(layer "B.Fab")
		)
		(fp_line
			(start -0.12065 -0.3048)
			(end -0.67945 -0.3048)
			(stroke
				(width 0.1)
				(type default)
			)
			(layer "B.Fab")
		)
		(fp_line
			(start -0.12065 -0.2794)
			(end -0.12065 -0.3048)
			(stroke
				(width 0.1)
				(type default)
			)
			(layer "B.Fab")
		)
		(fp_line
			(start -0.120396 0.2794)
			(end 0.12065 0.2794)
			(stroke
				(width 0.1)
				(type default)
			)
			(layer "B.Fab")
		)
		(fp_line
			(start -0.120396 0.3048)
			(end -0.120396 0.2794)
			(stroke
				(width 0.1)
				(type default)
			)
			(layer "B.Fab")
		)
		(fp_line
			(start 0.12065 -0.305054)
			(end 0.12065 -0.2794)
			(stroke
				(width 0.1)
				(type default)
			)
			(layer "B.Fab")
		)
		(fp_line
			(start 0.12065 -0.2794)
			(end -0.12065 -0.2794)
			(stroke
				(width 0.1)
				(type default)
			)
			(layer "B.Fab")
		)
		(fp_line
			(start 0.12065 0.2794)
			(end 0.12065 0.3048)
			(stroke
				(width 0.1)
				(type default)
			)
			(layer "B.Fab")
		)
		(fp_line
			(start 0.12065 0.3048)
			(end 0.67945 0.3048)
			(stroke
				(width 0.1)
				(type default)
			)
			(layer "B.Fab")
		)
		(fp_line
			(start 0.67945 -0.305054)
			(end 0.12065 -0.305054)
			(stroke
				(width 0.1)
				(type default)
			)
			(layer "B.Fab")
		)
		(fp_line
			(start 0.67945 0.3048)
			(end 0.67945 -0.305054)
			(stroke
				(width 0.1)
				(type default)
			)
			(layer "B.Fab")
		)
		(pad "1" smd circle
			(at 0.40005 0 180)
			(size 0 0)
			(layers "B.Cu" "B.Mask" "B.Paste")
			(net "P1V0_STBY_DP_VCC10A")
		)
		(pad "2" smd circle
			(at -0.40005 0 180)
			(size 0 0)
			(layers "B.Cu" "B.Mask" "B.Paste")
			(net "GND")
		)
	)
	(footprint ""
		(layer "B.Cu")
		(at 33.1089 -97.1042 90)
		(property "Reference" "U58"
			(at 0.1778 2.17043 270)
			(unlocked yes)
			(layer "B.SilkS")
			(effects
				(font
					(size 0.7874 0.5842)
					(thickness 0.1524)
				)
				(justify mirror)
			)
		)
		(property "Value" ""
			(at 0 0 90)
			(layer "B.Fab")
			(effects
				(font
					(size 1.27 1.27)
				)
				(justify mirror)
			)
		)
		(duplicate_pad_numbers_are_jumpers no)
		(fp_line
			(start 1.834896 -1.575054)
			(end 0.508 -1.575054)
			(stroke
				(width 0.1524)
				(type default)
			)
			(layer "B.SilkS")
		)
		(fp_line
			(start 0.508 -1.575054)
			(end 0 -1.016)
			(stroke
				(width 0.1524)
				(type default)
			)
			(layer "B.SilkS")
		)
		(fp_line
			(start -0.508 -1.575054)
			(end -1.834896 -1.575054)
			(stroke
				(width 0.1524)
				(type default)
			)
			(layer "B.SilkS")
		)
		(fp_line
			(start -1.834896 -1.575054)
			(end -1.834896 1.575054)
			(stroke
				(width 0.1524)
				(type default)
			)
			(layer "B.SilkS")
		)
		(fp_line
			(start 0 -1.016)
			(end -0.508 -1.575054)
			(stroke
				(width 0.1524)
				(type default)
			)
			(layer "B.SilkS")
		)
		(fp_line
			(start 1.834896 1.575054)
			(end 1.834896 -1.575054)
			(stroke
				(width 0.1524)
				(type default)
			)
			(layer "B.SilkS")
		)
		(fp_line
			(start -1.834896 1.575054)
			(end 1.834896 1.575054)
			(stroke
				(width 0.1524)
				(type default)
			)
			(layer "B.SilkS")
		)
		(fp_poly
			(pts
				(xy 3.003296 -1.45796) (xy 3.003296 -0.44196) (xy 1.987296 -0.94996)
			)
			(stroke
				(width 0)
				(type default)
			)
			(fill yes)
			(layer "B.SilkS")
		)
		(fp_line
			(start 0.824992 -1.575054)
			(end -0.824992 -1.575054)
			(stroke
				(width 0.1)
				(type default)
			)
			(layer "B.Fab")
		)
		(fp_line
			(start -0.824992 -1.575054)
			(end -0.824992 1.575054)
			(stroke
				(width 0.1)
				(type default)
			)
			(layer "B.Fab")
		)
		(fp_line
			(start 0.824992 1.575054)
			(end 0.824992 -1.575054)
			(stroke
				(width 0.1)
				(type default)
			)
			(layer "B.Fab")
		)
		(fp_line
			(start -0.824992 1.575054)
			(end 0.824992 1.575054)
			(stroke
				(width 0.1)
				(type default)
			)
			(layer "B.Fab")
		)
		(fp_poly
			(pts
				(xy 3.003296 -1.45796) (xy 3.003296 -0.44196) (xy 1.987296 -0.94996)
			)
			(stroke
				(width 0)
				(type default)
			)
			(fill yes)
			(layer "B.Fab")
		)
		(pad "1" smd rect
			(at 1.199896 -0.94996)
			(size 0.7112 1.016)
			(layers "B.Cu" "B.Mask" "B.Paste")
			(net "RST_BMC_SELF_HW_R3")
		)
		(pad "2" smd rect
			(at 1.199896 0)
			(size 0.7112 1.016)
			(layers "B.Cu" "B.Mask" "B.Paste")
			(net "RST_BMC_HW_R1")
		)
		(pad "3" smd rect
			(at 1.199896 0.94996)
			(size 0.7112 1.016)
			(layers "B.Cu" "B.Mask" "B.Paste")
			(net "GND")
		)
		(pad "4" smd rect
			(at -1.199896 0.94996)
			(size 0.7112 1.016)
			(layers "B.Cu" "B.Mask" "B.Paste")
			(net "RST_BMC_HW_OUT")
		)
		(pad "5" smd rect
			(at -1.199896 -0.94996)
			(size 0.7112 1.016)
			(layers "B.Cu" "B.Mask" "B.Paste")
			(net "P3V3_AUX")
		)
	)
	(footprint ""
		(layer "B.Cu")
		(at 10.40892 -94.6404 90)
		(property "Reference" "R607"
			(at 0 0 90)
			(layer "B.SilkS")
			(hide yes)
			(effects
				(font
					(size 1.27 1.27)
				)
				(justify mirror)
			)
		)
		(property "Value" ""
			(at 0 0 90)
			(layer "B.Fab")
			(effects
				(font
					(size 1.27 1.27)
				)
				(justify mirror)
			)
		)
		(duplicate_pad_numbers_are_jumpers no)
		(fp_line
			(start 0.7874 -0.4064)
			(end -0.7874 -0.4064)
			(stroke
				(width 0.1524)
				(type default)
			)
			(layer "B.SilkS")
		)
		(fp_line
			(start -0.7874 -0.4064)
			(end -0.7874 0.4064)
			(stroke
				(width 0.1524)
				(type default)
			)
			(layer "B.SilkS")
		)
		(fp_line
			(start 0.7874 0.4064)
			(end 0.7874 -0.4064)
			(stroke
				(width 0.1524)
				(type default)
			)
			(layer "B.SilkS")
		)
		(fp_line
			(start -0.7874 0.4064)
			(end 0.7874 0.4064)
			(stroke
				(width 0.1524)
				(type default)
			)
			(layer "B.SilkS")
		)
		(fp_line
			(start 0.67945 -0.305054)
			(end 0.12065 -0.305054)
			(stroke
				(width 0.1)
				(type default)
			)
			(layer "B.Fab")
		)
		(fp_line
			(start 0.12065 -0.305054)
			(end 0.12065 -0.2794)
			(stroke
				(width 0.1)
				(type default)
			)
			(layer "B.Fab")
		)
		(fp_line
			(start -0.12065 -0.3048)
			(end -0.67945 -0.3048)
			(stroke
				(width 0.1)
				(type default)
			)
			(layer "B.Fab")
		)
		(fp_line
			(start -0.67945 -0.3048)
			(end -0.67945 0.3048)
			(stroke
				(width 0.1)
				(type default)
			)
			(layer "B.Fab")
		)
		(fp_line
			(start 0.12065 -0.2794)
			(end -0.12065 -0.2794)
			(stroke
				(width 0.1)
				(type default)
			)
			(layer "B.Fab")
		)
		(fp_line
			(start -0.12065 -0.2794)
			(end -0.12065 -0.3048)
			(stroke
				(width 0.1)
				(type default)
			)
			(layer "B.Fab")
		)
		(fp_line
			(start 0.12065 0.2794)
			(end 0.12065 0.3048)
			(stroke
				(width 0.1)
				(type default)
			)
			(layer "B.Fab")
		)
		(fp_line
			(start -0.120396 0.2794)
			(end 0.12065 0.2794)
			(stroke
				(width 0.1)
				(type default)
			)
			(layer "B.Fab")
		)
		(fp_line
			(start 0.67945 0.3048)
			(end 0.67945 -0.305054)
			(stroke
				(width 0.1)
				(type default)
			)
			(layer "B.Fab")
		)
		(fp_line
			(start 0.12065 0.3048)
			(end 0.67945 0.3048)
			(stroke
				(width 0.1)
				(type default)
			)
			(layer "B.Fab")
		)
		(fp_line
			(start -0.120396 0.3048)
			(end -0.120396 0.2794)
			(stroke
				(width 0.1)
				(type default)
			)
			(layer "B.Fab")
		)
		(fp_line
			(start -0.67945 0.3048)
			(end -0.120396 0.3048)
			(stroke
				(width 0.1)
				(type default)
			)
			(layer "B.Fab")
		)
		(pad "1" smd circle
			(at 0.40005 0 270)
			(size 0 0)
			(layers "B.Cu" "B.Mask" "B.Paste")
			(net "P3V3_AUX")
		)
		(pad "2" smd circle
			(at -0.40005 0 270)
			(size 0 0)
			(layers "B.Cu" "B.Mask" "B.Paste")
			(net "BMC_CPLD_GPIO_12")
		)
	)
	(footprint ""
		(layer "B.Cu")
		(at 58.547 -34.671 90)
		(property "Reference" "R143"
			(at 0 0 90)
			(layer "B.SilkS")
			(hide yes)
			(effects
				(font
					(size 1.27 1.27)
				)
				(justify mirror)
			)
		)
		(property "Value" ""
			(at 0 0 90)
			(layer "B.Fab")
			(effects
				(font
					(size 1.27 1.27)
				)
				(justify mirror)
			)
		)
		(duplicate_pad_numbers_are_jumpers no)
		(fp_line
			(start 0.7874 -0.4064)
			(end -0.7874 -0.4064)
			(stroke
				(width 0.1524)
				(type default)
			)
			(layer "B.SilkS")
		)
		(fp_line
			(start -0.7874 -0.4064)
			(end -0.7874 0.4064)
			(stroke
				(width 0.1524)
				(type default)
			)
			(layer "B.SilkS")
		)
		(fp_line
			(start 0.7874 0.4064)
			(end 0.7874 -0.4064)
			(stroke
				(width 0.1524)
				(type default)
			)
			(layer "B.SilkS")
		)
		(fp_line
			(start -0.7874 0.4064)
			(end 0.7874 0.4064)
			(stroke
				(width 0.1524)
				(type default)
			)
			(layer "B.SilkS")
		)
		(fp_line
			(start 0.67945 -0.305054)
			(end 0.12065 -0.305054)
			(stroke
				(width 0.1)
				(type default)
			)
			(layer "B.Fab")
		)
		(fp_line
			(start 0.12065 -0.305054)
			(end 0.12065 -0.2794)
			(stroke
				(width 0.1)
				(type default)
			)
			(layer "B.Fab")
		)
		(fp_line
			(start -0.12065 -0.3048)
			(end -0.67945 -0.3048)
			(stroke
				(width 0.1)
				(type default)
			)
			(layer "B.Fab")
		)
		(fp_line
			(start -0.67945 -0.3048)
			(end -0.67945 0.3048)
			(stroke
				(width 0.1)
				(type default)
			)
			(layer "B.Fab")
		)
		(fp_line
			(start 0.12065 -0.2794)
			(end -0.12065 -0.2794)
			(stroke
				(width 0.1)
				(type default)
			)
			(layer "B.Fab")
		)
		(fp_line
			(start -0.12065 -0.2794)
			(end -0.12065 -0.3048)
			(stroke
				(width 0.1)
				(type default)
			)
			(layer "B.Fab")
		)
		(fp_line
			(start 0.12065 0.2794)
			(end 0.12065 0.3048)
			(stroke
				(width 0.1)
				(type default)
			)
			(layer "B.Fab")
		)
		(fp_line
			(start -0.120396 0.2794)
			(end 0.12065 0.2794)
			(stroke
				(width 0.1)
				(type default)
			)
			(layer "B.Fab")
		)
		(fp_line
			(start 0.67945 0.3048)
			(end 0.67945 -0.305054)
			(stroke
				(width 0.1)
				(type default)
			)
			(layer "B.Fab")
		)
		(fp_line
			(start 0.12065 0.3048)
			(end 0.67945 0.3048)
			(stroke
				(width 0.1)
				(type default)
			)
			(layer "B.Fab")
		)
		(fp_line
			(start -0.120396 0.3048)
			(end -0.120396 0.2794)
			(stroke
				(width 0.1)
				(type default)
			)
			(layer "B.Fab")
		)
		(fp_line
			(start -0.67945 0.3048)
			(end -0.120396 0.3048)
			(stroke
				(width 0.1)
				(type default)
			)
			(layer "B.Fab")
		)
		(pad "1" smd circle
			(at 0.40005 0 270)
			(size 0 0)
			(layers "B.Cu" "B.Mask" "B.Paste")
			(net "SMB_BMC_MM6_R_SDA")
		)
		(pad "2" smd circle
			(at -0.40005 0 270)
			(size 0 0)
			(layers "B.Cu" "B.Mask" "B.Paste")
			(net "SMB_BMC_MM6_SDA")
		)
	)
	(footprint ""
		(layer "B.Cu")
		(at 29.972 -100.838 180)
		(property "Reference" "C145"
			(at 0 0 0)
			(layer "B.SilkS")
			(hide yes)
			(effects
				(font
					(size 1.27 1.27)
				)
				(justify mirror)
			)
		)
		(property "Value" ""
			(at 0 0 0)
			(layer "B.Fab")
			(effects
				(font
					(size 1.27 1.27)
				)
				(justify mirror)
			)
		)
		(duplicate_pad_numbers_are_jumpers no)
		(fp_line
			(start 0.7874 0.4064)
			(end 0.7874 -0.4064)
			(stroke
				(width 0.1524)
				(type default)
			)
			(layer "B.SilkS")
		)
		(fp_line
			(start 0.7874 -0.4064)
			(end -0.7874 -0.4064)
			(stroke
				(width 0.1524)
				(type default)
			)
			(layer "B.SilkS")
		)
		(fp_line
			(start -0.7874 0.4064)
			(end 0.7874 0.4064)
			(stroke
				(width 0.1524)
				(type default)
			)
			(layer "B.SilkS")
		)
		(fp_line
			(start -0.7874 -0.4064)
			(end -0.7874 0.4064)
			(stroke
				(width 0.1524)
				(type default)
			)
			(layer "B.SilkS")
		)
		(fp_line
			(start 0.67945 0.3048)
			(end 0.67945 -0.305054)
			(stroke
				(width 0.1)
				(type default)
			)
			(layer "B.Fab")
		)
		(fp_line
			(start 0.67945 -0.305054)
			(end 0.12065 -0.305054)
			(stroke
				(width 0.1)
				(type default)
			)
			(layer "B.Fab")
		)
		(fp_line
			(start 0.12065 0.3048)
			(end 0.67945 0.3048)
			(stroke
				(width 0.1)
				(type default)
			)
			(layer "B.Fab")
		)
		(fp_line
			(start 0.12065 0.2794)
			(end 0.12065 0.3048)
			(stroke
				(width 0.1)
				(type default)
			)
			(layer "B.Fab")
		)
		(fp_line
			(start 0.12065 -0.2794)
			(end -0.12065 -0.2794)
			(stroke
				(width 0.1)
				(type default)
			)
			(layer "B.Fab")
		)
		(fp_line
			(start 0.12065 -0.305054)
			(end 0.12065 -0.2794)
			(stroke
				(width 0.1)
				(type default)
			)
			(layer "B.Fab")
		)
		(fp_line
			(start -0.120396 0.3048)
			(end -0.120396 0.2794)
			(stroke
				(width 0.1)
				(type default)
			)
			(layer "B.Fab")
		)
		(fp_line
			(start -0.120396 0.2794)
			(end 0.12065 0.2794)
			(stroke
				(width 0.1)
				(type default)
			)
			(layer "B.Fab")
		)
		(fp_line
			(start -0.12065 -0.2794)
			(end -0.12065 -0.3048)
			(stroke
				(width 0.1)
				(type default)
			)
			(layer "B.Fab")
		)
		(fp_line
			(start -0.12065 -0.3048)
			(end -0.67945 -0.3048)
			(stroke
				(width 0.1)
				(type default)
			)
			(layer "B.Fab")
		)
		(fp_line
			(start -0.67945 0.3048)
			(end -0.120396 0.3048)
			(stroke
				(width 0.1)
				(type default)
			)
			(layer "B.Fab")
		)
		(fp_line
			(start -0.67945 -0.3048)
			(end -0.67945 0.3048)
			(stroke
				(width 0.1)
				(type default)
			)
			(layer "B.Fab")
		)
		(pad "1" smd circle
			(at 0.40005 0)
			(size 0 0)
			(layers "B.Cu" "B.Mask" "B.Paste")
			(net "P3V3_AUX")
		)
		(pad "2" smd circle
			(at -0.40005 0)
			(size 0 0)
			(layers "B.Cu" "B.Mask" "B.Paste")
			(net "GND")
		)
	)
	(footprint ""
		(layer "B.Cu")
		(at 34.925 -32.004 -90)
		(property "Reference" "L9"
			(at 0 0 90)
			(layer "B.SilkS")
			(hide yes)
			(effects
				(font
					(size 1.27 1.27)
				)
				(justify mirror)
			)
		)
		(property "Value" ""
			(at 0 0 90)
			(layer "B.Fab")
			(effects
				(font
					(size 1.27 1.27)
				)
				(justify mirror)
			)
		)
		(duplicate_pad_numbers_are_jumpers no)
		(fp_line
			(start -1.27 0.5842)
			(end 1.27 0.5842)
			(stroke
				(width 0.1524)
				(type default)
			)
			(layer "B.SilkS")
		)
		(fp_line
			(start -1.27 0.5842)
			(end -1.27 -0.5842)
			(stroke
				(width 0.1524)
				(type default)
			)
			(layer "B.SilkS")
		)
		(fp_line
			(start -0.127 0.5842)
			(end -0.127 -0.5842)
			(stroke
				(width 0.1524)
				(type default)
			)
			(layer "B.SilkS")
		)
		(fp_line
			(start 0.127 0.5842)
			(end 0.127 -0.5842)
			(stroke
				(width 0.1524)
				(type default)
			)
			(layer "B.SilkS")
		)
		(fp_line
			(start 1.27 0.5842)
			(end 1.27 -0.5842)
			(stroke
				(width 0.1524)
				(type default)
			)
			(layer "B.SilkS")
		)
		(fp_line
			(start 1.27 -0.5588)
			(end 1.27 -0.5842)
			(stroke
				(width 0.1524)
				(type default)
			)
			(layer "B.SilkS")
		)
		(fp_line
			(start 1.27 -0.5842)
			(end -1.27 -0.5842)
			(stroke
				(width 0.1524)
				(type default)
			)
			(layer "B.SilkS")
		)
		(fp_line
			(start -0.9144 0.508)
			(end 0.9144 0.508)
			(stroke
				(width 0.1)
				(type default)
			)
			(layer "B.Fab")
		)
		(fp_line
			(start 0.9144 0.508)
			(end 0.9144 0.406654)
			(stroke
				(width 0.1)
				(type default)
			)
			(layer "B.Fab")
		)
		(fp_line
			(start 0.9144 0.406654)
			(end 1.194308 0.406654)
			(stroke
				(width 0.1)
				(type default)
			)
			(layer "B.Fab")
		)
		(fp_line
			(start 1.194308 0.406654)
			(end 1.194308 -0.406654)
			(stroke
				(width 0.1)
				(type default)
			)
			(layer "B.Fab")
		)
		(fp_line
			(start -1.1938 0.4064)
			(end -0.9144 0.4064)
			(stroke
				(width 0.1)
				(type default)
			)
			(layer "B.Fab")
		)
		(fp_line
			(start -0.9144 0.4064)
			(end -0.9144 0.508)
			(stroke
				(width 0.1)
				(type default)
			)
			(layer "B.Fab")
		)
		(fp_line
			(start -1.1938 -0.406654)
			(end -1.1938 0.4064)
			(stroke
				(width 0.1)
				(type default)
			)
			(layer "B.Fab")
		)
		(fp_line
			(start -0.9144 -0.406654)
			(end -1.1938 -0.406654)
			(stroke
				(width 0.1)
				(type default)
			)
			(layer "B.Fab")
		)
		(fp_line
			(start 0.9144 -0.406654)
			(end 0.9144 -0.508)
			(stroke
				(width 0.1)
				(type default)
			)
			(layer "B.Fab")
		)
		(fp_line
			(start 1.194308 -0.406654)
			(end 0.9144 -0.406654)
			(stroke
				(width 0.1)
				(type default)
			)
			(layer "B.Fab")
		)
		(fp_line
			(start -0.9144 -0.508)
			(end -0.9144 -0.406654)
			(stroke
				(width 0.1)
				(type default)
			)
			(layer "B.Fab")
		)
		(fp_line
			(start 0.9144 -0.508)
			(end -0.9144 -0.508)
			(stroke
				(width 0.1)
				(type default)
			)
			(layer "B.Fab")
		)
		(pad "1" smd rect
			(at 0.7366 0 180)
			(size 0.7112 0.8128)
			(layers "B.Cu" "B.Mask" "B.Paste")
			(net "P3V3_AUX")
		)
		(pad "2" smd rect
			(at -0.7366 0 180)
			(size 0.7112 0.8128)
			(layers "B.Cu" "B.Mask" "B.Paste")
			(net "P3V3_STBY_PLLAHVDD")
		)
	)
	(footprint ""
		(layer "B.Cu")
		(at 40.4114 -58.097928)
		(property "Reference" "R566"
			(at 0 0 0)
			(layer "B.SilkS")
			(hide yes)
			(effects
				(font
					(size 1.27 1.27)
				)
				(justify mirror)
			)
		)
		(property "Value" ""
			(at 0 0 0)
			(layer "B.Fab")
			(effects
				(font
					(size 1.27 1.27)
				)
				(justify mirror)
			)
		)
		(duplicate_pad_numbers_are_jumpers no)
		(fp_line
			(start -0.7874 -0.4064)
			(end -0.7874 0.4064)
			(stroke
				(width 0.1524)
				(type default)
			)
			(layer "B.SilkS")
		)
		(fp_line
			(start -0.7874 0.4064)
			(end 0.7874 0.4064)
			(stroke
				(width 0.1524)
				(type default)
			)
			(layer "B.SilkS")
		)
		(fp_line
			(start 0.7874 -0.4064)
			(end -0.7874 -0.4064)
			(stroke
				(width 0.1524)
				(type default)
			)
			(layer "B.SilkS")
		)
		(fp_line
			(start 0.7874 0.4064)
			(end 0.7874 -0.4064)
			(stroke
				(width 0.1524)
				(type default)
			)
			(layer "B.SilkS")
		)
		(fp_line
			(start -0.67945 -0.3048)
			(end -0.67945 0.3048)
			(stroke
				(width 0.1)
				(type default)
			)
			(layer "B.Fab")
		)
		(fp_line
			(start -0.67945 0.3048)
			(end -0.120396 0.3048)
			(stroke
				(width 0.1)
				(type default)
			)
			(layer "B.Fab")
		)
		(fp_line
			(start -0.12065 -0.3048)
			(end -0.67945 -0.3048)
			(stroke
				(width 0.1)
				(type default)
			)
			(layer "B.Fab")
		)
		(fp_line
			(start -0.12065 -0.2794)
			(end -0.12065 -0.3048)
			(stroke
				(width 0.1)
				(type default)
			)
			(layer "B.Fab")
		)
		(fp_line
			(start -0.120396 0.2794)
			(end 0.12065 0.2794)
			(stroke
				(width 0.1)
				(type default)
			)
			(layer "B.Fab")
		)
		(fp_line
			(start -0.120396 0.3048)
			(end -0.120396 0.2794)
			(stroke
				(width 0.1)
				(type default)
			)
			(layer "B.Fab")
		)
		(fp_line
			(start 0.12065 -0.305054)
			(end 0.12065 -0.2794)
			(stroke
				(width 0.1)
				(type default)
			)
			(layer "B.Fab")
		)
		(fp_line
			(start 0.12065 -0.2794)
			(end -0.12065 -0.2794)
			(stroke
				(width 0.1)
				(type default)
			)
			(layer "B.Fab")
		)
		(fp_line
			(start 0.12065 0.2794)
			(end 0.12065 0.3048)
			(stroke
				(width 0.1)
				(type default)
			)
			(layer "B.Fab")
		)
		(fp_line
			(start 0.12065 0.3048)
			(end 0.67945 0.3048)
			(stroke
				(width 0.1)
				(type default)
			)
			(layer "B.Fab")
		)
		(fp_line
			(start 0.67945 -0.305054)
			(end 0.12065 -0.305054)
			(stroke
				(width 0.1)
				(type default)
			)
			(layer "B.Fab")
		)
		(fp_line
			(start 0.67945 0.3048)
			(end 0.67945 -0.305054)
			(stroke
				(width 0.1)
				(type default)
			)
			(layer "B.Fab")
		)
		(pad "1" smd circle
			(at 0.40005 0 180)
			(size 0 0)
			(layers "B.Cu" "B.Mask" "B.Paste")
			(net "RST_BMC_RSTBTN_OUT_R_N")
		)
		(pad "2" smd circle
			(at -0.40005 0 180)
			(size 0 0)
			(layers "B.Cu" "B.Mask" "B.Paste")
			(net "RST_BMC_RSTBTN_OUT_N")
		)
	)
	(footprint ""
		(layer "B.Cu")
		(at 57.04586 -50.94097)
		(property "Reference" "C92"
			(at 0 0 0)
			(layer "B.SilkS")
			(hide yes)
			(effects
				(font
					(size 1.27 1.27)
				)
				(justify mirror)
			)
		)
		(property "Value" ""
			(at 0 0 0)
			(layer "B.Fab")
			(effects
				(font
					(size 1.27 1.27)
				)
				(justify mirror)
			)
		)
		(duplicate_pad_numbers_are_jumpers no)
		(fp_line
			(start -0.7874 -0.4064)
			(end -0.7874 0.4064)
			(stroke
				(width 0.1524)
				(type default)
			)
			(layer "B.SilkS")
		)
		(fp_line
			(start -0.7874 0.4064)
			(end 0.7874 0.4064)
			(stroke
				(width 0.1524)
				(type default)
			)
			(layer "B.SilkS")
		)
		(fp_line
			(start 0.7874 -0.4064)
			(end -0.7874 -0.4064)
			(stroke
				(width 0.1524)
				(type default)
			)
			(layer "B.SilkS")
		)
		(fp_line
			(start 0.7874 0.4064)
			(end 0.7874 -0.4064)
			(stroke
				(width 0.1524)
				(type default)
			)
			(layer "B.SilkS")
		)
		(fp_line
			(start -0.67945 -0.3048)
			(end -0.67945 0.3048)
			(stroke
				(width 0.1)
				(type default)
			)
			(layer "B.Fab")
		)
		(fp_line
			(start -0.67945 0.3048)
			(end -0.120396 0.3048)
			(stroke
				(width 0.1)
				(type default)
			)
			(layer "B.Fab")
		)
		(fp_line
			(start -0.12065 -0.3048)
			(end -0.67945 -0.3048)
			(stroke
				(width 0.1)
				(type default)
			)
			(layer "B.Fab")
		)
		(fp_line
			(start -0.12065 -0.2794)
			(end -0.12065 -0.3048)
			(stroke
				(width 0.1)
				(type default)
			)
			(layer "B.Fab")
		)
		(fp_line
			(start -0.120396 0.2794)
			(end 0.12065 0.2794)
			(stroke
				(width 0.1)
				(type default)
			)
			(layer "B.Fab")
		)
		(fp_line
			(start -0.120396 0.3048)
			(end -0.120396 0.2794)
			(stroke
				(width 0.1)
				(type default)
			)
			(layer "B.Fab")
		)
		(fp_line
			(start 0.12065 -0.305054)
			(end 0.12065 -0.2794)
			(stroke
				(width 0.1)
				(type default)
			)
			(layer "B.Fab")
		)
		(fp_line
			(start 0.12065 -0.2794)
			(end -0.12065 -0.2794)
			(stroke
				(width 0.1)
				(type default)
			)
			(layer "B.Fab")
		)
		(fp_line
			(start 0.12065 0.2794)
			(end 0.12065 0.3048)
			(stroke
				(width 0.1)
				(type default)
			)
			(layer "B.Fab")
		)
		(fp_line
			(start 0.12065 0.3048)
			(end 0.67945 0.3048)
			(stroke
				(width 0.1)
				(type default)
			)
			(layer "B.Fab")
		)
		(fp_line
			(start 0.67945 -0.305054)
			(end 0.12065 -0.305054)
			(stroke
				(width 0.1)
				(type default)
			)
			(layer "B.Fab")
		)
		(fp_line
			(start 0.67945 0.3048)
			(end 0.67945 -0.305054)
			(stroke
				(width 0.1)
				(type default)
			)
			(layer "B.Fab")
		)
		(pad "1" smd circle
			(at 0.40005 0 180)
			(size 0 0)
			(layers "B.Cu" "B.Mask" "B.Paste")
			(net "P1V0_AUX")
		)
		(pad "2" smd circle
			(at -0.40005 0 180)
			(size 0 0)
			(layers "B.Cu" "B.Mask" "B.Paste")
			(net "GND")
		)
	)
	(footprint ""
		(layer "B.Cu")
		(at 27.3304 -85.7758)
		(property "Reference" "R837"
			(at 0 0 0)
			(layer "B.SilkS")
			(hide yes)
			(effects
				(font
					(size 1.27 1.27)
				)
				(justify mirror)
			)
		)
		(property "Value" ""
			(at 0 0 0)
			(layer "B.Fab")
			(effects
				(font
					(size 1.27 1.27)
				)
				(justify mirror)
			)
		)
		(duplicate_pad_numbers_are_jumpers no)
		(fp_line
			(start -0.7874 -0.4064)
			(end -0.7874 0.4064)
			(stroke
				(width 0.1524)
				(type default)
			)
			(layer "B.SilkS")
		)
		(fp_line
			(start -0.7874 0.4064)
			(end 0.7874 0.4064)
			(stroke
				(width 0.1524)
				(type default)
			)
			(layer "B.SilkS")
		)
		(fp_line
			(start 0.7874 -0.4064)
			(end -0.7874 -0.4064)
			(stroke
				(width 0.1524)
				(type default)
			)
			(layer "B.SilkS")
		)
		(fp_line
			(start 0.7874 0.4064)
			(end 0.7874 -0.4064)
			(stroke
				(width 0.1524)
				(type default)
			)
			(layer "B.SilkS")
		)
		(fp_line
			(start -0.67945 -0.3048)
			(end -0.67945 0.3048)
			(stroke
				(width 0.1)
				(type default)
			)
			(layer "B.Fab")
		)
		(fp_line
			(start -0.67945 0.3048)
			(end -0.120396 0.3048)
			(stroke
				(width 0.1)
				(type default)
			)
			(layer "B.Fab")
		)
		(fp_line
			(start -0.12065 -0.3048)
			(end -0.67945 -0.3048)
			(stroke
				(width 0.1)
				(type default)
			)
			(layer "B.Fab")
		)
		(fp_line
			(start -0.12065 -0.2794)
			(end -0.12065 -0.3048)
			(stroke
				(width 0.1)
				(type default)
			)
			(layer "B.Fab")
		)
		(fp_line
			(start -0.120396 0.2794)
			(end 0.12065 0.2794)
			(stroke
				(width 0.1)
				(type default)
			)
			(layer "B.Fab")
		)
		(fp_line
			(start -0.120396 0.3048)
			(end -0.120396 0.2794)
			(stroke
				(width 0.1)
				(type default)
			)
			(layer "B.Fab")
		)
		(fp_line
			(start 0.12065 -0.305054)
			(end 0.12065 -0.2794)
			(stroke
				(width 0.1)
				(type default)
			)
			(layer "B.Fab")
		)
		(fp_line
			(start 0.12065 -0.2794)
			(end -0.12065 -0.2794)
			(stroke
				(width 0.1)
				(type default)
			)
			(layer "B.Fab")
		)
		(fp_line
			(start 0.12065 0.2794)
			(end 0.12065 0.3048)
			(stroke
				(width 0.1)
				(type default)
			)
			(layer "B.Fab")
		)
		(fp_line
			(start 0.12065 0.3048)
			(end 0.67945 0.3048)
			(stroke
				(width 0.1)
				(type default)
			)
			(layer "B.Fab")
		)
		(fp_line
			(start 0.67945 -0.305054)
			(end 0.12065 -0.305054)
			(stroke
				(width 0.1)
				(type default)
			)
			(layer "B.Fab")
		)
		(fp_line
			(start 0.67945 0.3048)
			(end 0.67945 -0.305054)
			(stroke
				(width 0.1)
				(type default)
			)
			(layer "B.Fab")
		)
		(pad "1" smd circle
			(at 0.40005 0 180)
			(size 0 0)
			(layers "B.Cu" "B.Mask" "B.Paste")
			(net "PWRGD_PSU_AC_PWROK")
		)
		(pad "2" smd circle
			(at -0.40005 0 180)
			(size 0 0)
			(layers "B.Cu" "B.Mask" "B.Paste")
			(net "PWRGD_PSU_AC_PWROK_PLD")
		)
	)
	(footprint ""
		(layer "B.Cu")
		(at 16.637 -65.151 -90)
		(property "Reference" "U37"
			(at 1.397 -2.13233 270)
			(unlocked yes)
			(layer "B.SilkS")
			(effects
				(font
					(size 0.7874 0.5842)
					(thickness 0.1524)
				)
				(justify left mirror)
			)
		)
		(property "Value" ""
			(at 0 0 90)
			(layer "B.Fab")
			(effects
				(font
					(size 1.27 1.27)
				)
				(justify mirror)
			)
		)
		(duplicate_pad_numbers_are_jumpers no)
		(fp_line
			(start -1.3208 1.525016)
			(end 1.3208 1.525016)
			(stroke
				(width 0.1524)
				(type default)
			)
			(layer "B.SilkS")
		)
		(fp_line
			(start 1.3208 1.525016)
			(end 1.3208 -1.525016)
			(stroke
				(width 0.1524)
				(type default)
			)
			(layer "B.SilkS")
		)
		(fp_line
			(start 0 -0.999998)
			(end -0.508 -1.525016)
			(stroke
				(width 0.1524)
				(type default)
			)
			(layer "B.SilkS")
		)
		(fp_line
			(start -1.3208 -1.525016)
			(end -1.3208 1.525016)
			(stroke
				(width 0.1524)
				(type default)
			)
			(layer "B.SilkS")
		)
		(fp_line
			(start -0.508 -1.525016)
			(end -1.3208 -1.525016)
			(stroke
				(width 0.1524)
				(type default)
			)
			(layer "B.SilkS")
		)
		(fp_line
			(start 0.508 -1.525016)
			(end 0 -0.999998)
			(stroke
				(width 0.1524)
				(type default)
			)
			(layer "B.SilkS")
		)
		(fp_line
			(start 1.3208 -1.525016)
			(end 0.508 -1.525016)
			(stroke
				(width 0.1524)
				(type default)
			)
			(layer "B.SilkS")
		)
		(fp_poly
			(pts
				(xy 3.175 -1.016) (xy 3.937 -0.635) (xy 3.937 -1.397)
			)
			(stroke
				(width 0)
				(type default)
			)
			(fill yes)
			(layer "B.SilkS")
		)
		(fp_line
			(start -1.524 1.5494)
			(end 1.5494 1.5494)
			(stroke
				(width 0.1)
				(type default)
			)
			(layer "B.Fab")
		)
		(fp_line
			(start 1.5494 1.5494)
			(end 1.5494 1.203706)
			(stroke
				(width 0.1)
				(type default)
			)
			(layer "B.Fab")
		)
		(fp_line
			(start -3.0353 1.208786)
			(end -1.524 1.208786)
			(stroke
				(width 0.1)
				(type default)
			)
			(layer "B.Fab")
		)
		(fp_line
			(start -1.524 1.208786)
			(end -1.524 1.5494)
			(stroke
				(width 0.1)
				(type default)
			)
			(layer "B.Fab")
		)
		(fp_line
			(start 1.5494 1.203706)
			(end 3.037078 1.203706)
			(stroke
				(width 0.1)
				(type default)
			)
			(layer "B.Fab")
		)
		(fp_line
			(start 3.037078 1.203706)
			(end 3.037078 -1.20777)
			(stroke
				(width 0.1)
				(type default)
			)
			(layer "B.Fab")
		)
		(fp_line
			(start -3.0353 -1.20777)
			(end -3.0353 1.208786)
			(stroke
				(width 0.1)
				(type default)
			)
			(layer "B.Fab")
		)
		(fp_line
			(start -1.524 -1.20777)
			(end -3.0353 -1.20777)
			(stroke
				(width 0.1)
				(type default)
			)
			(layer "B.Fab")
		)
		(fp_line
			(start 1.524 -1.20777)
			(end 1.524 -1.524)
			(stroke
				(width 0.1)
				(type default)
			)
			(layer "B.Fab")
		)
		(fp_line
			(start 3.037078 -1.20777)
			(end 1.524 -1.20777)
			(stroke
				(width 0.1)
				(type default)
			)
			(layer "B.Fab")
		)
		(fp_line
			(start -1.524 -1.524)
			(end -1.524 -1.20777)
			(stroke
				(width 0.1)
				(type default)
			)
			(layer "B.Fab")
		)
		(fp_line
			(start 1.524 -1.524)
			(end -1.524 -1.524)
			(stroke
				(width 0.1)
				(type default)
			)
			(layer "B.Fab")
		)
		(fp_poly
			(pts
				(xy 3.175 -1.016) (xy 3.937 -0.635) (xy 3.937 -1.397)
			)
			(stroke
				(width 0)
				(type default)
			)
			(fill yes)
			(layer "B.Fab")
		)
		(pad "1" smd rect
			(at 2.234946 -0.975106 180)
			(size 0.3556 1.4986)
			(layers "B.Cu" "B.Mask" "B.Paste")
			(net "P3V3_AUX")
		)
		(pad "2" smd rect
			(at 2.234946 -0.32512 180)
			(size 0.3556 1.4986)
			(layers "B.Cu" "B.Mask" "B.Paste")
			(net "SMB_BMC_MM15_R1_SCL")
		)
		(pad "3" smd rect
			(at 2.234946 0.32512 180)
			(size 0.3556 1.4986)
			(layers "B.Cu" "B.Mask" "B.Paste")
			(net "SMB_BMC_MM15_R1_SDA")
		)
		(pad "4" smd rect
			(at 2.234946 0.975106 180)
			(size 0.3556 1.4986)
			(layers "B.Cu" "B.Mask" "B.Paste")
			(net "GND")
		)
		(pad "5" smd rect
			(at -2.234946 0.975106 180)
			(size 0.3556 1.4986)
			(layers "B.Cu" "B.Mask" "B.Paste")
			(net "DEBUG_PORT_PRSNT_BUF_EN")
		)
		(pad "6" smd rect
			(at -2.234946 0.32512 180)
			(size 0.3556 1.4986)
			(layers "B.Cu" "B.Mask" "B.Paste")
			(net "SMB_DEBUG_AUX_LVC3_USB_R1_SDA")
		)
		(pad "7" smd rect
			(at -2.234946 -0.32512 180)
			(size 0.3556 1.4986)
			(layers "B.Cu" "B.Mask" "B.Paste")
			(net "SMB_DEBUG_AUX_LVC3_USB_R1_SCL")
		)
		(pad "8" smd rect
			(at -2.234946 -0.975106 180)
			(size 0.3556 1.4986)
			(layers "B.Cu" "B.Mask" "B.Paste")
			(net "P3V3_AUX")
		)
	)
	(footprint ""
		(layer "B.Cu")
		(at 44.8818 -88.4936 -90)
		(property "Reference" "R712"
			(at 0 0 90)
			(layer "B.SilkS")
			(hide yes)
			(effects
				(font
					(size 1.27 1.27)
				)
				(justify mirror)
			)
		)
		(property "Value" ""
			(at 0 0 90)
			(layer "B.Fab")
			(effects
				(font
					(size 1.27 1.27)
				)
				(justify mirror)
			)
		)
		(duplicate_pad_numbers_are_jumpers no)
		(fp_line
			(start -0.7874 0.4064)
			(end 0.7874 0.4064)
			(stroke
				(width 0.1524)
				(type default)
			)
			(layer "B.SilkS")
		)
		(fp_line
			(start 0.7874 0.4064)
			(end 0.7874 -0.4064)
			(stroke
				(width 0.1524)
				(type default)
			)
			(layer "B.SilkS")
		)
		(fp_line
			(start -0.7874 -0.4064)
			(end -0.7874 0.4064)
			(stroke
				(width 0.1524)
				(type default)
			)
			(layer "B.SilkS")
		)
		(fp_line
			(start 0.7874 -0.4064)
			(end -0.7874 -0.4064)
			(stroke
				(width 0.1524)
				(type default)
			)
			(layer "B.SilkS")
		)
		(fp_line
			(start -0.67945 0.3048)
			(end -0.120396 0.3048)
			(stroke
				(width 0.1)
				(type default)
			)
			(layer "B.Fab")
		)
		(fp_line
			(start -0.120396 0.3048)
			(end -0.120396 0.2794)
			(stroke
				(width 0.1)
				(type default)
			)
			(layer "B.Fab")
		)
		(fp_line
			(start 0.12065 0.3048)
			(end 0.67945 0.3048)
			(stroke
				(width 0.1)
				(type default)
			)
			(layer "B.Fab")
		)
		(fp_line
			(start 0.67945 0.3048)
			(end 0.67945 -0.305054)
			(stroke
				(width 0.1)
				(type default)
			)
			(layer "B.Fab")
		)
		(fp_line
			(start -0.120396 0.2794)
			(end 0.12065 0.2794)
			(stroke
				(width 0.1)
				(type default)
			)
			(layer "B.Fab")
		)
		(fp_line
			(start 0.12065 0.2794)
			(end 0.12065 0.3048)
			(stroke
				(width 0.1)
				(type default)
			)
			(layer "B.Fab")
		)
		(fp_line
			(start -0.12065 -0.2794)
			(end -0.12065 -0.3048)
			(stroke
				(width 0.1)
				(type default)
			)
			(layer "B.Fab")
		)
		(fp_line
			(start 0.12065 -0.2794)
			(end -0.12065 -0.2794)
			(stroke
				(width 0.1)
				(type default)
			)
			(layer "B.Fab")
		)
		(fp_line
			(start -0.67945 -0.3048)
			(end -0.67945 0.3048)
			(stroke
				(width 0.1)
				(type default)
			)
			(layer "B.Fab")
		)
		(fp_line
			(start -0.12065 -0.3048)
			(end -0.67945 -0.3048)
			(stroke
				(width 0.1)
				(type default)
			)
			(layer "B.Fab")
		)
		(fp_line
			(start 0.12065 -0.305054)
			(end 0.12065 -0.2794)
			(stroke
				(width 0.1)
				(type default)
			)
			(layer "B.Fab")
		)
		(fp_line
			(start 0.67945 -0.305054)
			(end 0.12065 -0.305054)
			(stroke
				(width 0.1)
				(type default)
			)
			(layer "B.Fab")
		)
		(pad "1" smd circle
			(at 0.40005 0 90)
			(size 0 0)
			(layers "B.Cu" "B.Mask" "B.Paste")
			(net "P3V3_AUX")
		)
		(pad "2" smd circle
			(at -0.40005 0 90)
			(size 0 0)
			(layers "B.Cu" "B.Mask" "B.Paste")
			(net "USB3_MUX_PD")
		)
	)
	(footprint ""
		(layer "B.Cu")
		(at 40.427656 -56.436006 -90)
		(property "Reference" "C43"
			(at 0 0 90)
			(layer "B.SilkS")
			(hide yes)
			(effects
				(font
					(size 1.27 1.27)
				)
				(justify mirror)
			)
		)
		(property "Value" ""
			(at 0 0 90)
			(layer "B.Fab")
			(effects
				(font
					(size 1.27 1.27)
				)
				(justify mirror)
			)
		)
		(duplicate_pad_numbers_are_jumpers no)
		(fp_line
			(start -0.7874 0.4064)
			(end 0.7874 0.4064)
			(stroke
				(width 0.1524)
				(type default)
			)
			(layer "B.SilkS")
		)
		(fp_line
			(start 0.7874 0.4064)
			(end 0.7874 -0.4064)
			(stroke
				(width 0.1524)
				(type default)
			)
			(layer "B.SilkS")
		)
		(fp_line
			(start -0.7874 -0.4064)
			(end -0.7874 0.4064)
			(stroke
				(width 0.1524)
				(type default)
			)
			(layer "B.SilkS")
		)
		(fp_line
			(start 0.7874 -0.4064)
			(end -0.7874 -0.4064)
			(stroke
				(width 0.1524)
				(type default)
			)
			(layer "B.SilkS")
		)
		(fp_line
			(start -0.67945 0.3048)
			(end -0.120396 0.3048)
			(stroke
				(width 0.1)
				(type default)
			)
			(layer "B.Fab")
		)
		(fp_line
			(start -0.120396 0.3048)
			(end -0.120396 0.2794)
			(stroke
				(width 0.1)
				(type default)
			)
			(layer "B.Fab")
		)
		(fp_line
			(start 0.12065 0.3048)
			(end 0.67945 0.3048)
			(stroke
				(width 0.1)
				(type default)
			)
			(layer "B.Fab")
		)
		(fp_line
			(start 0.67945 0.3048)
			(end 0.67945 -0.305054)
			(stroke
				(width 0.1)
				(type default)
			)
			(layer "B.Fab")
		)
		(fp_line
			(start -0.120396 0.2794)
			(end 0.12065 0.2794)
			(stroke
				(width 0.1)
				(type default)
			)
			(layer "B.Fab")
		)
		(fp_line
			(start 0.12065 0.2794)
			(end 0.12065 0.3048)
			(stroke
				(width 0.1)
				(type default)
			)
			(layer "B.Fab")
		)
		(fp_line
			(start -0.12065 -0.2794)
			(end -0.12065 -0.3048)
			(stroke
				(width 0.1)
				(type default)
			)
			(layer "B.Fab")
		)
		(fp_line
			(start 0.12065 -0.2794)
			(end -0.12065 -0.2794)
			(stroke
				(width 0.1)
				(type default)
			)
			(layer "B.Fab")
		)
		(fp_line
			(start -0.67945 -0.3048)
			(end -0.67945 0.3048)
			(stroke
				(width 0.1)
				(type default)
			)
			(layer "B.Fab")
		)
		(fp_line
			(start -0.12065 -0.3048)
			(end -0.67945 -0.3048)
			(stroke
				(width 0.1)
				(type default)
			)
			(layer "B.Fab")
		)
		(fp_line
			(start 0.12065 -0.305054)
			(end 0.12065 -0.2794)
			(stroke
				(width 0.1)
				(type default)
			)
			(layer "B.Fab")
		)
		(fp_line
			(start 0.67945 -0.305054)
			(end 0.12065 -0.305054)
			(stroke
				(width 0.1)
				(type default)
			)
			(layer "B.Fab")
		)
		(pad "1" smd circle
			(at 0.40005 0 90)
			(size 0 0)
			(layers "B.Cu" "B.Mask" "B.Paste")
			(net "PVCCIO_PECI_BMC")
		)
		(pad "2" smd circle
			(at -0.40005 0 90)
			(size 0 0)
			(layers "B.Cu" "B.Mask" "B.Paste")
			(net "GND")
		)
	)
	(footprint ""
		(layer "B.Cu")
		(at 18.664428 -96.786954 90)
		(property "Reference" "C165"
			(at 0 0 90)
			(layer "B.SilkS")
			(hide yes)
			(effects
				(font
					(size 1.27 1.27)
				)
				(justify mirror)
			)
		)
		(property "Value" ""
			(at 0 0 90)
			(layer "B.Fab")
			(effects
				(font
					(size 1.27 1.27)
				)
				(justify mirror)
			)
		)
		(duplicate_pad_numbers_are_jumpers no)
		(fp_line
			(start 0.69215 -0.2921)
			(end -0.69215 -0.2921)
			(stroke
				(width 0.1524)
				(type default)
			)
			(layer "B.SilkS")
		)
		(fp_line
			(start -0.69215 -0.2921)
			(end -0.69215 0.2921)
			(stroke
				(width 0.1524)
				(type default)
			)
			(layer "B.SilkS")
		)
		(fp_line
			(start 0.69215 0.2921)
			(end 0.69215 -0.2921)
			(stroke
				(width 0.1524)
				(type default)
			)
			(layer "B.SilkS")
		)
		(fp_line
			(start -0.69215 0.2921)
			(end 0.69215 0.2921)
			(stroke
				(width 0.1524)
				(type default)
			)
			(layer "B.SilkS")
		)
		(fp_line
			(start 0.51435 -0.2794)
			(end -0.51435 -0.2794)
			(stroke
				(width 0.1)
				(type default)
			)
			(layer "B.Fab")
		)
		(fp_line
			(start -0.51435 -0.2794)
			(end -0.51435 0.2794)
			(stroke
				(width 0.1)
				(type default)
			)
			(layer "B.Fab")
		)
		(fp_line
			(start 0.51435 0.2794)
			(end 0.51435 -0.2794)
			(stroke
				(width 0.1)
				(type default)
			)
			(layer "B.Fab")
		)
		(fp_line
			(start -0.51435 0.2794)
			(end 0.51435 0.2794)
			(stroke
				(width 0.1)
				(type default)
			)
			(layer "B.Fab")
		)
		(pad "1" smd circle
			(at 0.40005 0 270)
			(size 0 0)
			(layers "B.Cu" "B.Mask" "B.Paste")
			(net "VCCIO2")
		)
		(pad "2" smd circle
			(at -0.40005 0 270)
			(size 0 0)
			(layers "B.Cu" "B.Mask" "B.Paste")
			(net "GND")
		)
		(zone
			(layer "B.Cu")
			(hatch none 0.5)
			(connect_pads
				(clearance 0)
			)
			(min_thickness 0.25)
			(keepout
				(tracks not_allowed)
				(vias allowed)
				(pads allowed)
				(copperpour not_allowed)
				(footprints allowed)
			)
			(placement
				(enabled no)
				(sheetname "")
			)
			(fill
				(thermal_gap 0.5)
				(thermal_bridge_width 0.5)
				(island_removal_mode 0)
			)
			(polygon
				(pts
					(xy 18.752058 -96.977454) (xy 18.810224 -96.886014) (xy 18.810224 -96.686624) (xy 18.752058 -96.596454)
					(xy 18.576798 -96.596454) (xy 18.518378 -96.686624) (xy 18.518378 -96.886014) (xy 18.576544 -96.977454)
				)
			)
		)
	)
	(footprint ""
		(layer "B.Cu")
		(at 101.2825 -54.403752 90)
		(property "Reference" "J24"
			(at -1.063752 -3.13817 270)
			(unlocked yes)
			(layer "B.SilkS")
			(effects
				(font
					(size 0.7874 0.5842)
					(thickness 0.1524)
				)
				(justify left mirror)
			)
		)
		(property "Value" ""
			(at 0 0 90)
			(layer "B.Fab")
			(effects
				(font
					(size 1.27 1.27)
				)
				(justify mirror)
			)
		)
		(duplicate_pad_numbers_are_jumpers no)
		(fp_line
			(start 1.2192 -2.1082)
			(end -1.2192 -2.1082)
			(stroke
				(width 0.1524)
				(type default)
			)
			(layer "B.SilkS")
		)
		(fp_line
			(start -1.2192 -2.1082)
			(end -1.2192 -0.466598)
			(stroke
				(width 0.1524)
				(type default)
			)
			(layer "B.SilkS")
		)
		(fp_line
			(start -1.2192 0.468122)
			(end -1.2192 2.1082)
			(stroke
				(width 0.1524)
				(type default)
			)
			(layer "B.SilkS")
		)
		(fp_line
			(start 1.2192 2.1082)
			(end 1.2192 -2.1082)
			(stroke
				(width 0.1524)
				(type default)
			)
			(layer "B.SilkS")
		)
		(fp_line
			(start -1.2192 2.1082)
			(end 1.2192 2.1082)
			(stroke
				(width 0.1524)
				(type default)
			)
			(layer "B.SilkS")
		)
		(pad "" np_thru_hole circle
			(at -3.4671 -1.27)
			(size 1.0414 1.0414)
			(drill 1.0414)
			(layers "*.Cu" "*.Mask")
			(clearance 0.381)
			(thermal_gap 0.381)
		)
		(pad "" np_thru_hole circle
			(at -3.4671 1.27)
			(size 1.0414 1.0414)
			(drill 1.0414)
			(layers "*.Cu" "*.Mask")
			(clearance 0.381)
			(thermal_gap 0.381)
		)
		(pad "" np_thru_hole circle
			(at 2.8829 -1.27)
			(size 1.0414 1.0414)
			(drill 1.0414)
			(layers "*.Cu" "*.Mask")
			(clearance 0.381)
			(thermal_gap 0.381)
		)
		(pad "" np_thru_hole circle
			(at 2.8829 1.27)
			(size 1.0414 1.0414)
			(drill 1.0414)
			(layers "*.Cu" "*.Mask")
			(clearance 0.381)
			(thermal_gap 0.381)
		)
		(pad "1" smd rect
			(at -0.8255 -0.249936)
			(size 0.3048 0.508)
			(layers "B.Cu" "B.Mask" "B.Paste")
			(net "85_10INCH_BOT_DP")
		)
		(pad "2" smd rect
			(at -0.8255 0.249936)
			(size 0.3048 0.508)
			(layers "B.Cu" "B.Mask" "B.Paste")
			(net "85_10INCH_BOT_DN")
		)
		(pad "3" smd circle
			(at 0 0 270)
			(size 0 0)
			(layers "B.Cu" "B.Mask" "B.Paste")
			(net "GND_P1")
		)
		(zone
			(layers "F.Cu" "B.Cu" "In1.Cu" "In2.Cu" "In3.Cu" "In4.Cu" "In5.Cu" "In6.Cu"
				"In7.Cu" "In8.Cu" "In9.Cu" "In10.Cu"
			)
			(hatch none 0.5)
			(connect_pads
				(clearance 0)
			)
			(min_thickness 0.25)
			(keepout
				(tracks not_allowed)
				(vias allowed)
				(pads allowed)
				(copperpour not_allowed)
				(footprints allowed)
			)
			(placement
				(enabled no)
				(sheetname "")
			)
			(fill
				(thermal_gap 0.5)
				(thermal_bridge_width 0.5)
				(island_removal_mode 0)
			)
			(polygon
				(pts
					(arc
						(start 100.9396 -57.286652)
						(mid 99.0854 -57.286652)
						(end 100.9396 -57.286652)
					)
				)
			)
		)
		(zone
			(layers "F.Cu" "B.Cu" "In1.Cu" "In2.Cu" "In3.Cu" "In4.Cu" "In5.Cu" "In6.Cu"
				"In7.Cu" "In8.Cu" "In9.Cu" "In10.Cu"
			)
			(hatch none 0.5)
			(connect_pads
				(clearance 0)
			)
			(min_thickness 0.25)
			(keepout
				(tracks not_allowed)
				(vias allowed)
				(pads allowed)
				(copperpour not_allowed)
				(footprints allowed)
			)
			(placement
				(enabled no)
				(sheetname "")
			)
			(fill
				(thermal_gap 0.5)
				(thermal_bridge_width 0.5)
				(island_removal_mode 0)
			)
			(polygon
				(pts
					(arc
						(start 100.9396 -50.936652)
						(mid 99.0854 -50.936652)
						(end 100.9396 -50.936652)
					)
				)
			)
		)
		(zone
			(layers "F.Cu" "B.Cu" "In1.Cu" "In2.Cu" "In3.Cu" "In4.Cu" "In5.Cu" "In6.Cu"
				"In7.Cu" "In8.Cu" "In9.Cu" "In10.Cu"
			)
			(hatch none 0.5)
			(connect_pads
				(clearance 0)
			)
			(min_thickness 0.25)
			(keepout
				(tracks not_allowed)
				(vias allowed)
				(pads allowed)
				(copperpour not_allowed)
				(footprints allowed)
			)
			(placement
				(enabled no)
				(sheetname "")
			)
			(fill
				(thermal_gap 0.5)
				(thermal_bridge_width 0.5)
				(island_removal_mode 0)
			)
			(polygon
				(pts
					(arc
						(start 103.4796 -57.286652)
						(mid 101.6254 -57.286652)
						(end 103.4796 -57.286652)
					)
				)
			)
		)
		(zone
			(layers "F.Cu" "B.Cu" "In1.Cu" "In2.Cu" "In3.Cu" "In4.Cu" "In5.Cu" "In6.Cu"
				"In7.Cu" "In8.Cu" "In9.Cu" "In10.Cu"
			)
			(hatch none 0.5)
			(connect_pads
				(clearance 0)
			)
			(min_thickness 0.25)
			(keepout
				(tracks not_allowed)
				(vias allowed)
				(pads allowed)
				(copperpour not_allowed)
				(footprints allowed)
			)
			(placement
				(enabled no)
				(sheetname "")
			)
			(fill
				(thermal_gap 0.5)
				(thermal_bridge_width 0.5)
				(island_removal_mode 0)
			)
			(polygon
				(pts
					(arc
						(start 103.4796 -50.936652)
						(mid 101.6254 -50.936652)
						(end 103.4796 -50.936652)
					)
				)
			)
		)
		(zone
			(layer "B.Cu")
			(hatch none 0.5)
			(connect_pads
				(clearance 0)
			)
			(min_thickness 0.25)
			(keepout
				(tracks not_allowed)
				(vias allowed)
				(pads allowed)
				(copperpour not_allowed)
				(footprints allowed)
			)
			(placement
				(enabled no)
				(sheetname "")
			)
			(fill
				(thermal_gap 0.5)
				(thermal_bridge_width 0.5)
				(island_removal_mode 0)
			)
			(polygon
				(pts
					(xy 100.73386 -53.286152) (xy 100.829364 -53.286152) (xy 100.829364 -53.883052) (xy 101.235764 -53.883052)
					(xy 101.235764 -53.286152) (xy 101.329236 -53.286152) (xy 101.329236 -53.883052) (xy 101.735636 -53.883052)
					(xy 101.735636 -53.286152) (xy 101.83114 -53.286152) (xy 101.83114 -53.984652) (xy 100.73386 -53.984652)
				)
			)
		)
	)
	(footprint ""
		(layer "B.Cu")
		(at 41.314878 -30.816804 90)
		(property "Reference" "R688"
			(at 0 0 90)
			(layer "B.SilkS")
			(hide yes)
			(effects
				(font
					(size 1.27 1.27)
				)
				(justify mirror)
			)
		)
		(property "Value" ""
			(at 0 0 90)
			(layer "B.Fab")
			(effects
				(font
					(size 1.27 1.27)
				)
				(justify mirror)
			)
		)
		(duplicate_pad_numbers_are_jumpers no)
		(fp_line
			(start 0.7874 -0.4064)
			(end -0.7874 -0.4064)
			(stroke
				(width 0.1524)
				(type default)
			)
			(layer "B.SilkS")
		)
		(fp_line
			(start -0.7874 -0.4064)
			(end -0.7874 0.4064)
			(stroke
				(width 0.1524)
				(type default)
			)
			(layer "B.SilkS")
		)
		(fp_line
			(start 0.7874 0.4064)
			(end 0.7874 -0.4064)
			(stroke
				(width 0.1524)
				(type default)
			)
			(layer "B.SilkS")
		)
		(fp_line
			(start -0.7874 0.4064)
			(end 0.7874 0.4064)
			(stroke
				(width 0.1524)
				(type default)
			)
			(layer "B.SilkS")
		)
		(fp_line
			(start 0.67945 -0.305054)
			(end 0.12065 -0.305054)
			(stroke
				(width 0.1)
				(type default)
			)
			(layer "B.Fab")
		)
		(fp_line
			(start 0.12065 -0.305054)
			(end 0.12065 -0.2794)
			(stroke
				(width 0.1)
				(type default)
			)
			(layer "B.Fab")
		)
		(fp_line
			(start -0.12065 -0.3048)
			(end -0.67945 -0.3048)
			(stroke
				(width 0.1)
				(type default)
			)
			(layer "B.Fab")
		)
		(fp_line
			(start -0.67945 -0.3048)
			(end -0.67945 0.3048)
			(stroke
				(width 0.1)
				(type default)
			)
			(layer "B.Fab")
		)
		(fp_line
			(start 0.12065 -0.2794)
			(end -0.12065 -0.2794)
			(stroke
				(width 0.1)
				(type default)
			)
			(layer "B.Fab")
		)
		(fp_line
			(start -0.12065 -0.2794)
			(end -0.12065 -0.3048)
			(stroke
				(width 0.1)
				(type default)
			)
			(layer "B.Fab")
		)
		(fp_line
			(start 0.12065 0.2794)
			(end 0.12065 0.3048)
			(stroke
				(width 0.1)
				(type default)
			)
			(layer "B.Fab")
		)
		(fp_line
			(start -0.120396 0.2794)
			(end 0.12065 0.2794)
			(stroke
				(width 0.1)
				(type default)
			)
			(layer "B.Fab")
		)
		(fp_line
			(start 0.67945 0.3048)
			(end 0.67945 -0.305054)
			(stroke
				(width 0.1)
				(type default)
			)
			(layer "B.Fab")
		)
		(fp_line
			(start 0.12065 0.3048)
			(end 0.67945 0.3048)
			(stroke
				(width 0.1)
				(type default)
			)
			(layer "B.Fab")
		)
		(fp_line
			(start -0.120396 0.3048)
			(end -0.120396 0.2794)
			(stroke
				(width 0.1)
				(type default)
			)
			(layer "B.Fab")
		)
		(fp_line
			(start -0.67945 0.3048)
			(end -0.120396 0.3048)
			(stroke
				(width 0.1)
				(type default)
			)
			(layer "B.Fab")
		)
		(pad "1" smd circle
			(at 0.40005 0 270)
			(size 0 0)
			(layers "B.Cu" "B.Mask" "B.Paste")
			(net "RST_SGPIO_RESET_BMC_N")
		)
		(pad "2" smd circle
			(at -0.40005 0 270)
			(size 0 0)
			(layers "B.Cu" "B.Mask" "B.Paste")
			(net "RST_SGPIO_RESET_N")
		)
	)
	(footprint ""
		(layer "B.Cu")
		(at 85.32241 -26.587704)
		(property "Reference" "R14"
			(at 0 0 0)
			(layer "B.SilkS")
			(hide yes)
			(effects
				(font
					(size 1.27 1.27)
				)
				(justify mirror)
			)
		)
		(property "Value" ""
			(at 0 0 0)
			(layer "B.Fab")
			(effects
				(font
					(size 1.27 1.27)
				)
				(justify mirror)
			)
		)
		(duplicate_pad_numbers_are_jumpers no)
		(fp_line
			(start -0.7874 -0.4064)
			(end -0.7874 0.4064)
			(stroke
				(width 0.1524)
				(type default)
			)
			(layer "B.SilkS")
		)
		(fp_line
			(start -0.7874 0.4064)
			(end 0.7874 0.4064)
			(stroke
				(width 0.1524)
				(type default)
			)
			(layer "B.SilkS")
		)
		(fp_line
			(start 0.7874 -0.4064)
			(end -0.7874 -0.4064)
			(stroke
				(width 0.1524)
				(type default)
			)
			(layer "B.SilkS")
		)
		(fp_line
			(start 0.7874 0.4064)
			(end 0.7874 -0.4064)
			(stroke
				(width 0.1524)
				(type default)
			)
			(layer "B.SilkS")
		)
		(fp_line
			(start -0.67945 -0.3048)
			(end -0.67945 0.3048)
			(stroke
				(width 0.1)
				(type default)
			)
			(layer "B.Fab")
		)
		(fp_line
			(start -0.67945 0.3048)
			(end -0.120396 0.3048)
			(stroke
				(width 0.1)
				(type default)
			)
			(layer "B.Fab")
		)
		(fp_line
			(start -0.12065 -0.3048)
			(end -0.67945 -0.3048)
			(stroke
				(width 0.1)
				(type default)
			)
			(layer "B.Fab")
		)
		(fp_line
			(start -0.12065 -0.2794)
			(end -0.12065 -0.3048)
			(stroke
				(width 0.1)
				(type default)
			)
			(layer "B.Fab")
		)
		(fp_line
			(start -0.120396 0.2794)
			(end 0.12065 0.2794)
			(stroke
				(width 0.1)
				(type default)
			)
			(layer "B.Fab")
		)
		(fp_line
			(start -0.120396 0.3048)
			(end -0.120396 0.2794)
			(stroke
				(width 0.1)
				(type default)
			)
			(layer "B.Fab")
		)
		(fp_line
			(start 0.12065 -0.305054)
			(end 0.12065 -0.2794)
			(stroke
				(width 0.1)
				(type default)
			)
			(layer "B.Fab")
		)
		(fp_line
			(start 0.12065 -0.2794)
			(end -0.12065 -0.2794)
			(stroke
				(width 0.1)
				(type default)
			)
			(layer "B.Fab")
		)
		(fp_line
			(start 0.12065 0.2794)
			(end 0.12065 0.3048)
			(stroke
				(width 0.1)
				(type default)
			)
			(layer "B.Fab")
		)
		(fp_line
			(start 0.12065 0.3048)
			(end 0.67945 0.3048)
			(stroke
				(width 0.1)
				(type default)
			)
			(layer "B.Fab")
		)
		(fp_line
			(start 0.67945 -0.305054)
			(end 0.12065 -0.305054)
			(stroke
				(width 0.1)
				(type default)
			)
			(layer "B.Fab")
		)
		(fp_line
			(start 0.67945 0.3048)
			(end 0.67945 -0.305054)
			(stroke
				(width 0.1)
				(type default)
			)
			(layer "B.Fab")
		)
		(pad "1" smd circle
			(at 0.40005 0 180)
			(size 0 0)
			(layers "B.Cu" "B.Mask" "B.Paste")
			(net "P3V3_AUX")
		)
		(pad "2" smd circle
			(at -0.40005 0 180)
			(size 0 0)
			(layers "B.Cu" "B.Mask" "B.Paste")
			(net "FRU_E2")
		)
	)
	(footprint ""
		(layer "B.Cu")
		(at 25.136856 -96.0882)
		(property "Reference" "C216"
			(at 0 0 0)
			(layer "B.SilkS")
			(hide yes)
			(effects
				(font
					(size 1.27 1.27)
				)
				(justify mirror)
			)
		)
		(property "Value" ""
			(at 0 0 0)
			(layer "B.Fab")
			(effects
				(font
					(size 1.27 1.27)
				)
				(justify mirror)
			)
		)
		(duplicate_pad_numbers_are_jumpers no)
		(fp_line
			(start -0.69215 -0.2921)
			(end -0.69215 0.2921)
			(stroke
				(width 0.1524)
				(type default)
			)
			(layer "B.SilkS")
		)
		(fp_line
			(start -0.69215 0.2921)
			(end 0.69215 0.2921)
			(stroke
				(width 0.1524)
				(type default)
			)
			(layer "B.SilkS")
		)
		(fp_line
			(start 0.69215 -0.2921)
			(end -0.69215 -0.2921)
			(stroke
				(width 0.1524)
				(type default)
			)
			(layer "B.SilkS")
		)
		(fp_line
			(start 0.69215 0.2921)
			(end 0.69215 -0.2921)
			(stroke
				(width 0.1524)
				(type default)
			)
			(layer "B.SilkS")
		)
		(fp_line
			(start -0.51435 -0.2794)
			(end -0.51435 0.2794)
			(stroke
				(width 0.1)
				(type default)
			)
			(layer "B.Fab")
		)
		(fp_line
			(start -0.51435 0.2794)
			(end 0.51435 0.2794)
			(stroke
				(width 0.1)
				(type default)
			)
			(layer "B.Fab")
		)
		(fp_line
			(start 0.51435 -0.2794)
			(end -0.51435 -0.2794)
			(stroke
				(width 0.1)
				(type default)
			)
			(layer "B.Fab")
		)
		(fp_line
			(start 0.51435 0.2794)
			(end 0.51435 -0.2794)
			(stroke
				(width 0.1)
				(type default)
			)
			(layer "B.Fab")
		)
		(pad "1" smd circle
			(at 0.40005 0 180)
			(size 0 0)
			(layers "B.Cu" "B.Mask" "B.Paste")
			(net "VCCIO3")
		)
		(pad "2" smd circle
			(at -0.40005 0 180)
			(size 0 0)
			(layers "B.Cu" "B.Mask" "B.Paste")
			(net "GND")
		)
		(zone
			(layer "B.Cu")
			(hatch none 0.5)
			(connect_pads
				(clearance 0)
			)
			(min_thickness 0.25)
			(keepout
				(tracks not_allowed)
				(vias allowed)
				(pads allowed)
				(copperpour not_allowed)
				(footprints allowed)
			)
			(placement
				(enabled no)
				(sheetname "")
			)
			(fill
				(thermal_gap 0.5)
				(thermal_bridge_width 0.5)
				(island_removal_mode 0)
			)
			(polygon
				(pts
					(xy 25.327356 -96.00057) (xy 25.235916 -95.942404) (xy 25.036526 -95.942404) (xy 24.946356 -96.00057)
					(xy 24.946356 -96.17583) (xy 25.036526 -96.23425) (xy 25.235916 -96.23425) (xy 25.327356 -96.176084)
				)
			)
		)
	)
	(footprint ""
		(layer "B.Cu")
		(at 83.018884 -38.13556 180)
		(property "Reference" "C15"
			(at 0 0 0)
			(layer "B.SilkS")
			(hide yes)
			(effects
				(font
					(size 1.27 1.27)
				)
				(justify mirror)
			)
		)
		(property "Value" ""
			(at 0 0 0)
			(layer "B.Fab")
			(effects
				(font
					(size 1.27 1.27)
				)
				(justify mirror)
			)
		)
		(duplicate_pad_numbers_are_jumpers no)
		(fp_line
			(start 0.7874 0.4064)
			(end 0.7874 -0.4064)
			(stroke
				(width 0.1524)
				(type default)
			)
			(layer "B.SilkS")
		)
		(fp_line
			(start 0.7874 -0.4064)
			(end -0.7874 -0.4064)
			(stroke
				(width 0.1524)
				(type default)
			)
			(layer "B.SilkS")
		)
		(fp_line
			(start -0.7874 0.4064)
			(end 0.7874 0.4064)
			(stroke
				(width 0.1524)
				(type default)
			)
			(layer "B.SilkS")
		)
		(fp_line
			(start -0.7874 -0.4064)
			(end -0.7874 0.4064)
			(stroke
				(width 0.1524)
				(type default)
			)
			(layer "B.SilkS")
		)
		(fp_line
			(start 0.67945 0.3048)
			(end 0.67945 -0.305054)
			(stroke
				(width 0.1)
				(type default)
			)
			(layer "B.Fab")
		)
		(fp_line
			(start 0.67945 -0.305054)
			(end 0.12065 -0.305054)
			(stroke
				(width 0.1)
				(type default)
			)
			(layer "B.Fab")
		)
		(fp_line
			(start 0.12065 0.3048)
			(end 0.67945 0.3048)
			(stroke
				(width 0.1)
				(type default)
			)
			(layer "B.Fab")
		)
		(fp_line
			(start 0.12065 0.2794)
			(end 0.12065 0.3048)
			(stroke
				(width 0.1)
				(type default)
			)
			(layer "B.Fab")
		)
		(fp_line
			(start 0.12065 -0.2794)
			(end -0.12065 -0.2794)
			(stroke
				(width 0.1)
				(type default)
			)
			(layer "B.Fab")
		)
		(fp_line
			(start 0.12065 -0.305054)
			(end 0.12065 -0.2794)
			(stroke
				(width 0.1)
				(type default)
			)
			(layer "B.Fab")
		)
		(fp_line
			(start -0.120396 0.3048)
			(end -0.120396 0.2794)
			(stroke
				(width 0.1)
				(type default)
			)
			(layer "B.Fab")
		)
		(fp_line
			(start -0.120396 0.2794)
			(end 0.12065 0.2794)
			(stroke
				(width 0.1)
				(type default)
			)
			(layer "B.Fab")
		)
		(fp_line
			(start -0.12065 -0.2794)
			(end -0.12065 -0.3048)
			(stroke
				(width 0.1)
				(type default)
			)
			(layer "B.Fab")
		)
		(fp_line
			(start -0.12065 -0.3048)
			(end -0.67945 -0.3048)
			(stroke
				(width 0.1)
				(type default)
			)
			(layer "B.Fab")
		)
		(fp_line
			(start -0.67945 0.3048)
			(end -0.120396 0.3048)
			(stroke
				(width 0.1)
				(type default)
			)
			(layer "B.Fab")
		)
		(fp_line
			(start -0.67945 -0.3048)
			(end -0.67945 0.3048)
			(stroke
				(width 0.1)
				(type default)
			)
			(layer "B.Fab")
		)
		(pad "1" smd circle
			(at 0.40005 0)
			(size 0 0)
			(layers "B.Cu" "B.Mask" "B.Paste")
			(net "P1V2_AUX")
		)
		(pad "2" smd circle
			(at -0.40005 0)
			(size 0 0)
			(layers "B.Cu" "B.Mask" "B.Paste")
			(net "GND")
		)
	)
	(footprint ""
		(layer "B.Cu")
		(at 58.44413 -47.990252)
		(property "Reference" "C104"
			(at 0 0 0)
			(layer "B.SilkS")
			(hide yes)
			(effects
				(font
					(size 1.27 1.27)
				)
				(justify mirror)
			)
		)
		(property "Value" ""
			(at 0 0 0)
			(layer "B.Fab")
			(effects
				(font
					(size 1.27 1.27)
				)
				(justify mirror)
			)
		)
		(duplicate_pad_numbers_are_jumpers no)
		(fp_line
			(start -0.7874 -0.4064)
			(end -0.7874 0.4064)
			(stroke
				(width 0.1524)
				(type default)
			)
			(layer "B.SilkS")
		)
		(fp_line
			(start -0.7874 0.4064)
			(end 0.7874 0.4064)
			(stroke
				(width 0.1524)
				(type default)
			)
			(layer "B.SilkS")
		)
		(fp_line
			(start 0.7874 -0.4064)
			(end -0.7874 -0.4064)
			(stroke
				(width 0.1524)
				(type default)
			)
			(layer "B.SilkS")
		)
		(fp_line
			(start 0.7874 0.4064)
			(end 0.7874 -0.4064)
			(stroke
				(width 0.1524)
				(type default)
			)
			(layer "B.SilkS")
		)
		(fp_line
			(start -0.67945 -0.3048)
			(end -0.67945 0.3048)
			(stroke
				(width 0.1)
				(type default)
			)
			(layer "B.Fab")
		)
		(fp_line
			(start -0.67945 0.3048)
			(end -0.120396 0.3048)
			(stroke
				(width 0.1)
				(type default)
			)
			(layer "B.Fab")
		)
		(fp_line
			(start -0.12065 -0.3048)
			(end -0.67945 -0.3048)
			(stroke
				(width 0.1)
				(type default)
			)
			(layer "B.Fab")
		)
		(fp_line
			(start -0.12065 -0.2794)
			(end -0.12065 -0.3048)
			(stroke
				(width 0.1)
				(type default)
			)
			(layer "B.Fab")
		)
		(fp_line
			(start -0.120396 0.2794)
			(end 0.12065 0.2794)
			(stroke
				(width 0.1)
				(type default)
			)
			(layer "B.Fab")
		)
		(fp_line
			(start -0.120396 0.3048)
			(end -0.120396 0.2794)
			(stroke
				(width 0.1)
				(type default)
			)
			(layer "B.Fab")
		)
		(fp_line
			(start 0.12065 -0.305054)
			(end 0.12065 -0.2794)
			(stroke
				(width 0.1)
				(type default)
			)
			(layer "B.Fab")
		)
		(fp_line
			(start 0.12065 -0.2794)
			(end -0.12065 -0.2794)
			(stroke
				(width 0.1)
				(type default)
			)
			(layer "B.Fab")
		)
		(fp_line
			(start 0.12065 0.2794)
			(end 0.12065 0.3048)
			(stroke
				(width 0.1)
				(type default)
			)
			(layer "B.Fab")
		)
		(fp_line
			(start 0.12065 0.3048)
			(end 0.67945 0.3048)
			(stroke
				(width 0.1)
				(type default)
			)
			(layer "B.Fab")
		)
		(fp_line
			(start 0.67945 -0.305054)
			(end 0.12065 -0.305054)
			(stroke
				(width 0.1)
				(type default)
			)
			(layer "B.Fab")
		)
		(fp_line
			(start 0.67945 0.3048)
			(end 0.67945 -0.305054)
			(stroke
				(width 0.1)
				(type default)
			)
			(layer "B.Fab")
		)
		(pad "1" smd circle
			(at 0.40005 0 180)
			(size 0 0)
			(layers "B.Cu" "B.Mask" "B.Paste")
			(net "P1V0_AUX")
		)
		(pad "2" smd circle
			(at -0.40005 0 180)
			(size 0 0)
			(layers "B.Cu" "B.Mask" "B.Paste")
			(net "GND")
		)
	)
	(footprint ""
		(layer "B.Cu")
		(at 85.29955 -39.347394 180)
		(property "Reference" "R368"
			(at 0 0 0)
			(layer "B.SilkS")
			(hide yes)
			(effects
				(font
					(size 1.27 1.27)
				)
				(justify mirror)
			)
		)
		(property "Value" ""
			(at 0 0 0)
			(layer "B.Fab")
			(effects
				(font
					(size 1.27 1.27)
				)
				(justify mirror)
			)
		)
		(duplicate_pad_numbers_are_jumpers no)
		(fp_line
			(start 0.7874 0.4064)
			(end 0.7874 -0.4064)
			(stroke
				(width 0.1524)
				(type default)
			)
			(layer "B.SilkS")
		)
		(fp_line
			(start 0.7874 -0.4064)
			(end -0.7874 -0.4064)
			(stroke
				(width 0.1524)
				(type default)
			)
			(layer "B.SilkS")
		)
		(fp_line
			(start -0.7874 0.4064)
			(end 0.7874 0.4064)
			(stroke
				(width 0.1524)
				(type default)
			)
			(layer "B.SilkS")
		)
		(fp_line
			(start -0.7874 -0.4064)
			(end -0.7874 0.4064)
			(stroke
				(width 0.1524)
				(type default)
			)
			(layer "B.SilkS")
		)
		(fp_line
			(start 0.67945 0.3048)
			(end 0.67945 -0.305054)
			(stroke
				(width 0.1)
				(type default)
			)
			(layer "B.Fab")
		)
		(fp_line
			(start 0.67945 -0.305054)
			(end 0.12065 -0.305054)
			(stroke
				(width 0.1)
				(type default)
			)
			(layer "B.Fab")
		)
		(fp_line
			(start 0.12065 0.3048)
			(end 0.67945 0.3048)
			(stroke
				(width 0.1)
				(type default)
			)
			(layer "B.Fab")
		)
		(fp_line
			(start 0.12065 0.2794)
			(end 0.12065 0.3048)
			(stroke
				(width 0.1)
				(type default)
			)
			(layer "B.Fab")
		)
		(fp_line
			(start 0.12065 -0.2794)
			(end -0.12065 -0.2794)
			(stroke
				(width 0.1)
				(type default)
			)
			(layer "B.Fab")
		)
		(fp_line
			(start 0.12065 -0.305054)
			(end 0.12065 -0.2794)
			(stroke
				(width 0.1)
				(type default)
			)
			(layer "B.Fab")
		)
		(fp_line
			(start -0.120396 0.3048)
			(end -0.120396 0.2794)
			(stroke
				(width 0.1)
				(type default)
			)
			(layer "B.Fab")
		)
		(fp_line
			(start -0.120396 0.2794)
			(end 0.12065 0.2794)
			(stroke
				(width 0.1)
				(type default)
			)
			(layer "B.Fab")
		)
		(fp_line
			(start -0.12065 -0.2794)
			(end -0.12065 -0.3048)
			(stroke
				(width 0.1)
				(type default)
			)
			(layer "B.Fab")
		)
		(fp_line
			(start -0.12065 -0.3048)
			(end -0.67945 -0.3048)
			(stroke
				(width 0.1)
				(type default)
			)
			(layer "B.Fab")
		)
		(fp_line
			(start -0.67945 0.3048)
			(end -0.120396 0.3048)
			(stroke
				(width 0.1)
				(type default)
			)
			(layer "B.Fab")
		)
		(fp_line
			(start -0.67945 -0.3048)
			(end -0.67945 0.3048)
			(stroke
				(width 0.1)
				(type default)
			)
			(layer "B.Fab")
		)
		(pad "1" smd circle
			(at 0.40005 0)
			(size 0 0)
			(layers "B.Cu" "B.Mask" "B.Paste")
			(net "M_BMC_DDR4_MCS_N")
		)
		(pad "2" smd circle
			(at -0.40005 0)
			(size 0 0)
			(layers "B.Cu" "B.Mask" "B.Paste")
			(net "P1V2_AUX")
		)
	)
	(footprint ""
		(layer "B.Cu")
		(at 75.438 -68.707)
		(property "Reference" ""
			(at 0 0 0)
			(layer "B.SilkS")
			(hide yes)
			(effects
				(font
					(size 1.27 1.27)
				)
				(justify mirror)
			)
		)
		(property "Value" ""
			(at 0 0 0)
			(layer "B.Fab")
			(effects
				(font
					(size 1.27 1.27)
				)
				(justify mirror)
			)
		)
		(duplicate_pad_numbers_are_jumpers no)
		(pad "1" smd circle
			(at 0 0 180)
			(size 0.9906 0.9906)
			(layers "B.Cu" "B.Mask" "B.Paste")
			(net "Net_599")
		)
		(zone
			(layer "B.Cu")
			(hatch none 0.5)
			(connect_pads
				(clearance 0)
			)
			(min_thickness 0.25)
			(keepout
				(tracks not_allowed)
				(vias allowed)
				(pads allowed)
				(copperpour not_allowed)
				(footprints allowed)
			)
			(placement
				(enabled no)
				(sheetname "")
			)
			(fill
				(thermal_gap 0.5)
				(thermal_bridge_width 0.5)
				(island_removal_mode 0)
			)
			(polygon
				(pts
					(arc
						(start 77.0636 -68.707)
						(mid 73.8124 -68.707)
						(end 77.0636 -68.707)
					)
				)
			)
		)
	)
	(footprint ""
		(layer "B.Cu")
		(at 79.4512 -66.1162 180)
		(property "Reference" "C301"
			(at 0 0 0)
			(layer "B.SilkS")
			(hide yes)
			(effects
				(font
					(size 1.27 1.27)
				)
				(justify mirror)
			)
		)
		(property "Value" ""
			(at 0 0 0)
			(layer "B.Fab")
			(effects
				(font
					(size 1.27 1.27)
				)
				(justify mirror)
			)
		)
		(duplicate_pad_numbers_are_jumpers no)
		(fp_line
			(start 0.7874 0.4064)
			(end 0.7874 -0.4064)
			(stroke
				(width 0.1524)
				(type default)
			)
			(layer "B.SilkS")
		)
		(fp_line
			(start 0.7874 -0.4064)
			(end -0.7874 -0.4064)
			(stroke
				(width 0.1524)
				(type default)
			)
			(layer "B.SilkS")
		)
		(fp_line
			(start -0.7874 0.4064)
			(end 0.7874 0.4064)
			(stroke
				(width 0.1524)
				(type default)
			)
			(layer "B.SilkS")
		)
		(fp_line
			(start -0.7874 -0.4064)
			(end -0.7874 0.4064)
			(stroke
				(width 0.1524)
				(type default)
			)
			(layer "B.SilkS")
		)
		(fp_line
			(start 0.67945 0.3048)
			(end 0.67945 -0.305054)
			(stroke
				(width 0.1)
				(type default)
			)
			(layer "B.Fab")
		)
		(fp_line
			(start 0.67945 -0.305054)
			(end 0.12065 -0.305054)
			(stroke
				(width 0.1)
				(type default)
			)
			(layer "B.Fab")
		)
		(fp_line
			(start 0.12065 0.3048)
			(end 0.67945 0.3048)
			(stroke
				(width 0.1)
				(type default)
			)
			(layer "B.Fab")
		)
		(fp_line
			(start 0.12065 0.2794)
			(end 0.12065 0.3048)
			(stroke
				(width 0.1)
				(type default)
			)
			(layer "B.Fab")
		)
		(fp_line
			(start 0.12065 -0.2794)
			(end -0.12065 -0.2794)
			(stroke
				(width 0.1)
				(type default)
			)
			(layer "B.Fab")
		)
		(fp_line
			(start 0.12065 -0.305054)
			(end 0.12065 -0.2794)
			(stroke
				(width 0.1)
				(type default)
			)
			(layer "B.Fab")
		)
		(fp_line
			(start -0.120396 0.3048)
			(end -0.120396 0.2794)
			(stroke
				(width 0.1)
				(type default)
			)
			(layer "B.Fab")
		)
		(fp_line
			(start -0.120396 0.2794)
			(end 0.12065 0.2794)
			(stroke
				(width 0.1)
				(type default)
			)
			(layer "B.Fab")
		)
		(fp_line
			(start -0.12065 -0.2794)
			(end -0.12065 -0.3048)
			(stroke
				(width 0.1)
				(type default)
			)
			(layer "B.Fab")
		)
		(fp_line
			(start -0.12065 -0.3048)
			(end -0.67945 -0.3048)
			(stroke
				(width 0.1)
				(type default)
			)
			(layer "B.Fab")
		)
		(fp_line
			(start -0.67945 0.3048)
			(end -0.120396 0.3048)
			(stroke
				(width 0.1)
				(type default)
			)
			(layer "B.Fab")
		)
		(fp_line
			(start -0.67945 -0.3048)
			(end -0.67945 0.3048)
			(stroke
				(width 0.1)
				(type default)
			)
			(layer "B.Fab")
		)
		(pad "1" smd circle
			(at 0.40005 0)
			(size 0 0)
			(layers "B.Cu" "B.Mask" "B.Paste")
			(net "P3V3_LDO")
		)
		(pad "2" smd circle
			(at -0.40005 0)
			(size 0 0)
			(layers "B.Cu" "B.Mask" "B.Paste")
			(net "GND")
		)
	)
	(footprint ""
		(layer "B.Cu")
		(at 29.4894 -93.1164)
		(property "Reference" "R773"
			(at 0 0 0)
			(layer "B.SilkS")
			(hide yes)
			(effects
				(font
					(size 1.27 1.27)
				)
				(justify mirror)
			)
		)
		(property "Value" ""
			(at 0 0 0)
			(layer "B.Fab")
			(effects
				(font
					(size 1.27 1.27)
				)
				(justify mirror)
			)
		)
		(duplicate_pad_numbers_are_jumpers no)
		(fp_line
			(start -0.7874 -0.4064)
			(end -0.7874 0.4064)
			(stroke
				(width 0.1524)
				(type default)
			)
			(layer "B.SilkS")
		)
		(fp_line
			(start -0.7874 0.4064)
			(end 0.7874 0.4064)
			(stroke
				(width 0.1524)
				(type default)
			)
			(layer "B.SilkS")
		)
		(fp_line
			(start 0.7874 -0.4064)
			(end -0.7874 -0.4064)
			(stroke
				(width 0.1524)
				(type default)
			)
			(layer "B.SilkS")
		)
		(fp_line
			(start 0.7874 0.4064)
			(end 0.7874 -0.4064)
			(stroke
				(width 0.1524)
				(type default)
			)
			(layer "B.SilkS")
		)
		(fp_line
			(start -0.67945 -0.3048)
			(end -0.67945 0.3048)
			(stroke
				(width 0.1)
				(type default)
			)
			(layer "B.Fab")
		)
		(fp_line
			(start -0.67945 0.3048)
			(end -0.120396 0.3048)
			(stroke
				(width 0.1)
				(type default)
			)
			(layer "B.Fab")
		)
		(fp_line
			(start -0.12065 -0.3048)
			(end -0.67945 -0.3048)
			(stroke
				(width 0.1)
				(type default)
			)
			(layer "B.Fab")
		)
		(fp_line
			(start -0.12065 -0.2794)
			(end -0.12065 -0.3048)
			(stroke
				(width 0.1)
				(type default)
			)
			(layer "B.Fab")
		)
		(fp_line
			(start -0.120396 0.2794)
			(end 0.12065 0.2794)
			(stroke
				(width 0.1)
				(type default)
			)
			(layer "B.Fab")
		)
		(fp_line
			(start -0.120396 0.3048)
			(end -0.120396 0.2794)
			(stroke
				(width 0.1)
				(type default)
			)
			(layer "B.Fab")
		)
		(fp_line
			(start 0.12065 -0.305054)
			(end 0.12065 -0.2794)
			(stroke
				(width 0.1)
				(type default)
			)
			(layer "B.Fab")
		)
		(fp_line
			(start 0.12065 -0.2794)
			(end -0.12065 -0.2794)
			(stroke
				(width 0.1)
				(type default)
			)
			(layer "B.Fab")
		)
		(fp_line
			(start 0.12065 0.2794)
			(end 0.12065 0.3048)
			(stroke
				(width 0.1)
				(type default)
			)
			(layer "B.Fab")
		)
		(fp_line
			(start 0.12065 0.3048)
			(end 0.67945 0.3048)
			(stroke
				(width 0.1)
				(type default)
			)
			(layer "B.Fab")
		)
		(fp_line
			(start 0.67945 -0.305054)
			(end 0.12065 -0.305054)
			(stroke
				(width 0.1)
				(type default)
			)
			(layer "B.Fab")
		)
		(fp_line
			(start 0.67945 0.3048)
			(end 0.67945 -0.305054)
			(stroke
				(width 0.1)
				(type default)
			)
			(layer "B.Fab")
		)
		(pad "1" smd circle
			(at 0.40005 0 180)
			(size 0 0)
			(layers "B.Cu" "B.Mask" "B.Paste")
			(net "FM_SLPS3_GF_N")
		)
		(pad "2" smd circle
			(at -0.40005 0 180)
			(size 0 0)
			(layers "B.Cu" "B.Mask" "B.Paste")
			(net "FM_SLPS3_GF_R_N")
		)
	)
	(footprint ""
		(layer "B.Cu")
		(at 12.319 -87.376 180)
		(property "Reference" "R456"
			(at 0 0 0)
			(layer "B.SilkS")
			(hide yes)
			(effects
				(font
					(size 1.27 1.27)
				)
				(justify mirror)
			)
		)
		(property "Value" ""
			(at 0 0 0)
			(layer "B.Fab")
			(effects
				(font
					(size 1.27 1.27)
				)
				(justify mirror)
			)
		)
		(duplicate_pad_numbers_are_jumpers no)
		(fp_line
			(start 0.7874 0.4064)
			(end 0.7874 -0.4064)
			(stroke
				(width 0.1524)
				(type default)
			)
			(layer "B.SilkS")
		)
		(fp_line
			(start 0.7874 -0.4064)
			(end -0.7874 -0.4064)
			(stroke
				(width 0.1524)
				(type default)
			)
			(layer "B.SilkS")
		)
		(fp_line
			(start -0.7874 0.4064)
			(end 0.7874 0.4064)
			(stroke
				(width 0.1524)
				(type default)
			)
			(layer "B.SilkS")
		)
		(fp_line
			(start -0.7874 -0.4064)
			(end -0.7874 0.4064)
			(stroke
				(width 0.1524)
				(type default)
			)
			(layer "B.SilkS")
		)
		(fp_line
			(start 0.67945 0.3048)
			(end 0.67945 -0.305054)
			(stroke
				(width 0.1)
				(type default)
			)
			(layer "B.Fab")
		)
		(fp_line
			(start 0.67945 -0.305054)
			(end 0.12065 -0.305054)
			(stroke
				(width 0.1)
				(type default)
			)
			(layer "B.Fab")
		)
		(fp_line
			(start 0.12065 0.3048)
			(end 0.67945 0.3048)
			(stroke
				(width 0.1)
				(type default)
			)
			(layer "B.Fab")
		)
		(fp_line
			(start 0.12065 0.2794)
			(end 0.12065 0.3048)
			(stroke
				(width 0.1)
				(type default)
			)
			(layer "B.Fab")
		)
		(fp_line
			(start 0.12065 -0.2794)
			(end -0.12065 -0.2794)
			(stroke
				(width 0.1)
				(type default)
			)
			(layer "B.Fab")
		)
		(fp_line
			(start 0.12065 -0.305054)
			(end 0.12065 -0.2794)
			(stroke
				(width 0.1)
				(type default)
			)
			(layer "B.Fab")
		)
		(fp_line
			(start -0.120396 0.3048)
			(end -0.120396 0.2794)
			(stroke
				(width 0.1)
				(type default)
			)
			(layer "B.Fab")
		)
		(fp_line
			(start -0.120396 0.2794)
			(end 0.12065 0.2794)
			(stroke
				(width 0.1)
				(type default)
			)
			(layer "B.Fab")
		)
		(fp_line
			(start -0.12065 -0.2794)
			(end -0.12065 -0.3048)
			(stroke
				(width 0.1)
				(type default)
			)
			(layer "B.Fab")
		)
		(fp_line
			(start -0.12065 -0.3048)
			(end -0.67945 -0.3048)
			(stroke
				(width 0.1)
				(type default)
			)
			(layer "B.Fab")
		)
		(fp_line
			(start -0.67945 0.3048)
			(end -0.120396 0.3048)
			(stroke
				(width 0.1)
				(type default)
			)
			(layer "B.Fab")
		)
		(fp_line
			(start -0.67945 -0.3048)
			(end -0.67945 0.3048)
			(stroke
				(width 0.1)
				(type default)
			)
			(layer "B.Fab")
		)
		(pad "1" smd circle
			(at 0.40005 0)
			(size 0 0)
			(layers "B.Cu" "B.Mask" "B.Paste")
			(net "SMB_BMC_ALERT9_N")
		)
		(pad "2" smd circle
			(at -0.40005 0)
			(size 0 0)
			(layers "B.Cu" "B.Mask" "B.Paste")
			(net "SMB_BMC_ALERT9_R1_N")
		)
	)
	(footprint ""
		(layer "B.Cu")
		(at 75.528678 -59.618118 90)
		(property "Reference" "C90"
			(at 0 0 90)
			(layer "B.SilkS")
			(hide yes)
			(effects
				(font
					(size 1.27 1.27)
				)
				(justify mirror)
			)
		)
		(property "Value" ""
			(at 0 0 90)
			(layer "B.Fab")
			(effects
				(font
					(size 1.27 1.27)
				)
				(justify mirror)
			)
		)
		(duplicate_pad_numbers_are_jumpers no)
		(fp_line
			(start 0.7874 -0.4064)
			(end -0.7874 -0.4064)
			(stroke
				(width 0.1524)
				(type default)
			)
			(layer "B.SilkS")
		)
		(fp_line
			(start -0.7874 -0.4064)
			(end -0.7874 0.4064)
			(stroke
				(width 0.1524)
				(type default)
			)
			(layer "B.SilkS")
		)
		(fp_line
			(start 0.7874 0.4064)
			(end 0.7874 -0.4064)
			(stroke
				(width 0.1524)
				(type default)
			)
			(layer "B.SilkS")
		)
		(fp_line
			(start -0.7874 0.4064)
			(end 0.7874 0.4064)
			(stroke
				(width 0.1524)
				(type default)
			)
			(layer "B.SilkS")
		)
		(fp_line
			(start 0.67945 -0.305054)
			(end 0.12065 -0.305054)
			(stroke
				(width 0.1)
				(type default)
			)
			(layer "B.Fab")
		)
		(fp_line
			(start 0.12065 -0.305054)
			(end 0.12065 -0.2794)
			(stroke
				(width 0.1)
				(type default)
			)
			(layer "B.Fab")
		)
		(fp_line
			(start -0.12065 -0.3048)
			(end -0.67945 -0.3048)
			(stroke
				(width 0.1)
				(type default)
			)
			(layer "B.Fab")
		)
		(fp_line
			(start -0.67945 -0.3048)
			(end -0.67945 0.3048)
			(stroke
				(width 0.1)
				(type default)
			)
			(layer "B.Fab")
		)
		(fp_line
			(start 0.12065 -0.2794)
			(end -0.12065 -0.2794)
			(stroke
				(width 0.1)
				(type default)
			)
			(layer "B.Fab")
		)
		(fp_line
			(start -0.12065 -0.2794)
			(end -0.12065 -0.3048)
			(stroke
				(width 0.1)
				(type default)
			)
			(layer "B.Fab")
		)
		(fp_line
			(start 0.12065 0.2794)
			(end 0.12065 0.3048)
			(stroke
				(width 0.1)
				(type default)
			)
			(layer "B.Fab")
		)
		(fp_line
			(start -0.120396 0.2794)
			(end 0.12065 0.2794)
			(stroke
				(width 0.1)
				(type default)
			)
			(layer "B.Fab")
		)
		(fp_line
			(start 0.67945 0.3048)
			(end 0.67945 -0.305054)
			(stroke
				(width 0.1)
				(type default)
			)
			(layer "B.Fab")
		)
		(fp_line
			(start 0.12065 0.3048)
			(end 0.67945 0.3048)
			(stroke
				(width 0.1)
				(type default)
			)
			(layer "B.Fab")
		)
		(fp_line
			(start -0.120396 0.3048)
			(end -0.120396 0.2794)
			(stroke
				(width 0.1)
				(type default)
			)
			(layer "B.Fab")
		)
		(fp_line
			(start -0.67945 0.3048)
			(end -0.120396 0.3048)
			(stroke
				(width 0.1)
				(type default)
			)
			(layer "B.Fab")
		)
		(pad "1" smd circle
			(at 0.40005 0 270)
			(size 0 0)
			(layers "B.Cu" "B.Mask" "B.Paste")
			(net "P1V0_STBY_DP_VCC10A")
		)
		(pad "2" smd circle
			(at -0.40005 0 270)
			(size 0 0)
			(layers "B.Cu" "B.Mask" "B.Paste")
			(net "GND")
		)
	)
	(footprint ""
		(layer "B.Cu")
		(at 85.281262 -43.411394 180)
		(property "Reference" "R360"
			(at 0 0 0)
			(layer "B.SilkS")
			(hide yes)
			(effects
				(font
					(size 1.27 1.27)
				)
				(justify mirror)
			)
		)
		(property "Value" ""
			(at 0 0 0)
			(layer "B.Fab")
			(effects
				(font
					(size 1.27 1.27)
				)
				(justify mirror)
			)
		)
		(duplicate_pad_numbers_are_jumpers no)
		(fp_line
			(start 0.7874 0.4064)
			(end 0.7874 -0.4064)
			(stroke
				(width 0.1524)
				(type default)
			)
			(layer "B.SilkS")
		)
		(fp_line
			(start 0.7874 -0.4064)
			(end -0.7874 -0.4064)
			(stroke
				(width 0.1524)
				(type default)
			)
			(layer "B.SilkS")
		)
		(fp_line
			(start -0.7874 0.4064)
			(end 0.7874 0.4064)
			(stroke
				(width 0.1524)
				(type default)
			)
			(layer "B.SilkS")
		)
		(fp_line
			(start -0.7874 -0.4064)
			(end -0.7874 0.4064)
			(stroke
				(width 0.1524)
				(type default)
			)
			(layer "B.SilkS")
		)
		(fp_line
			(start 0.67945 0.3048)
			(end 0.67945 -0.305054)
			(stroke
				(width 0.1)
				(type default)
			)
			(layer "B.Fab")
		)
		(fp_line
			(start 0.67945 -0.305054)
			(end 0.12065 -0.305054)
			(stroke
				(width 0.1)
				(type default)
			)
			(layer "B.Fab")
		)
		(fp_line
			(start 0.12065 0.3048)
			(end 0.67945 0.3048)
			(stroke
				(width 0.1)
				(type default)
			)
			(layer "B.Fab")
		)
		(fp_line
			(start 0.12065 0.2794)
			(end 0.12065 0.3048)
			(stroke
				(width 0.1)
				(type default)
			)
			(layer "B.Fab")
		)
		(fp_line
			(start 0.12065 -0.2794)
			(end -0.12065 -0.2794)
			(stroke
				(width 0.1)
				(type default)
			)
			(layer "B.Fab")
		)
		(fp_line
			(start 0.12065 -0.305054)
			(end 0.12065 -0.2794)
			(stroke
				(width 0.1)
				(type default)
			)
			(layer "B.Fab")
		)
		(fp_line
			(start -0.120396 0.3048)
			(end -0.120396 0.2794)
			(stroke
				(width 0.1)
				(type default)
			)
			(layer "B.Fab")
		)
		(fp_line
			(start -0.120396 0.2794)
			(end 0.12065 0.2794)
			(stroke
				(width 0.1)
				(type default)
			)
			(layer "B.Fab")
		)
		(fp_line
			(start -0.12065 -0.2794)
			(end -0.12065 -0.3048)
			(stroke
				(width 0.1)
				(type default)
			)
			(layer "B.Fab")
		)
		(fp_line
			(start -0.12065 -0.3048)
			(end -0.67945 -0.3048)
			(stroke
				(width 0.1)
				(type default)
			)
			(layer "B.Fab")
		)
		(fp_line
			(start -0.67945 0.3048)
			(end -0.120396 0.3048)
			(stroke
				(width 0.1)
				(type default)
			)
			(layer "B.Fab")
		)
		(fp_line
			(start -0.67945 -0.3048)
			(end -0.67945 0.3048)
			(stroke
				(width 0.1)
				(type default)
			)
			(layer "B.Fab")
		)
		(pad "1" smd circle
			(at 0.40005 0)
			(size 0 0)
			(layers "B.Cu" "B.Mask" "B.Paste")
			(net "M_BMC_DDR4_MA<9>")
		)
		(pad "2" smd circle
			(at -0.40005 0)
			(size 0 0)
			(layers "B.Cu" "B.Mask" "B.Paste")
			(net "P1V2_AUX")
		)
	)
	(footprint ""
		(layer "B.Cu")
		(at 64.634364 -62.037722 -90)
		(property "Reference" "R128"
			(at 0 0 90)
			(layer "B.SilkS")
			(hide yes)
			(effects
				(font
					(size 1.27 1.27)
				)
				(justify mirror)
			)
		)
		(property "Value" ""
			(at 0 0 90)
			(layer "B.Fab")
			(effects
				(font
					(size 1.27 1.27)
				)
				(justify mirror)
			)
		)
		(duplicate_pad_numbers_are_jumpers no)
		(fp_line
			(start -0.7874 0.4064)
			(end 0.7874 0.4064)
			(stroke
				(width 0.1524)
				(type default)
			)
			(layer "B.SilkS")
		)
		(fp_line
			(start 0.7874 0.4064)
			(end 0.7874 -0.4064)
			(stroke
				(width 0.1524)
				(type default)
			)
			(layer "B.SilkS")
		)
		(fp_line
			(start -0.7874 -0.4064)
			(end -0.7874 0.4064)
			(stroke
				(width 0.1524)
				(type default)
			)
			(layer "B.SilkS")
		)
		(fp_line
			(start 0.7874 -0.4064)
			(end -0.7874 -0.4064)
			(stroke
				(width 0.1524)
				(type default)
			)
			(layer "B.SilkS")
		)
		(fp_line
			(start -0.67945 0.3048)
			(end -0.120396 0.3048)
			(stroke
				(width 0.1)
				(type default)
			)
			(layer "B.Fab")
		)
		(fp_line
			(start -0.120396 0.3048)
			(end -0.120396 0.2794)
			(stroke
				(width 0.1)
				(type default)
			)
			(layer "B.Fab")
		)
		(fp_line
			(start 0.12065 0.3048)
			(end 0.67945 0.3048)
			(stroke
				(width 0.1)
				(type default)
			)
			(layer "B.Fab")
		)
		(fp_line
			(start 0.67945 0.3048)
			(end 0.67945 -0.305054)
			(stroke
				(width 0.1)
				(type default)
			)
			(layer "B.Fab")
		)
		(fp_line
			(start -0.120396 0.2794)
			(end 0.12065 0.2794)
			(stroke
				(width 0.1)
				(type default)
			)
			(layer "B.Fab")
		)
		(fp_line
			(start 0.12065 0.2794)
			(end 0.12065 0.3048)
			(stroke
				(width 0.1)
				(type default)
			)
			(layer "B.Fab")
		)
		(fp_line
			(start -0.12065 -0.2794)
			(end -0.12065 -0.3048)
			(stroke
				(width 0.1)
				(type default)
			)
			(layer "B.Fab")
		)
		(fp_line
			(start 0.12065 -0.2794)
			(end -0.12065 -0.2794)
			(stroke
				(width 0.1)
				(type default)
			)
			(layer "B.Fab")
		)
		(fp_line
			(start -0.67945 -0.3048)
			(end -0.67945 0.3048)
			(stroke
				(width 0.1)
				(type default)
			)
			(layer "B.Fab")
		)
		(fp_line
			(start -0.12065 -0.3048)
			(end -0.67945 -0.3048)
			(stroke
				(width 0.1)
				(type default)
			)
			(layer "B.Fab")
		)
		(fp_line
			(start 0.12065 -0.305054)
			(end 0.12065 -0.2794)
			(stroke
				(width 0.1)
				(type default)
			)
			(layer "B.Fab")
		)
		(fp_line
			(start 0.67945 -0.305054)
			(end 0.12065 -0.305054)
			(stroke
				(width 0.1)
				(type default)
			)
			(layer "B.Fab")
		)
		(pad "1" smd circle
			(at 0.40005 0 90)
			(size 0 0)
			(layers "B.Cu" "B.Mask" "B.Paste")
			(net "ESPI_LPC_D0_IO0")
		)
		(pad "2" smd circle
			(at -0.40005 0 90)
			(size 0 0)
			(layers "B.Cu" "B.Mask" "B.Paste")
			(net "ESPI_LPC_LAD0_IO0")
		)
	)
	(footprint ""
		(layer "B.Cu")
		(at 50.905156 -60.26277 180)
		(property "Reference" "C137"
			(at 0 0 0)
			(layer "B.SilkS")
			(hide yes)
			(effects
				(font
					(size 1.27 1.27)
				)
				(justify mirror)
			)
		)
		(property "Value" ""
			(at 0 0 0)
			(layer "B.Fab")
			(effects
				(font
					(size 1.27 1.27)
				)
				(justify mirror)
			)
		)
		(duplicate_pad_numbers_are_jumpers no)
		(fp_line
			(start 0.7874 0.4064)
			(end 0.7874 -0.4064)
			(stroke
				(width 0.1524)
				(type default)
			)
			(layer "B.SilkS")
		)
		(fp_line
			(start 0.7874 -0.4064)
			(end -0.7874 -0.4064)
			(stroke
				(width 0.1524)
				(type default)
			)
			(layer "B.SilkS")
		)
		(fp_line
			(start -0.7874 0.4064)
			(end 0.7874 0.4064)
			(stroke
				(width 0.1524)
				(type default)
			)
			(layer "B.SilkS")
		)
		(fp_line
			(start -0.7874 -0.4064)
			(end -0.7874 0.4064)
			(stroke
				(width 0.1524)
				(type default)
			)
			(layer "B.SilkS")
		)
		(fp_line
			(start 0.67945 0.3048)
			(end 0.67945 -0.305054)
			(stroke
				(width 0.1)
				(type default)
			)
			(layer "B.Fab")
		)
		(fp_line
			(start 0.67945 -0.305054)
			(end 0.12065 -0.305054)
			(stroke
				(width 0.1)
				(type default)
			)
			(layer "B.Fab")
		)
		(fp_line
			(start 0.12065 0.3048)
			(end 0.67945 0.3048)
			(stroke
				(width 0.1)
				(type default)
			)
			(layer "B.Fab")
		)
		(fp_line
			(start 0.12065 0.2794)
			(end 0.12065 0.3048)
			(stroke
				(width 0.1)
				(type default)
			)
			(layer "B.Fab")
		)
		(fp_line
			(start 0.12065 -0.2794)
			(end -0.12065 -0.2794)
			(stroke
				(width 0.1)
				(type default)
			)
			(layer "B.Fab")
		)
		(fp_line
			(start 0.12065 -0.305054)
			(end 0.12065 -0.2794)
			(stroke
				(width 0.1)
				(type default)
			)
			(layer "B.Fab")
		)
		(fp_line
			(start -0.120396 0.3048)
			(end -0.120396 0.2794)
			(stroke
				(width 0.1)
				(type default)
			)
			(layer "B.Fab")
		)
		(fp_line
			(start -0.120396 0.2794)
			(end 0.12065 0.2794)
			(stroke
				(width 0.1)
				(type default)
			)
			(layer "B.Fab")
		)
		(fp_line
			(start -0.12065 -0.2794)
			(end -0.12065 -0.3048)
			(stroke
				(width 0.1)
				(type default)
			)
			(layer "B.Fab")
		)
		(fp_line
			(start -0.12065 -0.3048)
			(end -0.67945 -0.3048)
			(stroke
				(width 0.1)
				(type default)
			)
			(layer "B.Fab")
		)
		(fp_line
			(start -0.67945 0.3048)
			(end -0.120396 0.3048)
			(stroke
				(width 0.1)
				(type default)
			)
			(layer "B.Fab")
		)
		(fp_line
			(start -0.67945 -0.3048)
			(end -0.67945 0.3048)
			(stroke
				(width 0.1)
				(type default)
			)
			(layer "B.Fab")
		)
		(pad "1" smd circle
			(at 0.40005 0)
			(size 0 0)
			(layers "B.Cu" "B.Mask" "B.Paste")
			(net "A_BMC_ADCVREFN1")
		)
		(pad "2" smd circle
			(at -0.40005 0)
			(size 0 0)
			(layers "B.Cu" "B.Mask" "B.Paste")
			(net "A_BMC_ADCVREFP1")
		)
	)
	(footprint ""
		(layer "B.Cu")
		(at 78.355444 -97.119186 90)
		(property "Reference" "Q10"
			(at -1.273556 3.877056 0)
			(unlocked yes)
			(layer "B.SilkS")
			(effects
				(font
					(size 0.7874 0.5842)
					(thickness 0.1524)
				)
				(justify left mirror)
			)
		)
		(property "Value" ""
			(at 0 0 90)
			(layer "B.Fab")
			(effects
				(font
					(size 1.27 1.27)
				)
				(justify mirror)
			)
		)
		(duplicate_pad_numbers_are_jumpers no)
		(fp_line
			(start 1.603248 -1.500124)
			(end -1.603248 -1.500124)
			(stroke
				(width 0.1524)
				(type default)
			)
			(layer "B.SilkS")
		)
		(fp_line
			(start -1.603248 -1.500124)
			(end -1.603248 1.500124)
			(stroke
				(width 0.1524)
				(type default)
			)
			(layer "B.SilkS")
		)
		(fp_line
			(start 1.603248 1.500124)
			(end 1.603248 -1.500124)
			(stroke
				(width 0.1524)
				(type default)
			)
			(layer "B.SilkS")
		)
		(fp_line
			(start -1.603248 1.500124)
			(end 1.603248 1.500124)
			(stroke
				(width 0.1524)
				(type default)
			)
			(layer "B.SilkS")
		)
		(fp_line
			(start 0.700024 -1.500124)
			(end 0.700024 -1.169924)
			(stroke
				(width 0.1)
				(type default)
			)
			(layer "B.Fab")
		)
		(fp_line
			(start -0.700024 -1.500124)
			(end 0.700024 -1.500124)
			(stroke
				(width 0.1)
				(type default)
			)
			(layer "B.Fab")
		)
		(fp_line
			(start 1.249934 -1.169924)
			(end 1.249934 -0.729996)
			(stroke
				(width 0.1)
				(type default)
			)
			(layer "B.Fab")
		)
		(fp_line
			(start 0.700024 -1.169924)
			(end 1.249934 -1.169924)
			(stroke
				(width 0.1)
				(type default)
			)
			(layer "B.Fab")
		)
		(fp_line
			(start 1.249934 -0.729996)
			(end 0.6985 -0.729996)
			(stroke
				(width 0.1)
				(type default)
			)
			(layer "B.Fab")
		)
		(fp_line
			(start 0.6985 -0.729996)
			(end 0.6985 0.729996)
			(stroke
				(width 0.1)
				(type default)
			)
			(layer "B.Fab")
		)
		(fp_line
			(start -0.700024 -0.219964)
			(end -0.700024 -1.500124)
			(stroke
				(width 0.1)
				(type default)
			)
			(layer "B.Fab")
		)
		(fp_line
			(start -1.249934 -0.219964)
			(end -0.700024 -0.219964)
			(stroke
				(width 0.1)
				(type default)
			)
			(layer "B.Fab")
		)
		(fp_line
			(start -0.700024 0.219964)
			(end -1.249934 0.219964)
			(stroke
				(width 0.1)
				(type default)
			)
			(layer "B.Fab")
		)
		(fp_line
			(start -1.249934 0.219964)
			(end -1.249934 -0.219964)
			(stroke
				(width 0.1)
				(type default)
			)
			(layer "B.Fab")
		)
		(fp_line
			(start 1.249934 0.729996)
			(end 1.249934 1.169924)
			(stroke
				(width 0.1)
				(type default)
			)
			(layer "B.Fab")
		)
		(fp_line
			(start 0.6985 0.729996)
			(end 1.249934 0.729996)
			(stroke
				(width 0.1)
				(type default)
			)
			(layer "B.Fab")
		)
		(fp_line
			(start 1.249934 1.169924)
			(end 0.700024 1.169924)
			(stroke
				(width 0.1)
				(type default)
			)
			(layer "B.Fab")
		)
		(fp_line
			(start 0.700024 1.169924)
			(end 0.700024 1.500124)
			(stroke
				(width 0.1)
				(type default)
			)
			(layer "B.Fab")
		)
		(fp_line
			(start 0.700024 1.500124)
			(end -0.700024 1.500124)
			(stroke
				(width 0.1)
				(type default)
			)
			(layer "B.Fab")
		)
		(fp_line
			(start -0.700024 1.500124)
			(end -0.700024 0.219964)
			(stroke
				(width 0.1)
				(type default)
			)
			(layer "B.Fab")
		)
		(fp_rect
			(start 0.700024 1.500124)
			(end -0.700024 -1.500124)
			(stroke
				(width 0)
				(type default)
			)
			(fill no)
			(layer "B.Fab")
		)
		(pad "D" smd rect
			(at -0.999998 0)
			(size 0.8128 0.9144)
			(layers "B.Cu" "B.Mask" "B.Paste")
			(net "LPC_ESPI_SEL_N")
		)
		(pad "G" smd rect
			(at 0.999998 -0.94996)
			(size 0.8128 0.9144)
			(layers "B.Cu" "B.Mask" "B.Paste")
			(net "LPC_ESPI_SEL_R")
		)
		(pad "S" smd rect
			(at 0.999998 0.94996)
			(size 0.8128 0.9144)
			(layers "B.Cu" "B.Mask" "B.Paste")
			(net "GND")
		)
	)
	(footprint ""
		(layer "B.Cu")
		(at 46.470316 -34.637726 90)
		(property "Reference" "R222"
			(at 0 0 90)
			(layer "B.SilkS")
			(hide yes)
			(effects
				(font
					(size 1.27 1.27)
				)
				(justify mirror)
			)
		)
		(property "Value" ""
			(at 0 0 90)
			(layer "B.Fab")
			(effects
				(font
					(size 1.27 1.27)
				)
				(justify mirror)
			)
		)
		(duplicate_pad_numbers_are_jumpers no)
		(fp_line
			(start 0.7874 -0.4064)
			(end -0.7874 -0.4064)
			(stroke
				(width 0.1524)
				(type default)
			)
			(layer "B.SilkS")
		)
		(fp_line
			(start -0.7874 -0.4064)
			(end -0.7874 0.4064)
			(stroke
				(width 0.1524)
				(type default)
			)
			(layer "B.SilkS")
		)
		(fp_line
			(start 0.7874 0.4064)
			(end 0.7874 -0.4064)
			(stroke
				(width 0.1524)
				(type default)
			)
			(layer "B.SilkS")
		)
		(fp_line
			(start -0.7874 0.4064)
			(end 0.7874 0.4064)
			(stroke
				(width 0.1524)
				(type default)
			)
			(layer "B.SilkS")
		)
		(fp_line
			(start 0.67945 -0.305054)
			(end 0.12065 -0.305054)
			(stroke
				(width 0.1)
				(type default)
			)
			(layer "B.Fab")
		)
		(fp_line
			(start 0.12065 -0.305054)
			(end 0.12065 -0.2794)
			(stroke
				(width 0.1)
				(type default)
			)
			(layer "B.Fab")
		)
		(fp_line
			(start -0.12065 -0.3048)
			(end -0.67945 -0.3048)
			(stroke
				(width 0.1)
				(type default)
			)
			(layer "B.Fab")
		)
		(fp_line
			(start -0.67945 -0.3048)
			(end -0.67945 0.3048)
			(stroke
				(width 0.1)
				(type default)
			)
			(layer "B.Fab")
		)
		(fp_line
			(start 0.12065 -0.2794)
			(end -0.12065 -0.2794)
			(stroke
				(width 0.1)
				(type default)
			)
			(layer "B.Fab")
		)
		(fp_line
			(start -0.12065 -0.2794)
			(end -0.12065 -0.3048)
			(stroke
				(width 0.1)
				(type default)
			)
			(layer "B.Fab")
		)
		(fp_line
			(start 0.12065 0.2794)
			(end 0.12065 0.3048)
			(stroke
				(width 0.1)
				(type default)
			)
			(layer "B.Fab")
		)
		(fp_line
			(start -0.120396 0.2794)
			(end 0.12065 0.2794)
			(stroke
				(width 0.1)
				(type default)
			)
			(layer "B.Fab")
		)
		(fp_line
			(start 0.67945 0.3048)
			(end 0.67945 -0.305054)
			(stroke
				(width 0.1)
				(type default)
			)
			(layer "B.Fab")
		)
		(fp_line
			(start 0.12065 0.3048)
			(end 0.67945 0.3048)
			(stroke
				(width 0.1)
				(type default)
			)
			(layer "B.Fab")
		)
		(fp_line
			(start -0.120396 0.3048)
			(end -0.120396 0.2794)
			(stroke
				(width 0.1)
				(type default)
			)
			(layer "B.Fab")
		)
		(fp_line
			(start -0.67945 0.3048)
			(end -0.120396 0.3048)
			(stroke
				(width 0.1)
				(type default)
			)
			(layer "B.Fab")
		)
		(pad "1" smd circle
			(at 0.40005 0 270)
			(size 0 0)
			(layers "B.Cu" "B.Mask" "B.Paste")
			(net "JTAG_1_BMC_TCK_R")
		)
		(pad "2" smd circle
			(at -0.40005 0 270)
			(size 0 0)
			(layers "B.Cu" "B.Mask" "B.Paste")
			(net "JTAG_MB_TCK")
		)
	)
	(footprint ""
		(layer "B.Cu")
		(at 54.16423 -61.0616 -90)
		(property "Reference" "R179"
			(at 0 0 90)
			(layer "B.SilkS")
			(hide yes)
			(effects
				(font
					(size 1.27 1.27)
				)
				(justify mirror)
			)
		)
		(property "Value" ""
			(at 0 0 90)
			(layer "B.Fab")
			(effects
				(font
					(size 1.27 1.27)
				)
				(justify mirror)
			)
		)
		(duplicate_pad_numbers_are_jumpers no)
		(fp_line
			(start -0.7874 0.4064)
			(end 0.7874 0.4064)
			(stroke
				(width 0.1524)
				(type default)
			)
			(layer "B.SilkS")
		)
		(fp_line
			(start 0.7874 0.4064)
			(end 0.7874 -0.4064)
			(stroke
				(width 0.1524)
				(type default)
			)
			(layer "B.SilkS")
		)
		(fp_line
			(start -0.7874 -0.4064)
			(end -0.7874 0.4064)
			(stroke
				(width 0.1524)
				(type default)
			)
			(layer "B.SilkS")
		)
		(fp_line
			(start 0.7874 -0.4064)
			(end -0.7874 -0.4064)
			(stroke
				(width 0.1524)
				(type default)
			)
			(layer "B.SilkS")
		)
		(fp_line
			(start -0.67945 0.3048)
			(end -0.120396 0.3048)
			(stroke
				(width 0.1)
				(type default)
			)
			(layer "B.Fab")
		)
		(fp_line
			(start -0.120396 0.3048)
			(end -0.120396 0.2794)
			(stroke
				(width 0.1)
				(type default)
			)
			(layer "B.Fab")
		)
		(fp_line
			(start 0.12065 0.3048)
			(end 0.67945 0.3048)
			(stroke
				(width 0.1)
				(type default)
			)
			(layer "B.Fab")
		)
		(fp_line
			(start 0.67945 0.3048)
			(end 0.67945 -0.305054)
			(stroke
				(width 0.1)
				(type default)
			)
			(layer "B.Fab")
		)
		(fp_line
			(start -0.120396 0.2794)
			(end 0.12065 0.2794)
			(stroke
				(width 0.1)
				(type default)
			)
			(layer "B.Fab")
		)
		(fp_line
			(start 0.12065 0.2794)
			(end 0.12065 0.3048)
			(stroke
				(width 0.1)
				(type default)
			)
			(layer "B.Fab")
		)
		(fp_line
			(start -0.12065 -0.2794)
			(end -0.12065 -0.3048)
			(stroke
				(width 0.1)
				(type default)
			)
			(layer "B.Fab")
		)
		(fp_line
			(start 0.12065 -0.2794)
			(end -0.12065 -0.2794)
			(stroke
				(width 0.1)
				(type default)
			)
			(layer "B.Fab")
		)
		(fp_line
			(start -0.67945 -0.3048)
			(end -0.67945 0.3048)
			(stroke
				(width 0.1)
				(type default)
			)
			(layer "B.Fab")
		)
		(fp_line
			(start -0.12065 -0.3048)
			(end -0.67945 -0.3048)
			(stroke
				(width 0.1)
				(type default)
			)
			(layer "B.Fab")
		)
		(fp_line
			(start 0.12065 -0.305054)
			(end 0.12065 -0.2794)
			(stroke
				(width 0.1)
				(type default)
			)
			(layer "B.Fab")
		)
		(fp_line
			(start 0.67945 -0.305054)
			(end 0.12065 -0.305054)
			(stroke
				(width 0.1)
				(type default)
			)
			(layer "B.Fab")
		)
		(pad "1" smd circle
			(at 0.40005 0 90)
			(size 0 0)
			(layers "B.Cu" "B.Mask" "B.Paste")
			(net "SPI_BMC_MOSI_IO0_R")
		)
		(pad "2" smd circle
			(at -0.40005 0 90)
			(size 0 0)
			(layers "B.Cu" "B.Mask" "B.Paste")
			(net "SPI_BMC_BOOT_MOSI")
		)
	)
	(footprint ""
		(layer "B.Cu")
		(at 58.23331 -66.147442 -90)
		(property "Reference" "R241"
			(at 0 0 90)
			(layer "B.SilkS")
			(hide yes)
			(effects
				(font
					(size 1.27 1.27)
				)
				(justify mirror)
			)
		)
		(property "Value" ""
			(at 0 0 90)
			(layer "B.Fab")
			(effects
				(font
					(size 1.27 1.27)
				)
				(justify mirror)
			)
		)
		(duplicate_pad_numbers_are_jumpers no)
		(fp_line
			(start -0.7874 0.4064)
			(end 0.7874 0.4064)
			(stroke
				(width 0.1524)
				(type default)
			)
			(layer "B.SilkS")
		)
		(fp_line
			(start 0.7874 0.4064)
			(end 0.7874 -0.4064)
			(stroke
				(width 0.1524)
				(type default)
			)
			(layer "B.SilkS")
		)
		(fp_line
			(start -0.7874 -0.4064)
			(end -0.7874 0.4064)
			(stroke
				(width 0.1524)
				(type default)
			)
			(layer "B.SilkS")
		)
		(fp_line
			(start 0.7874 -0.4064)
			(end -0.7874 -0.4064)
			(stroke
				(width 0.1524)
				(type default)
			)
			(layer "B.SilkS")
		)
		(fp_line
			(start -0.67945 0.3048)
			(end -0.120396 0.3048)
			(stroke
				(width 0.1)
				(type default)
			)
			(layer "B.Fab")
		)
		(fp_line
			(start -0.120396 0.3048)
			(end -0.120396 0.2794)
			(stroke
				(width 0.1)
				(type default)
			)
			(layer "B.Fab")
		)
		(fp_line
			(start 0.12065 0.3048)
			(end 0.67945 0.3048)
			(stroke
				(width 0.1)
				(type default)
			)
			(layer "B.Fab")
		)
		(fp_line
			(start 0.67945 0.3048)
			(end 0.67945 -0.305054)
			(stroke
				(width 0.1)
				(type default)
			)
			(layer "B.Fab")
		)
		(fp_line
			(start -0.120396 0.2794)
			(end 0.12065 0.2794)
			(stroke
				(width 0.1)
				(type default)
			)
			(layer "B.Fab")
		)
		(fp_line
			(start 0.12065 0.2794)
			(end 0.12065 0.3048)
			(stroke
				(width 0.1)
				(type default)
			)
			(layer "B.Fab")
		)
		(fp_line
			(start -0.12065 -0.2794)
			(end -0.12065 -0.3048)
			(stroke
				(width 0.1)
				(type default)
			)
			(layer "B.Fab")
		)
		(fp_line
			(start 0.12065 -0.2794)
			(end -0.12065 -0.2794)
			(stroke
				(width 0.1)
				(type default)
			)
			(layer "B.Fab")
		)
		(fp_line
			(start -0.67945 -0.3048)
			(end -0.67945 0.3048)
			(stroke
				(width 0.1)
				(type default)
			)
			(layer "B.Fab")
		)
		(fp_line
			(start -0.12065 -0.3048)
			(end -0.67945 -0.3048)
			(stroke
				(width 0.1)
				(type default)
			)
			(layer "B.Fab")
		)
		(fp_line
			(start 0.12065 -0.305054)
			(end 0.12065 -0.2794)
			(stroke
				(width 0.1)
				(type default)
			)
			(layer "B.Fab")
		)
		(fp_line
			(start 0.67945 -0.305054)
			(end 0.12065 -0.305054)
			(stroke
				(width 0.1)
				(type default)
			)
			(layer "B.Fab")
		)
		(pad "1" smd circle
			(at 0.40005 0 90)
			(size 0 0)
			(layers "B.Cu" "B.Mask" "B.Paste")
			(net "P3V3_AUX")
		)
		(pad "2" smd circle
			(at -0.40005 0 90)
			(size 0 0)
			(layers "B.Cu" "B.Mask" "B.Paste")
			(net "PU_SPI1ABR")
		)
	)
	(footprint ""
		(layer "B.Cu")
		(at 64.036194 -28.356306 -90)
		(property "Reference" "R257"
			(at 0 0 90)
			(layer "B.SilkS")
			(hide yes)
			(effects
				(font
					(size 1.27 1.27)
				)
				(justify mirror)
			)
		)
		(property "Value" ""
			(at 0 0 90)
			(layer "B.Fab")
			(effects
				(font
					(size 1.27 1.27)
				)
				(justify mirror)
			)
		)
		(duplicate_pad_numbers_are_jumpers no)
		(fp_line
			(start -0.7874 0.4064)
			(end 0.7874 0.4064)
			(stroke
				(width 0.1524)
				(type default)
			)
			(layer "B.SilkS")
		)
		(fp_line
			(start 0.7874 0.4064)
			(end 0.7874 -0.4064)
			(stroke
				(width 0.1524)
				(type default)
			)
			(layer "B.SilkS")
		)
		(fp_line
			(start -0.7874 -0.4064)
			(end -0.7874 0.4064)
			(stroke
				(width 0.1524)
				(type default)
			)
			(layer "B.SilkS")
		)
		(fp_line
			(start 0.7874 -0.4064)
			(end -0.7874 -0.4064)
			(stroke
				(width 0.1524)
				(type default)
			)
			(layer "B.SilkS")
		)
		(fp_line
			(start -0.67945 0.3048)
			(end -0.120396 0.3048)
			(stroke
				(width 0.1)
				(type default)
			)
			(layer "B.Fab")
		)
		(fp_line
			(start -0.120396 0.3048)
			(end -0.120396 0.2794)
			(stroke
				(width 0.1)
				(type default)
			)
			(layer "B.Fab")
		)
		(fp_line
			(start 0.12065 0.3048)
			(end 0.67945 0.3048)
			(stroke
				(width 0.1)
				(type default)
			)
			(layer "B.Fab")
		)
		(fp_line
			(start 0.67945 0.3048)
			(end 0.67945 -0.305054)
			(stroke
				(width 0.1)
				(type default)
			)
			(layer "B.Fab")
		)
		(fp_line
			(start -0.120396 0.2794)
			(end 0.12065 0.2794)
			(stroke
				(width 0.1)
				(type default)
			)
			(layer "B.Fab")
		)
		(fp_line
			(start 0.12065 0.2794)
			(end 0.12065 0.3048)
			(stroke
				(width 0.1)
				(type default)
			)
			(layer "B.Fab")
		)
		(fp_line
			(start -0.12065 -0.2794)
			(end -0.12065 -0.3048)
			(stroke
				(width 0.1)
				(type default)
			)
			(layer "B.Fab")
		)
		(fp_line
			(start 0.12065 -0.2794)
			(end -0.12065 -0.2794)
			(stroke
				(width 0.1)
				(type default)
			)
			(layer "B.Fab")
		)
		(fp_line
			(start -0.67945 -0.3048)
			(end -0.67945 0.3048)
			(stroke
				(width 0.1)
				(type default)
			)
			(layer "B.Fab")
		)
		(fp_line
			(start -0.12065 -0.3048)
			(end -0.67945 -0.3048)
			(stroke
				(width 0.1)
				(type default)
			)
			(layer "B.Fab")
		)
		(fp_line
			(start 0.12065 -0.305054)
			(end 0.12065 -0.2794)
			(stroke
				(width 0.1)
				(type default)
			)
			(layer "B.Fab")
		)
		(fp_line
			(start 0.67945 -0.305054)
			(end 0.12065 -0.305054)
			(stroke
				(width 0.1)
				(type default)
			)
			(layer "B.Fab")
		)
		(pad "1" smd circle
			(at 0.40005 0 90)
			(size 0 0)
			(layers "B.Cu" "B.Mask" "B.Paste")
			(net "P3V3_AUX")
		)
		(pad "2" smd circle
			(at -0.40005 0 90)
			(size 0 0)
			(layers "B.Cu" "B.Mask" "B.Paste")
			(net "SMB_BMC_MM7_R_SDA")
		)
	)
	(footprint ""
		(layer "B.Cu")
		(at 47.649384 -47.96409 -90)
		(property "Reference" "C31"
			(at 0 0 90)
			(layer "B.SilkS")
			(hide yes)
			(effects
				(font
					(size 1.27 1.27)
				)
				(justify mirror)
			)
		)
		(property "Value" ""
			(at 0 0 90)
			(layer "B.Fab")
			(effects
				(font
					(size 1.27 1.27)
				)
				(justify mirror)
			)
		)
		(duplicate_pad_numbers_are_jumpers no)
		(fp_line
			(start -0.7874 0.4064)
			(end 0.7874 0.4064)
			(stroke
				(width 0.1524)
				(type default)
			)
			(layer "B.SilkS")
		)
		(fp_line
			(start 0.7874 0.4064)
			(end 0.7874 -0.4064)
			(stroke
				(width 0.1524)
				(type default)
			)
			(layer "B.SilkS")
		)
		(fp_line
			(start -0.7874 -0.4064)
			(end -0.7874 0.4064)
			(stroke
				(width 0.1524)
				(type default)
			)
			(layer "B.SilkS")
		)
		(fp_line
			(start 0.7874 -0.4064)
			(end -0.7874 -0.4064)
			(stroke
				(width 0.1524)
				(type default)
			)
			(layer "B.SilkS")
		)
		(fp_line
			(start -0.67945 0.3048)
			(end -0.120396 0.3048)
			(stroke
				(width 0.1)
				(type default)
			)
			(layer "B.Fab")
		)
		(fp_line
			(start -0.120396 0.3048)
			(end -0.120396 0.2794)
			(stroke
				(width 0.1)
				(type default)
			)
			(layer "B.Fab")
		)
		(fp_line
			(start 0.12065 0.3048)
			(end 0.67945 0.3048)
			(stroke
				(width 0.1)
				(type default)
			)
			(layer "B.Fab")
		)
		(fp_line
			(start 0.67945 0.3048)
			(end 0.67945 -0.305054)
			(stroke
				(width 0.1)
				(type default)
			)
			(layer "B.Fab")
		)
		(fp_line
			(start -0.120396 0.2794)
			(end 0.12065 0.2794)
			(stroke
				(width 0.1)
				(type default)
			)
			(layer "B.Fab")
		)
		(fp_line
			(start 0.12065 0.2794)
			(end 0.12065 0.3048)
			(stroke
				(width 0.1)
				(type default)
			)
			(layer "B.Fab")
		)
		(fp_line
			(start -0.12065 -0.2794)
			(end -0.12065 -0.3048)
			(stroke
				(width 0.1)
				(type default)
			)
			(layer "B.Fab")
		)
		(fp_line
			(start 0.12065 -0.2794)
			(end -0.12065 -0.2794)
			(stroke
				(width 0.1)
				(type default)
			)
			(layer "B.Fab")
		)
		(fp_line
			(start -0.67945 -0.3048)
			(end -0.67945 0.3048)
			(stroke
				(width 0.1)
				(type default)
			)
			(layer "B.Fab")
		)
		(fp_line
			(start -0.12065 -0.3048)
			(end -0.67945 -0.3048)
			(stroke
				(width 0.1)
				(type default)
			)
			(layer "B.Fab")
		)
		(fp_line
			(start 0.12065 -0.305054)
			(end 0.12065 -0.2794)
			(stroke
				(width 0.1)
				(type default)
			)
			(layer "B.Fab")
		)
		(fp_line
			(start 0.67945 -0.305054)
			(end 0.12065 -0.305054)
			(stroke
				(width 0.1)
				(type default)
			)
			(layer "B.Fab")
		)
		(pad "1" smd circle
			(at 0.40005 0 90)
			(size 0 0)
			(layers "B.Cu" "B.Mask" "B.Paste")
			(net "P3V3_P2V5_P1V8_RVDD")
		)
		(pad "2" smd circle
			(at -0.40005 0 90)
			(size 0 0)
			(layers "B.Cu" "B.Mask" "B.Paste")
			(net "GND")
		)
	)
	(footprint ""
		(layer "B.Cu")
		(at 55.486808 -94.520766 180)
		(property "Reference" "C300"
			(at 0 0 0)
			(layer "B.SilkS")
			(hide yes)
			(effects
				(font
					(size 1.27 1.27)
				)
				(justify mirror)
			)
		)
		(property "Value" ""
			(at 0 0 0)
			(layer "B.Fab")
			(effects
				(font
					(size 1.27 1.27)
				)
				(justify mirror)
			)
		)
		(duplicate_pad_numbers_are_jumpers no)
		(fp_line
			(start 0.7874 0.4064)
			(end 0.7874 -0.4064)
			(stroke
				(width 0.1524)
				(type default)
			)
			(layer "B.SilkS")
		)
		(fp_line
			(start 0.7874 -0.4064)
			(end -0.7874 -0.4064)
			(stroke
				(width 0.1524)
				(type default)
			)
			(layer "B.SilkS")
		)
		(fp_line
			(start -0.7874 0.4064)
			(end 0.7874 0.4064)
			(stroke
				(width 0.1524)
				(type default)
			)
			(layer "B.SilkS")
		)
		(fp_line
			(start -0.7874 -0.4064)
			(end -0.7874 0.4064)
			(stroke
				(width 0.1524)
				(type default)
			)
			(layer "B.SilkS")
		)
		(fp_line
			(start 0.67945 0.3048)
			(end 0.67945 -0.305054)
			(stroke
				(width 0.1)
				(type default)
			)
			(layer "B.Fab")
		)
		(fp_line
			(start 0.67945 -0.305054)
			(end 0.12065 -0.305054)
			(stroke
				(width 0.1)
				(type default)
			)
			(layer "B.Fab")
		)
		(fp_line
			(start 0.12065 0.3048)
			(end 0.67945 0.3048)
			(stroke
				(width 0.1)
				(type default)
			)
			(layer "B.Fab")
		)
		(fp_line
			(start 0.12065 0.2794)
			(end 0.12065 0.3048)
			(stroke
				(width 0.1)
				(type default)
			)
			(layer "B.Fab")
		)
		(fp_line
			(start 0.12065 -0.2794)
			(end -0.12065 -0.2794)
			(stroke
				(width 0.1)
				(type default)
			)
			(layer "B.Fab")
		)
		(fp_line
			(start 0.12065 -0.305054)
			(end 0.12065 -0.2794)
			(stroke
				(width 0.1)
				(type default)
			)
			(layer "B.Fab")
		)
		(fp_line
			(start -0.120396 0.3048)
			(end -0.120396 0.2794)
			(stroke
				(width 0.1)
				(type default)
			)
			(layer "B.Fab")
		)
		(fp_line
			(start -0.120396 0.2794)
			(end 0.12065 0.2794)
			(stroke
				(width 0.1)
				(type default)
			)
			(layer "B.Fab")
		)
		(fp_line
			(start -0.12065 -0.2794)
			(end -0.12065 -0.3048)
			(stroke
				(width 0.1)
				(type default)
			)
			(layer "B.Fab")
		)
		(fp_line
			(start -0.12065 -0.3048)
			(end -0.67945 -0.3048)
			(stroke
				(width 0.1)
				(type default)
			)
			(layer "B.Fab")
		)
		(fp_line
			(start -0.67945 0.3048)
			(end -0.120396 0.3048)
			(stroke
				(width 0.1)
				(type default)
			)
			(layer "B.Fab")
		)
		(fp_line
			(start -0.67945 -0.3048)
			(end -0.67945 0.3048)
			(stroke
				(width 0.1)
				(type default)
			)
			(layer "B.Fab")
		)
		(pad "1" smd circle
			(at 0.40005 0)
			(size 0 0)
			(layers "B.Cu" "B.Mask" "B.Paste")
			(net "P3V3_AUX")
		)
		(pad "2" smd circle
			(at -0.40005 0)
			(size 0 0)
			(layers "B.Cu" "B.Mask" "B.Paste")
			(net "GND")
		)
	)
	(footprint ""
		(layer "B.Cu")
		(at 26.67 -90.805 180)
		(property "Reference" "C160"
			(at 0 0 0)
			(layer "B.SilkS")
			(hide yes)
			(effects
				(font
					(size 1.27 1.27)
				)
				(justify mirror)
			)
		)
		(property "Value" ""
			(at 0 0 0)
			(layer "B.Fab")
			(effects
				(font
					(size 1.27 1.27)
				)
				(justify mirror)
			)
		)
		(duplicate_pad_numbers_are_jumpers no)
		(fp_line
			(start 0.69215 0.2921)
			(end 0.69215 -0.2921)
			(stroke
				(width 0.1524)
				(type default)
			)
			(layer "B.SilkS")
		)
		(fp_line
			(start 0.69215 -0.2921)
			(end -0.69215 -0.2921)
			(stroke
				(width 0.1524)
				(type default)
			)
			(layer "B.SilkS")
		)
		(fp_line
			(start -0.69215 0.2921)
			(end 0.69215 0.2921)
			(stroke
				(width 0.1524)
				(type default)
			)
			(layer "B.SilkS")
		)
		(fp_line
			(start -0.69215 -0.2921)
			(end -0.69215 0.2921)
			(stroke
				(width 0.1524)
				(type default)
			)
			(layer "B.SilkS")
		)
		(fp_line
			(start 0.51435 0.2794)
			(end 0.51435 -0.2794)
			(stroke
				(width 0.1)
				(type default)
			)
			(layer "B.Fab")
		)
		(fp_line
			(start 0.51435 -0.2794)
			(end -0.51435 -0.2794)
			(stroke
				(width 0.1)
				(type default)
			)
			(layer "B.Fab")
		)
		(fp_line
			(start -0.51435 0.2794)
			(end 0.51435 0.2794)
			(stroke
				(width 0.1)
				(type default)
			)
			(layer "B.Fab")
		)
		(fp_line
			(start -0.51435 -0.2794)
			(end -0.51435 0.2794)
			(stroke
				(width 0.1)
				(type default)
			)
			(layer "B.Fab")
		)
		(pad "1" smd circle
			(at 0.40005 0)
			(size 0 0)
			(layers "B.Cu" "B.Mask" "B.Paste")
			(net "VCCIO5")
		)
		(pad "2" smd circle
			(at -0.40005 0)
			(size 0 0)
			(layers "B.Cu" "B.Mask" "B.Paste")
			(net "GND")
		)
		(zone
			(layer "B.Cu")
			(hatch none 0.5)
			(connect_pads
				(clearance 0)
			)
			(min_thickness 0.25)
			(keepout
				(tracks not_allowed)
				(vias allowed)
				(pads allowed)
				(copperpour not_allowed)
				(footprints allowed)
			)
			(placement
				(enabled no)
				(sheetname "")
			)
			(fill
				(thermal_gap 0.5)
				(thermal_bridge_width 0.5)
				(island_removal_mode 0)
			)
			(polygon
				(pts
					(xy 26.4795 -90.89263) (xy 26.57094 -90.950796) (xy 26.77033 -90.950796) (xy 26.8605 -90.89263)
					(xy 26.8605 -90.71737) (xy 26.77033 -90.65895) (xy 26.57094 -90.65895) (xy 26.4795 -90.717116)
				)
			)
		)
	)
	(footprint ""
		(layer "B.Cu")
		(at 30.31998 -88.97112 90)
		(property "Reference" "R767"
			(at 0 0 90)
			(layer "B.SilkS")
			(hide yes)
			(effects
				(font
					(size 1.27 1.27)
				)
				(justify mirror)
			)
		)
		(property "Value" ""
			(at 0 0 90)
			(layer "B.Fab")
			(effects
				(font
					(size 1.27 1.27)
				)
				(justify mirror)
			)
		)
		(duplicate_pad_numbers_are_jumpers no)
		(fp_line
			(start 0.7874 -0.4064)
			(end -0.7874 -0.4064)
			(stroke
				(width 0.1524)
				(type default)
			)
			(layer "B.SilkS")
		)
		(fp_line
			(start -0.7874 -0.4064)
			(end -0.7874 0.4064)
			(stroke
				(width 0.1524)
				(type default)
			)
			(layer "B.SilkS")
		)
		(fp_line
			(start 0.7874 0.4064)
			(end 0.7874 -0.4064)
			(stroke
				(width 0.1524)
				(type default)
			)
			(layer "B.SilkS")
		)
		(fp_line
			(start -0.7874 0.4064)
			(end 0.7874 0.4064)
			(stroke
				(width 0.1524)
				(type default)
			)
			(layer "B.SilkS")
		)
		(fp_line
			(start 0.67945 -0.305054)
			(end 0.12065 -0.305054)
			(stroke
				(width 0.1)
				(type default)
			)
			(layer "B.Fab")
		)
		(fp_line
			(start 0.12065 -0.305054)
			(end 0.12065 -0.2794)
			(stroke
				(width 0.1)
				(type default)
			)
			(layer "B.Fab")
		)
		(fp_line
			(start -0.12065 -0.3048)
			(end -0.67945 -0.3048)
			(stroke
				(width 0.1)
				(type default)
			)
			(layer "B.Fab")
		)
		(fp_line
			(start -0.67945 -0.3048)
			(end -0.67945 0.3048)
			(stroke
				(width 0.1)
				(type default)
			)
			(layer "B.Fab")
		)
		(fp_line
			(start 0.12065 -0.2794)
			(end -0.12065 -0.2794)
			(stroke
				(width 0.1)
				(type default)
			)
			(layer "B.Fab")
		)
		(fp_line
			(start -0.12065 -0.2794)
			(end -0.12065 -0.3048)
			(stroke
				(width 0.1)
				(type default)
			)
			(layer "B.Fab")
		)
		(fp_line
			(start 0.12065 0.2794)
			(end 0.12065 0.3048)
			(stroke
				(width 0.1)
				(type default)
			)
			(layer "B.Fab")
		)
		(fp_line
			(start -0.120396 0.2794)
			(end 0.12065 0.2794)
			(stroke
				(width 0.1)
				(type default)
			)
			(layer "B.Fab")
		)
		(fp_line
			(start 0.67945 0.3048)
			(end 0.67945 -0.305054)
			(stroke
				(width 0.1)
				(type default)
			)
			(layer "B.Fab")
		)
		(fp_line
			(start 0.12065 0.3048)
			(end 0.67945 0.3048)
			(stroke
				(width 0.1)
				(type default)
			)
			(layer "B.Fab")
		)
		(fp_line
			(start -0.120396 0.3048)
			(end -0.120396 0.2794)
			(stroke
				(width 0.1)
				(type default)
			)
			(layer "B.Fab")
		)
		(fp_line
			(start -0.67945 0.3048)
			(end -0.120396 0.3048)
			(stroke
				(width 0.1)
				(type default)
			)
			(layer "B.Fab")
		)
		(pad "1" smd circle
			(at 0.40005 0 270)
			(size 0 0)
			(layers "B.Cu" "B.Mask" "B.Paste")
			(net "FM_TPM_PRSNT_0_N")
		)
		(pad "2" smd circle
			(at -0.40005 0 270)
			(size 0 0)
			(layers "B.Cu" "B.Mask" "B.Paste")
			(net "FM_TPM_PRSNT_0_R_N")
		)
	)
	(footprint ""
		(layer "B.Cu")
		(at 114.554 -106.68 -90)
		(property "Reference" "X7"
			(at 2.19837 1.2192 0)
			(unlocked yes)
			(layer "B.SilkS")
			(effects
				(font
					(size 0.7874 0.5842)
					(thickness 0.1524)
				)
				(justify left mirror)
			)
		)
		(property "Value" ""
			(at 0 0 90)
			(layer "B.Fab")
			(effects
				(font
					(size 1.27 1.27)
				)
				(justify mirror)
			)
		)
		(property "Device Type" "TP_TDR_4P_FTS_TH-TP_TDR_4P_DIPA"
			(at -1.30175 1.27 180)
			(unlocked yes)
			(layer "B.Fab")
			(hide yes)
			(effects
				(font
					(size 0.635 0.4064)
					(thickness 0.1524)
				)
				(justify mirror)
			)
		)
		(property "User Part Number" "N_A"
			(at -1.30175 1.27 180)
			(unlocked yes)
			(layer "Cmts.User")
			(hide yes)
			(effects
				(font
					(size 0.635 0.4064)
					(thickness 0.1524)
				)
				(justify mirror)
			)
		)
		(duplicate_pad_numbers_are_jumpers no)
		(fp_line
			(start -2.54 3.81)
			(end -2.54 3.6703)
			(stroke
				(width 0.1524)
				(type default)
			)
			(layer "B.SilkS")
		)
		(fp_line
			(start 0 3.81)
			(end -2.54 3.81)
			(stroke
				(width 0.1524)
				(type default)
			)
			(layer "B.SilkS")
		)
		(fp_line
			(start 0 3.175)
			(end 0 3.81)
			(stroke
				(width 0.1524)
				(type default)
			)
			(layer "B.SilkS")
		)
		(fp_line
			(start -2.54 1.4097)
			(end -2.54 1.1303)
			(stroke
				(width 0.1524)
				(type default)
			)
			(layer "B.SilkS")
		)
		(fp_line
			(start 0 0.635)
			(end 0 1.905)
			(stroke
				(width 0.1524)
				(type default)
			)
			(layer "B.SilkS")
		)
		(fp_line
			(start -2.54 -1.1303)
			(end -2.54 -1.27)
			(stroke
				(width 0.1524)
				(type default)
			)
			(layer "B.SilkS")
		)
		(fp_line
			(start -2.54 -1.27)
			(end 0 -1.27)
			(stroke
				(width 0.1524)
				(type default)
			)
			(layer "B.SilkS")
		)
		(fp_line
			(start 0 -1.27)
			(end 0 -0.635)
			(stroke
				(width 0.1524)
				(type default)
			)
			(layer "B.SilkS")
		)
		(fp_poly
			(pts
				(xy 0.761746 0) (xy 2.285746 -0.762) (xy 2.285746 0.762)
			)
			(stroke
				(width 0)
				(type default)
			)
			(fill yes)
			(layer "B.SilkS")
		)
		(fp_line
			(start -2.54 3.81)
			(end -2.54 -1.27)
			(stroke
				(width 0.1)
				(type default)
			)
			(layer "B.Fab")
		)
		(fp_line
			(start 0 3.81)
			(end -2.54 3.81)
			(stroke
				(width 0.1)
				(type default)
			)
			(layer "B.Fab")
		)
		(fp_line
			(start -2.54 -1.27)
			(end 0 -1.27)
			(stroke
				(width 0.1)
				(type default)
			)
			(layer "B.Fab")
		)
		(fp_line
			(start 0 -1.27)
			(end 0 3.81)
			(stroke
				(width 0.1)
				(type default)
			)
			(layer "B.Fab")
		)
		(fp_poly
			(pts
				(xy 0.761746 0) (xy 2.285746 -0.762) (xy 2.285746 0.762)
			)
			(stroke
				(width 0)
				(type default)
			)
			(fill yes)
			(layer "B.Fab")
		)
		(pad "1" thru_hole circle
			(at 0 0 90)
			(size 1.0033 1.0033)
			(drill 0.249936)
			(layers "*.Cu" "*.Mask")
			(remove_unused_layers no)
			(net "TDR_DIFF_85_TOP_DN")
			(clearance 0.10795)
			(padstack
				(mode front_inner_back)
				(layer "Inner"
					(shape circle)
					(size 0.8001 0.8001)
					(clearance 0.1524)
				)
				(layer "B.Cu"
					(shape circle)
					(size 1.0033 1.0033)
					(thermal_gap 0.10795)
					(clearance 0.10795)
				)
			)
		)
		(pad "2" thru_hole circle
			(at -2.54 0 90)
			(size 1.9939 1.9939)
			(drill 0.249936)
			(layers "*.Cu" "*.Mask")
			(remove_unused_layers no)
			(net "GND_P1")
			(clearance 0.10795)
			(padstack
				(mode front_inner_back)
				(layer "Inner"
					(shape circle)
					(size 0.8001 0.8001)
					(clearance 0.1524)
				)
				(layer "B.Cu"
					(shape circle)
					(size 1.9939 1.9939)
					(thermal_gap 0.10795)
					(clearance 0.10795)
				)
			)
		)
		(pad "3" thru_hole circle
			(at -2.54 2.54 90)
			(size 1.9939 1.9939)
			(drill 0.249936)
			(layers "*.Cu" "*.Mask")
			(remove_unused_layers no)
			(net "GND_P1")
			(clearance 0.10795)
			(padstack
				(mode front_inner_back)
				(layer "Inner"
					(shape circle)
					(size 0.8001 0.8001)
					(clearance 0.1524)
				)
				(layer "B.Cu"
					(shape circle)
					(size 1.9939 1.9939)
					(thermal_gap 0.10795)
					(clearance 0.10795)
				)
			)
		)
		(pad "4" thru_hole circle
			(at 0 2.54 90)
			(size 1.0033 1.0033)
			(drill 0.249936)
			(layers "*.Cu" "*.Mask")
			(remove_unused_layers no)
			(net "TDR_DIFF_85_TOP_DP")
			(clearance 0.10795)
			(padstack
				(mode front_inner_back)
				(layer "Inner"
					(shape circle)
					(size 0.8001 0.8001)
					(clearance 0.1524)
				)
				(layer "B.Cu"
					(shape circle)
					(size 1.0033 1.0033)
					(thermal_gap 0.10795)
					(clearance 0.10795)
				)
			)
		)
	)
	(footprint ""
		(layer "B.Cu")
		(at 51.2445 -94.1705 180)
		(property "Reference" "R95"
			(at 0 0 0)
			(layer "B.SilkS")
			(hide yes)
			(effects
				(font
					(size 1.27 1.27)
				)
				(justify mirror)
			)
		)
		(property "Value" ""
			(at 0 0 0)
			(layer "B.Fab")
			(effects
				(font
					(size 1.27 1.27)
				)
				(justify mirror)
			)
		)
		(duplicate_pad_numbers_are_jumpers no)
		(fp_line
			(start 0.7874 0.4064)
			(end 0.7874 -0.4064)
			(stroke
				(width 0.1524)
				(type default)
			)
			(layer "B.SilkS")
		)
		(fp_line
			(start 0.7874 -0.4064)
			(end -0.7874 -0.4064)
			(stroke
				(width 0.1524)
				(type default)
			)
			(layer "B.SilkS")
		)
		(fp_line
			(start -0.7874 0.4064)
			(end 0.7874 0.4064)
			(stroke
				(width 0.1524)
				(type default)
			)
			(layer "B.SilkS")
		)
		(fp_line
			(start -0.7874 -0.4064)
			(end -0.7874 0.4064)
			(stroke
				(width 0.1524)
				(type default)
			)
			(layer "B.SilkS")
		)
		(fp_line
			(start 0.67945 0.3048)
			(end 0.67945 -0.305054)
			(stroke
				(width 0.1)
				(type default)
			)
			(layer "B.Fab")
		)
		(fp_line
			(start 0.67945 -0.305054)
			(end 0.12065 -0.305054)
			(stroke
				(width 0.1)
				(type default)
			)
			(layer "B.Fab")
		)
		(fp_line
			(start 0.12065 0.3048)
			(end 0.67945 0.3048)
			(stroke
				(width 0.1)
				(type default)
			)
			(layer "B.Fab")
		)
		(fp_line
			(start 0.12065 0.2794)
			(end 0.12065 0.3048)
			(stroke
				(width 0.1)
				(type default)
			)
			(layer "B.Fab")
		)
		(fp_line
			(start 0.12065 -0.2794)
			(end -0.12065 -0.2794)
			(stroke
				(width 0.1)
				(type default)
			)
			(layer "B.Fab")
		)
		(fp_line
			(start 0.12065 -0.305054)
			(end 0.12065 -0.2794)
			(stroke
				(width 0.1)
				(type default)
			)
			(layer "B.Fab")
		)
		(fp_line
			(start -0.120396 0.3048)
			(end -0.120396 0.2794)
			(stroke
				(width 0.1)
				(type default)
			)
			(layer "B.Fab")
		)
		(fp_line
			(start -0.120396 0.2794)
			(end 0.12065 0.2794)
			(stroke
				(width 0.1)
				(type default)
			)
			(layer "B.Fab")
		)
		(fp_line
			(start -0.12065 -0.2794)
			(end -0.12065 -0.3048)
			(stroke
				(width 0.1)
				(type default)
			)
			(layer "B.Fab")
		)
		(fp_line
			(start -0.12065 -0.3048)
			(end -0.67945 -0.3048)
			(stroke
				(width 0.1)
				(type default)
			)
			(layer "B.Fab")
		)
		(fp_line
			(start -0.67945 0.3048)
			(end -0.120396 0.3048)
			(stroke
				(width 0.1)
				(type default)
			)
			(layer "B.Fab")
		)
		(fp_line
			(start -0.67945 -0.3048)
			(end -0.67945 0.3048)
			(stroke
				(width 0.1)
				(type default)
			)
			(layer "B.Fab")
		)
		(pad "1" smd circle
			(at 0.40005 0)
			(size 0 0)
			(layers "B.Cu" "B.Mask" "B.Paste")
			(net "SMB_DEBUG_AUX_LVC3_USB_SDA")
		)
		(pad "2" smd circle
			(at -0.40005 0)
			(size 0 0)
			(layers "B.Cu" "B.Mask" "B.Paste")
			(net "SMB_DEBUG_AUX_LVC3_USB_R3_SDA")
		)
	)
	(footprint ""
		(layer "B.Cu")
		(at 18.259298 -89.18702 180)
		(property "Reference" "C283"
			(at 0 0 0)
			(layer "B.SilkS")
			(hide yes)
			(effects
				(font
					(size 1.27 1.27)
				)
				(justify mirror)
			)
		)
		(property "Value" ""
			(at 0 0 0)
			(layer "B.Fab")
			(effects
				(font
					(size 1.27 1.27)
				)
				(justify mirror)
			)
		)
		(duplicate_pad_numbers_are_jumpers no)
		(fp_line
			(start 0.69215 0.2921)
			(end 0.69215 -0.2921)
			(stroke
				(width 0.1524)
				(type default)
			)
			(layer "B.SilkS")
		)
		(fp_line
			(start 0.69215 -0.2921)
			(end -0.69215 -0.2921)
			(stroke
				(width 0.1524)
				(type default)
			)
			(layer "B.SilkS")
		)
		(fp_line
			(start -0.69215 0.2921)
			(end 0.69215 0.2921)
			(stroke
				(width 0.1524)
				(type default)
			)
			(layer "B.SilkS")
		)
		(fp_line
			(start -0.69215 -0.2921)
			(end -0.69215 0.2921)
			(stroke
				(width 0.1524)
				(type default)
			)
			(layer "B.SilkS")
		)
		(fp_line
			(start 0.51435 0.2794)
			(end 0.51435 -0.2794)
			(stroke
				(width 0.1)
				(type default)
			)
			(layer "B.Fab")
		)
		(fp_line
			(start 0.51435 -0.2794)
			(end -0.51435 -0.2794)
			(stroke
				(width 0.1)
				(type default)
			)
			(layer "B.Fab")
		)
		(fp_line
			(start -0.51435 0.2794)
			(end 0.51435 0.2794)
			(stroke
				(width 0.1)
				(type default)
			)
			(layer "B.Fab")
		)
		(fp_line
			(start -0.51435 -0.2794)
			(end -0.51435 0.2794)
			(stroke
				(width 0.1)
				(type default)
			)
			(layer "B.Fab")
		)
		(pad "1" smd circle
			(at 0.40005 0)
			(size 0 0)
			(layers "B.Cu" "B.Mask" "B.Paste")
			(net "VCCIO0")
		)
		(pad "2" smd circle
			(at -0.40005 0)
			(size 0 0)
			(layers "B.Cu" "B.Mask" "B.Paste")
			(net "GND")
		)
		(zone
			(layer "B.Cu")
			(hatch none 0.5)
			(connect_pads
				(clearance 0)
			)
			(min_thickness 0.25)
			(keepout
				(tracks not_allowed)
				(vias allowed)
				(pads allowed)
				(copperpour not_allowed)
				(footprints allowed)
			)
			(placement
				(enabled no)
				(sheetname "")
			)
			(fill
				(thermal_gap 0.5)
				(thermal_bridge_width 0.5)
				(island_removal_mode 0)
			)
			(polygon
				(pts
					(xy 18.068798 -89.27465) (xy 18.160238 -89.332816) (xy 18.359628 -89.332816) (xy 18.449798 -89.27465)
					(xy 18.449798 -89.09939) (xy 18.359628 -89.04097) (xy 18.160238 -89.04097) (xy 18.068798 -89.099136)
				)
			)
		)
	)
	(footprint ""
		(layer "B.Cu")
		(at 12.32662 -56.00192 180)
		(property "Reference" "R292"
			(at 0 0 0)
			(layer "B.SilkS")
			(hide yes)
			(effects
				(font
					(size 1.27 1.27)
				)
				(justify mirror)
			)
		)
		(property "Value" ""
			(at 0 0 0)
			(layer "B.Fab")
			(effects
				(font
					(size 1.27 1.27)
				)
				(justify mirror)
			)
		)
		(duplicate_pad_numbers_are_jumpers no)
		(fp_line
			(start 0.7874 0.4064)
			(end 0.7874 -0.4064)
			(stroke
				(width 0.1524)
				(type default)
			)
			(layer "B.SilkS")
		)
		(fp_line
			(start 0.7874 -0.4064)
			(end -0.7874 -0.4064)
			(stroke
				(width 0.1524)
				(type default)
			)
			(layer "B.SilkS")
		)
		(fp_line
			(start -0.7874 0.4064)
			(end 0.7874 0.4064)
			(stroke
				(width 0.1524)
				(type default)
			)
			(layer "B.SilkS")
		)
		(fp_line
			(start -0.7874 -0.4064)
			(end -0.7874 0.4064)
			(stroke
				(width 0.1524)
				(type default)
			)
			(layer "B.SilkS")
		)
		(fp_line
			(start 0.67945 0.3048)
			(end 0.67945 -0.305054)
			(stroke
				(width 0.1)
				(type default)
			)
			(layer "B.Fab")
		)
		(fp_line
			(start 0.67945 -0.305054)
			(end 0.12065 -0.305054)
			(stroke
				(width 0.1)
				(type default)
			)
			(layer "B.Fab")
		)
		(fp_line
			(start 0.12065 0.3048)
			(end 0.67945 0.3048)
			(stroke
				(width 0.1)
				(type default)
			)
			(layer "B.Fab")
		)
		(fp_line
			(start 0.12065 0.2794)
			(end 0.12065 0.3048)
			(stroke
				(width 0.1)
				(type default)
			)
			(layer "B.Fab")
		)
		(fp_line
			(start 0.12065 -0.2794)
			(end -0.12065 -0.2794)
			(stroke
				(width 0.1)
				(type default)
			)
			(layer "B.Fab")
		)
		(fp_line
			(start 0.12065 -0.305054)
			(end 0.12065 -0.2794)
			(stroke
				(width 0.1)
				(type default)
			)
			(layer "B.Fab")
		)
		(fp_line
			(start -0.120396 0.3048)
			(end -0.120396 0.2794)
			(stroke
				(width 0.1)
				(type default)
			)
			(layer "B.Fab")
		)
		(fp_line
			(start -0.120396 0.2794)
			(end 0.12065 0.2794)
			(stroke
				(width 0.1)
				(type default)
			)
			(layer "B.Fab")
		)
		(fp_line
			(start -0.12065 -0.2794)
			(end -0.12065 -0.3048)
			(stroke
				(width 0.1)
				(type default)
			)
			(layer "B.Fab")
		)
		(fp_line
			(start -0.12065 -0.3048)
			(end -0.67945 -0.3048)
			(stroke
				(width 0.1)
				(type default)
			)
			(layer "B.Fab")
		)
		(fp_line
			(start -0.67945 0.3048)
			(end -0.120396 0.3048)
			(stroke
				(width 0.1)
				(type default)
			)
			(layer "B.Fab")
		)
		(fp_line
			(start -0.67945 -0.3048)
			(end -0.67945 0.3048)
			(stroke
				(width 0.1)
				(type default)
			)
			(layer "B.Fab")
		)
		(pad "1" smd circle
			(at 0.40005 0)
			(size 0 0)
			(layers "B.Cu" "B.Mask" "B.Paste")
			(net "PWRGD_P5V_AUX_R")
		)
		(pad "2" smd circle
			(at -0.40005 0)
			(size 0 0)
			(layers "B.Cu" "B.Mask" "B.Paste")
			(net "PWRGD_P5V_AUX")
		)
	)
	(footprint ""
		(layer "B.Cu")
		(at 32.004 -101.854 90)
		(property "Reference" "R450"
			(at 0 0 90)
			(layer "B.SilkS")
			(hide yes)
			(effects
				(font
					(size 1.27 1.27)
				)
				(justify mirror)
			)
		)
		(property "Value" ""
			(at 0 0 90)
			(layer "B.Fab")
			(effects
				(font
					(size 1.27 1.27)
				)
				(justify mirror)
			)
		)
		(duplicate_pad_numbers_are_jumpers no)
		(fp_line
			(start 0.7874 -0.4064)
			(end -0.7874 -0.4064)
			(stroke
				(width 0.1524)
				(type default)
			)
			(layer "B.SilkS")
		)
		(fp_line
			(start -0.7874 -0.4064)
			(end -0.7874 0.4064)
			(stroke
				(width 0.1524)
				(type default)
			)
			(layer "B.SilkS")
		)
		(fp_line
			(start 0.7874 0.4064)
			(end 0.7874 -0.4064)
			(stroke
				(width 0.1524)
				(type default)
			)
			(layer "B.SilkS")
		)
		(fp_line
			(start -0.7874 0.4064)
			(end 0.7874 0.4064)
			(stroke
				(width 0.1524)
				(type default)
			)
			(layer "B.SilkS")
		)
		(fp_line
			(start 0.67945 -0.305054)
			(end 0.12065 -0.305054)
			(stroke
				(width 0.1)
				(type default)
			)
			(layer "B.Fab")
		)
		(fp_line
			(start 0.12065 -0.305054)
			(end 0.12065 -0.2794)
			(stroke
				(width 0.1)
				(type default)
			)
			(layer "B.Fab")
		)
		(fp_line
			(start -0.12065 -0.3048)
			(end -0.67945 -0.3048)
			(stroke
				(width 0.1)
				(type default)
			)
			(layer "B.Fab")
		)
		(fp_line
			(start -0.67945 -0.3048)
			(end -0.67945 0.3048)
			(stroke
				(width 0.1)
				(type default)
			)
			(layer "B.Fab")
		)
		(fp_line
			(start 0.12065 -0.2794)
			(end -0.12065 -0.2794)
			(stroke
				(width 0.1)
				(type default)
			)
			(layer "B.Fab")
		)
		(fp_line
			(start -0.12065 -0.2794)
			(end -0.12065 -0.3048)
			(stroke
				(width 0.1)
				(type default)
			)
			(layer "B.Fab")
		)
		(fp_line
			(start 0.12065 0.2794)
			(end 0.12065 0.3048)
			(stroke
				(width 0.1)
				(type default)
			)
			(layer "B.Fab")
		)
		(fp_line
			(start -0.120396 0.2794)
			(end 0.12065 0.2794)
			(stroke
				(width 0.1)
				(type default)
			)
			(layer "B.Fab")
		)
		(fp_line
			(start 0.67945 0.3048)
			(end 0.67945 -0.305054)
			(stroke
				(width 0.1)
				(type default)
			)
			(layer "B.Fab")
		)
		(fp_line
			(start 0.12065 0.3048)
			(end 0.67945 0.3048)
			(stroke
				(width 0.1)
				(type default)
			)
			(layer "B.Fab")
		)
		(fp_line
			(start -0.120396 0.3048)
			(end -0.120396 0.2794)
			(stroke
				(width 0.1)
				(type default)
			)
			(layer "B.Fab")
		)
		(fp_line
			(start -0.67945 0.3048)
			(end -0.120396 0.3048)
			(stroke
				(width 0.1)
				(type default)
			)
			(layer "B.Fab")
		)
		(pad "1" smd circle
			(at 0.40005 0 270)
			(size 0 0)
			(layers "B.Cu" "B.Mask" "B.Paste")
			(net "RST_BMC_SELF_HW")
		)
		(pad "2" smd circle
			(at -0.40005 0 270)
			(size 0 0)
			(layers "B.Cu" "B.Mask" "B.Paste")
			(net "RST_BMC_SELF_HW_R3")
		)
	)
	(footprint ""
		(layer "B.Cu")
		(at 75.5396 -29.5402 180)
		(property "Reference" "R697"
			(at 0 0 0)
			(layer "B.SilkS")
			(hide yes)
			(effects
				(font
					(size 1.27 1.27)
				)
				(justify mirror)
			)
		)
		(property "Value" ""
			(at 0 0 0)
			(layer "B.Fab")
			(effects
				(font
					(size 1.27 1.27)
				)
				(justify mirror)
			)
		)
		(duplicate_pad_numbers_are_jumpers no)
		(fp_line
			(start 0.7874 0.4064)
			(end 0.7874 -0.4064)
			(stroke
				(width 0.1524)
				(type default)
			)
			(layer "B.SilkS")
		)
		(fp_line
			(start 0.7874 -0.4064)
			(end -0.7874 -0.4064)
			(stroke
				(width 0.1524)
				(type default)
			)
			(layer "B.SilkS")
		)
		(fp_line
			(start -0.7874 0.4064)
			(end 0.7874 0.4064)
			(stroke
				(width 0.1524)
				(type default)
			)
			(layer "B.SilkS")
		)
		(fp_line
			(start -0.7874 -0.4064)
			(end -0.7874 0.4064)
			(stroke
				(width 0.1524)
				(type default)
			)
			(layer "B.SilkS")
		)
		(fp_line
			(start 0.67945 0.3048)
			(end 0.67945 -0.305054)
			(stroke
				(width 0.1)
				(type default)
			)
			(layer "B.Fab")
		)
		(fp_line
			(start 0.67945 -0.305054)
			(end 0.12065 -0.305054)
			(stroke
				(width 0.1)
				(type default)
			)
			(layer "B.Fab")
		)
		(fp_line
			(start 0.12065 0.3048)
			(end 0.67945 0.3048)
			(stroke
				(width 0.1)
				(type default)
			)
			(layer "B.Fab")
		)
		(fp_line
			(start 0.12065 0.2794)
			(end 0.12065 0.3048)
			(stroke
				(width 0.1)
				(type default)
			)
			(layer "B.Fab")
		)
		(fp_line
			(start 0.12065 -0.2794)
			(end -0.12065 -0.2794)
			(stroke
				(width 0.1)
				(type default)
			)
			(layer "B.Fab")
		)
		(fp_line
			(start 0.12065 -0.305054)
			(end 0.12065 -0.2794)
			(stroke
				(width 0.1)
				(type default)
			)
			(layer "B.Fab")
		)
		(fp_line
			(start -0.120396 0.3048)
			(end -0.120396 0.2794)
			(stroke
				(width 0.1)
				(type default)
			)
			(layer "B.Fab")
		)
		(fp_line
			(start -0.120396 0.2794)
			(end 0.12065 0.2794)
			(stroke
				(width 0.1)
				(type default)
			)
			(layer "B.Fab")
		)
		(fp_line
			(start -0.12065 -0.2794)
			(end -0.12065 -0.3048)
			(stroke
				(width 0.1)
				(type default)
			)
			(layer "B.Fab")
		)
		(fp_line
			(start -0.12065 -0.3048)
			(end -0.67945 -0.3048)
			(stroke
				(width 0.1)
				(type default)
			)
			(layer "B.Fab")
		)
		(fp_line
			(start -0.67945 0.3048)
			(end -0.120396 0.3048)
			(stroke
				(width 0.1)
				(type default)
			)
			(layer "B.Fab")
		)
		(fp_line
			(start -0.67945 -0.3048)
			(end -0.67945 0.3048)
			(stroke
				(width 0.1)
				(type default)
			)
			(layer "B.Fab")
		)
		(pad "1" smd circle
			(at 0.40005 0)
			(size 0 0)
			(layers "B.Cu" "B.Mask" "B.Paste")
			(net "LED_POSTCODE_2")
		)
		(pad "2" smd circle
			(at -0.40005 0)
			(size 0 0)
			(layers "B.Cu" "B.Mask" "B.Paste")
			(net "LED_POSTCODE_2_R1")
		)
	)
	(footprint ""
		(layer "B.Cu")
		(at 38.1 -106.3625 -90)
		(property "Reference" "R227"
			(at 0 0 90)
			(layer "B.SilkS")
			(hide yes)
			(effects
				(font
					(size 1.27 1.27)
				)
				(justify mirror)
			)
		)
		(property "Value" ""
			(at 0 0 90)
			(layer "B.Fab")
			(effects
				(font
					(size 1.27 1.27)
				)
				(justify mirror)
			)
		)
		(duplicate_pad_numbers_are_jumpers no)
		(fp_line
			(start -0.7874 0.4064)
			(end 0.7874 0.4064)
			(stroke
				(width 0.1524)
				(type default)
			)
			(layer "B.SilkS")
		)
		(fp_line
			(start 0.7874 0.4064)
			(end 0.7874 -0.4064)
			(stroke
				(width 0.1524)
				(type default)
			)
			(layer "B.SilkS")
		)
		(fp_line
			(start -0.7874 -0.4064)
			(end -0.7874 0.4064)
			(stroke
				(width 0.1524)
				(type default)
			)
			(layer "B.SilkS")
		)
		(fp_line
			(start 0.7874 -0.4064)
			(end -0.7874 -0.4064)
			(stroke
				(width 0.1524)
				(type default)
			)
			(layer "B.SilkS")
		)
		(fp_line
			(start -0.67945 0.3048)
			(end -0.120396 0.3048)
			(stroke
				(width 0.1)
				(type default)
			)
			(layer "B.Fab")
		)
		(fp_line
			(start -0.120396 0.3048)
			(end -0.120396 0.2794)
			(stroke
				(width 0.1)
				(type default)
			)
			(layer "B.Fab")
		)
		(fp_line
			(start 0.12065 0.3048)
			(end 0.67945 0.3048)
			(stroke
				(width 0.1)
				(type default)
			)
			(layer "B.Fab")
		)
		(fp_line
			(start 0.67945 0.3048)
			(end 0.67945 -0.305054)
			(stroke
				(width 0.1)
				(type default)
			)
			(layer "B.Fab")
		)
		(fp_line
			(start -0.120396 0.2794)
			(end 0.12065 0.2794)
			(stroke
				(width 0.1)
				(type default)
			)
			(layer "B.Fab")
		)
		(fp_line
			(start 0.12065 0.2794)
			(end 0.12065 0.3048)
			(stroke
				(width 0.1)
				(type default)
			)
			(layer "B.Fab")
		)
		(fp_line
			(start -0.12065 -0.2794)
			(end -0.12065 -0.3048)
			(stroke
				(width 0.1)
				(type default)
			)
			(layer "B.Fab")
		)
		(fp_line
			(start 0.12065 -0.2794)
			(end -0.12065 -0.2794)
			(stroke
				(width 0.1)
				(type default)
			)
			(layer "B.Fab")
		)
		(fp_line
			(start -0.67945 -0.3048)
			(end -0.67945 0.3048)
			(stroke
				(width 0.1)
				(type default)
			)
			(layer "B.Fab")
		)
		(fp_line
			(start -0.12065 -0.3048)
			(end -0.67945 -0.3048)
			(stroke
				(width 0.1)
				(type default)
			)
			(layer "B.Fab")
		)
		(fp_line
			(start 0.12065 -0.305054)
			(end 0.12065 -0.2794)
			(stroke
				(width 0.1)
				(type default)
			)
			(layer "B.Fab")
		)
		(fp_line
			(start 0.67945 -0.305054)
			(end 0.12065 -0.305054)
			(stroke
				(width 0.1)
				(type default)
			)
			(layer "B.Fab")
		)
		(pad "1" smd circle
			(at 0.40005 0 90)
			(size 0 0)
			(layers "B.Cu" "B.Mask" "B.Paste")
			(net "P3V3_AUX")
		)
		(pad "2" smd circle
			(at -0.40005 0 90)
			(size 0 0)
			(layers "B.Cu" "B.Mask" "B.Paste")
			(net "JTAG_MB_TMS")
		)
	)
	(footprint ""
		(layer "B.Cu")
		(at 32.766 -90.805 180)
		(property "Reference" "C256"
			(at 0 0 0)
			(layer "B.SilkS")
			(hide yes)
			(effects
				(font
					(size 1.27 1.27)
				)
				(justify mirror)
			)
		)
		(property "Value" ""
			(at 0 0 0)
			(layer "B.Fab")
			(effects
				(font
					(size 1.27 1.27)
				)
				(justify mirror)
			)
		)
		(duplicate_pad_numbers_are_jumpers no)
		(fp_line
			(start 0.7874 0.4064)
			(end 0.7874 -0.4064)
			(stroke
				(width 0.1524)
				(type default)
			)
			(layer "B.SilkS")
		)
		(fp_line
			(start 0.7874 -0.4064)
			(end -0.7874 -0.4064)
			(stroke
				(width 0.1524)
				(type default)
			)
			(layer "B.SilkS")
		)
		(fp_line
			(start -0.7874 0.4064)
			(end 0.7874 0.4064)
			(stroke
				(width 0.1524)
				(type default)
			)
			(layer "B.SilkS")
		)
		(fp_line
			(start -0.7874 -0.4064)
			(end -0.7874 0.4064)
			(stroke
				(width 0.1524)
				(type default)
			)
			(layer "B.SilkS")
		)
		(fp_line
			(start 0.67945 0.3048)
			(end 0.67945 -0.305054)
			(stroke
				(width 0.1)
				(type default)
			)
			(layer "B.Fab")
		)
		(fp_line
			(start 0.67945 -0.305054)
			(end 0.12065 -0.305054)
			(stroke
				(width 0.1)
				(type default)
			)
			(layer "B.Fab")
		)
		(fp_line
			(start 0.12065 0.3048)
			(end 0.67945 0.3048)
			(stroke
				(width 0.1)
				(type default)
			)
			(layer "B.Fab")
		)
		(fp_line
			(start 0.12065 0.2794)
			(end 0.12065 0.3048)
			(stroke
				(width 0.1)
				(type default)
			)
			(layer "B.Fab")
		)
		(fp_line
			(start 0.12065 -0.2794)
			(end -0.12065 -0.2794)
			(stroke
				(width 0.1)
				(type default)
			)
			(layer "B.Fab")
		)
		(fp_line
			(start 0.12065 -0.305054)
			(end 0.12065 -0.2794)
			(stroke
				(width 0.1)
				(type default)
			)
			(layer "B.Fab")
		)
		(fp_line
			(start -0.120396 0.3048)
			(end -0.120396 0.2794)
			(stroke
				(width 0.1)
				(type default)
			)
			(layer "B.Fab")
		)
		(fp_line
			(start -0.120396 0.2794)
			(end 0.12065 0.2794)
			(stroke
				(width 0.1)
				(type default)
			)
			(layer "B.Fab")
		)
		(fp_line
			(start -0.12065 -0.2794)
			(end -0.12065 -0.3048)
			(stroke
				(width 0.1)
				(type default)
			)
			(layer "B.Fab")
		)
		(fp_line
			(start -0.12065 -0.3048)
			(end -0.67945 -0.3048)
			(stroke
				(width 0.1)
				(type default)
			)
			(layer "B.Fab")
		)
		(fp_line
			(start -0.67945 0.3048)
			(end -0.120396 0.3048)
			(stroke
				(width 0.1)
				(type default)
			)
			(layer "B.Fab")
		)
		(fp_line
			(start -0.67945 -0.3048)
			(end -0.67945 0.3048)
			(stroke
				(width 0.1)
				(type default)
			)
			(layer "B.Fab")
		)
		(pad "1" smd circle
			(at 0.40005 0)
			(size 0 0)
			(layers "B.Cu" "B.Mask" "B.Paste")
			(net "PVCCIO_AUX_PLD")
		)
		(pad "2" smd circle
			(at -0.40005 0)
			(size 0 0)
			(layers "B.Cu" "B.Mask" "B.Paste")
			(net "GND")
		)
	)
	(footprint ""
		(layer "B.Cu")
		(at 19.05 -98.679 90)
		(property "Reference" "R304"
			(at 0 0 90)
			(layer "B.SilkS")
			(hide yes)
			(effects
				(font
					(size 1.27 1.27)
				)
				(justify mirror)
			)
		)
		(property "Value" ""
			(at 0 0 90)
			(layer "B.Fab")
			(effects
				(font
					(size 1.27 1.27)
				)
				(justify mirror)
			)
		)
		(duplicate_pad_numbers_are_jumpers no)
		(fp_line
			(start 0.7874 -0.4064)
			(end -0.7874 -0.4064)
			(stroke
				(width 0.1524)
				(type default)
			)
			(layer "B.SilkS")
		)
		(fp_line
			(start -0.7874 -0.4064)
			(end -0.7874 0.4064)
			(stroke
				(width 0.1524)
				(type default)
			)
			(layer "B.SilkS")
		)
		(fp_line
			(start 0.7874 0.4064)
			(end 0.7874 -0.4064)
			(stroke
				(width 0.1524)
				(type default)
			)
			(layer "B.SilkS")
		)
		(fp_line
			(start -0.7874 0.4064)
			(end 0.7874 0.4064)
			(stroke
				(width 0.1524)
				(type default)
			)
			(layer "B.SilkS")
		)
		(fp_line
			(start 0.67945 -0.305054)
			(end 0.12065 -0.305054)
			(stroke
				(width 0.1)
				(type default)
			)
			(layer "B.Fab")
		)
		(fp_line
			(start 0.12065 -0.305054)
			(end 0.12065 -0.2794)
			(stroke
				(width 0.1)
				(type default)
			)
			(layer "B.Fab")
		)
		(fp_line
			(start -0.12065 -0.3048)
			(end -0.67945 -0.3048)
			(stroke
				(width 0.1)
				(type default)
			)
			(layer "B.Fab")
		)
		(fp_line
			(start -0.67945 -0.3048)
			(end -0.67945 0.3048)
			(stroke
				(width 0.1)
				(type default)
			)
			(layer "B.Fab")
		)
		(fp_line
			(start 0.12065 -0.2794)
			(end -0.12065 -0.2794)
			(stroke
				(width 0.1)
				(type default)
			)
			(layer "B.Fab")
		)
		(fp_line
			(start -0.12065 -0.2794)
			(end -0.12065 -0.3048)
			(stroke
				(width 0.1)
				(type default)
			)
			(layer "B.Fab")
		)
		(fp_line
			(start 0.12065 0.2794)
			(end 0.12065 0.3048)
			(stroke
				(width 0.1)
				(type default)
			)
			(layer "B.Fab")
		)
		(fp_line
			(start -0.120396 0.2794)
			(end 0.12065 0.2794)
			(stroke
				(width 0.1)
				(type default)
			)
			(layer "B.Fab")
		)
		(fp_line
			(start 0.67945 0.3048)
			(end 0.67945 -0.305054)
			(stroke
				(width 0.1)
				(type default)
			)
			(layer "B.Fab")
		)
		(fp_line
			(start 0.12065 0.3048)
			(end 0.67945 0.3048)
			(stroke
				(width 0.1)
				(type default)
			)
			(layer "B.Fab")
		)
		(fp_line
			(start -0.120396 0.3048)
			(end -0.120396 0.2794)
			(stroke
				(width 0.1)
				(type default)
			)
			(layer "B.Fab")
		)
		(fp_line
			(start -0.67945 0.3048)
			(end -0.120396 0.3048)
			(stroke
				(width 0.1)
				(type default)
			)
			(layer "B.Fab")
		)
		(pad "1" smd circle
			(at 0.40005 0 270)
			(size 0 0)
			(layers "B.Cu" "B.Mask" "B.Paste")
			(net "P3V3_AUX")
		)
		(pad "2" smd circle
			(at -0.40005 0 270)
			(size 0 0)
			(layers "B.Cu" "B.Mask" "B.Paste")
			(net "VCCIO2")
		)
	)
	(footprint ""
		(layer "B.Cu")
		(at 70.832472 -47.106332 90)
		(property "Reference" "R349"
			(at 0 0 90)
			(layer "B.SilkS")
			(hide yes)
			(effects
				(font
					(size 1.27 1.27)
				)
				(justify mirror)
			)
		)
		(property "Value" ""
			(at 0 0 90)
			(layer "B.Fab")
			(effects
				(font
					(size 1.27 1.27)
				)
				(justify mirror)
			)
		)
		(duplicate_pad_numbers_are_jumpers no)
		(fp_line
			(start 0.7874 -0.4064)
			(end -0.7874 -0.4064)
			(stroke
				(width 0.1524)
				(type default)
			)
			(layer "B.SilkS")
		)
		(fp_line
			(start -0.7874 -0.4064)
			(end -0.7874 0.4064)
			(stroke
				(width 0.1524)
				(type default)
			)
			(layer "B.SilkS")
		)
		(fp_line
			(start 0.7874 0.4064)
			(end 0.7874 -0.4064)
			(stroke
				(width 0.1524)
				(type default)
			)
			(layer "B.SilkS")
		)
		(fp_line
			(start -0.7874 0.4064)
			(end 0.7874 0.4064)
			(stroke
				(width 0.1524)
				(type default)
			)
			(layer "B.SilkS")
		)
		(fp_line
			(start 0.67945 -0.305054)
			(end 0.12065 -0.305054)
			(stroke
				(width 0.1)
				(type default)
			)
			(layer "B.Fab")
		)
		(fp_line
			(start 0.12065 -0.305054)
			(end 0.12065 -0.2794)
			(stroke
				(width 0.1)
				(type default)
			)
			(layer "B.Fab")
		)
		(fp_line
			(start -0.12065 -0.3048)
			(end -0.67945 -0.3048)
			(stroke
				(width 0.1)
				(type default)
			)
			(layer "B.Fab")
		)
		(fp_line
			(start -0.67945 -0.3048)
			(end -0.67945 0.3048)
			(stroke
				(width 0.1)
				(type default)
			)
			(layer "B.Fab")
		)
		(fp_line
			(start 0.12065 -0.2794)
			(end -0.12065 -0.2794)
			(stroke
				(width 0.1)
				(type default)
			)
			(layer "B.Fab")
		)
		(fp_line
			(start -0.12065 -0.2794)
			(end -0.12065 -0.3048)
			(stroke
				(width 0.1)
				(type default)
			)
			(layer "B.Fab")
		)
		(fp_line
			(start 0.12065 0.2794)
			(end 0.12065 0.3048)
			(stroke
				(width 0.1)
				(type default)
			)
			(layer "B.Fab")
		)
		(fp_line
			(start -0.120396 0.2794)
			(end 0.12065 0.2794)
			(stroke
				(width 0.1)
				(type default)
			)
			(layer "B.Fab")
		)
		(fp_line
			(start 0.67945 0.3048)
			(end 0.67945 -0.305054)
			(stroke
				(width 0.1)
				(type default)
			)
			(layer "B.Fab")
		)
		(fp_line
			(start 0.12065 0.3048)
			(end 0.67945 0.3048)
			(stroke
				(width 0.1)
				(type default)
			)
			(layer "B.Fab")
		)
		(fp_line
			(start -0.120396 0.3048)
			(end -0.120396 0.2794)
			(stroke
				(width 0.1)
				(type default)
			)
			(layer "B.Fab")
		)
		(fp_line
			(start -0.67945 0.3048)
			(end -0.120396 0.3048)
			(stroke
				(width 0.1)
				(type default)
			)
			(layer "B.Fab")
		)
		(pad "1" smd circle
			(at 0.40005 0 270)
			(size 0 0)
			(layers "B.Cu" "B.Mask" "B.Paste")
			(net "GND")
		)
		(pad "2" smd circle
			(at -0.40005 0 270)
			(size 0 0)
			(layers "B.Cu" "B.Mask" "B.Paste")
			(net "M_BMC_DDR4_MCKE")
		)
	)
	(footprint ""
		(layer "B.Cu")
		(at 68.2752 -97.5614 180)
		(property "Reference" "R493"
			(at 0 0 0)
			(layer "B.SilkS")
			(hide yes)
			(effects
				(font
					(size 1.27 1.27)
				)
				(justify mirror)
			)
		)
		(property "Value" ""
			(at 0 0 0)
			(layer "B.Fab")
			(effects
				(font
					(size 1.27 1.27)
				)
				(justify mirror)
			)
		)
		(duplicate_pad_numbers_are_jumpers no)
		(fp_line
			(start 0.7874 0.4064)
			(end 0.7874 -0.4064)
			(stroke
				(width 0.1524)
				(type default)
			)
			(layer "B.SilkS")
		)
		(fp_line
			(start 0.7874 -0.4064)
			(end -0.7874 -0.4064)
			(stroke
				(width 0.1524)
				(type default)
			)
			(layer "B.SilkS")
		)
		(fp_line
			(start -0.7874 0.4064)
			(end 0.7874 0.4064)
			(stroke
				(width 0.1524)
				(type default)
			)
			(layer "B.SilkS")
		)
		(fp_line
			(start -0.7874 -0.4064)
			(end -0.7874 0.4064)
			(stroke
				(width 0.1524)
				(type default)
			)
			(layer "B.SilkS")
		)
		(fp_line
			(start 0.67945 0.3048)
			(end 0.67945 -0.305054)
			(stroke
				(width 0.1)
				(type default)
			)
			(layer "B.Fab")
		)
		(fp_line
			(start 0.67945 -0.305054)
			(end 0.12065 -0.305054)
			(stroke
				(width 0.1)
				(type default)
			)
			(layer "B.Fab")
		)
		(fp_line
			(start 0.12065 0.3048)
			(end 0.67945 0.3048)
			(stroke
				(width 0.1)
				(type default)
			)
			(layer "B.Fab")
		)
		(fp_line
			(start 0.12065 0.2794)
			(end 0.12065 0.3048)
			(stroke
				(width 0.1)
				(type default)
			)
			(layer "B.Fab")
		)
		(fp_line
			(start 0.12065 -0.2794)
			(end -0.12065 -0.2794)
			(stroke
				(width 0.1)
				(type default)
			)
			(layer "B.Fab")
		)
		(fp_line
			(start 0.12065 -0.305054)
			(end 0.12065 -0.2794)
			(stroke
				(width 0.1)
				(type default)
			)
			(layer "B.Fab")
		)
		(fp_line
			(start -0.120396 0.3048)
			(end -0.120396 0.2794)
			(stroke
				(width 0.1)
				(type default)
			)
			(layer "B.Fab")
		)
		(fp_line
			(start -0.120396 0.2794)
			(end 0.12065 0.2794)
			(stroke
				(width 0.1)
				(type default)
			)
			(layer "B.Fab")
		)
		(fp_line
			(start -0.12065 -0.2794)
			(end -0.12065 -0.3048)
			(stroke
				(width 0.1)
				(type default)
			)
			(layer "B.Fab")
		)
		(fp_line
			(start -0.12065 -0.3048)
			(end -0.67945 -0.3048)
			(stroke
				(width 0.1)
				(type default)
			)
			(layer "B.Fab")
		)
		(fp_line
			(start -0.67945 0.3048)
			(end -0.120396 0.3048)
			(stroke
				(width 0.1)
				(type default)
			)
			(layer "B.Fab")
		)
		(fp_line
			(start -0.67945 -0.3048)
			(end -0.67945 0.3048)
			(stroke
				(width 0.1)
				(type default)
			)
			(layer "B.Fab")
		)
		(pad "1" smd circle
			(at 0.40005 0)
			(size 0 0)
			(layers "B.Cu" "B.Mask" "B.Paste")
			(net "LPC_ESPI_SEL_N")
		)
		(pad "2" smd circle
			(at -0.40005 0)
			(size 0 0)
			(layers "B.Cu" "B.Mask" "B.Paste")
			(net "GND")
		)
	)
	(footprint ""
		(layer "B.Cu")
		(at 32.766 -89.789 180)
		(property "Reference" "C257"
			(at 0 0 0)
			(layer "B.SilkS")
			(hide yes)
			(effects
				(font
					(size 1.27 1.27)
				)
				(justify mirror)
			)
		)
		(property "Value" ""
			(at 0 0 0)
			(layer "B.Fab")
			(effects
				(font
					(size 1.27 1.27)
				)
				(justify mirror)
			)
		)
		(duplicate_pad_numbers_are_jumpers no)
		(fp_line
			(start 0.7874 0.4064)
			(end 0.7874 -0.4064)
			(stroke
				(width 0.1524)
				(type default)
			)
			(layer "B.SilkS")
		)
		(fp_line
			(start 0.7874 -0.4064)
			(end -0.7874 -0.4064)
			(stroke
				(width 0.1524)
				(type default)
			)
			(layer "B.SilkS")
		)
		(fp_line
			(start -0.7874 0.4064)
			(end 0.7874 0.4064)
			(stroke
				(width 0.1524)
				(type default)
			)
			(layer "B.SilkS")
		)
		(fp_line
			(start -0.7874 -0.4064)
			(end -0.7874 0.4064)
			(stroke
				(width 0.1524)
				(type default)
			)
			(layer "B.SilkS")
		)
		(fp_line
			(start 0.67945 0.3048)
			(end 0.67945 -0.305054)
			(stroke
				(width 0.1)
				(type default)
			)
			(layer "B.Fab")
		)
		(fp_line
			(start 0.67945 -0.305054)
			(end 0.12065 -0.305054)
			(stroke
				(width 0.1)
				(type default)
			)
			(layer "B.Fab")
		)
		(fp_line
			(start 0.12065 0.3048)
			(end 0.67945 0.3048)
			(stroke
				(width 0.1)
				(type default)
			)
			(layer "B.Fab")
		)
		(fp_line
			(start 0.12065 0.2794)
			(end 0.12065 0.3048)
			(stroke
				(width 0.1)
				(type default)
			)
			(layer "B.Fab")
		)
		(fp_line
			(start 0.12065 -0.2794)
			(end -0.12065 -0.2794)
			(stroke
				(width 0.1)
				(type default)
			)
			(layer "B.Fab")
		)
		(fp_line
			(start 0.12065 -0.305054)
			(end 0.12065 -0.2794)
			(stroke
				(width 0.1)
				(type default)
			)
			(layer "B.Fab")
		)
		(fp_line
			(start -0.120396 0.3048)
			(end -0.120396 0.2794)
			(stroke
				(width 0.1)
				(type default)
			)
			(layer "B.Fab")
		)
		(fp_line
			(start -0.120396 0.2794)
			(end 0.12065 0.2794)
			(stroke
				(width 0.1)
				(type default)
			)
			(layer "B.Fab")
		)
		(fp_line
			(start -0.12065 -0.2794)
			(end -0.12065 -0.3048)
			(stroke
				(width 0.1)
				(type default)
			)
			(layer "B.Fab")
		)
		(fp_line
			(start -0.12065 -0.3048)
			(end -0.67945 -0.3048)
			(stroke
				(width 0.1)
				(type default)
			)
			(layer "B.Fab")
		)
		(fp_line
			(start -0.67945 0.3048)
			(end -0.120396 0.3048)
			(stroke
				(width 0.1)
				(type default)
			)
			(layer "B.Fab")
		)
		(fp_line
			(start -0.67945 -0.3048)
			(end -0.67945 0.3048)
			(stroke
				(width 0.1)
				(type default)
			)
			(layer "B.Fab")
		)
		(pad "1" smd circle
			(at 0.40005 0)
			(size 0 0)
			(layers "B.Cu" "B.Mask" "B.Paste")
			(net "PVCCIO_AUX_PLD")
		)
		(pad "2" smd circle
			(at -0.40005 0)
			(size 0 0)
			(layers "B.Cu" "B.Mask" "B.Paste")
			(net "GND")
		)
	)
	(footprint ""
		(layer "B.Cu")
		(at 45.419264 -34.637726 90)
		(property "Reference" "R138"
			(at 0 0 90)
			(layer "B.SilkS")
			(hide yes)
			(effects
				(font
					(size 1.27 1.27)
				)
				(justify mirror)
			)
		)
		(property "Value" ""
			(at 0 0 90)
			(layer "B.Fab")
			(effects
				(font
					(size 1.27 1.27)
				)
				(justify mirror)
			)
		)
		(duplicate_pad_numbers_are_jumpers no)
		(fp_line
			(start 0.7874 -0.4064)
			(end -0.7874 -0.4064)
			(stroke
				(width 0.1524)
				(type default)
			)
			(layer "B.SilkS")
		)
		(fp_line
			(start -0.7874 -0.4064)
			(end -0.7874 0.4064)
			(stroke
				(width 0.1524)
				(type default)
			)
			(layer "B.SilkS")
		)
		(fp_line
			(start 0.7874 0.4064)
			(end 0.7874 -0.4064)
			(stroke
				(width 0.1524)
				(type default)
			)
			(layer "B.SilkS")
		)
		(fp_line
			(start -0.7874 0.4064)
			(end 0.7874 0.4064)
			(stroke
				(width 0.1524)
				(type default)
			)
			(layer "B.SilkS")
		)
		(fp_line
			(start 0.67945 -0.305054)
			(end 0.12065 -0.305054)
			(stroke
				(width 0.1)
				(type default)
			)
			(layer "B.Fab")
		)
		(fp_line
			(start 0.12065 -0.305054)
			(end 0.12065 -0.2794)
			(stroke
				(width 0.1)
				(type default)
			)
			(layer "B.Fab")
		)
		(fp_line
			(start -0.12065 -0.3048)
			(end -0.67945 -0.3048)
			(stroke
				(width 0.1)
				(type default)
			)
			(layer "B.Fab")
		)
		(fp_line
			(start -0.67945 -0.3048)
			(end -0.67945 0.3048)
			(stroke
				(width 0.1)
				(type default)
			)
			(layer "B.Fab")
		)
		(fp_line
			(start 0.12065 -0.2794)
			(end -0.12065 -0.2794)
			(stroke
				(width 0.1)
				(type default)
			)
			(layer "B.Fab")
		)
		(fp_line
			(start -0.12065 -0.2794)
			(end -0.12065 -0.3048)
			(stroke
				(width 0.1)
				(type default)
			)
			(layer "B.Fab")
		)
		(fp_line
			(start 0.12065 0.2794)
			(end 0.12065 0.3048)
			(stroke
				(width 0.1)
				(type default)
			)
			(layer "B.Fab")
		)
		(fp_line
			(start -0.120396 0.2794)
			(end 0.12065 0.2794)
			(stroke
				(width 0.1)
				(type default)
			)
			(layer "B.Fab")
		)
		(fp_line
			(start 0.67945 0.3048)
			(end 0.67945 -0.305054)
			(stroke
				(width 0.1)
				(type default)
			)
			(layer "B.Fab")
		)
		(fp_line
			(start 0.12065 0.3048)
			(end 0.67945 0.3048)
			(stroke
				(width 0.1)
				(type default)
			)
			(layer "B.Fab")
		)
		(fp_line
			(start -0.120396 0.3048)
			(end -0.120396 0.2794)
			(stroke
				(width 0.1)
				(type default)
			)
			(layer "B.Fab")
		)
		(fp_line
			(start -0.67945 0.3048)
			(end -0.120396 0.3048)
			(stroke
				(width 0.1)
				(type default)
			)
			(layer "B.Fab")
		)
		(pad "1" smd circle
			(at 0.40005 0 270)
			(size 0 0)
			(layers "B.Cu" "B.Mask" "B.Paste")
			(net "SMB_BMC_MM4_R_SCL")
		)
		(pad "2" smd circle
			(at -0.40005 0 270)
			(size 0 0)
			(layers "B.Cu" "B.Mask" "B.Paste")
			(net "SMB_BMC_MM4_SCL")
		)
	)
	(footprint ""
		(layer "B.Cu")
		(at 32.4612 -63.4238 180)
		(property "Reference" "R546"
			(at 0 0 0)
			(layer "B.SilkS")
			(hide yes)
			(effects
				(font
					(size 1.27 1.27)
				)
				(justify mirror)
			)
		)
		(property "Value" ""
			(at 0 0 0)
			(layer "B.Fab")
			(effects
				(font
					(size 1.27 1.27)
				)
				(justify mirror)
			)
		)
		(duplicate_pad_numbers_are_jumpers no)
		(fp_line
			(start 0.7874 0.4064)
			(end 0.7874 -0.4064)
			(stroke
				(width 0.1524)
				(type default)
			)
			(layer "B.SilkS")
		)
		(fp_line
			(start 0.7874 -0.4064)
			(end -0.7874 -0.4064)
			(stroke
				(width 0.1524)
				(type default)
			)
			(layer "B.SilkS")
		)
		(fp_line
			(start -0.7874 0.4064)
			(end 0.7874 0.4064)
			(stroke
				(width 0.1524)
				(type default)
			)
			(layer "B.SilkS")
		)
		(fp_line
			(start -0.7874 -0.4064)
			(end -0.7874 0.4064)
			(stroke
				(width 0.1524)
				(type default)
			)
			(layer "B.SilkS")
		)
		(fp_line
			(start 0.67945 0.3048)
			(end 0.67945 -0.305054)
			(stroke
				(width 0.1)
				(type default)
			)
			(layer "B.Fab")
		)
		(fp_line
			(start 0.67945 -0.305054)
			(end 0.12065 -0.305054)
			(stroke
				(width 0.1)
				(type default)
			)
			(layer "B.Fab")
		)
		(fp_line
			(start 0.12065 0.3048)
			(end 0.67945 0.3048)
			(stroke
				(width 0.1)
				(type default)
			)
			(layer "B.Fab")
		)
		(fp_line
			(start 0.12065 0.2794)
			(end 0.12065 0.3048)
			(stroke
				(width 0.1)
				(type default)
			)
			(layer "B.Fab")
		)
		(fp_line
			(start 0.12065 -0.2794)
			(end -0.12065 -0.2794)
			(stroke
				(width 0.1)
				(type default)
			)
			(layer "B.Fab")
		)
		(fp_line
			(start 0.12065 -0.305054)
			(end 0.12065 -0.2794)
			(stroke
				(width 0.1)
				(type default)
			)
			(layer "B.Fab")
		)
		(fp_line
			(start -0.120396 0.3048)
			(end -0.120396 0.2794)
			(stroke
				(width 0.1)
				(type default)
			)
			(layer "B.Fab")
		)
		(fp_line
			(start -0.120396 0.2794)
			(end 0.12065 0.2794)
			(stroke
				(width 0.1)
				(type default)
			)
			(layer "B.Fab")
		)
		(fp_line
			(start -0.12065 -0.2794)
			(end -0.12065 -0.3048)
			(stroke
				(width 0.1)
				(type default)
			)
			(layer "B.Fab")
		)
		(fp_line
			(start -0.12065 -0.3048)
			(end -0.67945 -0.3048)
			(stroke
				(width 0.1)
				(type default)
			)
			(layer "B.Fab")
		)
		(fp_line
			(start -0.67945 0.3048)
			(end -0.120396 0.3048)
			(stroke
				(width 0.1)
				(type default)
			)
			(layer "B.Fab")
		)
		(fp_line
			(start -0.67945 -0.3048)
			(end -0.67945 0.3048)
			(stroke
				(width 0.1)
				(type default)
			)
			(layer "B.Fab")
		)
		(pad "1" smd circle
			(at 0.40005 0)
			(size 0 0)
			(layers "B.Cu" "B.Mask" "B.Paste")
			(net "SPA_SOUT_SW_DBG")
		)
		(pad "2" smd circle
			(at -0.40005 0)
			(size 0 0)
			(layers "B.Cu" "B.Mask" "B.Paste")
			(net "SPA_SOUT_SW_DBG_R")
		)
	)
	(footprint ""
		(layer "B.Cu")
		(at 39.37508 -44.63288)
		(property "Reference" "R422"
			(at 0 0 0)
			(layer "B.SilkS")
			(hide yes)
			(effects
				(font
					(size 1.27 1.27)
				)
				(justify mirror)
			)
		)
		(property "Value" ""
			(at 0 0 0)
			(layer "B.Fab")
			(effects
				(font
					(size 1.27 1.27)
				)
				(justify mirror)
			)
		)
		(duplicate_pad_numbers_are_jumpers no)
		(fp_line
			(start -0.7874 -0.4064)
			(end -0.7874 0.4064)
			(stroke
				(width 0.1524)
				(type default)
			)
			(layer "B.SilkS")
		)
		(fp_line
			(start -0.7874 0.4064)
			(end 0.7874 0.4064)
			(stroke
				(width 0.1524)
				(type default)
			)
			(layer "B.SilkS")
		)
		(fp_line
			(start 0.7874 -0.4064)
			(end -0.7874 -0.4064)
			(stroke
				(width 0.1524)
				(type default)
			)
			(layer "B.SilkS")
		)
		(fp_line
			(start 0.7874 0.4064)
			(end 0.7874 -0.4064)
			(stroke
				(width 0.1524)
				(type default)
			)
			(layer "B.SilkS")
		)
		(fp_line
			(start -0.67945 -0.3048)
			(end -0.67945 0.3048)
			(stroke
				(width 0.1)
				(type default)
			)
			(layer "B.Fab")
		)
		(fp_line
			(start -0.67945 0.3048)
			(end -0.120396 0.3048)
			(stroke
				(width 0.1)
				(type default)
			)
			(layer "B.Fab")
		)
		(fp_line
			(start -0.12065 -0.3048)
			(end -0.67945 -0.3048)
			(stroke
				(width 0.1)
				(type default)
			)
			(layer "B.Fab")
		)
		(fp_line
			(start -0.12065 -0.2794)
			(end -0.12065 -0.3048)
			(stroke
				(width 0.1)
				(type default)
			)
			(layer "B.Fab")
		)
		(fp_line
			(start -0.120396 0.2794)
			(end 0.12065 0.2794)
			(stroke
				(width 0.1)
				(type default)
			)
			(layer "B.Fab")
		)
		(fp_line
			(start -0.120396 0.3048)
			(end -0.120396 0.2794)
			(stroke
				(width 0.1)
				(type default)
			)
			(layer "B.Fab")
		)
		(fp_line
			(start 0.12065 -0.305054)
			(end 0.12065 -0.2794)
			(stroke
				(width 0.1)
				(type default)
			)
			(layer "B.Fab")
		)
		(fp_line
			(start 0.12065 -0.2794)
			(end -0.12065 -0.2794)
			(stroke
				(width 0.1)
				(type default)
			)
			(layer "B.Fab")
		)
		(fp_line
			(start 0.12065 0.2794)
			(end 0.12065 0.3048)
			(stroke
				(width 0.1)
				(type default)
			)
			(layer "B.Fab")
		)
		(fp_line
			(start 0.12065 0.3048)
			(end 0.67945 0.3048)
			(stroke
				(width 0.1)
				(type default)
			)
			(layer "B.Fab")
		)
		(fp_line
			(start 0.67945 -0.305054)
			(end 0.12065 -0.305054)
			(stroke
				(width 0.1)
				(type default)
			)
			(layer "B.Fab")
		)
		(fp_line
			(start 0.67945 0.3048)
			(end 0.67945 -0.305054)
			(stroke
				(width 0.1)
				(type default)
			)
			(layer "B.Fab")
		)
		(pad "1" smd circle
			(at 0.40005 0 180)
			(size 0 0)
			(layers "B.Cu" "B.Mask" "B.Paste")
			(net "P3V3_AUX")
		)
		(pad "2" smd circle
			(at -0.40005 0 180)
			(size 0 0)
			(layers "B.Cu" "B.Mask" "B.Paste")
			(net "SMB_BMC_MM13_SCL")
		)
	)
	(footprint ""
		(layer "B.Cu")
		(at 52.555648 -37.005006 90)
		(property "Reference" "R223"
			(at 0 0 90)
			(layer "B.SilkS")
			(hide yes)
			(effects
				(font
					(size 1.27 1.27)
				)
				(justify mirror)
			)
		)
		(property "Value" ""
			(at 0 0 90)
			(layer "B.Fab")
			(effects
				(font
					(size 1.27 1.27)
				)
				(justify mirror)
			)
		)
		(duplicate_pad_numbers_are_jumpers no)
		(fp_line
			(start 0.7874 -0.4064)
			(end -0.7874 -0.4064)
			(stroke
				(width 0.1524)
				(type default)
			)
			(layer "B.SilkS")
		)
		(fp_line
			(start -0.7874 -0.4064)
			(end -0.7874 0.4064)
			(stroke
				(width 0.1524)
				(type default)
			)
			(layer "B.SilkS")
		)
		(fp_line
			(start 0.7874 0.4064)
			(end 0.7874 -0.4064)
			(stroke
				(width 0.1524)
				(type default)
			)
			(layer "B.SilkS")
		)
		(fp_line
			(start -0.7874 0.4064)
			(end 0.7874 0.4064)
			(stroke
				(width 0.1524)
				(type default)
			)
			(layer "B.SilkS")
		)
		(fp_line
			(start 0.67945 -0.305054)
			(end 0.12065 -0.305054)
			(stroke
				(width 0.1)
				(type default)
			)
			(layer "B.Fab")
		)
		(fp_line
			(start 0.12065 -0.305054)
			(end 0.12065 -0.2794)
			(stroke
				(width 0.1)
				(type default)
			)
			(layer "B.Fab")
		)
		(fp_line
			(start -0.12065 -0.3048)
			(end -0.67945 -0.3048)
			(stroke
				(width 0.1)
				(type default)
			)
			(layer "B.Fab")
		)
		(fp_line
			(start -0.67945 -0.3048)
			(end -0.67945 0.3048)
			(stroke
				(width 0.1)
				(type default)
			)
			(layer "B.Fab")
		)
		(fp_line
			(start 0.12065 -0.2794)
			(end -0.12065 -0.2794)
			(stroke
				(width 0.1)
				(type default)
			)
			(layer "B.Fab")
		)
		(fp_line
			(start -0.12065 -0.2794)
			(end -0.12065 -0.3048)
			(stroke
				(width 0.1)
				(type default)
			)
			(layer "B.Fab")
		)
		(fp_line
			(start 0.12065 0.2794)
			(end 0.12065 0.3048)
			(stroke
				(width 0.1)
				(type default)
			)
			(layer "B.Fab")
		)
		(fp_line
			(start -0.120396 0.2794)
			(end 0.12065 0.2794)
			(stroke
				(width 0.1)
				(type default)
			)
			(layer "B.Fab")
		)
		(fp_line
			(start 0.67945 0.3048)
			(end 0.67945 -0.305054)
			(stroke
				(width 0.1)
				(type default)
			)
			(layer "B.Fab")
		)
		(fp_line
			(start 0.12065 0.3048)
			(end 0.67945 0.3048)
			(stroke
				(width 0.1)
				(type default)
			)
			(layer "B.Fab")
		)
		(fp_line
			(start -0.120396 0.3048)
			(end -0.120396 0.2794)
			(stroke
				(width 0.1)
				(type default)
			)
			(layer "B.Fab")
		)
		(fp_line
			(start -0.67945 0.3048)
			(end -0.120396 0.3048)
			(stroke
				(width 0.1)
				(type default)
			)
			(layer "B.Fab")
		)
		(pad "1" smd circle
			(at 0.40005 0 270)
			(size 0 0)
			(layers "B.Cu" "B.Mask" "B.Paste")
			(net "JTAG_1_BMC_TMS_R")
		)
		(pad "2" smd circle
			(at -0.40005 0 270)
			(size 0 0)
			(layers "B.Cu" "B.Mask" "B.Paste")
			(net "JTAG_MB_TMS")
		)
	)
	(footprint ""
		(layer "B.Cu")
		(at 61.18352 -96.06788 180)
		(property "Reference" "R626"
			(at 0 0 0)
			(layer "B.SilkS")
			(hide yes)
			(effects
				(font
					(size 1.27 1.27)
				)
				(justify mirror)
			)
		)
		(property "Value" ""
			(at 0 0 0)
			(layer "B.Fab")
			(effects
				(font
					(size 1.27 1.27)
				)
				(justify mirror)
			)
		)
		(duplicate_pad_numbers_are_jumpers no)
		(fp_line
			(start 0.7874 0.4064)
			(end 0.7874 -0.4064)
			(stroke
				(width 0.1524)
				(type default)
			)
			(layer "B.SilkS")
		)
		(fp_line
			(start 0.7874 -0.4064)
			(end -0.7874 -0.4064)
			(stroke
				(width 0.1524)
				(type default)
			)
			(layer "B.SilkS")
		)
		(fp_line
			(start -0.7874 0.4064)
			(end 0.7874 0.4064)
			(stroke
				(width 0.1524)
				(type default)
			)
			(layer "B.SilkS")
		)
		(fp_line
			(start -0.7874 -0.4064)
			(end -0.7874 0.4064)
			(stroke
				(width 0.1524)
				(type default)
			)
			(layer "B.SilkS")
		)
		(fp_line
			(start 0.67945 0.3048)
			(end 0.67945 -0.305054)
			(stroke
				(width 0.1)
				(type default)
			)
			(layer "B.Fab")
		)
		(fp_line
			(start 0.67945 -0.305054)
			(end 0.12065 -0.305054)
			(stroke
				(width 0.1)
				(type default)
			)
			(layer "B.Fab")
		)
		(fp_line
			(start 0.12065 0.3048)
			(end 0.67945 0.3048)
			(stroke
				(width 0.1)
				(type default)
			)
			(layer "B.Fab")
		)
		(fp_line
			(start 0.12065 0.2794)
			(end 0.12065 0.3048)
			(stroke
				(width 0.1)
				(type default)
			)
			(layer "B.Fab")
		)
		(fp_line
			(start 0.12065 -0.2794)
			(end -0.12065 -0.2794)
			(stroke
				(width 0.1)
				(type default)
			)
			(layer "B.Fab")
		)
		(fp_line
			(start 0.12065 -0.305054)
			(end 0.12065 -0.2794)
			(stroke
				(width 0.1)
				(type default)
			)
			(layer "B.Fab")
		)
		(fp_line
			(start -0.120396 0.3048)
			(end -0.120396 0.2794)
			(stroke
				(width 0.1)
				(type default)
			)
			(layer "B.Fab")
		)
		(fp_line
			(start -0.120396 0.2794)
			(end 0.12065 0.2794)
			(stroke
				(width 0.1)
				(type default)
			)
			(layer "B.Fab")
		)
		(fp_line
			(start -0.12065 -0.2794)
			(end -0.12065 -0.3048)
			(stroke
				(width 0.1)
				(type default)
			)
			(layer "B.Fab")
		)
		(fp_line
			(start -0.12065 -0.3048)
			(end -0.67945 -0.3048)
			(stroke
				(width 0.1)
				(type default)
			)
			(layer "B.Fab")
		)
		(fp_line
			(start -0.67945 0.3048)
			(end -0.120396 0.3048)
			(stroke
				(width 0.1)
				(type default)
			)
			(layer "B.Fab")
		)
		(fp_line
			(start -0.67945 -0.3048)
			(end -0.67945 0.3048)
			(stroke
				(width 0.1)
				(type default)
			)
			(layer "B.Fab")
		)
		(pad "1" smd circle
			(at 0.40005 0)
			(size 0 0)
			(layers "B.Cu" "B.Mask" "B.Paste")
			(net "FM_SOL_UART_CH_SEL")
		)
		(pad "2" smd circle
			(at -0.40005 0)
			(size 0 0)
			(layers "B.Cu" "B.Mask" "B.Paste")
			(net "FM_SOL_UART_CH_SEL_R3")
		)
	)
	(footprint ""
		(layer "B.Cu")
		(at 65.336674 -100.265738)
		(property "Reference" "Q4"
			(at -1.963674 -1.434592 0)
			(unlocked yes)
			(layer "B.SilkS")
			(effects
				(font
					(size 0.7874 0.5842)
					(thickness 0.1524)
				)
				(justify left mirror)
			)
		)
		(property "Value" ""
			(at 0 0 0)
			(layer "B.Fab")
			(effects
				(font
					(size 1.27 1.27)
				)
				(justify mirror)
			)
		)
		(duplicate_pad_numbers_are_jumpers no)
		(fp_line
			(start -1.584198 -1.519936)
			(end -1.584198 1.519936)
			(stroke
				(width 0.1524)
				(type default)
			)
			(layer "B.SilkS")
		)
		(fp_line
			(start -1.584198 1.519936)
			(end 1.584198 1.519936)
			(stroke
				(width 0.1524)
				(type default)
			)
			(layer "B.SilkS")
		)
		(fp_line
			(start 1.584198 -1.519936)
			(end -1.584198 -1.519936)
			(stroke
				(width 0.1524)
				(type default)
			)
			(layer "B.SilkS")
		)
		(fp_line
			(start 1.584198 1.519936)
			(end 1.584198 -1.519936)
			(stroke
				(width 0.1524)
				(type default)
			)
			(layer "B.SilkS")
		)
		(fp_line
			(start -0.700024 -1.519936)
			(end -0.700024 1.519936)
			(stroke
				(width 0.1)
				(type default)
			)
			(layer "B.Fab")
		)
		(fp_line
			(start -0.700024 1.519936)
			(end 0.700024 1.519936)
			(stroke
				(width 0.1)
				(type default)
			)
			(layer "B.Fab")
		)
		(fp_line
			(start 0.700024 -1.519936)
			(end -0.700024 -1.519936)
			(stroke
				(width 0.1)
				(type default)
			)
			(layer "B.Fab")
		)
		(fp_line
			(start 0.700024 1.519936)
			(end 0.700024 -1.519936)
			(stroke
				(width 0.1)
				(type default)
			)
			(layer "B.Fab")
		)
		(pad "D" smd rect
			(at -0.999998 0 270)
			(size 0.8128 0.9144)
			(layers "B.Cu" "B.Mask" "B.Paste")
			(net "PGPPA_BMC_AUX_L")
		)
		(pad "G" smd rect
			(at 0.999998 -0.94996 270)
			(size 0.8128 0.9144)
			(layers "B.Cu" "B.Mask" "B.Paste")
			(net "LPC_ESPI_SEL_N")
		)
		(pad "S" smd rect
			(at 0.999998 0.94996 270)
			(size 0.8128 0.9144)
			(layers "B.Cu" "B.Mask" "B.Paste")
			(net "P3V3_AUX")
		)
	)
	(footprint ""
		(layer "B.Cu")
		(at 18.8722 -70.1294 -90)
		(property "Reference" "C159"
			(at 0 0 90)
			(layer "B.SilkS")
			(hide yes)
			(effects
				(font
					(size 1.27 1.27)
				)
				(justify mirror)
			)
		)
		(property "Value" ""
			(at 0 0 90)
			(layer "B.Fab")
			(effects
				(font
					(size 1.27 1.27)
				)
				(justify mirror)
			)
		)
		(duplicate_pad_numbers_are_jumpers no)
		(fp_line
			(start -0.7874 0.4064)
			(end 0.7874 0.4064)
			(stroke
				(width 0.1524)
				(type default)
			)
			(layer "B.SilkS")
		)
		(fp_line
			(start 0.7874 0.4064)
			(end 0.7874 -0.4064)
			(stroke
				(width 0.1524)
				(type default)
			)
			(layer "B.SilkS")
		)
		(fp_line
			(start -0.7874 -0.4064)
			(end -0.7874 0.4064)
			(stroke
				(width 0.1524)
				(type default)
			)
			(layer "B.SilkS")
		)
		(fp_line
			(start 0.7874 -0.4064)
			(end -0.7874 -0.4064)
			(stroke
				(width 0.1524)
				(type default)
			)
			(layer "B.SilkS")
		)
		(fp_line
			(start -0.67945 0.3048)
			(end -0.120396 0.3048)
			(stroke
				(width 0.1)
				(type default)
			)
			(layer "B.Fab")
		)
		(fp_line
			(start -0.120396 0.3048)
			(end -0.120396 0.2794)
			(stroke
				(width 0.1)
				(type default)
			)
			(layer "B.Fab")
		)
		(fp_line
			(start 0.12065 0.3048)
			(end 0.67945 0.3048)
			(stroke
				(width 0.1)
				(type default)
			)
			(layer "B.Fab")
		)
		(fp_line
			(start 0.67945 0.3048)
			(end 0.67945 -0.305054)
			(stroke
				(width 0.1)
				(type default)
			)
			(layer "B.Fab")
		)
		(fp_line
			(start -0.120396 0.2794)
			(end 0.12065 0.2794)
			(stroke
				(width 0.1)
				(type default)
			)
			(layer "B.Fab")
		)
		(fp_line
			(start 0.12065 0.2794)
			(end 0.12065 0.3048)
			(stroke
				(width 0.1)
				(type default)
			)
			(layer "B.Fab")
		)
		(fp_line
			(start -0.12065 -0.2794)
			(end -0.12065 -0.3048)
			(stroke
				(width 0.1)
				(type default)
			)
			(layer "B.Fab")
		)
		(fp_line
			(start 0.12065 -0.2794)
			(end -0.12065 -0.2794)
			(stroke
				(width 0.1)
				(type default)
			)
			(layer "B.Fab")
		)
		(fp_line
			(start -0.67945 -0.3048)
			(end -0.67945 0.3048)
			(stroke
				(width 0.1)
				(type default)
			)
			(layer "B.Fab")
		)
		(fp_line
			(start -0.12065 -0.3048)
			(end -0.67945 -0.3048)
			(stroke
				(width 0.1)
				(type default)
			)
			(layer "B.Fab")
		)
		(fp_line
			(start 0.12065 -0.305054)
			(end 0.12065 -0.2794)
			(stroke
				(width 0.1)
				(type default)
			)
			(layer "B.Fab")
		)
		(fp_line
			(start 0.67945 -0.305054)
			(end 0.12065 -0.305054)
			(stroke
				(width 0.1)
				(type default)
			)
			(layer "B.Fab")
		)
		(pad "1" smd circle
			(at 0.40005 0 90)
			(size 0 0)
			(layers "B.Cu" "B.Mask" "B.Paste")
			(net "P3V3_AUX")
		)
		(pad "2" smd circle
			(at -0.40005 0 90)
			(size 0 0)
			(layers "B.Cu" "B.Mask" "B.Paste")
			(net "GND")
		)
	)
	(footprint ""
		(layer "B.Cu")
		(at 21.971 -17.907 90)
		(property "Reference" "R569"
			(at 0 0 90)
			(layer "B.SilkS")
			(hide yes)
			(effects
				(font
					(size 1.27 1.27)
				)
				(justify mirror)
			)
		)
		(property "Value" ""
			(at 0 0 90)
			(layer "B.Fab")
			(effects
				(font
					(size 1.27 1.27)
				)
				(justify mirror)
			)
		)
		(duplicate_pad_numbers_are_jumpers no)
		(fp_line
			(start 0.7874 -0.4064)
			(end -0.7874 -0.4064)
			(stroke
				(width 0.1524)
				(type default)
			)
			(layer "B.SilkS")
		)
		(fp_line
			(start -0.7874 -0.4064)
			(end -0.7874 0.4064)
			(stroke
				(width 0.1524)
				(type default)
			)
			(layer "B.SilkS")
		)
		(fp_line
			(start 0.7874 0.4064)
			(end 0.7874 -0.4064)
			(stroke
				(width 0.1524)
				(type default)
			)
			(layer "B.SilkS")
		)
		(fp_line
			(start -0.7874 0.4064)
			(end 0.7874 0.4064)
			(stroke
				(width 0.1524)
				(type default)
			)
			(layer "B.SilkS")
		)
		(fp_line
			(start 0.67945 -0.305054)
			(end 0.12065 -0.305054)
			(stroke
				(width 0.1)
				(type default)
			)
			(layer "B.Fab")
		)
		(fp_line
			(start 0.12065 -0.305054)
			(end 0.12065 -0.2794)
			(stroke
				(width 0.1)
				(type default)
			)
			(layer "B.Fab")
		)
		(fp_line
			(start -0.12065 -0.3048)
			(end -0.67945 -0.3048)
			(stroke
				(width 0.1)
				(type default)
			)
			(layer "B.Fab")
		)
		(fp_line
			(start -0.67945 -0.3048)
			(end -0.67945 0.3048)
			(stroke
				(width 0.1)
				(type default)
			)
			(layer "B.Fab")
		)
		(fp_line
			(start 0.12065 -0.2794)
			(end -0.12065 -0.2794)
			(stroke
				(width 0.1)
				(type default)
			)
			(layer "B.Fab")
		)
		(fp_line
			(start -0.12065 -0.2794)
			(end -0.12065 -0.3048)
			(stroke
				(width 0.1)
				(type default)
			)
			(layer "B.Fab")
		)
		(fp_line
			(start 0.12065 0.2794)
			(end 0.12065 0.3048)
			(stroke
				(width 0.1)
				(type default)
			)
			(layer "B.Fab")
		)
		(fp_line
			(start -0.120396 0.2794)
			(end 0.12065 0.2794)
			(stroke
				(width 0.1)
				(type default)
			)
			(layer "B.Fab")
		)
		(fp_line
			(start 0.67945 0.3048)
			(end 0.67945 -0.305054)
			(stroke
				(width 0.1)
				(type default)
			)
			(layer "B.Fab")
		)
		(fp_line
			(start 0.12065 0.3048)
			(end 0.67945 0.3048)
			(stroke
				(width 0.1)
				(type default)
			)
			(layer "B.Fab")
		)
		(fp_line
			(start -0.120396 0.3048)
			(end -0.120396 0.2794)
			(stroke
				(width 0.1)
				(type default)
			)
			(layer "B.Fab")
		)
		(fp_line
			(start -0.67945 0.3048)
			(end -0.120396 0.3048)
			(stroke
				(width 0.1)
				(type default)
			)
			(layer "B.Fab")
		)
		(pad "1" smd circle
			(at 0.40005 0 270)
			(size 0 0)
			(layers "B.Cu" "B.Mask" "B.Paste")
			(net "HDD_LED_P5V_AUX")
		)
		(pad "2" smd circle
			(at -0.40005 0 270)
			(size 0 0)
			(layers "B.Cu" "B.Mask" "B.Paste")
			(net "P5V_AUX")
		)
	)
	(footprint ""
		(layer "B.Cu")
		(at 19.939 -101.981 -90)
		(property "Reference" "R321"
			(at 0 0 90)
			(layer "B.SilkS")
			(hide yes)
			(effects
				(font
					(size 1.27 1.27)
				)
				(justify mirror)
			)
		)
		(property "Value" ""
			(at 0 0 90)
			(layer "B.Fab")
			(effects
				(font
					(size 1.27 1.27)
				)
				(justify mirror)
			)
		)
		(duplicate_pad_numbers_are_jumpers no)
		(fp_line
			(start -0.7874 0.4064)
			(end 0.7874 0.4064)
			(stroke
				(width 0.1524)
				(type default)
			)
			(layer "B.SilkS")
		)
		(fp_line
			(start 0.7874 0.4064)
			(end 0.7874 -0.4064)
			(stroke
				(width 0.1524)
				(type default)
			)
			(layer "B.SilkS")
		)
		(fp_line
			(start -0.7874 -0.4064)
			(end -0.7874 0.4064)
			(stroke
				(width 0.1524)
				(type default)
			)
			(layer "B.SilkS")
		)
		(fp_line
			(start 0.7874 -0.4064)
			(end -0.7874 -0.4064)
			(stroke
				(width 0.1524)
				(type default)
			)
			(layer "B.SilkS")
		)
		(fp_line
			(start -0.67945 0.3048)
			(end -0.120396 0.3048)
			(stroke
				(width 0.1)
				(type default)
			)
			(layer "B.Fab")
		)
		(fp_line
			(start -0.120396 0.3048)
			(end -0.120396 0.2794)
			(stroke
				(width 0.1)
				(type default)
			)
			(layer "B.Fab")
		)
		(fp_line
			(start 0.12065 0.3048)
			(end 0.67945 0.3048)
			(stroke
				(width 0.1)
				(type default)
			)
			(layer "B.Fab")
		)
		(fp_line
			(start 0.67945 0.3048)
			(end 0.67945 -0.305054)
			(stroke
				(width 0.1)
				(type default)
			)
			(layer "B.Fab")
		)
		(fp_line
			(start -0.120396 0.2794)
			(end 0.12065 0.2794)
			(stroke
				(width 0.1)
				(type default)
			)
			(layer "B.Fab")
		)
		(fp_line
			(start 0.12065 0.2794)
			(end 0.12065 0.3048)
			(stroke
				(width 0.1)
				(type default)
			)
			(layer "B.Fab")
		)
		(fp_line
			(start -0.12065 -0.2794)
			(end -0.12065 -0.3048)
			(stroke
				(width 0.1)
				(type default)
			)
			(layer "B.Fab")
		)
		(fp_line
			(start 0.12065 -0.2794)
			(end -0.12065 -0.2794)
			(stroke
				(width 0.1)
				(type default)
			)
			(layer "B.Fab")
		)
		(fp_line
			(start -0.67945 -0.3048)
			(end -0.67945 0.3048)
			(stroke
				(width 0.1)
				(type default)
			)
			(layer "B.Fab")
		)
		(fp_line
			(start -0.12065 -0.3048)
			(end -0.67945 -0.3048)
			(stroke
				(width 0.1)
				(type default)
			)
			(layer "B.Fab")
		)
		(fp_line
			(start 0.12065 -0.305054)
			(end 0.12065 -0.2794)
			(stroke
				(width 0.1)
				(type default)
			)
			(layer "B.Fab")
		)
		(fp_line
			(start 0.67945 -0.305054)
			(end 0.12065 -0.305054)
			(stroke
				(width 0.1)
				(type default)
			)
			(layer "B.Fab")
		)
		(pad "1" smd circle
			(at 0.40005 0 90)
			(size 0 0)
			(layers "B.Cu" "B.Mask" "B.Paste")
			(net "PWRGD_P1V8_AUX_R1")
		)
		(pad "2" smd circle
			(at -0.40005 0 90)
			(size 0 0)
			(layers "B.Cu" "B.Mask" "B.Paste")
			(net "PWRGD_P1V8_AUX")
		)
	)
	(footprint ""
		(layer "B.Cu")
		(at 66.802 -12.446 180)
		(property "Reference" "R885"
			(at 0 0 0)
			(layer "B.SilkS")
			(hide yes)
			(effects
				(font
					(size 1.27 1.27)
				)
				(justify mirror)
			)
		)
		(property "Value" ""
			(at 0 0 0)
			(layer "B.Fab")
			(effects
				(font
					(size 1.27 1.27)
				)
				(justify mirror)
			)
		)
		(duplicate_pad_numbers_are_jumpers no)
		(fp_line
			(start 0.7874 0.4064)
			(end 0.7874 -0.4064)
			(stroke
				(width 0.1524)
				(type default)
			)
			(layer "B.SilkS")
		)
		(fp_line
			(start 0.7874 -0.4064)
			(end -0.7874 -0.4064)
			(stroke
				(width 0.1524)
				(type default)
			)
			(layer "B.SilkS")
		)
		(fp_line
			(start -0.7874 0.4064)
			(end 0.7874 0.4064)
			(stroke
				(width 0.1524)
				(type default)
			)
			(layer "B.SilkS")
		)
		(fp_line
			(start -0.7874 -0.4064)
			(end -0.7874 0.4064)
			(stroke
				(width 0.1524)
				(type default)
			)
			(layer "B.SilkS")
		)
		(fp_line
			(start 0.67945 0.3048)
			(end 0.67945 -0.305054)
			(stroke
				(width 0.1)
				(type default)
			)
			(layer "B.Fab")
		)
		(fp_line
			(start 0.67945 -0.305054)
			(end 0.12065 -0.305054)
			(stroke
				(width 0.1)
				(type default)
			)
			(layer "B.Fab")
		)
		(fp_line
			(start 0.12065 0.3048)
			(end 0.67945 0.3048)
			(stroke
				(width 0.1)
				(type default)
			)
			(layer "B.Fab")
		)
		(fp_line
			(start 0.12065 0.2794)
			(end 0.12065 0.3048)
			(stroke
				(width 0.1)
				(type default)
			)
			(layer "B.Fab")
		)
		(fp_line
			(start 0.12065 -0.2794)
			(end -0.12065 -0.2794)
			(stroke
				(width 0.1)
				(type default)
			)
			(layer "B.Fab")
		)
		(fp_line
			(start 0.12065 -0.305054)
			(end 0.12065 -0.2794)
			(stroke
				(width 0.1)
				(type default)
			)
			(layer "B.Fab")
		)
		(fp_line
			(start -0.120396 0.3048)
			(end -0.120396 0.2794)
			(stroke
				(width 0.1)
				(type default)
			)
			(layer "B.Fab")
		)
		(fp_line
			(start -0.120396 0.2794)
			(end 0.12065 0.2794)
			(stroke
				(width 0.1)
				(type default)
			)
			(layer "B.Fab")
		)
		(fp_line
			(start -0.12065 -0.2794)
			(end -0.12065 -0.3048)
			(stroke
				(width 0.1)
				(type default)
			)
			(layer "B.Fab")
		)
		(fp_line
			(start -0.12065 -0.3048)
			(end -0.67945 -0.3048)
			(stroke
				(width 0.1)
				(type default)
			)
			(layer "B.Fab")
		)
		(fp_line
			(start -0.67945 0.3048)
			(end -0.120396 0.3048)
			(stroke
				(width 0.1)
				(type default)
			)
			(layer "B.Fab")
		)
		(fp_line
			(start -0.67945 -0.3048)
			(end -0.67945 0.3048)
			(stroke
				(width 0.1)
				(type default)
			)
			(layer "B.Fab")
		)
		(pad "1" smd circle
			(at 0.40005 0)
			(size 0 0)
			(layers "B.Cu" "B.Mask" "B.Paste")
			(net "P1V8_AUX")
		)
		(pad "2" smd circle
			(at -0.40005 0)
			(size 0 0)
			(layers "B.Cu" "B.Mask" "B.Paste")
			(net "AC_PWR_BMC_BTN_N")
		)
	)
	(footprint ""
		(layer "B.Cu")
		(at 59.7916 -95.0214 180)
		(property "Reference" "R743"
			(at 0 0 0)
			(layer "B.SilkS")
			(hide yes)
			(effects
				(font
					(size 1.27 1.27)
				)
				(justify mirror)
			)
		)
		(property "Value" ""
			(at 0 0 0)
			(layer "B.Fab")
			(effects
				(font
					(size 1.27 1.27)
				)
				(justify mirror)
			)
		)
		(duplicate_pad_numbers_are_jumpers no)
		(fp_line
			(start 0.7874 0.4064)
			(end 0.7874 -0.4064)
			(stroke
				(width 0.1524)
				(type default)
			)
			(layer "B.SilkS")
		)
		(fp_line
			(start 0.7874 -0.4064)
			(end -0.7874 -0.4064)
			(stroke
				(width 0.1524)
				(type default)
			)
			(layer "B.SilkS")
		)
		(fp_line
			(start -0.7874 0.4064)
			(end 0.7874 0.4064)
			(stroke
				(width 0.1524)
				(type default)
			)
			(layer "B.SilkS")
		)
		(fp_line
			(start -0.7874 -0.4064)
			(end -0.7874 0.4064)
			(stroke
				(width 0.1524)
				(type default)
			)
			(layer "B.SilkS")
		)
		(fp_line
			(start 0.67945 0.3048)
			(end 0.67945 -0.305054)
			(stroke
				(width 0.1)
				(type default)
			)
			(layer "B.Fab")
		)
		(fp_line
			(start 0.67945 -0.305054)
			(end 0.12065 -0.305054)
			(stroke
				(width 0.1)
				(type default)
			)
			(layer "B.Fab")
		)
		(fp_line
			(start 0.12065 0.3048)
			(end 0.67945 0.3048)
			(stroke
				(width 0.1)
				(type default)
			)
			(layer "B.Fab")
		)
		(fp_line
			(start 0.12065 0.2794)
			(end 0.12065 0.3048)
			(stroke
				(width 0.1)
				(type default)
			)
			(layer "B.Fab")
		)
		(fp_line
			(start 0.12065 -0.2794)
			(end -0.12065 -0.2794)
			(stroke
				(width 0.1)
				(type default)
			)
			(layer "B.Fab")
		)
		(fp_line
			(start 0.12065 -0.305054)
			(end 0.12065 -0.2794)
			(stroke
				(width 0.1)
				(type default)
			)
			(layer "B.Fab")
		)
		(fp_line
			(start -0.120396 0.3048)
			(end -0.120396 0.2794)
			(stroke
				(width 0.1)
				(type default)
			)
			(layer "B.Fab")
		)
		(fp_line
			(start -0.120396 0.2794)
			(end 0.12065 0.2794)
			(stroke
				(width 0.1)
				(type default)
			)
			(layer "B.Fab")
		)
		(fp_line
			(start -0.12065 -0.2794)
			(end -0.12065 -0.3048)
			(stroke
				(width 0.1)
				(type default)
			)
			(layer "B.Fab")
		)
		(fp_line
			(start -0.12065 -0.3048)
			(end -0.67945 -0.3048)
			(stroke
				(width 0.1)
				(type default)
			)
			(layer "B.Fab")
		)
		(fp_line
			(start -0.67945 0.3048)
			(end -0.120396 0.3048)
			(stroke
				(width 0.1)
				(type default)
			)
			(layer "B.Fab")
		)
		(fp_line
			(start -0.67945 -0.3048)
			(end -0.67945 0.3048)
			(stroke
				(width 0.1)
				(type default)
			)
			(layer "B.Fab")
		)
		(pad "1" smd circle
			(at 0.40005 0)
			(size 0 0)
			(layers "B.Cu" "B.Mask" "B.Paste")
			(net "LED_POSTCODE_A0")
		)
		(pad "2" smd circle
			(at -0.40005 0)
			(size 0 0)
			(layers "B.Cu" "B.Mask" "B.Paste")
			(net "GND")
		)
	)
	(footprint ""
		(layer "B.Cu")
		(at 5.334 -81.534 -90)
		(property "Reference" "R10"
			(at 0 0 90)
			(layer "B.SilkS")
			(hide yes)
			(effects
				(font
					(size 1.27 1.27)
				)
				(justify mirror)
			)
		)
		(property "Value" ""
			(at 0 0 90)
			(layer "B.Fab")
			(effects
				(font
					(size 1.27 1.27)
				)
				(justify mirror)
			)
		)
		(duplicate_pad_numbers_are_jumpers no)
		(fp_line
			(start -0.7874 0.4064)
			(end 0.7874 0.4064)
			(stroke
				(width 0.1524)
				(type default)
			)
			(layer "B.SilkS")
		)
		(fp_line
			(start 0.7874 0.4064)
			(end 0.7874 -0.4064)
			(stroke
				(width 0.1524)
				(type default)
			)
			(layer "B.SilkS")
		)
		(fp_line
			(start -0.7874 -0.4064)
			(end -0.7874 0.4064)
			(stroke
				(width 0.1524)
				(type default)
			)
			(layer "B.SilkS")
		)
		(fp_line
			(start 0.7874 -0.4064)
			(end -0.7874 -0.4064)
			(stroke
				(width 0.1524)
				(type default)
			)
			(layer "B.SilkS")
		)
		(fp_line
			(start -0.67945 0.3048)
			(end -0.120396 0.3048)
			(stroke
				(width 0.1)
				(type default)
			)
			(layer "B.Fab")
		)
		(fp_line
			(start -0.120396 0.3048)
			(end -0.120396 0.2794)
			(stroke
				(width 0.1)
				(type default)
			)
			(layer "B.Fab")
		)
		(fp_line
			(start 0.12065 0.3048)
			(end 0.67945 0.3048)
			(stroke
				(width 0.1)
				(type default)
			)
			(layer "B.Fab")
		)
		(fp_line
			(start 0.67945 0.3048)
			(end 0.67945 -0.305054)
			(stroke
				(width 0.1)
				(type default)
			)
			(layer "B.Fab")
		)
		(fp_line
			(start -0.120396 0.2794)
			(end 0.12065 0.2794)
			(stroke
				(width 0.1)
				(type default)
			)
			(layer "B.Fab")
		)
		(fp_line
			(start 0.12065 0.2794)
			(end 0.12065 0.3048)
			(stroke
				(width 0.1)
				(type default)
			)
			(layer "B.Fab")
		)
		(fp_line
			(start -0.12065 -0.2794)
			(end -0.12065 -0.3048)
			(stroke
				(width 0.1)
				(type default)
			)
			(layer "B.Fab")
		)
		(fp_line
			(start 0.12065 -0.2794)
			(end -0.12065 -0.2794)
			(stroke
				(width 0.1)
				(type default)
			)
			(layer "B.Fab")
		)
		(fp_line
			(start -0.67945 -0.3048)
			(end -0.67945 0.3048)
			(stroke
				(width 0.1)
				(type default)
			)
			(layer "B.Fab")
		)
		(fp_line
			(start -0.12065 -0.3048)
			(end -0.67945 -0.3048)
			(stroke
				(width 0.1)
				(type default)
			)
			(layer "B.Fab")
		)
		(fp_line
			(start 0.12065 -0.305054)
			(end 0.12065 -0.2794)
			(stroke
				(width 0.1)
				(type default)
			)
			(layer "B.Fab")
		)
		(fp_line
			(start 0.67945 -0.305054)
			(end 0.12065 -0.305054)
			(stroke
				(width 0.1)
				(type default)
			)
			(layer "B.Fab")
		)
		(pad "1" smd circle
			(at 0.40005 0 90)
			(size 0 0)
			(layers "B.Cu" "B.Mask" "B.Paste")
			(net "RST_SRST_PLD_BMC_R2_N")
		)
		(pad "2" smd circle
			(at -0.40005 0 90)
			(size 0 0)
			(layers "B.Cu" "B.Mask" "B.Paste")
			(net "RST_SRST_PLD_BMC_R_N")
		)
	)
	(footprint ""
		(layer "B.Cu")
		(at 22.65934 -95.187008 90)
		(property "Reference" "C285"
			(at 0 0 90)
			(layer "B.SilkS")
			(hide yes)
			(effects
				(font
					(size 1.27 1.27)
				)
				(justify mirror)
			)
		)
		(property "Value" ""
			(at 0 0 90)
			(layer "B.Fab")
			(effects
				(font
					(size 1.27 1.27)
				)
				(justify mirror)
			)
		)
		(duplicate_pad_numbers_are_jumpers no)
		(fp_line
			(start 0.69215 -0.2921)
			(end -0.69215 -0.2921)
			(stroke
				(width 0.1524)
				(type default)
			)
			(layer "B.SilkS")
		)
		(fp_line
			(start -0.69215 -0.2921)
			(end -0.69215 0.2921)
			(stroke
				(width 0.1524)
				(type default)
			)
			(layer "B.SilkS")
		)
		(fp_line
			(start 0.69215 0.2921)
			(end 0.69215 -0.2921)
			(stroke
				(width 0.1524)
				(type default)
			)
			(layer "B.SilkS")
		)
		(fp_line
			(start -0.69215 0.2921)
			(end 0.69215 0.2921)
			(stroke
				(width 0.1524)
				(type default)
			)
			(layer "B.SilkS")
		)
		(fp_line
			(start 0.51435 -0.2794)
			(end -0.51435 -0.2794)
			(stroke
				(width 0.1)
				(type default)
			)
			(layer "B.Fab")
		)
		(fp_line
			(start -0.51435 -0.2794)
			(end -0.51435 0.2794)
			(stroke
				(width 0.1)
				(type default)
			)
			(layer "B.Fab")
		)
		(fp_line
			(start 0.51435 0.2794)
			(end 0.51435 -0.2794)
			(stroke
				(width 0.1)
				(type default)
			)
			(layer "B.Fab")
		)
		(fp_line
			(start -0.51435 0.2794)
			(end 0.51435 0.2794)
			(stroke
				(width 0.1)
				(type default)
			)
			(layer "B.Fab")
		)
		(pad "1" smd circle
			(at 0.40005 0 270)
			(size 0 0)
			(layers "B.Cu" "B.Mask" "B.Paste")
			(net "VCCIO2")
		)
		(pad "2" smd circle
			(at -0.40005 0 270)
			(size 0 0)
			(layers "B.Cu" "B.Mask" "B.Paste")
			(net "GND")
		)
		(zone
			(layer "B.Cu")
			(hatch none 0.5)
			(connect_pads
				(clearance 0)
			)
			(min_thickness 0.25)
			(keepout
				(tracks not_allowed)
				(vias allowed)
				(pads allowed)
				(copperpour not_allowed)
				(footprints allowed)
			)
			(placement
				(enabled no)
				(sheetname "")
			)
			(fill
				(thermal_gap 0.5)
				(thermal_bridge_width 0.5)
				(island_removal_mode 0)
			)
			(polygon
				(pts
					(xy 22.74697 -95.377508) (xy 22.805136 -95.286068) (xy 22.805136 -95.086678) (xy 22.74697 -94.996508)
					(xy 22.57171 -94.996508) (xy 22.51329 -95.086678) (xy 22.51329 -95.286068) (xy 22.571456 -95.377508)
				)
			)
		)
	)
	(footprint ""
		(layer "B.Cu")
		(at 12.319 -96.52)
		(property "Reference" "R432"
			(at 0 0 0)
			(layer "B.SilkS")
			(hide yes)
			(effects
				(font
					(size 1.27 1.27)
				)
				(justify mirror)
			)
		)
		(property "Value" ""
			(at 0 0 0)
			(layer "B.Fab")
			(effects
				(font
					(size 1.27 1.27)
				)
				(justify mirror)
			)
		)
		(duplicate_pad_numbers_are_jumpers no)
		(fp_line
			(start -0.7874 -0.4064)
			(end -0.7874 0.4064)
			(stroke
				(width 0.1524)
				(type default)
			)
			(layer "B.SilkS")
		)
		(fp_line
			(start -0.7874 0.4064)
			(end 0.7874 0.4064)
			(stroke
				(width 0.1524)
				(type default)
			)
			(layer "B.SilkS")
		)
		(fp_line
			(start 0.7874 -0.4064)
			(end -0.7874 -0.4064)
			(stroke
				(width 0.1524)
				(type default)
			)
			(layer "B.SilkS")
		)
		(fp_line
			(start 0.7874 0.4064)
			(end 0.7874 -0.4064)
			(stroke
				(width 0.1524)
				(type default)
			)
			(layer "B.SilkS")
		)
		(fp_line
			(start -0.67945 -0.3048)
			(end -0.67945 0.3048)
			(stroke
				(width 0.1)
				(type default)
			)
			(layer "B.Fab")
		)
		(fp_line
			(start -0.67945 0.3048)
			(end -0.120396 0.3048)
			(stroke
				(width 0.1)
				(type default)
			)
			(layer "B.Fab")
		)
		(fp_line
			(start -0.12065 -0.3048)
			(end -0.67945 -0.3048)
			(stroke
				(width 0.1)
				(type default)
			)
			(layer "B.Fab")
		)
		(fp_line
			(start -0.12065 -0.2794)
			(end -0.12065 -0.3048)
			(stroke
				(width 0.1)
				(type default)
			)
			(layer "B.Fab")
		)
		(fp_line
			(start -0.120396 0.2794)
			(end 0.12065 0.2794)
			(stroke
				(width 0.1)
				(type default)
			)
			(layer "B.Fab")
		)
		(fp_line
			(start -0.120396 0.3048)
			(end -0.120396 0.2794)
			(stroke
				(width 0.1)
				(type default)
			)
			(layer "B.Fab")
		)
		(fp_line
			(start 0.12065 -0.305054)
			(end 0.12065 -0.2794)
			(stroke
				(width 0.1)
				(type default)
			)
			(layer "B.Fab")
		)
		(fp_line
			(start 0.12065 -0.2794)
			(end -0.12065 -0.2794)
			(stroke
				(width 0.1)
				(type default)
			)
			(layer "B.Fab")
		)
		(fp_line
			(start 0.12065 0.2794)
			(end 0.12065 0.3048)
			(stroke
				(width 0.1)
				(type default)
			)
			(layer "B.Fab")
		)
		(fp_line
			(start 0.12065 0.3048)
			(end 0.67945 0.3048)
			(stroke
				(width 0.1)
				(type default)
			)
			(layer "B.Fab")
		)
		(fp_line
			(start 0.67945 -0.305054)
			(end 0.12065 -0.305054)
			(stroke
				(width 0.1)
				(type default)
			)
			(layer "B.Fab")
		)
		(fp_line
			(start 0.67945 0.3048)
			(end 0.67945 -0.305054)
			(stroke
				(width 0.1)
				(type default)
			)
			(layer "B.Fab")
		)
		(pad "1" smd circle
			(at 0.40005 0 180)
			(size 0 0)
			(layers "B.Cu" "B.Mask" "B.Paste")
			(net "FM_PWR_R_BTN")
		)
		(pad "2" smd circle
			(at -0.40005 0 180)
			(size 0 0)
			(layers "B.Cu" "B.Mask" "B.Paste")
			(net "FM_PWR_BTN")
		)
	)
	(footprint ""
		(layer "B.Cu")
		(at 83.16722 -47.602394)
		(property "Reference" "R350"
			(at 0 0 0)
			(layer "B.SilkS")
			(hide yes)
			(effects
				(font
					(size 1.27 1.27)
				)
				(justify mirror)
			)
		)
		(property "Value" ""
			(at 0 0 0)
			(layer "B.Fab")
			(effects
				(font
					(size 1.27 1.27)
				)
				(justify mirror)
			)
		)
		(duplicate_pad_numbers_are_jumpers no)
		(fp_line
			(start -0.7874 -0.4064)
			(end -0.7874 0.4064)
			(stroke
				(width 0.1524)
				(type default)
			)
			(layer "B.SilkS")
		)
		(fp_line
			(start -0.7874 0.4064)
			(end 0.7874 0.4064)
			(stroke
				(width 0.1524)
				(type default)
			)
			(layer "B.SilkS")
		)
		(fp_line
			(start 0.7874 -0.4064)
			(end -0.7874 -0.4064)
			(stroke
				(width 0.1524)
				(type default)
			)
			(layer "B.SilkS")
		)
		(fp_line
			(start 0.7874 0.4064)
			(end 0.7874 -0.4064)
			(stroke
				(width 0.1524)
				(type default)
			)
			(layer "B.SilkS")
		)
		(fp_line
			(start -0.67945 -0.3048)
			(end -0.67945 0.3048)
			(stroke
				(width 0.1)
				(type default)
			)
			(layer "B.Fab")
		)
		(fp_line
			(start -0.67945 0.3048)
			(end -0.120396 0.3048)
			(stroke
				(width 0.1)
				(type default)
			)
			(layer "B.Fab")
		)
		(fp_line
			(start -0.12065 -0.3048)
			(end -0.67945 -0.3048)
			(stroke
				(width 0.1)
				(type default)
			)
			(layer "B.Fab")
		)
		(fp_line
			(start -0.12065 -0.2794)
			(end -0.12065 -0.3048)
			(stroke
				(width 0.1)
				(type default)
			)
			(layer "B.Fab")
		)
		(fp_line
			(start -0.120396 0.2794)
			(end 0.12065 0.2794)
			(stroke
				(width 0.1)
				(type default)
			)
			(layer "B.Fab")
		)
		(fp_line
			(start -0.120396 0.3048)
			(end -0.120396 0.2794)
			(stroke
				(width 0.1)
				(type default)
			)
			(layer "B.Fab")
		)
		(fp_line
			(start 0.12065 -0.305054)
			(end 0.12065 -0.2794)
			(stroke
				(width 0.1)
				(type default)
			)
			(layer "B.Fab")
		)
		(fp_line
			(start 0.12065 -0.2794)
			(end -0.12065 -0.2794)
			(stroke
				(width 0.1)
				(type default)
			)
			(layer "B.Fab")
		)
		(fp_line
			(start 0.12065 0.2794)
			(end 0.12065 0.3048)
			(stroke
				(width 0.1)
				(type default)
			)
			(layer "B.Fab")
		)
		(fp_line
			(start 0.12065 0.3048)
			(end 0.67945 0.3048)
			(stroke
				(width 0.1)
				(type default)
			)
			(layer "B.Fab")
		)
		(fp_line
			(start 0.67945 -0.305054)
			(end 0.12065 -0.305054)
			(stroke
				(width 0.1)
				(type default)
			)
			(layer "B.Fab")
		)
		(fp_line
			(start 0.67945 0.3048)
			(end 0.67945 -0.305054)
			(stroke
				(width 0.1)
				(type default)
			)
			(layer "B.Fab")
		)
		(pad "1" smd circle
			(at 0.40005 0 180)
			(size 0 0)
			(layers "B.Cu" "B.Mask" "B.Paste")
			(net "GND")
		)
		(pad "2" smd circle
			(at -0.40005 0 180)
			(size 0 0)
			(layers "B.Cu" "B.Mask" "B.Paste")
			(net "M_BMC_DDR4_MBG1")
		)
	)
	(footprint ""
		(layer "B.Cu")
		(at 83.283552 -27.607768 180)
		(property "Reference" "R412"
			(at 0 0 0)
			(layer "B.SilkS")
			(hide yes)
			(effects
				(font
					(size 1.27 1.27)
				)
				(justify mirror)
			)
		)
		(property "Value" ""
			(at 0 0 0)
			(layer "B.Fab")
			(effects
				(font
					(size 1.27 1.27)
				)
				(justify mirror)
			)
		)
		(duplicate_pad_numbers_are_jumpers no)
		(fp_line
			(start 0.7874 0.4064)
			(end 0.7874 -0.4064)
			(stroke
				(width 0.1524)
				(type default)
			)
			(layer "B.SilkS")
		)
		(fp_line
			(start 0.7874 -0.4064)
			(end -0.7874 -0.4064)
			(stroke
				(width 0.1524)
				(type default)
			)
			(layer "B.SilkS")
		)
		(fp_line
			(start -0.7874 0.4064)
			(end 0.7874 0.4064)
			(stroke
				(width 0.1524)
				(type default)
			)
			(layer "B.SilkS")
		)
		(fp_line
			(start -0.7874 -0.4064)
			(end -0.7874 0.4064)
			(stroke
				(width 0.1524)
				(type default)
			)
			(layer "B.SilkS")
		)
		(fp_line
			(start 0.67945 0.3048)
			(end 0.67945 -0.305054)
			(stroke
				(width 0.1)
				(type default)
			)
			(layer "B.Fab")
		)
		(fp_line
			(start 0.67945 -0.305054)
			(end 0.12065 -0.305054)
			(stroke
				(width 0.1)
				(type default)
			)
			(layer "B.Fab")
		)
		(fp_line
			(start 0.12065 0.3048)
			(end 0.67945 0.3048)
			(stroke
				(width 0.1)
				(type default)
			)
			(layer "B.Fab")
		)
		(fp_line
			(start 0.12065 0.2794)
			(end 0.12065 0.3048)
			(stroke
				(width 0.1)
				(type default)
			)
			(layer "B.Fab")
		)
		(fp_line
			(start 0.12065 -0.2794)
			(end -0.12065 -0.2794)
			(stroke
				(width 0.1)
				(type default)
			)
			(layer "B.Fab")
		)
		(fp_line
			(start 0.12065 -0.305054)
			(end 0.12065 -0.2794)
			(stroke
				(width 0.1)
				(type default)
			)
			(layer "B.Fab")
		)
		(fp_line
			(start -0.120396 0.3048)
			(end -0.120396 0.2794)
			(stroke
				(width 0.1)
				(type default)
			)
			(layer "B.Fab")
		)
		(fp_line
			(start -0.120396 0.2794)
			(end 0.12065 0.2794)
			(stroke
				(width 0.1)
				(type default)
			)
			(layer "B.Fab")
		)
		(fp_line
			(start -0.12065 -0.2794)
			(end -0.12065 -0.3048)
			(stroke
				(width 0.1)
				(type default)
			)
			(layer "B.Fab")
		)
		(fp_line
			(start -0.12065 -0.3048)
			(end -0.67945 -0.3048)
			(stroke
				(width 0.1)
				(type default)
			)
			(layer "B.Fab")
		)
		(fp_line
			(start -0.67945 0.3048)
			(end -0.120396 0.3048)
			(stroke
				(width 0.1)
				(type default)
			)
			(layer "B.Fab")
		)
		(fp_line
			(start -0.67945 -0.3048)
			(end -0.67945 0.3048)
			(stroke
				(width 0.1)
				(type default)
			)
			(layer "B.Fab")
		)
		(pad "1" smd circle
			(at 0.40005 0)
			(size 0 0)
			(layers "B.Cu" "B.Mask" "B.Paste")
			(net "FRU_E1")
		)
		(pad "2" smd circle
			(at -0.40005 0)
			(size 0 0)
			(layers "B.Cu" "B.Mask" "B.Paste")
			(net "GND")
		)
	)
	(footprint ""
		(layer "B.Cu")
		(at 33.6296 -22.8346 -90)
		(property "Reference" "R28"
			(at 0 0 90)
			(layer "B.SilkS")
			(hide yes)
			(effects
				(font
					(size 1.27 1.27)
				)
				(justify mirror)
			)
		)
		(property "Value" ""
			(at 0 0 90)
			(layer "B.Fab")
			(effects
				(font
					(size 1.27 1.27)
				)
				(justify mirror)
			)
		)
		(duplicate_pad_numbers_are_jumpers no)
		(fp_line
			(start -0.7874 0.4064)
			(end 0.7874 0.4064)
			(stroke
				(width 0.1524)
				(type default)
			)
			(layer "B.SilkS")
		)
		(fp_line
			(start 0.7874 0.4064)
			(end 0.7874 -0.4064)
			(stroke
				(width 0.1524)
				(type default)
			)
			(layer "B.SilkS")
		)
		(fp_line
			(start -0.7874 -0.4064)
			(end -0.7874 0.4064)
			(stroke
				(width 0.1524)
				(type default)
			)
			(layer "B.SilkS")
		)
		(fp_line
			(start 0.7874 -0.4064)
			(end -0.7874 -0.4064)
			(stroke
				(width 0.1524)
				(type default)
			)
			(layer "B.SilkS")
		)
		(fp_line
			(start -0.67945 0.3048)
			(end -0.120396 0.3048)
			(stroke
				(width 0.1)
				(type default)
			)
			(layer "B.Fab")
		)
		(fp_line
			(start -0.120396 0.3048)
			(end -0.120396 0.2794)
			(stroke
				(width 0.1)
				(type default)
			)
			(layer "B.Fab")
		)
		(fp_line
			(start 0.12065 0.3048)
			(end 0.67945 0.3048)
			(stroke
				(width 0.1)
				(type default)
			)
			(layer "B.Fab")
		)
		(fp_line
			(start 0.67945 0.3048)
			(end 0.67945 -0.305054)
			(stroke
				(width 0.1)
				(type default)
			)
			(layer "B.Fab")
		)
		(fp_line
			(start -0.120396 0.2794)
			(end 0.12065 0.2794)
			(stroke
				(width 0.1)
				(type default)
			)
			(layer "B.Fab")
		)
		(fp_line
			(start 0.12065 0.2794)
			(end 0.12065 0.3048)
			(stroke
				(width 0.1)
				(type default)
			)
			(layer "B.Fab")
		)
		(fp_line
			(start -0.12065 -0.2794)
			(end -0.12065 -0.3048)
			(stroke
				(width 0.1)
				(type default)
			)
			(layer "B.Fab")
		)
		(fp_line
			(start 0.12065 -0.2794)
			(end -0.12065 -0.2794)
			(stroke
				(width 0.1)
				(type default)
			)
			(layer "B.Fab")
		)
		(fp_line
			(start -0.67945 -0.3048)
			(end -0.67945 0.3048)
			(stroke
				(width 0.1)
				(type default)
			)
			(layer "B.Fab")
		)
		(fp_line
			(start -0.12065 -0.3048)
			(end -0.67945 -0.3048)
			(stroke
				(width 0.1)
				(type default)
			)
			(layer "B.Fab")
		)
		(fp_line
			(start 0.12065 -0.305054)
			(end 0.12065 -0.2794)
			(stroke
				(width 0.1)
				(type default)
			)
			(layer "B.Fab")
		)
		(fp_line
			(start 0.67945 -0.305054)
			(end 0.12065 -0.305054)
			(stroke
				(width 0.1)
				(type default)
			)
			(layer "B.Fab")
		)
		(pad "1" smd circle
			(at 0.40005 0 90)
			(size 0 0)
			(layers "B.Cu" "B.Mask" "B.Paste")
			(net "V_BMC_LS_DDC_SCL")
		)
		(pad "2" smd circle
			(at -0.40005 0 90)
			(size 0 0)
			(layers "B.Cu" "B.Mask" "B.Paste")
			(net "V_BMC_LS_DDC_SCL_R")
		)
	)
	(footprint ""
		(layer "B.Cu")
		(at 48.00092 -24.11984 -90)
		(property "Reference" "R296"
			(at 0 0 90)
			(layer "B.SilkS")
			(hide yes)
			(effects
				(font
					(size 1.27 1.27)
				)
				(justify mirror)
			)
		)
		(property "Value" ""
			(at 0 0 90)
			(layer "B.Fab")
			(effects
				(font
					(size 1.27 1.27)
				)
				(justify mirror)
			)
		)
		(duplicate_pad_numbers_are_jumpers no)
		(fp_line
			(start -0.7874 0.4064)
			(end 0.7874 0.4064)
			(stroke
				(width 0.1524)
				(type default)
			)
			(layer "B.SilkS")
		)
		(fp_line
			(start 0.7874 0.4064)
			(end 0.7874 -0.4064)
			(stroke
				(width 0.1524)
				(type default)
			)
			(layer "B.SilkS")
		)
		(fp_line
			(start -0.7874 -0.4064)
			(end -0.7874 0.4064)
			(stroke
				(width 0.1524)
				(type default)
			)
			(layer "B.SilkS")
		)
		(fp_line
			(start 0.7874 -0.4064)
			(end -0.7874 -0.4064)
			(stroke
				(width 0.1524)
				(type default)
			)
			(layer "B.SilkS")
		)
		(fp_line
			(start -0.67945 0.3048)
			(end -0.120396 0.3048)
			(stroke
				(width 0.1)
				(type default)
			)
			(layer "B.Fab")
		)
		(fp_line
			(start -0.120396 0.3048)
			(end -0.120396 0.2794)
			(stroke
				(width 0.1)
				(type default)
			)
			(layer "B.Fab")
		)
		(fp_line
			(start 0.12065 0.3048)
			(end 0.67945 0.3048)
			(stroke
				(width 0.1)
				(type default)
			)
			(layer "B.Fab")
		)
		(fp_line
			(start 0.67945 0.3048)
			(end 0.67945 -0.305054)
			(stroke
				(width 0.1)
				(type default)
			)
			(layer "B.Fab")
		)
		(fp_line
			(start -0.120396 0.2794)
			(end 0.12065 0.2794)
			(stroke
				(width 0.1)
				(type default)
			)
			(layer "B.Fab")
		)
		(fp_line
			(start 0.12065 0.2794)
			(end 0.12065 0.3048)
			(stroke
				(width 0.1)
				(type default)
			)
			(layer "B.Fab")
		)
		(fp_line
			(start -0.12065 -0.2794)
			(end -0.12065 -0.3048)
			(stroke
				(width 0.1)
				(type default)
			)
			(layer "B.Fab")
		)
		(fp_line
			(start 0.12065 -0.2794)
			(end -0.12065 -0.2794)
			(stroke
				(width 0.1)
				(type default)
			)
			(layer "B.Fab")
		)
		(fp_line
			(start -0.67945 -0.3048)
			(end -0.67945 0.3048)
			(stroke
				(width 0.1)
				(type default)
			)
			(layer "B.Fab")
		)
		(fp_line
			(start -0.12065 -0.3048)
			(end -0.67945 -0.3048)
			(stroke
				(width 0.1)
				(type default)
			)
			(layer "B.Fab")
		)
		(fp_line
			(start 0.12065 -0.305054)
			(end 0.12065 -0.2794)
			(stroke
				(width 0.1)
				(type default)
			)
			(layer "B.Fab")
		)
		(fp_line
			(start 0.67945 -0.305054)
			(end 0.12065 -0.305054)
			(stroke
				(width 0.1)
				(type default)
			)
			(layer "B.Fab")
		)
		(pad "1" smd circle
			(at 0.40005 0 90)
			(size 0 0)
			(layers "B.Cu" "B.Mask" "B.Paste")
			(net "DEBUG_PORT_PRSNT_BUF_R_EN")
		)
		(pad "2" smd circle
			(at -0.40005 0 90)
			(size 0 0)
			(layers "B.Cu" "B.Mask" "B.Paste")
			(net "GND")
		)
	)
	(footprint ""
		(layer "B.Cu")
		(at 46.577758 -60.564776 180)
		(property "Reference" "C138"
			(at 0 0 0)
			(layer "B.SilkS")
			(hide yes)
			(effects
				(font
					(size 1.27 1.27)
				)
				(justify mirror)
			)
		)
		(property "Value" ""
			(at 0 0 0)
			(layer "B.Fab")
			(effects
				(font
					(size 1.27 1.27)
				)
				(justify mirror)
			)
		)
		(duplicate_pad_numbers_are_jumpers no)
		(fp_line
			(start 0.7874 0.4064)
			(end 0.7874 -0.4064)
			(stroke
				(width 0.1524)
				(type default)
			)
			(layer "B.SilkS")
		)
		(fp_line
			(start 0.7874 -0.4064)
			(end -0.7874 -0.4064)
			(stroke
				(width 0.1524)
				(type default)
			)
			(layer "B.SilkS")
		)
		(fp_line
			(start -0.7874 0.4064)
			(end 0.7874 0.4064)
			(stroke
				(width 0.1524)
				(type default)
			)
			(layer "B.SilkS")
		)
		(fp_line
			(start -0.7874 -0.4064)
			(end -0.7874 0.4064)
			(stroke
				(width 0.1524)
				(type default)
			)
			(layer "B.SilkS")
		)
		(fp_line
			(start 0.67945 0.3048)
			(end 0.67945 -0.305054)
			(stroke
				(width 0.1)
				(type default)
			)
			(layer "B.Fab")
		)
		(fp_line
			(start 0.67945 -0.305054)
			(end 0.12065 -0.305054)
			(stroke
				(width 0.1)
				(type default)
			)
			(layer "B.Fab")
		)
		(fp_line
			(start 0.12065 0.3048)
			(end 0.67945 0.3048)
			(stroke
				(width 0.1)
				(type default)
			)
			(layer "B.Fab")
		)
		(fp_line
			(start 0.12065 0.2794)
			(end 0.12065 0.3048)
			(stroke
				(width 0.1)
				(type default)
			)
			(layer "B.Fab")
		)
		(fp_line
			(start 0.12065 -0.2794)
			(end -0.12065 -0.2794)
			(stroke
				(width 0.1)
				(type default)
			)
			(layer "B.Fab")
		)
		(fp_line
			(start 0.12065 -0.305054)
			(end 0.12065 -0.2794)
			(stroke
				(width 0.1)
				(type default)
			)
			(layer "B.Fab")
		)
		(fp_line
			(start -0.120396 0.3048)
			(end -0.120396 0.2794)
			(stroke
				(width 0.1)
				(type default)
			)
			(layer "B.Fab")
		)
		(fp_line
			(start -0.120396 0.2794)
			(end 0.12065 0.2794)
			(stroke
				(width 0.1)
				(type default)
			)
			(layer "B.Fab")
		)
		(fp_line
			(start -0.12065 -0.2794)
			(end -0.12065 -0.3048)
			(stroke
				(width 0.1)
				(type default)
			)
			(layer "B.Fab")
		)
		(fp_line
			(start -0.12065 -0.3048)
			(end -0.67945 -0.3048)
			(stroke
				(width 0.1)
				(type default)
			)
			(layer "B.Fab")
		)
		(fp_line
			(start -0.67945 0.3048)
			(end -0.120396 0.3048)
			(stroke
				(width 0.1)
				(type default)
			)
			(layer "B.Fab")
		)
		(fp_line
			(start -0.67945 -0.3048)
			(end -0.67945 0.3048)
			(stroke
				(width 0.1)
				(type default)
			)
			(layer "B.Fab")
		)
		(pad "1" smd circle
			(at 0.40005 0)
			(size 0 0)
			(layers "B.Cu" "B.Mask" "B.Paste")
			(net "A_BMC_ADCVREFN0")
		)
		(pad "2" smd circle
			(at -0.40005 0)
			(size 0 0)
			(layers "B.Cu" "B.Mask" "B.Paste")
			(net "A_BMC_ADCVREFP0")
		)
	)
	(footprint ""
		(layer "B.Cu")
		(at 54.3814 -65.3288 90)
		(property "Reference" "R452"
			(at 0 0 90)
			(layer "B.SilkS")
			(hide yes)
			(effects
				(font
					(size 1.27 1.27)
				)
				(justify mirror)
			)
		)
		(property "Value" ""
			(at 0 0 90)
			(layer "B.Fab")
			(effects
				(font
					(size 1.27 1.27)
				)
				(justify mirror)
			)
		)
		(duplicate_pad_numbers_are_jumpers no)
		(fp_line
			(start 0.7874 -0.4064)
			(end -0.7874 -0.4064)
			(stroke
				(width 0.1524)
				(type default)
			)
			(layer "B.SilkS")
		)
		(fp_line
			(start -0.7874 -0.4064)
			(end -0.7874 0.4064)
			(stroke
				(width 0.1524)
				(type default)
			)
			(layer "B.SilkS")
		)
		(fp_line
			(start 0.7874 0.4064)
			(end 0.7874 -0.4064)
			(stroke
				(width 0.1524)
				(type default)
			)
			(layer "B.SilkS")
		)
		(fp_line
			(start -0.7874 0.4064)
			(end 0.7874 0.4064)
			(stroke
				(width 0.1524)
				(type default)
			)
			(layer "B.SilkS")
		)
		(fp_line
			(start 0.67945 -0.305054)
			(end 0.12065 -0.305054)
			(stroke
				(width 0.1)
				(type default)
			)
			(layer "B.Fab")
		)
		(fp_line
			(start 0.12065 -0.305054)
			(end 0.12065 -0.2794)
			(stroke
				(width 0.1)
				(type default)
			)
			(layer "B.Fab")
		)
		(fp_line
			(start -0.12065 -0.3048)
			(end -0.67945 -0.3048)
			(stroke
				(width 0.1)
				(type default)
			)
			(layer "B.Fab")
		)
		(fp_line
			(start -0.67945 -0.3048)
			(end -0.67945 0.3048)
			(stroke
				(width 0.1)
				(type default)
			)
			(layer "B.Fab")
		)
		(fp_line
			(start 0.12065 -0.2794)
			(end -0.12065 -0.2794)
			(stroke
				(width 0.1)
				(type default)
			)
			(layer "B.Fab")
		)
		(fp_line
			(start -0.12065 -0.2794)
			(end -0.12065 -0.3048)
			(stroke
				(width 0.1)
				(type default)
			)
			(layer "B.Fab")
		)
		(fp_line
			(start 0.12065 0.2794)
			(end 0.12065 0.3048)
			(stroke
				(width 0.1)
				(type default)
			)
			(layer "B.Fab")
		)
		(fp_line
			(start -0.120396 0.2794)
			(end 0.12065 0.2794)
			(stroke
				(width 0.1)
				(type default)
			)
			(layer "B.Fab")
		)
		(fp_line
			(start 0.67945 0.3048)
			(end 0.67945 -0.305054)
			(stroke
				(width 0.1)
				(type default)
			)
			(layer "B.Fab")
		)
		(fp_line
			(start 0.12065 0.3048)
			(end 0.67945 0.3048)
			(stroke
				(width 0.1)
				(type default)
			)
			(layer "B.Fab")
		)
		(fp_line
			(start -0.120396 0.3048)
			(end -0.120396 0.2794)
			(stroke
				(width 0.1)
				(type default)
			)
			(layer "B.Fab")
		)
		(fp_line
			(start -0.67945 0.3048)
			(end -0.120396 0.3048)
			(stroke
				(width 0.1)
				(type default)
			)
			(layer "B.Fab")
		)
		(pad "1" smd circle
			(at 0.40005 0 270)
			(size 0 0)
			(layers "B.Cu" "B.Mask" "B.Paste")
			(net "P3V3_AUX")
		)
		(pad "2" smd circle
			(at -0.40005 0 270)
			(size 0 0)
			(layers "B.Cu" "B.Mask" "B.Paste")
			(net "RST_WDTRST_PLD_N")
		)
	)
	(footprint ""
		(layer "B.Cu")
		(at 68.58254 -29.810964)
		(property "Reference" "R15"
			(at 0 0 0)
			(layer "B.SilkS")
			(hide yes)
			(effects
				(font
					(size 1.27 1.27)
				)
				(justify mirror)
			)
		)
		(property "Value" ""
			(at 0 0 0)
			(layer "B.Fab")
			(effects
				(font
					(size 1.27 1.27)
				)
				(justify mirror)
			)
		)
		(duplicate_pad_numbers_are_jumpers no)
		(fp_line
			(start -0.7874 -0.4064)
			(end -0.7874 0.4064)
			(stroke
				(width 0.1524)
				(type default)
			)
			(layer "B.SilkS")
		)
		(fp_line
			(start -0.7874 0.4064)
			(end 0.7874 0.4064)
			(stroke
				(width 0.1524)
				(type default)
			)
			(layer "B.SilkS")
		)
		(fp_line
			(start 0.7874 -0.4064)
			(end -0.7874 -0.4064)
			(stroke
				(width 0.1524)
				(type default)
			)
			(layer "B.SilkS")
		)
		(fp_line
			(start 0.7874 0.4064)
			(end 0.7874 -0.4064)
			(stroke
				(width 0.1524)
				(type default)
			)
			(layer "B.SilkS")
		)
		(fp_line
			(start -0.67945 -0.3048)
			(end -0.67945 0.3048)
			(stroke
				(width 0.1)
				(type default)
			)
			(layer "B.Fab")
		)
		(fp_line
			(start -0.67945 0.3048)
			(end -0.120396 0.3048)
			(stroke
				(width 0.1)
				(type default)
			)
			(layer "B.Fab")
		)
		(fp_line
			(start -0.12065 -0.3048)
			(end -0.67945 -0.3048)
			(stroke
				(width 0.1)
				(type default)
			)
			(layer "B.Fab")
		)
		(fp_line
			(start -0.12065 -0.2794)
			(end -0.12065 -0.3048)
			(stroke
				(width 0.1)
				(type default)
			)
			(layer "B.Fab")
		)
		(fp_line
			(start -0.120396 0.2794)
			(end 0.12065 0.2794)
			(stroke
				(width 0.1)
				(type default)
			)
			(layer "B.Fab")
		)
		(fp_line
			(start -0.120396 0.3048)
			(end -0.120396 0.2794)
			(stroke
				(width 0.1)
				(type default)
			)
			(layer "B.Fab")
		)
		(fp_line
			(start 0.12065 -0.305054)
			(end 0.12065 -0.2794)
			(stroke
				(width 0.1)
				(type default)
			)
			(layer "B.Fab")
		)
		(fp_line
			(start 0.12065 -0.2794)
			(end -0.12065 -0.2794)
			(stroke
				(width 0.1)
				(type default)
			)
			(layer "B.Fab")
		)
		(fp_line
			(start 0.12065 0.2794)
			(end 0.12065 0.3048)
			(stroke
				(width 0.1)
				(type default)
			)
			(layer "B.Fab")
		)
		(fp_line
			(start 0.12065 0.3048)
			(end 0.67945 0.3048)
			(stroke
				(width 0.1)
				(type default)
			)
			(layer "B.Fab")
		)
		(fp_line
			(start 0.67945 -0.305054)
			(end 0.12065 -0.305054)
			(stroke
				(width 0.1)
				(type default)
			)
			(layer "B.Fab")
		)
		(fp_line
			(start 0.67945 0.3048)
			(end 0.67945 -0.305054)
			(stroke
				(width 0.1)
				(type default)
			)
			(layer "B.Fab")
		)
		(pad "1" smd circle
			(at 0.40005 0 180)
			(size 0 0)
			(layers "B.Cu" "B.Mask" "B.Paste")
			(net "PD_FRU_WC_N")
		)
		(pad "2" smd circle
			(at -0.40005 0 180)
			(size 0 0)
			(layers "B.Cu" "B.Mask" "B.Paste")
			(net "GND")
		)
	)
	(footprint ""
		(layer "B.Cu")
		(at 43.511216 -73.955148)
		(property "Reference" "Q11"
			(at -3.328416 -0.922782 0)
			(unlocked yes)
			(layer "B.SilkS")
			(effects
				(font
					(size 0.7874 0.5842)
					(thickness 0.1524)
				)
				(justify mirror)
			)
		)
		(property "Value" ""
			(at 0 0 0)
			(layer "B.Fab")
			(effects
				(font
					(size 1.27 1.27)
				)
				(justify mirror)
			)
		)
		(duplicate_pad_numbers_are_jumpers no)
		(fp_line
			(start -1.8796 -0.746252)
			(end -1.8796 0.803148)
			(stroke
				(width 0.1524)
				(type default)
			)
			(layer "B.SilkS")
		)
		(fp_line
			(start -1.423416 1.651)
			(end 1.8796 1.651)
			(stroke
				(width 0.1524)
				(type default)
			)
			(layer "B.SilkS")
		)
		(fp_line
			(start 1.8796 -1.651)
			(end -0.915416 -1.651)
			(stroke
				(width 0.1524)
				(type default)
			)
			(layer "B.SilkS")
		)
		(fp_line
			(start 1.8796 1.651)
			(end 1.8796 -1.651)
			(stroke
				(width 0.1524)
				(type default)
			)
			(layer "B.SilkS")
		)
		(fp_line
			(start -0.700024 -1.500124)
			(end -0.700024 1.500124)
			(stroke
				(width 0.1)
				(type default)
			)
			(layer "B.Fab")
		)
		(fp_line
			(start -0.700024 1.500124)
			(end 0.700024 1.500124)
			(stroke
				(width 0.1)
				(type default)
			)
			(layer "B.Fab")
		)
		(fp_line
			(start 0.700024 -1.500124)
			(end -0.700024 -1.500124)
			(stroke
				(width 0.1)
				(type default)
			)
			(layer "B.Fab")
		)
		(fp_line
			(start 0.700024 1.500124)
			(end 0.700024 -1.500124)
			(stroke
				(width 0.1)
				(type default)
			)
			(layer "B.Fab")
		)
		(pad "D" smd rect
			(at -1.119886 0 270)
			(size 1.016 1.2192)
			(layers "B.Cu" "B.Mask" "B.Paste")
			(net "P3V_BAT_R1")
		)
		(pad "G" smd rect
			(at 1.119886 -0.999998 270)
			(size 1.016 1.2192)
			(layers "B.Cu" "B.Mask" "B.Paste")
			(net "BATTERY_DETECT_R")
		)
		(pad "S" smd rect
			(at 1.119886 0.999998 270)
			(size 1.016 1.2192)
			(layers "B.Cu" "B.Mask" "B.Paste")
			(net "P3V_BAT_SENSOR")
		)
	)
	(footprint ""
		(layer "B.Cu")
		(at 45.405294 -30.816804 -90)
		(property "Reference" "R250"
			(at 0 0 90)
			(layer "B.SilkS")
			(hide yes)
			(effects
				(font
					(size 1.27 1.27)
				)
				(justify mirror)
			)
		)
		(property "Value" ""
			(at 0 0 90)
			(layer "B.Fab")
			(effects
				(font
					(size 1.27 1.27)
				)
				(justify mirror)
			)
		)
		(duplicate_pad_numbers_are_jumpers no)
		(fp_line
			(start -0.7874 0.4064)
			(end 0.7874 0.4064)
			(stroke
				(width 0.1524)
				(type default)
			)
			(layer "B.SilkS")
		)
		(fp_line
			(start 0.7874 0.4064)
			(end 0.7874 -0.4064)
			(stroke
				(width 0.1524)
				(type default)
			)
			(layer "B.SilkS")
		)
		(fp_line
			(start -0.7874 -0.4064)
			(end -0.7874 0.4064)
			(stroke
				(width 0.1524)
				(type default)
			)
			(layer "B.SilkS")
		)
		(fp_line
			(start 0.7874 -0.4064)
			(end -0.7874 -0.4064)
			(stroke
				(width 0.1524)
				(type default)
			)
			(layer "B.SilkS")
		)
		(fp_line
			(start -0.67945 0.3048)
			(end -0.120396 0.3048)
			(stroke
				(width 0.1)
				(type default)
			)
			(layer "B.Fab")
		)
		(fp_line
			(start -0.120396 0.3048)
			(end -0.120396 0.2794)
			(stroke
				(width 0.1)
				(type default)
			)
			(layer "B.Fab")
		)
		(fp_line
			(start 0.12065 0.3048)
			(end 0.67945 0.3048)
			(stroke
				(width 0.1)
				(type default)
			)
			(layer "B.Fab")
		)
		(fp_line
			(start 0.67945 0.3048)
			(end 0.67945 -0.305054)
			(stroke
				(width 0.1)
				(type default)
			)
			(layer "B.Fab")
		)
		(fp_line
			(start -0.120396 0.2794)
			(end 0.12065 0.2794)
			(stroke
				(width 0.1)
				(type default)
			)
			(layer "B.Fab")
		)
		(fp_line
			(start 0.12065 0.2794)
			(end 0.12065 0.3048)
			(stroke
				(width 0.1)
				(type default)
			)
			(layer "B.Fab")
		)
		(fp_line
			(start -0.12065 -0.2794)
			(end -0.12065 -0.3048)
			(stroke
				(width 0.1)
				(type default)
			)
			(layer "B.Fab")
		)
		(fp_line
			(start 0.12065 -0.2794)
			(end -0.12065 -0.2794)
			(stroke
				(width 0.1)
				(type default)
			)
			(layer "B.Fab")
		)
		(fp_line
			(start -0.67945 -0.3048)
			(end -0.67945 0.3048)
			(stroke
				(width 0.1)
				(type default)
			)
			(layer "B.Fab")
		)
		(fp_line
			(start -0.12065 -0.3048)
			(end -0.67945 -0.3048)
			(stroke
				(width 0.1)
				(type default)
			)
			(layer "B.Fab")
		)
		(fp_line
			(start 0.12065 -0.305054)
			(end 0.12065 -0.2794)
			(stroke
				(width 0.1)
				(type default)
			)
			(layer "B.Fab")
		)
		(fp_line
			(start 0.67945 -0.305054)
			(end 0.12065 -0.305054)
			(stroke
				(width 0.1)
				(type default)
			)
			(layer "B.Fab")
		)
		(pad "1" smd circle
			(at 0.40005 0 90)
			(size 0 0)
			(layers "B.Cu" "B.Mask" "B.Paste")
			(net "P3V3_AUX")
		)
		(pad "2" smd circle
			(at -0.40005 0 90)
			(size 0 0)
			(layers "B.Cu" "B.Mask" "B.Paste")
			(net "SMB_BMC_MM4_SCL")
		)
	)
	(footprint ""
		(layer "B.Cu")
		(at 67.4116 -106.4387 -90)
		(property "Reference" "R36"
			(at 0 0 90)
			(layer "B.SilkS")
			(hide yes)
			(effects
				(font
					(size 1.27 1.27)
				)
				(justify mirror)
			)
		)
		(property "Value" ""
			(at 0 0 90)
			(layer "B.Fab")
			(effects
				(font
					(size 1.27 1.27)
				)
				(justify mirror)
			)
		)
		(duplicate_pad_numbers_are_jumpers no)
		(fp_line
			(start -0.7874 0.4064)
			(end 0.7874 0.4064)
			(stroke
				(width 0.1524)
				(type default)
			)
			(layer "B.SilkS")
		)
		(fp_line
			(start 0.7874 0.4064)
			(end 0.7874 -0.4064)
			(stroke
				(width 0.1524)
				(type default)
			)
			(layer "B.SilkS")
		)
		(fp_line
			(start -0.7874 -0.4064)
			(end -0.7874 0.4064)
			(stroke
				(width 0.1524)
				(type default)
			)
			(layer "B.SilkS")
		)
		(fp_line
			(start 0.7874 -0.4064)
			(end -0.7874 -0.4064)
			(stroke
				(width 0.1524)
				(type default)
			)
			(layer "B.SilkS")
		)
		(fp_line
			(start -0.67945 0.3048)
			(end -0.120396 0.3048)
			(stroke
				(width 0.1)
				(type default)
			)
			(layer "B.Fab")
		)
		(fp_line
			(start -0.120396 0.3048)
			(end -0.120396 0.2794)
			(stroke
				(width 0.1)
				(type default)
			)
			(layer "B.Fab")
		)
		(fp_line
			(start 0.12065 0.3048)
			(end 0.67945 0.3048)
			(stroke
				(width 0.1)
				(type default)
			)
			(layer "B.Fab")
		)
		(fp_line
			(start 0.67945 0.3048)
			(end 0.67945 -0.305054)
			(stroke
				(width 0.1)
				(type default)
			)
			(layer "B.Fab")
		)
		(fp_line
			(start -0.120396 0.2794)
			(end 0.12065 0.2794)
			(stroke
				(width 0.1)
				(type default)
			)
			(layer "B.Fab")
		)
		(fp_line
			(start 0.12065 0.2794)
			(end 0.12065 0.3048)
			(stroke
				(width 0.1)
				(type default)
			)
			(layer "B.Fab")
		)
		(fp_line
			(start -0.12065 -0.2794)
			(end -0.12065 -0.3048)
			(stroke
				(width 0.1)
				(type default)
			)
			(layer "B.Fab")
		)
		(fp_line
			(start 0.12065 -0.2794)
			(end -0.12065 -0.2794)
			(stroke
				(width 0.1)
				(type default)
			)
			(layer "B.Fab")
		)
		(fp_line
			(start -0.67945 -0.3048)
			(end -0.67945 0.3048)
			(stroke
				(width 0.1)
				(type default)
			)
			(layer "B.Fab")
		)
		(fp_line
			(start -0.12065 -0.3048)
			(end -0.67945 -0.3048)
			(stroke
				(width 0.1)
				(type default)
			)
			(layer "B.Fab")
		)
		(fp_line
			(start 0.12065 -0.305054)
			(end 0.12065 -0.2794)
			(stroke
				(width 0.1)
				(type default)
			)
			(layer "B.Fab")
		)
		(fp_line
			(start 0.67945 -0.305054)
			(end 0.12065 -0.305054)
			(stroke
				(width 0.1)
				(type default)
			)
			(layer "B.Fab")
		)
		(pad "1" smd circle
			(at 0.40005 0 90)
			(size 0 0)
			(layers "B.Cu" "B.Mask" "B.Paste")
			(net "SMB_BMC_MM14_SCL")
		)
		(pad "2" smd circle
			(at -0.40005 0 90)
			(size 0 0)
			(layers "B.Cu" "B.Mask" "B.Paste")
			(net "SMB_BMC_MM14_R1_SCL")
		)
	)
	(footprint ""
		(layer "B.Cu")
		(at 45.085 -92.5322 -90)
		(property "Reference" "C219"
			(at 0 0 90)
			(layer "B.SilkS")
			(hide yes)
			(effects
				(font
					(size 1.27 1.27)
				)
				(justify mirror)
			)
		)
		(property "Value" ""
			(at 0 0 90)
			(layer "B.Fab")
			(effects
				(font
					(size 1.27 1.27)
				)
				(justify mirror)
			)
		)
		(duplicate_pad_numbers_are_jumpers no)
		(fp_line
			(start -0.7874 0.4064)
			(end 0.7874 0.4064)
			(stroke
				(width 0.1524)
				(type default)
			)
			(layer "B.SilkS")
		)
		(fp_line
			(start 0.7874 0.4064)
			(end 0.7874 -0.4064)
			(stroke
				(width 0.1524)
				(type default)
			)
			(layer "B.SilkS")
		)
		(fp_line
			(start -0.7874 -0.4064)
			(end -0.7874 0.4064)
			(stroke
				(width 0.1524)
				(type default)
			)
			(layer "B.SilkS")
		)
		(fp_line
			(start 0.7874 -0.4064)
			(end -0.7874 -0.4064)
			(stroke
				(width 0.1524)
				(type default)
			)
			(layer "B.SilkS")
		)
		(fp_line
			(start -0.67945 0.3048)
			(end -0.120396 0.3048)
			(stroke
				(width 0.1)
				(type default)
			)
			(layer "B.Fab")
		)
		(fp_line
			(start -0.120396 0.3048)
			(end -0.120396 0.2794)
			(stroke
				(width 0.1)
				(type default)
			)
			(layer "B.Fab")
		)
		(fp_line
			(start 0.12065 0.3048)
			(end 0.67945 0.3048)
			(stroke
				(width 0.1)
				(type default)
			)
			(layer "B.Fab")
		)
		(fp_line
			(start 0.67945 0.3048)
			(end 0.67945 -0.305054)
			(stroke
				(width 0.1)
				(type default)
			)
			(layer "B.Fab")
		)
		(fp_line
			(start -0.120396 0.2794)
			(end 0.12065 0.2794)
			(stroke
				(width 0.1)
				(type default)
			)
			(layer "B.Fab")
		)
		(fp_line
			(start 0.12065 0.2794)
			(end 0.12065 0.3048)
			(stroke
				(width 0.1)
				(type default)
			)
			(layer "B.Fab")
		)
		(fp_line
			(start -0.12065 -0.2794)
			(end -0.12065 -0.3048)
			(stroke
				(width 0.1)
				(type default)
			)
			(layer "B.Fab")
		)
		(fp_line
			(start 0.12065 -0.2794)
			(end -0.12065 -0.2794)
			(stroke
				(width 0.1)
				(type default)
			)
			(layer "B.Fab")
		)
		(fp_line
			(start -0.67945 -0.3048)
			(end -0.67945 0.3048)
			(stroke
				(width 0.1)
				(type default)
			)
			(layer "B.Fab")
		)
		(fp_line
			(start -0.12065 -0.3048)
			(end -0.67945 -0.3048)
			(stroke
				(width 0.1)
				(type default)
			)
			(layer "B.Fab")
		)
		(fp_line
			(start 0.12065 -0.305054)
			(end 0.12065 -0.2794)
			(stroke
				(width 0.1)
				(type default)
			)
			(layer "B.Fab")
		)
		(fp_line
			(start 0.67945 -0.305054)
			(end 0.12065 -0.305054)
			(stroke
				(width 0.1)
				(type default)
			)
			(layer "B.Fab")
		)
		(pad "1" smd circle
			(at 0.40005 0 90)
			(size 0 0)
			(layers "B.Cu" "B.Mask" "B.Paste")
			(net "P3V3_AUX")
		)
		(pad "2" smd circle
			(at -0.40005 0 90)
			(size 0 0)
			(layers "B.Cu" "B.Mask" "B.Paste")
			(net "GND")
		)
	)
	(footprint ""
		(layer "B.Cu")
		(at 81.686908 -47.98568 -90)
		(property "Reference" "R367"
			(at 0 0 90)
			(layer "B.SilkS")
			(hide yes)
			(effects
				(font
					(size 1.27 1.27)
				)
				(justify mirror)
			)
		)
		(property "Value" ""
			(at 0 0 90)
			(layer "B.Fab")
			(effects
				(font
					(size 1.27 1.27)
				)
				(justify mirror)
			)
		)
		(duplicate_pad_numbers_are_jumpers no)
		(fp_line
			(start -0.7874 0.4064)
			(end 0.7874 0.4064)
			(stroke
				(width 0.1524)
				(type default)
			)
			(layer "B.SilkS")
		)
		(fp_line
			(start 0.7874 0.4064)
			(end 0.7874 -0.4064)
			(stroke
				(width 0.1524)
				(type default)
			)
			(layer "B.SilkS")
		)
		(fp_line
			(start -0.7874 -0.4064)
			(end -0.7874 0.4064)
			(stroke
				(width 0.1524)
				(type default)
			)
			(layer "B.SilkS")
		)
		(fp_line
			(start 0.7874 -0.4064)
			(end -0.7874 -0.4064)
			(stroke
				(width 0.1524)
				(type default)
			)
			(layer "B.SilkS")
		)
		(fp_line
			(start -0.67945 0.3048)
			(end -0.120396 0.3048)
			(stroke
				(width 0.1)
				(type default)
			)
			(layer "B.Fab")
		)
		(fp_line
			(start -0.120396 0.3048)
			(end -0.120396 0.2794)
			(stroke
				(width 0.1)
				(type default)
			)
			(layer "B.Fab")
		)
		(fp_line
			(start 0.12065 0.3048)
			(end 0.67945 0.3048)
			(stroke
				(width 0.1)
				(type default)
			)
			(layer "B.Fab")
		)
		(fp_line
			(start 0.67945 0.3048)
			(end 0.67945 -0.305054)
			(stroke
				(width 0.1)
				(type default)
			)
			(layer "B.Fab")
		)
		(fp_line
			(start -0.120396 0.2794)
			(end 0.12065 0.2794)
			(stroke
				(width 0.1)
				(type default)
			)
			(layer "B.Fab")
		)
		(fp_line
			(start 0.12065 0.2794)
			(end 0.12065 0.3048)
			(stroke
				(width 0.1)
				(type default)
			)
			(layer "B.Fab")
		)
		(fp_line
			(start -0.12065 -0.2794)
			(end -0.12065 -0.3048)
			(stroke
				(width 0.1)
				(type default)
			)
			(layer "B.Fab")
		)
		(fp_line
			(start 0.12065 -0.2794)
			(end -0.12065 -0.2794)
			(stroke
				(width 0.1)
				(type default)
			)
			(layer "B.Fab")
		)
		(fp_line
			(start -0.67945 -0.3048)
			(end -0.67945 0.3048)
			(stroke
				(width 0.1)
				(type default)
			)
			(layer "B.Fab")
		)
		(fp_line
			(start -0.12065 -0.3048)
			(end -0.67945 -0.3048)
			(stroke
				(width 0.1)
				(type default)
			)
			(layer "B.Fab")
		)
		(fp_line
			(start 0.12065 -0.305054)
			(end 0.12065 -0.2794)
			(stroke
				(width 0.1)
				(type default)
			)
			(layer "B.Fab")
		)
		(fp_line
			(start 0.67945 -0.305054)
			(end 0.12065 -0.305054)
			(stroke
				(width 0.1)
				(type default)
			)
			(layer "B.Fab")
		)
		(pad "1" smd circle
			(at 0.40005 0 90)
			(size 0 0)
			(layers "B.Cu" "B.Mask" "B.Paste")
			(net "M_BMC_DDR4_MRAS_N")
		)
		(pad "2" smd circle
			(at -0.40005 0 90)
			(size 0 0)
			(layers "B.Cu" "B.Mask" "B.Paste")
			(net "P1V2_AUX")
		)
	)
	(footprint ""
		(layer "B.Cu")
		(at 14.859 -93.3958 180)
		(property "Reference" "R263"
			(at 0 0 0)
			(layer "B.SilkS")
			(hide yes)
			(effects
				(font
					(size 1.27 1.27)
				)
				(justify mirror)
			)
		)
		(property "Value" ""
			(at 0 0 0)
			(layer "B.Fab")
			(effects
				(font
					(size 1.27 1.27)
				)
				(justify mirror)
			)
		)
		(duplicate_pad_numbers_are_jumpers no)
		(fp_line
			(start 0.7874 0.4064)
			(end 0.7874 -0.4064)
			(stroke
				(width 0.1524)
				(type default)
			)
			(layer "B.SilkS")
		)
		(fp_line
			(start 0.7874 -0.4064)
			(end -0.7874 -0.4064)
			(stroke
				(width 0.1524)
				(type default)
			)
			(layer "B.SilkS")
		)
		(fp_line
			(start -0.7874 0.4064)
			(end 0.7874 0.4064)
			(stroke
				(width 0.1524)
				(type default)
			)
			(layer "B.SilkS")
		)
		(fp_line
			(start -0.7874 -0.4064)
			(end -0.7874 0.4064)
			(stroke
				(width 0.1524)
				(type default)
			)
			(layer "B.SilkS")
		)
		(fp_line
			(start 0.67945 0.3048)
			(end 0.67945 -0.305054)
			(stroke
				(width 0.1)
				(type default)
			)
			(layer "B.Fab")
		)
		(fp_line
			(start 0.67945 -0.305054)
			(end 0.12065 -0.305054)
			(stroke
				(width 0.1)
				(type default)
			)
			(layer "B.Fab")
		)
		(fp_line
			(start 0.12065 0.3048)
			(end 0.67945 0.3048)
			(stroke
				(width 0.1)
				(type default)
			)
			(layer "B.Fab")
		)
		(fp_line
			(start 0.12065 0.2794)
			(end 0.12065 0.3048)
			(stroke
				(width 0.1)
				(type default)
			)
			(layer "B.Fab")
		)
		(fp_line
			(start 0.12065 -0.2794)
			(end -0.12065 -0.2794)
			(stroke
				(width 0.1)
				(type default)
			)
			(layer "B.Fab")
		)
		(fp_line
			(start 0.12065 -0.305054)
			(end 0.12065 -0.2794)
			(stroke
				(width 0.1)
				(type default)
			)
			(layer "B.Fab")
		)
		(fp_line
			(start -0.120396 0.3048)
			(end -0.120396 0.2794)
			(stroke
				(width 0.1)
				(type default)
			)
			(layer "B.Fab")
		)
		(fp_line
			(start -0.120396 0.2794)
			(end 0.12065 0.2794)
			(stroke
				(width 0.1)
				(type default)
			)
			(layer "B.Fab")
		)
		(fp_line
			(start -0.12065 -0.2794)
			(end -0.12065 -0.3048)
			(stroke
				(width 0.1)
				(type default)
			)
			(layer "B.Fab")
		)
		(fp_line
			(start -0.12065 -0.3048)
			(end -0.67945 -0.3048)
			(stroke
				(width 0.1)
				(type default)
			)
			(layer "B.Fab")
		)
		(fp_line
			(start -0.67945 0.3048)
			(end -0.120396 0.3048)
			(stroke
				(width 0.1)
				(type default)
			)
			(layer "B.Fab")
		)
		(fp_line
			(start -0.67945 -0.3048)
			(end -0.67945 0.3048)
			(stroke
				(width 0.1)
				(type default)
			)
			(layer "B.Fab")
		)
		(pad "1" smd circle
			(at 0.40005 0)
			(size 0 0)
			(layers "B.Cu" "B.Mask" "B.Paste")
			(net "RST_MB_STBY_N")
		)
		(pad "2" smd circle
			(at -0.40005 0)
			(size 0 0)
			(layers "B.Cu" "B.Mask" "B.Paste")
			(net "RST_MB_STBY_R_N")
		)
	)
	(footprint ""
		(layer "B.Cu")
		(at 36.77412 -97.22104 180)
		(property "Reference" "R731"
			(at 0 0 0)
			(layer "B.SilkS")
			(hide yes)
			(effects
				(font
					(size 1.27 1.27)
				)
				(justify mirror)
			)
		)
		(property "Value" ""
			(at 0 0 0)
			(layer "B.Fab")
			(effects
				(font
					(size 1.27 1.27)
				)
				(justify mirror)
			)
		)
		(duplicate_pad_numbers_are_jumpers no)
		(fp_line
			(start 0.7874 0.4064)
			(end 0.7874 -0.4064)
			(stroke
				(width 0.1524)
				(type default)
			)
			(layer "B.SilkS")
		)
		(fp_line
			(start 0.7874 -0.4064)
			(end -0.7874 -0.4064)
			(stroke
				(width 0.1524)
				(type default)
			)
			(layer "B.SilkS")
		)
		(fp_line
			(start -0.7874 0.4064)
			(end 0.7874 0.4064)
			(stroke
				(width 0.1524)
				(type default)
			)
			(layer "B.SilkS")
		)
		(fp_line
			(start -0.7874 -0.4064)
			(end -0.7874 0.4064)
			(stroke
				(width 0.1524)
				(type default)
			)
			(layer "B.SilkS")
		)
		(fp_line
			(start 0.67945 0.3048)
			(end 0.67945 -0.305054)
			(stroke
				(width 0.1)
				(type default)
			)
			(layer "B.Fab")
		)
		(fp_line
			(start 0.67945 -0.305054)
			(end 0.12065 -0.305054)
			(stroke
				(width 0.1)
				(type default)
			)
			(layer "B.Fab")
		)
		(fp_line
			(start 0.12065 0.3048)
			(end 0.67945 0.3048)
			(stroke
				(width 0.1)
				(type default)
			)
			(layer "B.Fab")
		)
		(fp_line
			(start 0.12065 0.2794)
			(end 0.12065 0.3048)
			(stroke
				(width 0.1)
				(type default)
			)
			(layer "B.Fab")
		)
		(fp_line
			(start 0.12065 -0.2794)
			(end -0.12065 -0.2794)
			(stroke
				(width 0.1)
				(type default)
			)
			(layer "B.Fab")
		)
		(fp_line
			(start 0.12065 -0.305054)
			(end 0.12065 -0.2794)
			(stroke
				(width 0.1)
				(type default)
			)
			(layer "B.Fab")
		)
		(fp_line
			(start -0.120396 0.3048)
			(end -0.120396 0.2794)
			(stroke
				(width 0.1)
				(type default)
			)
			(layer "B.Fab")
		)
		(fp_line
			(start -0.120396 0.2794)
			(end 0.12065 0.2794)
			(stroke
				(width 0.1)
				(type default)
			)
			(layer "B.Fab")
		)
		(fp_line
			(start -0.12065 -0.2794)
			(end -0.12065 -0.3048)
			(stroke
				(width 0.1)
				(type default)
			)
			(layer "B.Fab")
		)
		(fp_line
			(start -0.12065 -0.3048)
			(end -0.67945 -0.3048)
			(stroke
				(width 0.1)
				(type default)
			)
			(layer "B.Fab")
		)
		(fp_line
			(start -0.67945 0.3048)
			(end -0.120396 0.3048)
			(stroke
				(width 0.1)
				(type default)
			)
			(layer "B.Fab")
		)
		(fp_line
			(start -0.67945 -0.3048)
			(end -0.67945 0.3048)
			(stroke
				(width 0.1)
				(type default)
			)
			(layer "B.Fab")
		)
		(pad "1" smd circle
			(at 0.40005 0)
			(size 0 0)
			(layers "B.Cu" "B.Mask" "B.Paste")
			(net "SMB_DEBUG_AUX_LVC3_USB_SDA")
		)
		(pad "2" smd circle
			(at -0.40005 0)
			(size 0 0)
			(layers "B.Cu" "B.Mask" "B.Paste")
			(net "SMB_DEBUG_AUX_LVC3_USB_R2_SDA")
		)
	)
	(footprint ""
		(layer "B.Cu")
		(at 42.909236 -71.589392)
		(property "Reference" "R777"
			(at 0 0 0)
			(layer "B.SilkS")
			(hide yes)
			(effects
				(font
					(size 1.27 1.27)
				)
				(justify mirror)
			)
		)
		(property "Value" ""
			(at 0 0 0)
			(layer "B.Fab")
			(effects
				(font
					(size 1.27 1.27)
				)
				(justify mirror)
			)
		)
		(duplicate_pad_numbers_are_jumpers no)
		(fp_line
			(start -0.7874 -0.4064)
			(end -0.7874 0.4064)
			(stroke
				(width 0.1524)
				(type default)
			)
			(layer "B.SilkS")
		)
		(fp_line
			(start -0.7874 0.4064)
			(end 0.7874 0.4064)
			(stroke
				(width 0.1524)
				(type default)
			)
			(layer "B.SilkS")
		)
		(fp_line
			(start 0.7874 -0.4064)
			(end -0.7874 -0.4064)
			(stroke
				(width 0.1524)
				(type default)
			)
			(layer "B.SilkS")
		)
		(fp_line
			(start 0.7874 0.4064)
			(end 0.7874 -0.4064)
			(stroke
				(width 0.1524)
				(type default)
			)
			(layer "B.SilkS")
		)
		(fp_line
			(start -0.67945 -0.3048)
			(end -0.67945 0.3048)
			(stroke
				(width 0.1)
				(type default)
			)
			(layer "B.Fab")
		)
		(fp_line
			(start -0.67945 0.3048)
			(end -0.120396 0.3048)
			(stroke
				(width 0.1)
				(type default)
			)
			(layer "B.Fab")
		)
		(fp_line
			(start -0.12065 -0.3048)
			(end -0.67945 -0.3048)
			(stroke
				(width 0.1)
				(type default)
			)
			(layer "B.Fab")
		)
		(fp_line
			(start -0.12065 -0.2794)
			(end -0.12065 -0.3048)
			(stroke
				(width 0.1)
				(type default)
			)
			(layer "B.Fab")
		)
		(fp_line
			(start -0.120396 0.2794)
			(end 0.12065 0.2794)
			(stroke
				(width 0.1)
				(type default)
			)
			(layer "B.Fab")
		)
		(fp_line
			(start -0.120396 0.3048)
			(end -0.120396 0.2794)
			(stroke
				(width 0.1)
				(type default)
			)
			(layer "B.Fab")
		)
		(fp_line
			(start 0.12065 -0.305054)
			(end 0.12065 -0.2794)
			(stroke
				(width 0.1)
				(type default)
			)
			(layer "B.Fab")
		)
		(fp_line
			(start 0.12065 -0.2794)
			(end -0.12065 -0.2794)
			(stroke
				(width 0.1)
				(type default)
			)
			(layer "B.Fab")
		)
		(fp_line
			(start 0.12065 0.2794)
			(end 0.12065 0.3048)
			(stroke
				(width 0.1)
				(type default)
			)
			(layer "B.Fab")
		)
		(fp_line
			(start 0.12065 0.3048)
			(end 0.67945 0.3048)
			(stroke
				(width 0.1)
				(type default)
			)
			(layer "B.Fab")
		)
		(fp_line
			(start 0.67945 -0.305054)
			(end 0.12065 -0.305054)
			(stroke
				(width 0.1)
				(type default)
			)
			(layer "B.Fab")
		)
		(fp_line
			(start 0.67945 0.3048)
			(end 0.67945 -0.305054)
			(stroke
				(width 0.1)
				(type default)
			)
			(layer "B.Fab")
		)
		(pad "1" smd circle
			(at 0.40005 0 180)
			(size 0 0)
			(layers "B.Cu" "B.Mask" "B.Paste")
			(net "P3V_BAT_R")
		)
		(pad "2" smd circle
			(at -0.40005 0 180)
			(size 0 0)
			(layers "B.Cu" "B.Mask" "B.Paste")
			(net "P3V_BAT_R1")
		)
	)
	(footprint ""
		(layer "B.Cu")
		(at 69.776848 -39.284402 180)
		(property "Reference" "L3"
			(at 0 0 0)
			(layer "B.SilkS")
			(hide yes)
			(effects
				(font
					(size 1.27 1.27)
				)
				(justify mirror)
			)
		)
		(property "Value" ""
			(at 0 0 0)
			(layer "B.Fab")
			(effects
				(font
					(size 1.27 1.27)
				)
				(justify mirror)
			)
		)
		(duplicate_pad_numbers_are_jumpers no)
		(fp_line
			(start 1.27 0.5842)
			(end 1.27 -0.5842)
			(stroke
				(width 0.1524)
				(type default)
			)
			(layer "B.SilkS")
		)
		(fp_line
			(start 1.27 -0.5588)
			(end 1.27 -0.5842)
			(stroke
				(width 0.1524)
				(type default)
			)
			(layer "B.SilkS")
		)
		(fp_line
			(start 1.27 -0.5842)
			(end -1.27 -0.5842)
			(stroke
				(width 0.1524)
				(type default)
			)
			(layer "B.SilkS")
		)
		(fp_line
			(start 0.127 0.5842)
			(end 0.127 -0.5842)
			(stroke
				(width 0.1524)
				(type default)
			)
			(layer "B.SilkS")
		)
		(fp_line
			(start -0.127 0.5842)
			(end -0.127 -0.5842)
			(stroke
				(width 0.1524)
				(type default)
			)
			(layer "B.SilkS")
		)
		(fp_line
			(start -1.27 0.5842)
			(end 1.27 0.5842)
			(stroke
				(width 0.1524)
				(type default)
			)
			(layer "B.SilkS")
		)
		(fp_line
			(start -1.27 0.5842)
			(end -1.27 -0.5842)
			(stroke
				(width 0.1524)
				(type default)
			)
			(layer "B.SilkS")
		)
		(fp_line
			(start 1.194308 0.406654)
			(end 1.194308 -0.406654)
			(stroke
				(width 0.1)
				(type default)
			)
			(layer "B.Fab")
		)
		(fp_line
			(start 1.194308 -0.406654)
			(end 0.9144 -0.406654)
			(stroke
				(width 0.1)
				(type default)
			)
			(layer "B.Fab")
		)
		(fp_line
			(start 0.9144 0.508)
			(end 0.9144 0.406654)
			(stroke
				(width 0.1)
				(type default)
			)
			(layer "B.Fab")
		)
		(fp_line
			(start 0.9144 0.406654)
			(end 1.194308 0.406654)
			(stroke
				(width 0.1)
				(type default)
			)
			(layer "B.Fab")
		)
		(fp_line
			(start 0.9144 -0.406654)
			(end 0.9144 -0.508)
			(stroke
				(width 0.1)
				(type default)
			)
			(layer "B.Fab")
		)
		(fp_line
			(start 0.9144 -0.508)
			(end -0.9144 -0.508)
			(stroke
				(width 0.1)
				(type default)
			)
			(layer "B.Fab")
		)
		(fp_line
			(start -0.9144 0.508)
			(end 0.9144 0.508)
			(stroke
				(width 0.1)
				(type default)
			)
			(layer "B.Fab")
		)
		(fp_line
			(start -0.9144 0.4064)
			(end -0.9144 0.508)
			(stroke
				(width 0.1)
				(type default)
			)
			(layer "B.Fab")
		)
		(fp_line
			(start -0.9144 -0.406654)
			(end -1.1938 -0.406654)
			(stroke
				(width 0.1)
				(type default)
			)
			(layer "B.Fab")
		)
		(fp_line
			(start -0.9144 -0.508)
			(end -0.9144 -0.406654)
			(stroke
				(width 0.1)
				(type default)
			)
			(layer "B.Fab")
		)
		(fp_line
			(start -1.1938 0.4064)
			(end -0.9144 0.4064)
			(stroke
				(width 0.1)
				(type default)
			)
			(layer "B.Fab")
		)
		(fp_line
			(start -1.1938 -0.406654)
			(end -1.1938 0.4064)
			(stroke
				(width 0.1)
				(type default)
			)
			(layer "B.Fab")
		)
		(pad "1" smd rect
			(at 0.7366 0 90)
			(size 0.7112 0.8128)
			(layers "B.Cu" "B.Mask" "B.Paste")
			(net "P1V8_AUX")
		)
		(pad "2" smd rect
			(at -0.7366 0 90)
			(size 0.7112 0.8128)
			(layers "B.Cu" "B.Mask" "B.Paste")
			(net "P1V8_BMC_USB2AV18")
		)
	)
	(footprint ""
		(layer "B.Cu")
		(at 46.111414 -53.754274 -90)
		(property "Reference" "C83"
			(at 0 0 90)
			(layer "B.SilkS")
			(hide yes)
			(effects
				(font
					(size 1.27 1.27)
				)
				(justify mirror)
			)
		)
		(property "Value" ""
			(at 0 0 90)
			(layer "B.Fab")
			(effects
				(font
					(size 1.27 1.27)
				)
				(justify mirror)
			)
		)
		(duplicate_pad_numbers_are_jumpers no)
		(fp_line
			(start -0.7874 0.4064)
			(end 0.7874 0.4064)
			(stroke
				(width 0.1524)
				(type default)
			)
			(layer "B.SilkS")
		)
		(fp_line
			(start 0.7874 0.4064)
			(end 0.7874 -0.4064)
			(stroke
				(width 0.1524)
				(type default)
			)
			(layer "B.SilkS")
		)
		(fp_line
			(start -0.7874 -0.4064)
			(end -0.7874 0.4064)
			(stroke
				(width 0.1524)
				(type default)
			)
			(layer "B.SilkS")
		)
		(fp_line
			(start 0.7874 -0.4064)
			(end -0.7874 -0.4064)
			(stroke
				(width 0.1524)
				(type default)
			)
			(layer "B.SilkS")
		)
		(fp_line
			(start -0.67945 0.3048)
			(end -0.120396 0.3048)
			(stroke
				(width 0.1)
				(type default)
			)
			(layer "B.Fab")
		)
		(fp_line
			(start -0.120396 0.3048)
			(end -0.120396 0.2794)
			(stroke
				(width 0.1)
				(type default)
			)
			(layer "B.Fab")
		)
		(fp_line
			(start 0.12065 0.3048)
			(end 0.67945 0.3048)
			(stroke
				(width 0.1)
				(type default)
			)
			(layer "B.Fab")
		)
		(fp_line
			(start 0.67945 0.3048)
			(end 0.67945 -0.305054)
			(stroke
				(width 0.1)
				(type default)
			)
			(layer "B.Fab")
		)
		(fp_line
			(start -0.120396 0.2794)
			(end 0.12065 0.2794)
			(stroke
				(width 0.1)
				(type default)
			)
			(layer "B.Fab")
		)
		(fp_line
			(start 0.12065 0.2794)
			(end 0.12065 0.3048)
			(stroke
				(width 0.1)
				(type default)
			)
			(layer "B.Fab")
		)
		(fp_line
			(start -0.12065 -0.2794)
			(end -0.12065 -0.3048)
			(stroke
				(width 0.1)
				(type default)
			)
			(layer "B.Fab")
		)
		(fp_line
			(start 0.12065 -0.2794)
			(end -0.12065 -0.2794)
			(stroke
				(width 0.1)
				(type default)
			)
			(layer "B.Fab")
		)
		(fp_line
			(start -0.67945 -0.3048)
			(end -0.67945 0.3048)
			(stroke
				(width 0.1)
				(type default)
			)
			(layer "B.Fab")
		)
		(fp_line
			(start -0.12065 -0.3048)
			(end -0.67945 -0.3048)
			(stroke
				(width 0.1)
				(type default)
			)
			(layer "B.Fab")
		)
		(fp_line
			(start 0.12065 -0.305054)
			(end 0.12065 -0.2794)
			(stroke
				(width 0.1)
				(type default)
			)
			(layer "B.Fab")
		)
		(fp_line
			(start 0.67945 -0.305054)
			(end 0.12065 -0.305054)
			(stroke
				(width 0.1)
				(type default)
			)
			(layer "B.Fab")
		)
		(pad "1" smd circle
			(at 0.40005 0 90)
			(size 0 0)
			(layers "B.Cu" "B.Mask" "B.Paste")
			(net "P3V3_RTC_AUX")
		)
		(pad "2" smd circle
			(at -0.40005 0 90)
			(size 0 0)
			(layers "B.Cu" "B.Mask" "B.Paste")
			(net "GND")
		)
	)
	(footprint ""
		(layer "B.Cu")
		(at 71.1708 -34.8996 180)
		(property "Reference" "C44"
			(at 0 0 0)
			(layer "B.SilkS")
			(hide yes)
			(effects
				(font
					(size 1.27 1.27)
				)
				(justify mirror)
			)
		)
		(property "Value" ""
			(at 0 0 0)
			(layer "B.Fab")
			(effects
				(font
					(size 1.27 1.27)
				)
				(justify mirror)
			)
		)
		(duplicate_pad_numbers_are_jumpers no)
		(fp_line
			(start 1.2954 0.5842)
			(end 1.2954 -0.5842)
			(stroke
				(width 0.1524)
				(type default)
			)
			(layer "B.SilkS")
		)
		(fp_line
			(start 1.2954 -0.5842)
			(end -1.2954 -0.5842)
			(stroke
				(width 0.1524)
				(type default)
			)
			(layer "B.SilkS")
		)
		(fp_line
			(start 0 -0.5842)
			(end 0 0.5842)
			(stroke
				(width 0.1524)
				(type default)
			)
			(layer "B.SilkS")
		)
		(fp_line
			(start -1.2954 0.5842)
			(end 1.2954 0.5842)
			(stroke
				(width 0.1524)
				(type default)
			)
			(layer "B.SilkS")
		)
		(fp_line
			(start -1.2954 -0.5842)
			(end -1.2954 0.5842)
			(stroke
				(width 0.1524)
				(type default)
			)
			(layer "B.SilkS")
		)
		(fp_line
			(start 1.1938 0.4064)
			(end 1.1938 -0.4064)
			(stroke
				(width 0.1)
				(type default)
			)
			(layer "B.Fab")
		)
		(fp_line
			(start 1.1938 -0.4064)
			(end 0.8636 -0.4064)
			(stroke
				(width 0.1)
				(type default)
			)
			(layer "B.Fab")
		)
		(fp_line
			(start 0.8636 0.4572)
			(end 0.8636 0.4064)
			(stroke
				(width 0.1)
				(type default)
			)
			(layer "B.Fab")
		)
		(fp_line
			(start 0.8636 0.4064)
			(end 1.1938 0.4064)
			(stroke
				(width 0.1)
				(type default)
			)
			(layer "B.Fab")
		)
		(fp_line
			(start 0.8636 -0.4064)
			(end 0.8636 -0.4572)
			(stroke
				(width 0.1)
				(type default)
			)
			(layer "B.Fab")
		)
		(fp_line
			(start 0.8636 -0.4572)
			(end -0.8636 -0.4572)
			(stroke
				(width 0.1)
				(type default)
			)
			(layer "B.Fab")
		)
		(fp_line
			(start -0.8636 0.4572)
			(end 0.8636 0.4572)
			(stroke
				(width 0.1)
				(type default)
			)
			(layer "B.Fab")
		)
		(fp_line
			(start -0.8636 0.4064)
			(end -0.8636 0.4572)
			(stroke
				(width 0.1)
				(type default)
			)
			(layer "B.Fab")
		)
		(fp_line
			(start -0.8636 -0.4064)
			(end -1.1938 -0.4064)
			(stroke
				(width 0.1)
				(type default)
			)
			(layer "B.Fab")
		)
		(fp_line
			(start -0.8636 -0.4572)
			(end -0.8636 -0.4064)
			(stroke
				(width 0.1)
				(type default)
			)
			(layer "B.Fab")
		)
		(fp_line
			(start -1.1938 0.4064)
			(end -0.8636 0.4064)
			(stroke
				(width 0.1)
				(type default)
			)
			(layer "B.Fab")
		)
		(fp_line
			(start -1.1938 -0.4064)
			(end -1.1938 0.4064)
			(stroke
				(width 0.1)
				(type default)
			)
			(layer "B.Fab")
		)
		(pad "1" smd rect
			(at 0.7366 0 90)
			(size 0.7112 0.8128)
			(layers "B.Cu" "B.Mask" "B.Paste")
			(net "P3V3_BMC_USB2AV33")
		)
		(pad "2" smd rect
			(at -0.7366 0 90)
			(size 0.7112 0.8128)
			(layers "B.Cu" "B.Mask" "B.Paste")
			(net "GND")
		)
	)
	(footprint ""
		(layer "B.Cu")
		(at 81.38922 -46.586394)
		(property "Reference" "R375"
			(at 0 0 0)
			(layer "B.SilkS")
			(hide yes)
			(effects
				(font
					(size 1.27 1.27)
				)
				(justify mirror)
			)
		)
		(property "Value" ""
			(at 0 0 0)
			(layer "B.Fab")
			(effects
				(font
					(size 1.27 1.27)
				)
				(justify mirror)
			)
		)
		(duplicate_pad_numbers_are_jumpers no)
		(fp_line
			(start -0.7874 -0.4064)
			(end -0.7874 0.4064)
			(stroke
				(width 0.1524)
				(type default)
			)
			(layer "B.SilkS")
		)
		(fp_line
			(start -0.7874 0.4064)
			(end 0.7874 0.4064)
			(stroke
				(width 0.1524)
				(type default)
			)
			(layer "B.SilkS")
		)
		(fp_line
			(start 0.7874 -0.4064)
			(end -0.7874 -0.4064)
			(stroke
				(width 0.1524)
				(type default)
			)
			(layer "B.SilkS")
		)
		(fp_line
			(start 0.7874 0.4064)
			(end 0.7874 -0.4064)
			(stroke
				(width 0.1524)
				(type default)
			)
			(layer "B.SilkS")
		)
		(fp_line
			(start -0.67945 -0.3048)
			(end -0.67945 0.3048)
			(stroke
				(width 0.1)
				(type default)
			)
			(layer "B.Fab")
		)
		(fp_line
			(start -0.67945 0.3048)
			(end -0.120396 0.3048)
			(stroke
				(width 0.1)
				(type default)
			)
			(layer "B.Fab")
		)
		(fp_line
			(start -0.12065 -0.3048)
			(end -0.67945 -0.3048)
			(stroke
				(width 0.1)
				(type default)
			)
			(layer "B.Fab")
		)
		(fp_line
			(start -0.12065 -0.2794)
			(end -0.12065 -0.3048)
			(stroke
				(width 0.1)
				(type default)
			)
			(layer "B.Fab")
		)
		(fp_line
			(start -0.120396 0.2794)
			(end 0.12065 0.2794)
			(stroke
				(width 0.1)
				(type default)
			)
			(layer "B.Fab")
		)
		(fp_line
			(start -0.120396 0.3048)
			(end -0.120396 0.2794)
			(stroke
				(width 0.1)
				(type default)
			)
			(layer "B.Fab")
		)
		(fp_line
			(start 0.12065 -0.305054)
			(end 0.12065 -0.2794)
			(stroke
				(width 0.1)
				(type default)
			)
			(layer "B.Fab")
		)
		(fp_line
			(start 0.12065 -0.2794)
			(end -0.12065 -0.2794)
			(stroke
				(width 0.1)
				(type default)
			)
			(layer "B.Fab")
		)
		(fp_line
			(start 0.12065 0.2794)
			(end 0.12065 0.3048)
			(stroke
				(width 0.1)
				(type default)
			)
			(layer "B.Fab")
		)
		(fp_line
			(start 0.12065 0.3048)
			(end 0.67945 0.3048)
			(stroke
				(width 0.1)
				(type default)
			)
			(layer "B.Fab")
		)
		(fp_line
			(start 0.67945 -0.305054)
			(end 0.12065 -0.305054)
			(stroke
				(width 0.1)
				(type default)
			)
			(layer "B.Fab")
		)
		(fp_line
			(start 0.67945 0.3048)
			(end 0.67945 -0.305054)
			(stroke
				(width 0.1)
				(type default)
			)
			(layer "B.Fab")
		)
		(pad "1" smd circle
			(at 0.40005 0 180)
			(size 0 0)
			(layers "B.Cu" "B.Mask" "B.Paste")
			(net "M_BMC_DDR4_MBG1")
		)
		(pad "2" smd circle
			(at -0.40005 0 180)
			(size 0 0)
			(layers "B.Cu" "B.Mask" "B.Paste")
			(net "P1V2_AUX")
		)
	)
	(footprint ""
		(layer "B.Cu")
		(at 83.16722 -45.570394)
		(property "Reference" "R338"
			(at 0 0 0)
			(layer "B.SilkS")
			(hide yes)
			(effects
				(font
					(size 1.27 1.27)
				)
				(justify mirror)
			)
		)
		(property "Value" ""
			(at 0 0 0)
			(layer "B.Fab")
			(effects
				(font
					(size 1.27 1.27)
				)
				(justify mirror)
			)
		)
		(duplicate_pad_numbers_are_jumpers no)
		(fp_line
			(start -0.7874 -0.4064)
			(end -0.7874 0.4064)
			(stroke
				(width 0.1524)
				(type default)
			)
			(layer "B.SilkS")
		)
		(fp_line
			(start -0.7874 0.4064)
			(end 0.7874 0.4064)
			(stroke
				(width 0.1524)
				(type default)
			)
			(layer "B.SilkS")
		)
		(fp_line
			(start 0.7874 -0.4064)
			(end -0.7874 -0.4064)
			(stroke
				(width 0.1524)
				(type default)
			)
			(layer "B.SilkS")
		)
		(fp_line
			(start 0.7874 0.4064)
			(end 0.7874 -0.4064)
			(stroke
				(width 0.1524)
				(type default)
			)
			(layer "B.SilkS")
		)
		(fp_line
			(start -0.67945 -0.3048)
			(end -0.67945 0.3048)
			(stroke
				(width 0.1)
				(type default)
			)
			(layer "B.Fab")
		)
		(fp_line
			(start -0.67945 0.3048)
			(end -0.120396 0.3048)
			(stroke
				(width 0.1)
				(type default)
			)
			(layer "B.Fab")
		)
		(fp_line
			(start -0.12065 -0.3048)
			(end -0.67945 -0.3048)
			(stroke
				(width 0.1)
				(type default)
			)
			(layer "B.Fab")
		)
		(fp_line
			(start -0.12065 -0.2794)
			(end -0.12065 -0.3048)
			(stroke
				(width 0.1)
				(type default)
			)
			(layer "B.Fab")
		)
		(fp_line
			(start -0.120396 0.2794)
			(end 0.12065 0.2794)
			(stroke
				(width 0.1)
				(type default)
			)
			(layer "B.Fab")
		)
		(fp_line
			(start -0.120396 0.3048)
			(end -0.120396 0.2794)
			(stroke
				(width 0.1)
				(type default)
			)
			(layer "B.Fab")
		)
		(fp_line
			(start 0.12065 -0.305054)
			(end 0.12065 -0.2794)
			(stroke
				(width 0.1)
				(type default)
			)
			(layer "B.Fab")
		)
		(fp_line
			(start 0.12065 -0.2794)
			(end -0.12065 -0.2794)
			(stroke
				(width 0.1)
				(type default)
			)
			(layer "B.Fab")
		)
		(fp_line
			(start 0.12065 0.2794)
			(end 0.12065 0.3048)
			(stroke
				(width 0.1)
				(type default)
			)
			(layer "B.Fab")
		)
		(fp_line
			(start 0.12065 0.3048)
			(end 0.67945 0.3048)
			(stroke
				(width 0.1)
				(type default)
			)
			(layer "B.Fab")
		)
		(fp_line
			(start 0.67945 -0.305054)
			(end 0.12065 -0.305054)
			(stroke
				(width 0.1)
				(type default)
			)
			(layer "B.Fab")
		)
		(fp_line
			(start 0.67945 0.3048)
			(end 0.67945 -0.305054)
			(stroke
				(width 0.1)
				(type default)
			)
			(layer "B.Fab")
		)
		(pad "1" smd circle
			(at 0.40005 0 180)
			(size 0 0)
			(layers "B.Cu" "B.Mask" "B.Paste")
			(net "GND")
		)
		(pad "2" smd circle
			(at -0.40005 0 180)
			(size 0 0)
			(layers "B.Cu" "B.Mask" "B.Paste")
			(net "M_BMC_DDR4_MA<12>")
		)
	)
	(footprint ""
		(layer "B.Cu")
		(at 42.4688 -59.2074 180)
		(property "Reference" "L12"
			(at 0 0 0)
			(layer "B.SilkS")
			(hide yes)
			(effects
				(font
					(size 1.27 1.27)
				)
				(justify mirror)
			)
		)
		(property "Value" ""
			(at 0 0 0)
			(layer "B.Fab")
			(effects
				(font
					(size 1.27 1.27)
				)
				(justify mirror)
			)
		)
		(duplicate_pad_numbers_are_jumpers no)
		(fp_line
			(start 1.27 0.5842)
			(end 1.27 -0.5842)
			(stroke
				(width 0.1524)
				(type default)
			)
			(layer "B.SilkS")
		)
		(fp_line
			(start 1.27 -0.5588)
			(end 1.27 -0.5842)
			(stroke
				(width 0.1524)
				(type default)
			)
			(layer "B.SilkS")
		)
		(fp_line
			(start 1.27 -0.5842)
			(end -1.27 -0.5842)
			(stroke
				(width 0.1524)
				(type default)
			)
			(layer "B.SilkS")
		)
		(fp_line
			(start 0.127 0.5842)
			(end 0.127 -0.5842)
			(stroke
				(width 0.1524)
				(type default)
			)
			(layer "B.SilkS")
		)
		(fp_line
			(start -0.127 0.5842)
			(end -0.127 -0.5842)
			(stroke
				(width 0.1524)
				(type default)
			)
			(layer "B.SilkS")
		)
		(fp_line
			(start -1.27 0.5842)
			(end 1.27 0.5842)
			(stroke
				(width 0.1524)
				(type default)
			)
			(layer "B.SilkS")
		)
		(fp_line
			(start -1.27 0.5842)
			(end -1.27 -0.5842)
			(stroke
				(width 0.1524)
				(type default)
			)
			(layer "B.SilkS")
		)
		(fp_line
			(start 1.194308 0.406654)
			(end 1.194308 -0.406654)
			(stroke
				(width 0.1)
				(type default)
			)
			(layer "B.Fab")
		)
		(fp_line
			(start 1.194308 -0.406654)
			(end 0.9144 -0.406654)
			(stroke
				(width 0.1)
				(type default)
			)
			(layer "B.Fab")
		)
		(fp_line
			(start 0.9144 0.508)
			(end 0.9144 0.406654)
			(stroke
				(width 0.1)
				(type default)
			)
			(layer "B.Fab")
		)
		(fp_line
			(start 0.9144 0.406654)
			(end 1.194308 0.406654)
			(stroke
				(width 0.1)
				(type default)
			)
			(layer "B.Fab")
		)
		(fp_line
			(start 0.9144 -0.406654)
			(end 0.9144 -0.508)
			(stroke
				(width 0.1)
				(type default)
			)
			(layer "B.Fab")
		)
		(fp_line
			(start 0.9144 -0.508)
			(end -0.9144 -0.508)
			(stroke
				(width 0.1)
				(type default)
			)
			(layer "B.Fab")
		)
		(fp_line
			(start -0.9144 0.508)
			(end 0.9144 0.508)
			(stroke
				(width 0.1)
				(type default)
			)
			(layer "B.Fab")
		)
		(fp_line
			(start -0.9144 0.4064)
			(end -0.9144 0.508)
			(stroke
				(width 0.1)
				(type default)
			)
			(layer "B.Fab")
		)
		(fp_line
			(start -0.9144 -0.406654)
			(end -1.1938 -0.406654)
			(stroke
				(width 0.1)
				(type default)
			)
			(layer "B.Fab")
		)
		(fp_line
			(start -0.9144 -0.508)
			(end -0.9144 -0.406654)
			(stroke
				(width 0.1)
				(type default)
			)
			(layer "B.Fab")
		)
		(fp_line
			(start -1.1938 0.4064)
			(end -0.9144 0.4064)
			(stroke
				(width 0.1)
				(type default)
			)
			(layer "B.Fab")
		)
		(fp_line
			(start -1.1938 -0.406654)
			(end -1.1938 0.4064)
			(stroke
				(width 0.1)
				(type default)
			)
			(layer "B.Fab")
		)
		(pad "1" smd rect
			(at 0.7366 0 90)
			(size 0.7112 0.8128)
			(layers "B.Cu" "B.Mask" "B.Paste")
			(net "P3V3_AUX")
		)
		(pad "2" smd rect
			(at -0.7366 0 90)
			(size 0.7112 0.8128)
			(layers "B.Cu" "B.Mask" "B.Paste")
			(net "A_BMC_ADCAV33")
		)
	)
	(footprint ""
		(layer "B.Cu")
		(at -14.2494 -66.929 180)
		(property "Reference" "DB3"
			(at 2.71526 -6.12521 0)
			(unlocked yes)
			(layer "B.SilkS")
			(effects
				(font
					(size 0.7874 0.5842)
					(thickness 0.1524)
				)
				(justify left mirror)
			)
		)
		(property "Value" ""
			(at 0 0 0)
			(layer "B.Fab")
			(effects
				(font
					(size 1.27 1.27)
				)
				(justify mirror)
			)
		)
		(duplicate_pad_numbers_are_jumpers no)
		(fp_line
			(start 3.330702 -4.771136)
			(end -3.330702 -4.771136)
			(stroke
				(width 0.1524)
				(type default)
			)
			(layer "B.SilkS")
		)
		(fp_line
			(start 0 4.011168)
			(end 3.330702 -4.771136)
			(stroke
				(width 0.1524)
				(type default)
			)
			(layer "B.SilkS")
		)
		(fp_line
			(start -3.330702 -4.771136)
			(end 0 4.011168)
			(stroke
				(width 0.1524)
				(type default)
			)
			(layer "B.SilkS")
		)
		(fp_line
			(start 3.330702 -4.771136)
			(end -3.330702 -4.771136)
			(stroke
				(width 0.1)
				(type default)
			)
			(layer "B.Fab")
		)
		(fp_line
			(start 0 4.011168)
			(end 3.330702 -4.771136)
			(stroke
				(width 0.1)
				(type default)
			)
			(layer "B.Fab")
		)
		(fp_line
			(start -3.330702 -4.771136)
			(end 0 4.011168)
			(stroke
				(width 0.1)
				(type default)
			)
			(layer "B.Fab")
		)
		(pad "1" thru_hole circle
			(at 0 0)
			(size 2.159 2.159)
			(drill 1.7018)
			(layers "*.Cu" "*.Mask")
			(remove_unused_layers no)
			(net "T_GND")
			(clearance 0.0254)
			(thermal_gap 0.0254)
		)
		(pad "2" thru_hole circle
			(at 1.27 -3.348736)
			(size 2.159 2.159)
			(drill 1.7018)
			(layers "*.Cu" "*.Mask")
			(remove_unused_layers no)
			(net "TDR_SE_50_OHM_IN2")
			(clearance 0.0254)
			(thermal_gap 0.0254)
		)
		(pad "3" thru_hole circle
			(at -1.27 -3.348736)
			(size 2.159 2.159)
			(drill 1.7018)
			(layers "*.Cu" "*.Mask")
			(remove_unused_layers no)
			(net "TDR_SE_50_OHM_IN2")
			(clearance 0.0254)
			(thermal_gap 0.0254)
		)
	)
	(footprint ""
		(layer "B.Cu")
		(at 41.143936 -52.40147 180)
		(property "Reference" "R281"
			(at 0 0 0)
			(layer "B.SilkS")
			(hide yes)
			(effects
				(font
					(size 1.27 1.27)
				)
				(justify mirror)
			)
		)
		(property "Value" ""
			(at 0 0 0)
			(layer "B.Fab")
			(effects
				(font
					(size 1.27 1.27)
				)
				(justify mirror)
			)
		)
		(duplicate_pad_numbers_are_jumpers no)
		(fp_line
			(start 0.7874 0.4064)
			(end 0.7874 -0.4064)
			(stroke
				(width 0.1524)
				(type default)
			)
			(layer "B.SilkS")
		)
		(fp_line
			(start 0.7874 -0.4064)
			(end -0.7874 -0.4064)
			(stroke
				(width 0.1524)
				(type default)
			)
			(layer "B.SilkS")
		)
		(fp_line
			(start -0.7874 0.4064)
			(end 0.7874 0.4064)
			(stroke
				(width 0.1524)
				(type default)
			)
			(layer "B.SilkS")
		)
		(fp_line
			(start -0.7874 -0.4064)
			(end -0.7874 0.4064)
			(stroke
				(width 0.1524)
				(type default)
			)
			(layer "B.SilkS")
		)
		(fp_line
			(start 0.67945 0.3048)
			(end 0.67945 -0.305054)
			(stroke
				(width 0.1)
				(type default)
			)
			(layer "B.Fab")
		)
		(fp_line
			(start 0.67945 -0.305054)
			(end 0.12065 -0.305054)
			(stroke
				(width 0.1)
				(type default)
			)
			(layer "B.Fab")
		)
		(fp_line
			(start 0.12065 0.3048)
			(end 0.67945 0.3048)
			(stroke
				(width 0.1)
				(type default)
			)
			(layer "B.Fab")
		)
		(fp_line
			(start 0.12065 0.2794)
			(end 0.12065 0.3048)
			(stroke
				(width 0.1)
				(type default)
			)
			(layer "B.Fab")
		)
		(fp_line
			(start 0.12065 -0.2794)
			(end -0.12065 -0.2794)
			(stroke
				(width 0.1)
				(type default)
			)
			(layer "B.Fab")
		)
		(fp_line
			(start 0.12065 -0.305054)
			(end 0.12065 -0.2794)
			(stroke
				(width 0.1)
				(type default)
			)
			(layer "B.Fab")
		)
		(fp_line
			(start -0.120396 0.3048)
			(end -0.120396 0.2794)
			(stroke
				(width 0.1)
				(type default)
			)
			(layer "B.Fab")
		)
		(fp_line
			(start -0.120396 0.2794)
			(end 0.12065 0.2794)
			(stroke
				(width 0.1)
				(type default)
			)
			(layer "B.Fab")
		)
		(fp_line
			(start -0.12065 -0.2794)
			(end -0.12065 -0.3048)
			(stroke
				(width 0.1)
				(type default)
			)
			(layer "B.Fab")
		)
		(fp_line
			(start -0.12065 -0.3048)
			(end -0.67945 -0.3048)
			(stroke
				(width 0.1)
				(type default)
			)
			(layer "B.Fab")
		)
		(fp_line
			(start -0.67945 0.3048)
			(end -0.120396 0.3048)
			(stroke
				(width 0.1)
				(type default)
			)
			(layer "B.Fab")
		)
		(fp_line
			(start -0.67945 -0.3048)
			(end -0.67945 0.3048)
			(stroke
				(width 0.1)
				(type default)
			)
			(layer "B.Fab")
		)
		(pad "1" smd circle
			(at 0.40005 0)
			(size 0 0)
			(layers "B.Cu" "B.Mask" "B.Paste")
			(net "P1V0_AUX")
		)
		(pad "2" smd circle
			(at -0.40005 0)
			(size 0 0)
			(layers "B.Cu" "B.Mask" "B.Paste")
			(net "P1V2_P1V0_I3C_VDDL2")
		)
	)
	(footprint ""
		(layer "B.Cu")
		(at 18.2626 -78.359 -90)
		(property "Reference" "R806"
			(at 0 0 90)
			(layer "B.SilkS")
			(hide yes)
			(effects
				(font
					(size 1.27 1.27)
				)
				(justify mirror)
			)
		)
		(property "Value" ""
			(at 0 0 90)
			(layer "B.Fab")
			(effects
				(font
					(size 1.27 1.27)
				)
				(justify mirror)
			)
		)
		(duplicate_pad_numbers_are_jumpers no)
		(fp_line
			(start -0.7874 0.4064)
			(end 0.7874 0.4064)
			(stroke
				(width 0.1524)
				(type default)
			)
			(layer "B.SilkS")
		)
		(fp_line
			(start 0.7874 0.4064)
			(end 0.7874 -0.4064)
			(stroke
				(width 0.1524)
				(type default)
			)
			(layer "B.SilkS")
		)
		(fp_line
			(start -0.7874 -0.4064)
			(end -0.7874 0.4064)
			(stroke
				(width 0.1524)
				(type default)
			)
			(layer "B.SilkS")
		)
		(fp_line
			(start 0.7874 -0.4064)
			(end -0.7874 -0.4064)
			(stroke
				(width 0.1524)
				(type default)
			)
			(layer "B.SilkS")
		)
		(fp_line
			(start -0.67945 0.3048)
			(end -0.120396 0.3048)
			(stroke
				(width 0.1)
				(type default)
			)
			(layer "B.Fab")
		)
		(fp_line
			(start -0.120396 0.3048)
			(end -0.120396 0.2794)
			(stroke
				(width 0.1)
				(type default)
			)
			(layer "B.Fab")
		)
		(fp_line
			(start 0.12065 0.3048)
			(end 0.67945 0.3048)
			(stroke
				(width 0.1)
				(type default)
			)
			(layer "B.Fab")
		)
		(fp_line
			(start 0.67945 0.3048)
			(end 0.67945 -0.305054)
			(stroke
				(width 0.1)
				(type default)
			)
			(layer "B.Fab")
		)
		(fp_line
			(start -0.120396 0.2794)
			(end 0.12065 0.2794)
			(stroke
				(width 0.1)
				(type default)
			)
			(layer "B.Fab")
		)
		(fp_line
			(start 0.12065 0.2794)
			(end 0.12065 0.3048)
			(stroke
				(width 0.1)
				(type default)
			)
			(layer "B.Fab")
		)
		(fp_line
			(start -0.12065 -0.2794)
			(end -0.12065 -0.3048)
			(stroke
				(width 0.1)
				(type default)
			)
			(layer "B.Fab")
		)
		(fp_line
			(start 0.12065 -0.2794)
			(end -0.12065 -0.2794)
			(stroke
				(width 0.1)
				(type default)
			)
			(layer "B.Fab")
		)
		(fp_line
			(start -0.67945 -0.3048)
			(end -0.67945 0.3048)
			(stroke
				(width 0.1)
				(type default)
			)
			(layer "B.Fab")
		)
		(fp_line
			(start -0.12065 -0.3048)
			(end -0.67945 -0.3048)
			(stroke
				(width 0.1)
				(type default)
			)
			(layer "B.Fab")
		)
		(fp_line
			(start 0.12065 -0.305054)
			(end 0.12065 -0.2794)
			(stroke
				(width 0.1)
				(type default)
			)
			(layer "B.Fab")
		)
		(fp_line
			(start 0.67945 -0.305054)
			(end 0.12065 -0.305054)
			(stroke
				(width 0.1)
				(type default)
			)
			(layer "B.Fab")
		)
		(pad "1" smd circle
			(at 0.40005 0 90)
			(size 0 0)
			(layers "B.Cu" "B.Mask" "B.Paste")
			(net "P3V3_AUX")
		)
		(pad "2" smd circle
			(at -0.40005 0 90)
			(size 0 0)
			(layers "B.Cu" "B.Mask" "B.Paste")
			(net "PU_25M_FPGA_CLK_EN")
		)
	)
	(footprint ""
		(layer "B.Cu")
		(at 53.04282 -51.69662)
		(property "Reference" "C82"
			(at 0 0 0)
			(layer "B.SilkS")
			(hide yes)
			(effects
				(font
					(size 1.27 1.27)
				)
				(justify mirror)
			)
		)
		(property "Value" ""
			(at 0 0 0)
			(layer "B.Fab")
			(effects
				(font
					(size 1.27 1.27)
				)
				(justify mirror)
			)
		)
		(duplicate_pad_numbers_are_jumpers no)
		(fp_line
			(start -0.7874 -0.4064)
			(end -0.7874 0.4064)
			(stroke
				(width 0.1524)
				(type default)
			)
			(layer "B.SilkS")
		)
		(fp_line
			(start -0.7874 0.4064)
			(end 0.7874 0.4064)
			(stroke
				(width 0.1524)
				(type default)
			)
			(layer "B.SilkS")
		)
		(fp_line
			(start 0.7874 -0.4064)
			(end -0.7874 -0.4064)
			(stroke
				(width 0.1524)
				(type default)
			)
			(layer "B.SilkS")
		)
		(fp_line
			(start 0.7874 0.4064)
			(end 0.7874 -0.4064)
			(stroke
				(width 0.1524)
				(type default)
			)
			(layer "B.SilkS")
		)
		(fp_line
			(start -0.67945 -0.3048)
			(end -0.67945 0.3048)
			(stroke
				(width 0.1)
				(type default)
			)
			(layer "B.Fab")
		)
		(fp_line
			(start -0.67945 0.3048)
			(end -0.120396 0.3048)
			(stroke
				(width 0.1)
				(type default)
			)
			(layer "B.Fab")
		)
		(fp_line
			(start -0.12065 -0.3048)
			(end -0.67945 -0.3048)
			(stroke
				(width 0.1)
				(type default)
			)
			(layer "B.Fab")
		)
		(fp_line
			(start -0.12065 -0.2794)
			(end -0.12065 -0.3048)
			(stroke
				(width 0.1)
				(type default)
			)
			(layer "B.Fab")
		)
		(fp_line
			(start -0.120396 0.2794)
			(end 0.12065 0.2794)
			(stroke
				(width 0.1)
				(type default)
			)
			(layer "B.Fab")
		)
		(fp_line
			(start -0.120396 0.3048)
			(end -0.120396 0.2794)
			(stroke
				(width 0.1)
				(type default)
			)
			(layer "B.Fab")
		)
		(fp_line
			(start 0.12065 -0.305054)
			(end 0.12065 -0.2794)
			(stroke
				(width 0.1)
				(type default)
			)
			(layer "B.Fab")
		)
		(fp_line
			(start 0.12065 -0.2794)
			(end -0.12065 -0.2794)
			(stroke
				(width 0.1)
				(type default)
			)
			(layer "B.Fab")
		)
		(fp_line
			(start 0.12065 0.2794)
			(end 0.12065 0.3048)
			(stroke
				(width 0.1)
				(type default)
			)
			(layer "B.Fab")
		)
		(fp_line
			(start 0.12065 0.3048)
			(end 0.67945 0.3048)
			(stroke
				(width 0.1)
				(type default)
			)
			(layer "B.Fab")
		)
		(fp_line
			(start 0.67945 -0.305054)
			(end 0.12065 -0.305054)
			(stroke
				(width 0.1)
				(type default)
			)
			(layer "B.Fab")
		)
		(fp_line
			(start 0.67945 0.3048)
			(end 0.67945 -0.305054)
			(stroke
				(width 0.1)
				(type default)
			)
			(layer "B.Fab")
		)
		(pad "1" smd circle
			(at 0.40005 0 180)
			(size 0 0)
			(layers "B.Cu" "B.Mask" "B.Paste")
			(net "P1V2_AUX")
		)
		(pad "2" smd circle
			(at -0.40005 0 180)
			(size 0 0)
			(layers "B.Cu" "B.Mask" "B.Paste")
			(net "GND")
		)
	)
	(footprint ""
		(layer "B.Cu")
		(at 78.723744 -37.559488 90)
		(property "Reference" "R359"
			(at 0 0 90)
			(layer "B.SilkS")
			(hide yes)
			(effects
				(font
					(size 1.27 1.27)
				)
				(justify mirror)
			)
		)
		(property "Value" ""
			(at 0 0 90)
			(layer "B.Fab")
			(effects
				(font
					(size 1.27 1.27)
				)
				(justify mirror)
			)
		)
		(duplicate_pad_numbers_are_jumpers no)
		(fp_line
			(start 0.7874 -0.4064)
			(end -0.7874 -0.4064)
			(stroke
				(width 0.1524)
				(type default)
			)
			(layer "B.SilkS")
		)
		(fp_line
			(start -0.7874 -0.4064)
			(end -0.7874 0.4064)
			(stroke
				(width 0.1524)
				(type default)
			)
			(layer "B.SilkS")
		)
		(fp_line
			(start 0.7874 0.4064)
			(end 0.7874 -0.4064)
			(stroke
				(width 0.1524)
				(type default)
			)
			(layer "B.SilkS")
		)
		(fp_line
			(start -0.7874 0.4064)
			(end 0.7874 0.4064)
			(stroke
				(width 0.1524)
				(type default)
			)
			(layer "B.SilkS")
		)
		(fp_line
			(start 0.67945 -0.305054)
			(end 0.12065 -0.305054)
			(stroke
				(width 0.1)
				(type default)
			)
			(layer "B.Fab")
		)
		(fp_line
			(start 0.12065 -0.305054)
			(end 0.12065 -0.2794)
			(stroke
				(width 0.1)
				(type default)
			)
			(layer "B.Fab")
		)
		(fp_line
			(start -0.12065 -0.3048)
			(end -0.67945 -0.3048)
			(stroke
				(width 0.1)
				(type default)
			)
			(layer "B.Fab")
		)
		(fp_line
			(start -0.67945 -0.3048)
			(end -0.67945 0.3048)
			(stroke
				(width 0.1)
				(type default)
			)
			(layer "B.Fab")
		)
		(fp_line
			(start 0.12065 -0.2794)
			(end -0.12065 -0.2794)
			(stroke
				(width 0.1)
				(type default)
			)
			(layer "B.Fab")
		)
		(fp_line
			(start -0.12065 -0.2794)
			(end -0.12065 -0.3048)
			(stroke
				(width 0.1)
				(type default)
			)
			(layer "B.Fab")
		)
		(fp_line
			(start 0.12065 0.2794)
			(end 0.12065 0.3048)
			(stroke
				(width 0.1)
				(type default)
			)
			(layer "B.Fab")
		)
		(fp_line
			(start -0.120396 0.2794)
			(end 0.12065 0.2794)
			(stroke
				(width 0.1)
				(type default)
			)
			(layer "B.Fab")
		)
		(fp_line
			(start 0.67945 0.3048)
			(end 0.67945 -0.305054)
			(stroke
				(width 0.1)
				(type default)
			)
			(layer "B.Fab")
		)
		(fp_line
			(start 0.12065 0.3048)
			(end 0.67945 0.3048)
			(stroke
				(width 0.1)
				(type default)
			)
			(layer "B.Fab")
		)
		(fp_line
			(start -0.120396 0.3048)
			(end -0.120396 0.2794)
			(stroke
				(width 0.1)
				(type default)
			)
			(layer "B.Fab")
		)
		(fp_line
			(start -0.67945 0.3048)
			(end -0.120396 0.3048)
			(stroke
				(width 0.1)
				(type default)
			)
			(layer "B.Fab")
		)
		(pad "1" smd circle
			(at 0.40005 0 270)
			(size 0 0)
			(layers "B.Cu" "B.Mask" "B.Paste")
			(net "M_BMC_DDR4_MA<8>")
		)
		(pad "2" smd circle
			(at -0.40005 0 270)
			(size 0 0)
			(layers "B.Cu" "B.Mask" "B.Paste")
			(net "P1V2_AUX")
		)
	)
	(gr_poly
		(pts
			(xy 11.4808 -58.1152) (xy 11.4808 -56.1848) (xy 10.966958 -55.670958) (xy 9.911842 -55.670958) (xy 9.750806 -55.831994)
			(xy 9.750806 -58.645806) (xy 10.033 -58.928) (xy 10.668 -58.928)
		)
		(stroke
			(width 0)
			(type solid)
		)
		(fill yes)
		(layer "F.Cu")
		(net "P12V_AUX")
	)
	(gr_poly
		(pts
			(xy 35.433254 -54.923436) (xy 35.433254 -53.501036) (xy 35.306254 -53.374036) (xy 34.747454 -53.374036)
			(xy 34.645854 -53.475636) (xy 34.645854 -54.999636) (xy 34.671254 -55.025036) (xy 35.331654 -55.025036)
		)
		(stroke
			(width 0)
			(type solid)
		)
		(fill yes)
		(layer "F.Cu")
		(net "P5V_AUX")
	)
	(gr_poly
		(pts
			(xy 69.441314 -64.05753) (xy 69.441314 -62.955424) (xy 69.390006 -62.904116) (xy 68.808854 -62.904116)
			(xy 68.74256 -62.97041) (xy 68.74256 -64.051434) (xy 68.826888 -64.135762) (xy 69.363082 -64.135762)
		)
		(stroke
			(width 0)
			(type solid)
		)
		(fill yes)
		(layer "F.Cu")
		(net "P1V8_STBY_RC_VCC18A")
	)
	(gr_poly
		(pts
			(xy 71.43877 -63.976504) (xy 71.43877 -62.965076) (xy 71.376794 -62.9031) (xy 69.913754 -62.9031)
			(xy 69.80682 -63.010034) (xy 69.80682 -63.90894) (xy 69.988684 -64.090804) (xy 71.32447 -64.090804)
		)
		(stroke
			(width 0)
			(type solid)
		)
		(fill yes)
		(layer "F.Cu")
		(net "P1V8_STBY_PE_VCC18A")
	)
	(gr_poly
		(pts
			(xy 80.255364 -118.737634) (xy 80.255364 -115.252754) (xy 80.174338 -115.171728) (xy 79.865474 -115.171728)
			(xy 79.748126 -115.289076) (xy 79.748126 -118.718584) (xy 79.85379 -118.824248) (xy 80.16875 -118.824248)
		)
		(stroke
			(width 0)
			(type solid)
		)
		(fill yes)
		(layer "F.Cu")
		(net "GND")
	)
	(gr_poly
		(pts
			(xy 81.77276 -32.46501) (xy 81.77276 -30.323536) (xy 81.724754 -30.275784) (xy 81.307432 -30.275784)
			(xy 81.2419 -30.341316) (xy 81.2419 -32.40786) (xy 81.305908 -32.471868) (xy 81.765902 -32.471868)
		)
		(stroke
			(width 0)
			(type solid)
		)
		(fill yes)
		(layer "F.Cu")
		(net "PWRGD_P3V3_AUX_R2")
	)
	(gr_poly
		(pts
			(xy 85.202014 -32.218122) (xy 85.202014 -31.659322) (xy 85.100414 -31.557722) (xy 83.576414 -31.557722)
			(xy 83.551014 -31.583122) (xy 83.551014 -32.243522) (xy 83.652614 -32.345122) (xy 85.075014 -32.345122)
		)
		(stroke
			(width 0)
			(type solid)
		)
		(fill yes)
		(layer "F.Cu")
		(net "P5V_AUX")
	)
	(gr_poly
		(pts
			(xy 5.6134 -109.5248) (xy 5.6134 -106.68) (xy 5.334 -106.4006) (xy 4.2164 -106.4006) (xy 4.1402 -106.4768)
			(xy 4.1402 -108.2294) (xy 4.1402 -109.474) (xy 4.3053 -109.6391) (xy 5.4991 -109.6391)
		)
		(stroke
			(width 0)
			(type solid)
		)
		(fill yes)
		(layer "F.Cu")
		(net "P3V3_AUX")
	)
	(gr_poly
		(pts
			(xy 81.74355 -29.959554) (xy 81.74355 -28.903168) (xy 81.74101 -28.900628) (xy 81.67751 -28.837128)
			(xy 81.320894 -28.837128) (xy 81.230978 -28.927044) (xy 81.230978 -29.970476) (xy 81.2546 -29.994098)
			(xy 81.709006 -29.994098)
		)
		(stroke
			(width 0)
			(type solid)
		)
		(fill yes)
		(layer "F.Cu")
		(net "PWRGD_P3V3_AUX")
	)
	(gr_poly
		(pts
			(xy 5.449824 -57.999376) (xy 6.313424 -57.999376) (xy 6.5278 -57.785) (xy 6.5278 -57.023) (xy 6.2484 -56.7436)
			(xy 3.937 -56.7436) (xy 3.7592 -56.9214) (xy 3.7592 -58.42) (xy 4.0386 -58.6994) (xy 4.7498 -58.6994)
		)
		(stroke
			(width 0)
			(type solid)
		)
		(fill yes)
		(layer "F.Cu")
		(net "P12V_AUX")
	)
	(gr_poly
		(pts
			(xy 40.787828 -57.637172) (xy 40.889428 -57.349136) (xy 40.889428 -56.614568) (xy 40.848534 -56.573674)
			(xy 40.301164 -56.573674) (xy 40.274748 -56.60009) (xy 40.274748 -57.651396) (xy 40.317928 -57.694576)
			(xy 40.381428 -57.758076) (xy 40.666924 -57.758076)
		)
		(stroke
			(width 0)
			(type solid)
		)
		(fill yes)
		(layer "F.Cu")
		(net "P3V3_AUX")
	)
	(gr_poly
		(pts
			(xy 86.143338 -58.753502) (xy 86.143338 -56.760618) (xy 85.97138 -56.58866) (xy 76.435712 -56.58866)
			(xy 76.236576 -56.787796) (xy 76.236576 -58.410856) (xy 76.614274 -58.788554) (xy 84.264754 -58.788554)
			(xy 84.609178 -58.788554) (xy 85.232494 -58.788554) (xy 86.108286 -58.788554)
		)
		(stroke
			(width 0)
			(type solid)
		)
		(fill yes)
		(layer "F.Cu")
		(net "GND")
	)
	(gr_poly
		(pts
			(xy 6.73227 -65.193418) (xy 6.73227 -64.967358) (xy 6.69163 -64.926718) (xy 5.87629 -64.926718) (xy 5.65404 -64.704468)
			(xy 4.96824 -64.704468) (xy 4.90347 -64.769238) (xy 4.90347 -65.015618) (xy 4.90347 -65.185798) (xy 4.93649 -65.218818)
			(xy 6.04647 -65.218818) (xy 6.70687 -65.218818)
		)
		(stroke
			(width 0)
			(type solid)
		)
		(fill yes)
		(layer "F.Cu")
		(net "P3V3_AUX_VCC")
	)
	(gr_poly
		(pts
			(xy 13.50772 -38.443916) (xy 13.50772 -32.000952) (xy 13.436092 -31.929324) (xy 4.548124 -31.929324)
			(xy 4.546092 -31.931356) (xy 4.252214 -31.931356) (xy 4.238244 -31.94558) (xy 4.23672 -31.94558)
			(xy 4.10591 -32.07639) (xy 4.10591 -38.537642) (xy 4.351782 -38.783514) (xy 13.168122 -38.783514)
		)
		(stroke
			(width 0)
			(type solid)
		)
		(fill yes)
		(layer "F.Cu")
		(net "P5V_AUX")
	)
	(gr_poly
		(pts
			(xy 24.765 -23.876) (xy 25.527 -23.876) (xy 25.6159 -23.7871) (xy 25.6159 -23.0759) (xy 25.019 -22.479)
			(xy 25.019 -21.209) (xy 24.638 -20.828) (xy 17.4498 -20.828) (xy 17.1958 -21.082) (xy 17.1958 -23.692358)
			(xy 17.7546 -24.251158) (xy 24.389842 -24.251158)
		)
		(stroke
			(width 0)
			(type solid)
		)
		(fill yes)
		(layer "F.Cu")
		(net "P1V0_AUX")
	)
	(gr_poly
		(pts
			(xy 35.534854 -56.472836) (xy 35.534854 -55.406036) (xy 35.484054 -55.355236) (xy 34.597848 -55.355236)
			(xy 34.170112 -54.9275) (xy 34.170112 -54.751732) (xy 34.003742 -54.585362) (xy 32.5374 -54.585362)
			(xy 32.3088 -54.813962) (xy 32.3088 -56.36641) (xy 32.491172 -56.549036) (xy 35.458908 -56.549036)
		)
		(stroke
			(width 0)
			(type solid)
		)
		(fill yes)
		(layer "F.Cu")
		(net "P3V3_AUX")
	)
	(gr_poly
		(pts
			(xy 50.8508 -22.6314) (xy 50.8508 -17.4244) (xy 50.6222 -17.1958) (xy 47.5742 -17.1958) (xy 47.1678 -17.6022)
			(xy 47.1678 -20.0914) (xy 47.3964 -20.32) (xy 49.022 -20.32) (xy 49.3268 -20.6248) (xy 49.3268 -22.6822)
			(xy 49.4792 -22.8346) (xy 50.6476 -22.8346)
		)
		(stroke
			(width 0)
			(type solid)
		)
		(fill yes)
		(layer "F.Cu")
		(net "P5V_USB_REAR")
	)
	(gr_poly
		(pts
			(xy 70.637908 -37.160454) (xy 71.500238 -37.160454) (xy 72.15378 -36.506912) (xy 72.15378 -34.94278)
			(xy 72.10933 -34.89833) (xy 71.65594 -34.89833) (xy 71.163434 -35.390836) (xy 69.090286 -35.390836)
			(xy 68.748402 -35.73272) (xy 68.748402 -37.120068) (xy 68.789042 -37.160708) (xy 70.637654 -37.160708)
		)
		(stroke
			(width 0)
			(type solid)
		)
		(fill yes)
		(layer "F.Cu")
		(net "GND")
	)
	(gr_poly
		(pts
			(xy 9.0424 -108.1278) (xy 9.0424 -105.791) (xy 9.0424 -104.4448) (xy 7.6454 -103.0478) (xy 5.2578 -103.0478)
			(xy 5.1308 -103.1748) (xy 5.1308 -104.7496) (xy 5.2578 -104.8766) (xy 6.6548 -104.8766) (xy 7.5184 -105.7402)
			(xy 7.5184 -108.1786) (xy 7.5946 -108.2548) (xy 8.9154 -108.2548)
		)
		(stroke
			(width 0)
			(type solid)
		)
		(fill yes)
		(layer "F.Cu")
		(net "J7_P1")
	)
	(gr_poly
		(pts
			(xy 13.035026 -77.795374) (xy 13.035026 -73.406) (xy 12.390374 -72.761348) (xy 12.24788 -72.761348)
			(xy 12.247626 -72.761094) (xy 3.393694 -72.761094) (xy 3.014218 -73.14057) (xy 3.014218 -77.683614)
			(xy 3.152394 -77.821536) (xy 3.161538 -77.83068) (xy 3.79222 -77.83068) (xy 3.792474 -77.831188)
			(xy 12.999212 -77.831188)
		)
		(stroke
			(width 0)
			(type solid)
		)
		(fill yes)
		(layer "F.Cu")
		(net "P3V3_AUX")
	)
	(gr_poly
		(pts
			(xy 35.56 -57.310528) (xy 35.56 -56.810148) (xy 35.553142 -56.80329) (xy 32.48025 -56.80329) (xy 32.39262 -56.89092)
			(xy 32.39262 -57.180226)
			(arc
				(start 32.396176 -57.18937)
				(mid 32.412059 -57.242487)
				(end 32.418274 -57.297574)
			)
			(xy 32.418782 -57.317894) (xy 32.532828 -57.43194) (xy 35.438588 -57.43194)
		)
		(stroke
			(width 0)
			(type solid)
		)
		(fill yes)
		(layer "F.Cu")
		(net "EN_P1V8_R")
	)
	(gr_poly
		(pts
			(xy 86.192614 -37.058092) (xy 86.192614 -36.891722) (xy 86.192614 -34.834322) (xy 86.040214 -34.681922)
			(xy 82.585814 -34.681922) (xy 82.509614 -34.758122) (xy 82.509614 -35.578796) (xy 83.0834 -36.152582)
			(xy 83.0834 -36.153598) (xy 83.33232 -36.402518) (xy 83.33232 -37.058854) (xy 83.461098 -37.187632)
			(xy 86.063074 -37.187632)
		)
		(stroke
			(width 0)
			(type solid)
		)
		(fill yes)
		(layer "F.Cu")
		(net "P2V5_AUX")
	)
	(gr_poly
		(pts
			(xy 22.352 -41.021) (xy 22.352 -38.862) (xy 22.1742 -38.6842) (xy 21.7678 -38.6842) (xy 21.463 -38.989)
			(xy 21.463 -39.7256) (xy 20.828 -40.3606) (xy 20.066 -40.3606) (xy 19.5834 -39.878) (xy 18.9738 -39.878)
			(xy 18.8976 -39.9542) (xy 18.8976 -40.3352) (xy 19.9898 -41.4274) (xy 21.9456 -41.4274)
		)
		(stroke
			(width 0)
			(type solid)
		)
		(fill yes)
		(layer "F.Cu")
		(net "P12V_AUX")
	)
	(gr_poly
		(pts
			(xy 74.049636 -119.523764) (xy 74.049636 -117.339872)
			(arc
				(start 74.204322 -117.18544)
				(mid 74.220707 -117.164122)
				(end 74.238866 -117.144292)
			)
			(xy 74.311256 -117.071902) (xy 74.311256 -115.001548) (xy 74.261726 -114.952018) (xy 73.762362 -114.952018)
			(xy 73.671684 -115.042696) (xy 73.671684 -119.522748) (xy 73.67524 -119.526304) (xy 74.047604 -119.526304)
		)
		(stroke
			(width 0)
			(type solid)
		)
		(fill yes)
		(layer "F.Cu")
		(net "GND")
	)
	(gr_poly
		(pts
			(xy 56.603646 -21.069554)
			(arc
				(start 56.606948 -21.054822)
				(mid 56.63027 -20.982594)
				(end 56.6674 -20.916392)
			)
			(xy 56.6674 -19.8628) (xy 56.2102 -19.4056) (xy 56.2102 -17.4752) (xy 55.8038 -17.0688) (xy 52.578 -17.0688)
			(xy 52.2986 -17.3482) (xy 52.2986 -21.0312) (xy 52.451 -21.1836) (xy 56.4896 -21.1836)
		)
		(stroke
			(width 0)
			(type solid)
		)
		(fill yes)
		(layer "F.Cu")
		(net "GND")
	)
	(gr_poly
		(pts
			(xy 81.866232 -72.877172) (xy 81.866232 -69.64172) (xy 82.259932 -69.24802) (xy 84.19338 -69.24802)
			(xy 84.2518 -69.1896) (xy 84.2518 -67.1322) (xy 84.1248 -67.0052) (xy 80.7974 -67.0052) (xy 80.596486 -67.206114)
			(xy 80.596486 -70.076314) (xy 81.63052 -71.110094) (xy 81.63052 -72.597264) (xy 81.631028 -72.597772)
			(xy 81.631028 -72.888348) (xy 81.855056 -72.888348)
		)
		(stroke
			(width 0)
			(type solid)
		)
		(fill yes)
		(layer "F.Cu")
		(net "SW_P1V2_AUX_SW")
	)
	(gr_poly
		(pts
			(xy 20.037298 -31.523686) (xy 20.037298 -31.206694) (xy 20.58162 -30.662372) (xy 20.912582 -30.33141)
			(xy 20.912582 -29.790644) (xy 20.836382 -29.714444) (xy 20.443952 -29.714444) (xy 20.389342 -29.714444)
			(xy 20.33778 -29.766006) (xy 20.33778 -30.40507) (xy 20.089368 -30.653482) (xy 19.713194 -31.029656)
			(xy 19.713194 -31.090108) (xy 19.713194 -31.631636) (xy 19.741134 -31.659576) (xy 19.901408 -31.659576)
		)
		(stroke
			(width 0)
			(type solid)
		)
		(fill yes)
		(layer "F.Cu")
		(net "SW_P1V0_AUX_BST")
	)
	(gr_poly
		(pts
			(xy 56.657748 -29.274008) (xy 56.657748 -28.337002) (xy 56.451246 -28.1305) (xy 52.455826 -28.1305)
			(xy 52.375308 -28.211018) (xy 52.375308 -28.366466) (xy 52.77485 -28.766008)
			(arc
				(start 54.852316 -28.766008)
				(mid 54.998269 -28.794946)
				(end 55.122064 -28.877514)
			)
			(xy 55.573422 -29.329126) (xy 56.60263 -29.329126)
		)
		(stroke
			(width 0)
			(type solid)
		)
		(fill yes)
		(layer "F.Cu")
		(net "P3V3_RGM")
	)
	(gr_poly
		(pts
			(xy 83.3374 -80.0608) (xy 83.3374 -79.8068) (xy 83.85556 -79.28864) (xy 83.85556 -74.50836) (xy 83.5914 -74.2442)
			(xy 82.816446 -74.2442) (xy 82.462878 -73.890632) (xy 82.462878 -72.528684) (xy 82.431636 -72.497442)
			(xy 82.150966 -72.497442) (xy 82.123534 -72.524874) (xy 82.123534 -73.07199) (xy 81.81848 -73.377044)
			(xy 81.81848 -79.76108) (xy 82.2706 -80.2132) (xy 83.185 -80.2132)
		)
		(stroke
			(width 0)
			(type solid)
		)
		(fill yes)
		(layer "F.Cu")
		(net "SW_P1V2_AUX_FLT")
	)
	(gr_poly
		(pts
			(arc
				(start 40.246808 -33.880806)
				(mid 40.3062 -33.86521)
				(end 40.367204 -33.8582)
			)
			(xy 40.386762 -33.857438) (xy 40.65016 -33.59404) (xy 40.65016 -31.45536) (xy 40.75684 -31.34868)
			(xy 40.75684 -30.87116) (xy 40.65524 -30.76956) (xy 38.60038 -30.76956) (xy 38.405562 -30.964378)
			(xy 38.405562 -33.631378) (xy 38.484556 -33.710372) (xy 38.75151 -33.710372) (xy 38.924738 -33.8836)
			(xy 40.23868 -33.8836)
		)
		(stroke
			(width 0)
			(type solid)
		)
		(fill yes)
		(layer "F.Cu")
		(net "P3V3_P1V8_SD2VDD")
	)
	(gr_poly
		(pts
			(xy 56.8706 -23.9776) (xy 56.8706 -23.0124) (xy 56.6928 -22.8346) (xy 56.6928 -21.8186) (xy 56.4134 -21.5392)
			(xy 52.1462 -21.5392) (xy 51.7906 -21.8948) (xy 51.7906 -22.733) (xy 51.8922 -22.8346) (xy 53.5178 -22.8346)
			(xy 54.102 -23.4188) (xy 54.737 -23.4188) (xy 54.886352 -23.568152) (xy 54.887114 -23.56866) (xy 54.899052 -23.580598)
			(xy 55.499508 -24.1808) (xy 56.6674 -24.1808)
		)
		(stroke
			(width 0)
			(type solid)
		)
		(fill yes)
		(layer "F.Cu")
		(net "P5V_AUX")
	)
	(gr_poly
		(pts
			(xy 68.344034 -29.456888) (xy 68.8848 -29.456888) (xy 69.4055 -28.936188) (xy 69.4055 -28.2067) (xy 69.1134 -27.9146)
			(xy 68.259452 -27.9146) (xy 67.8561 -28.317952) (xy 67.8561 -28.32354) (xy 67.850766 -28.32354) (xy 67.7672 -28.406852)
			(xy 67.129406 -28.406852) (xy 67.030854 -28.505404) (xy 67.030854 -28.800806) (xy 66.591942 -29.239718)
			(xy 66.591942 -30.37205) (xy 66.628772 -30.40888) (xy 67.392042 -30.40888)
		)
		(stroke
			(width 0)
			(type solid)
		)
		(fill yes)
		(layer "F.Cu")
		(net "EN_P3V3_RGM_R")
	)
	(gr_poly
		(pts
			(xy 77.978 -81.9404) (xy 77.978 -80.6704) (xy 77.7494 -80.4418) (xy 77.7494 -78.8924) (xy 78.105 -78.5368)
			(xy 78.105 -78.232) (xy 77.9272 -78.0542) (xy 77.597 -78.0542) (xy 77.0636 -78.0542) (xy 76.5048 -78.613)
			(xy 76.2762 -78.613) (xy 76.0222 -78.867) (xy 76.0222 -79.7052) (xy 76.6064 -80.2894) (xy 76.6064 -81.8642)
			(xy 76.7588 -82.0166) (xy 77.9018 -82.0166)
		)
		(stroke
			(width 0)
			(type solid)
		)
		(fill yes)
		(layer "F.Cu")
		(net "P3V3_LDO")
	)
	(gr_poly
		(pts
			(xy 83.220814 -32.395922) (xy 83.220814 -31.509716) (xy 83.64855 -31.08198) (xy 83.824318 -31.08198)
			(xy 83.990688 -30.91561) (xy 83.990688 -29.512006) (xy 83.990688 -29.235908) (xy 83.987132 -29.232352)
			(xy 83.874102 -29.119322) (xy 83.598004 -29.119322) (xy 83.144614 -29.119322) (xy 82.151982 -29.119322)
			(xy 82.027014 -29.24429) (xy 82.027014 -31.430722) (xy 82.027014 -32.370522) (xy 82.103214 -32.446722)
			(xy 83.170014 -32.446722)
		)
		(stroke
			(width 0)
			(type solid)
		)
		(fill yes)
		(layer "F.Cu")
		(net "P3V3_AUX")
	)
	(gr_poly
		(pts
			(xy 6.06679 -48.40097) (xy 6.06679 -48.0822) (xy 5.309362 -47.324772) (xy 4.021328 -47.324772) (xy 3.995928 -47.350172)
			(xy 3.995928 -47.35068) (xy 3.96494 -47.381668) (xy 3.96494 -47.817024) (xy 4.016248 -47.867824)
			(xy 4.019042 -47.867824) (xy 4.024122 -47.873412) (xy 4.901692 -47.873412) (xy 5.24002 -48.21174)
			(xy 5.24002 -48.43526) (xy 5.259324 -48.454564) (xy 5.265166 -48.454564) (xy 5.268214 -48.45812)
			(xy 6.00964 -48.45812)
		)
		(stroke
			(width 0)
			(type solid)
		)
		(fill yes)
		(layer "F.Cu")
		(net "P5V_AUX_VCC")
	)
	(gr_poly
		(pts
			(xy 71.628 -32.385) (xy 71.628 -31.75) (xy 71.755 -31.623) (xy 71.755 -30.0355) (xy 71.6915 -29.972)
			(xy 70.993 -29.972) (xy 70.2056 -29.972) (xy 70.1294 -30.0482) (xy 70.1294 -30.4292) (xy 70.1802 -30.48)
			(xy 70.809612 -30.48) (xy 70.936612 -30.607) (xy 70.936612 -30.794452) (xy 70.936612 -30.946852)
			(xy 70.936612 -31.378652) (xy 70.936612 -32.455612) (xy 70.993 -32.512) (xy 71.501 -32.512)
		)
		(stroke
			(width 0)
			(type solid)
		)
		(fill yes)
		(layer "F.Cu")
		(net "PWRGD_P3V3_RGM_R")
	)
	(gr_poly
		(pts
			(xy 74.419714 -36.414202)
			(arc
				(start 74.414126 -36.387532)
				(mid 74.407439 -36.343179)
				(end 74.405236 -36.298378)
			)
			(xy 74.405236 -36.026852) (xy 74.31532 -35.93719) (xy 73.642474 -35.93719) (xy 73.320148 -35.614864)
			(xy 73.320148 -35.360102) (xy 72.860662 -34.900616) (xy 72.482456 -34.900616) (xy 72.411336 -34.971736)
			(xy 72.411336 -36.516564) (xy 72.643746 -36.74872) (xy 73.746868 -36.74872) (xy 73.75017 -36.752276)
			(xy 74.08164 -36.752276)
		)
		(stroke
			(width 0)
			(type solid)
		)
		(fill yes)
		(layer "F.Cu")
		(net "P1V2_AUX")
	)
	(gr_poly
		(pts
			(xy 82.461354 -72.022716) (xy 82.461354 -71.637906) (xy 82.461354 -71.320914) (xy 82.461354 -70.53072)
			(xy 82.73796 -70.254114) (xy 82.73796 -69.82968) (xy 82.701384 -69.793104) (xy 82.369914 -69.793104)
			(xy 82.204052 -69.793104) (xy 82.131916 -69.86524) (xy 82.131916 -70.518274) (xy 82.13725 -70.523608)
			(xy 82.13725 -71.143876) (xy 82.13725 -71.204328) (xy 82.13725 -71.745856) (xy 82.13725 -72.059546)
			(xy 82.168746 -72.091042) (xy 82.393028 -72.091042)
		)
		(stroke
			(width 0)
			(type solid)
		)
		(fill yes)
		(layer "F.Cu")
		(net "SW_P1V2_AUX_BST")
	)
	(gr_poly
		(pts
			(xy 37.490654 -57.1754) (xy 37.490654 -52.611274) (xy 37.215064 -52.335684) (xy 36.257992 -52.335684)
			(xy 36.125404 -52.203096) (xy 32.951166 -52.203096) (xy 32.639762 -52.5145) (xy 32.639762 -52.634642)
			(xy 32.639762 -53.973984) (xy 32.712152 -54.046374) (xy 34.036508 -54.046374) (xy 34.163254 -53.919628)
			(xy 34.163254 -53.196236) (xy 34.315654 -53.043836) (xy 35.53206 -53.043836) (xy 35.814254 -53.32603)
			(xy 35.814254 -57.201054) (xy 35.8648 -57.2516) (xy 37.414454 -57.2516)
		)
		(stroke
			(width 0)
			(type solid)
		)
		(fill yes)
		(layer "F.Cu")
		(net "GND")
	)
	(gr_poly
		(pts
			(xy 21.208492 -39.548308) (xy 21.208492 -38.88359) (xy 21.209 -38.883336) (xy 21.209 -38.862) (xy 22.238716 -37.832284)
			(xy 22.238716 -37.072316) (xy 21.4376 -36.2712) (xy 21.4376 -35.687) (xy 20.038822 -34.288222) (xy 20.038822 -32.160464)
			(xy 20.00758 -32.129222) (xy 19.72691 -32.129222) (xy 19.699478 -32.156654) (xy 19.699478 -32.70377)
			(xy 19.394424 -33.008824) (xy 19.394424 -38.444424) (xy 19.8374 -38.8874) (xy 19.8374 -39.7002) (xy 20.0914 -39.9542)
			(xy 20.8026 -39.9542)
		)
		(stroke
			(width 0)
			(type solid)
		)
		(fill yes)
		(layer "F.Cu")
		(net "SW_P1V0_AUX_FLT")
	)
	(gr_poly
		(pts
			(arc
				(start 39.105586 -55.606442)
				(mid 39.146752 -55.571932)
				(end 39.193216 -55.544974)
			)
			(xy 39.20109 -55.541164) (xy 39.313612 -55.428388) (xy 39.313612 -55.42534) (xy 39.317168 -55.42534)
			(xy 39.322502 -55.419752) (xy 39.939722 -55.419752) (xy 39.940992 -55.421022) (xy 40.130984 -55.421022)
			(xy 40.157654 -55.394352) (xy 40.157654 -52.85486) (xy 39.6748 -52.372006) (xy 37.859208 -52.372006)
			(xy 37.770054 -52.46116) (xy 37.770054 -55.990236) (xy 37.846254 -56.066436) (xy 38.645592 -56.066436)
		)
		(stroke
			(width 0)
			(type solid)
		)
		(fill yes)
		(layer "F.Cu")
		(net "P1V8_AUX")
	)
	(gr_poly
		(pts
			(arc
				(start 73.574656 -38.468046)
				(mid 73.614747 -38.420413)
				(end 73.662032 -38.379908)
			)
			(xy 73.665334 -38.377368) (xy 73.689972 -38.35273) (xy 73.689972 -37.051996) (xy 73.662032 -37.023802)
			(xy 73.641458 -37.003228) (xy 72.020684 -37.003228) (xy 71.611744 -37.412168) (xy 71.608188 -37.412168)
			(xy 71.605648 -37.414708) (xy 70.743318 -37.414708) (xy 70.743064 -37.415216) (xy 68.794376 -37.415216)
			(xy 68.742052 -37.467286) (xy 68.742052 -38.448996) (xy 68.892928 -38.599618) (xy 73.443084 -38.599618)
		)
		(stroke
			(width 0)
			(type solid)
		)
		(fill yes)
		(layer "F.Cu")
		(net "P1V0_STBY_PLAVDD")
	)
	(gr_poly
		(pts
			(xy 66.0908 -67.77736) (xy 66.0908 -67.47764) (xy 65.970912 -67.357752) (xy 65.947036 -67.359784)
			(arc
				(start 65.913 -67.361308)
				(mid 65.820028 -67.34987)
				(end 65.73266 -67.316096)
			)
			(xy 65.721484 -67.31) (xy 65.6844 -67.31) (xy 65.49898 -67.12458) (xy 65.49898 -66.87058) (xy 65.16878 -66.54038)
			(xy 64.01308 -66.54038) (xy 63.96736 -66.5861) (xy 63.96736 -67.28714) (xy 64.28486 -67.60464) (xy 64.70396 -67.60464)
			(xy 65.0113 -67.91198) (xy 65.95618 -67.91198)
		)
		(stroke
			(width 0)
			(type solid)
		)
		(fill yes)
		(layer "F.Cu")
		(net "PGPPA_BMC_AUX_L")
	)
	(gr_poly
		(pts
			(xy 87.89162 -34.125662) (xy 87.89162 -29.48178) (xy 87.503762 -29.093922) (xy 86.36889 -29.093922)
			(xy 86.155022 -29.093922) (xy 86.065614 -29.093922) (xy 84.61502 -29.093922) (xy 84.512912 -29.19603)
			(xy 84.512912 -30.948884) (xy 84.63915 -31.075122) (xy 85.379814 -31.075122) (xy 85.532214 -31.227522)
			(xy 85.532214 -32.573722) (xy 85.379814 -32.726122) (xy 81.383632 -32.726122) (xy 81.328514 -32.78124)
			(xy 81.328514 -34.372804) (xy 81.358232 -34.402522) (xy 86.014814 -34.402522) (xy 86.436708 -34.402522)
			(xy 87.61476 -34.402522)
		)
		(stroke
			(width 0)
			(type solid)
		)
		(fill yes)
		(layer "F.Cu")
		(net "GND")
	)
	(gr_poly
		(pts
			(xy 70.694042 -32.856424) (xy 70.694042 -32.572706) (xy 70.682104 -32.561022) (xy 70.682104 -30.992064)
			(xy 70.5739 -30.88386) (xy 69.64299 -30.88386) (xy 69.2785 -31.24835) (xy 69.153278 -31.24835)
			(arc
				(start 69.144388 -31.251652)
				(mid 69.066962 -31.273286)
				(end 68.986908 -31.280608)
			)
			(arc
				(start 68.986908 -31.280608)
				(mid 68.906859 -31.273256)
				(end 68.829428 -31.251652)
			)
			(xy 68.820538 -31.24835) (xy 68.729098 -31.24835) (xy 68.482972 -31.494476) (xy 68.482972 -32.79902)
			(xy 68.594986 -32.911034) (xy 70.639432 -32.911034)
		)
		(stroke
			(width 0)
			(type solid)
		)
		(fill yes)
		(layer "F.Cu")
		(net "P3V3_RGM")
	)
	(gr_poly
		(pts
			(arc
				(start 14.451076 -114.387376)
				(mid 14.24178 -114.387376)
				(end 14.451076 -114.387376)
			)
		)
		(stroke
			(width 0)
			(type solid)
		)
		(fill yes)
		(layer "F.Cu")
		(net "GND")
	)
	(gr_poly
		(pts
			(arc
				(start 16.005048 -114.4778)
				(mid 15.795752 -114.4778)
				(end 16.005048 -114.4778)
			)
		)
		(stroke
			(width 0)
			(type solid)
		)
		(fill yes)
		(layer "F.Cu")
		(net "GND")
	)
	(gr_poly
		(pts
			(arc
				(start 24.89708 -85.225636)
				(mid 24.687784 -85.225636)
				(end 24.89708 -85.225636)
			)
		)
		(stroke
			(width 0)
			(type solid)
		)
		(fill yes)
		(layer "F.Cu")
		(net "GND")
	)
	(gr_poly
		(pts
			(arc
				(start 32.438848 -99.7204)
				(mid 32.229552 -99.7204)
				(end 32.438848 -99.7204)
			)
		)
		(stroke
			(width 0)
			(type solid)
		)
		(fill yes)
		(layer "F.Cu")
		(net "GND")
	)
	(gr_poly
		(pts
			(arc
				(start 35.740848 -100.3554)
				(mid 35.531552 -100.3554)
				(end 35.740848 -100.3554)
			)
		)
		(stroke
			(width 0)
			(type solid)
		)
		(fill yes)
		(layer "F.Cu")
		(net "GND")
	)
	(gr_poly
		(pts
			(xy 38.202616 -36.282884) (xy 38.202616 -35.888422) (xy 38.23716 -35.853878) (xy 38.23716 -35.836352)
			(xy 38.3921 -35.681412) (xy 38.926516 -35.681412) (xy 38.947344 -35.660584) (xy 38.947344 -35.319462)
			(xy 38.632892 -35.00501) (xy 38.632892 -34.59099) (xy 38.721284 -34.502852) (xy 38.721284 -34.454846)
			(xy 38.786562 -34.389568) (xy 38.786562 -34.105088) (xy 38.6461 -33.964626) (xy 37.648134 -33.964626)
			(xy 36.46678 -35.14598) (xy 35.73272 -35.14598) (xy 35.6616 -35.2171) (xy 35.6616 -35.8267) (xy 35.81146 -35.97656)
			(xy 37.29228 -35.97656) (xy 37.65296 -36.33724) (xy 38.14826 -36.33724)
		)
		(stroke
			(width 0)
			(type solid)
		)
		(fill yes)
		(layer "F.Cu")
		(net "P3V3_P1V8_I2C_I3C")
	)
	(gr_poly
		(pts
			(arc
				(start 39.957248 -97.9678)
				(mid 39.747952 -97.9678)
				(end 39.957248 -97.9678)
			)
		)
		(stroke
			(width 0)
			(type solid)
		)
		(fill yes)
		(layer "F.Cu")
		(net "GND")
	)
	(gr_poly
		(pts
			(arc
				(start 40.054276 -98.831908)
				(mid 39.84498 -98.831908)
				(end 40.054276 -98.831908)
			)
		)
		(stroke
			(width 0)
			(type solid)
		)
		(fill yes)
		(layer "F.Cu")
		(net "GND")
	)
	(gr_poly
		(pts
			(arc
				(start 41.84142 -98.831908)
				(mid 41.632124 -98.831908)
				(end 41.84142 -98.831908)
			)
		)
		(stroke
			(width 0)
			(type solid)
		)
		(fill yes)
		(layer "F.Cu")
		(net "GND")
	)
	(gr_poly
		(pts
			(arc
				(start 45.083476 -98.400108)
				(mid 44.87418 -98.400108)
				(end 45.083476 -98.400108)
			)
		)
		(stroke
			(width 0)
			(type solid)
		)
		(fill yes)
		(layer "F.Cu")
		(net "GND")
	)
	(gr_poly
		(pts
			(arc
				(start 46.87062 -98.400108)
				(mid 46.661324 -98.400108)
				(end 46.87062 -98.400108)
			)
		)
		(stroke
			(width 0)
			(type solid)
		)
		(fill yes)
		(layer "F.Cu")
		(net "GND")
	)
	(gr_poly
		(pts
			(arc
				(start 51.712368 -105.758234)
				(mid 51.503072 -105.758234)
				(end 51.712368 -105.758234)
			)
		)
		(stroke
			(width 0)
			(type solid)
		)
		(fill yes)
		(layer "F.Cu")
		(net "GND")
	)
	(gr_poly
		(pts
			(arc
				(start 53.918358 -112.90808)
				(mid 53.709062 -112.90808)
				(end 53.918358 -112.90808)
			)
		)
		(stroke
			(width 0)
			(type solid)
		)
		(fill yes)
		(layer "F.Cu")
		(net "GND")
	)
	(gr_poly
		(pts
			(arc
				(start 55.152798 -103.5431)
				(mid 54.943502 -103.5431)
				(end 55.152798 -103.5431)
			)
		)
		(stroke
			(width 0)
			(type solid)
		)
		(fill yes)
		(layer "F.Cu")
		(net "GND")
	)
	(gr_poly
		(pts
			(arc
				(start 55.498238 -112.90808)
				(mid 55.288942 -112.90808)
				(end 55.498238 -112.90808)
			)
		)
		(stroke
			(width 0)
			(type solid)
		)
		(fill yes)
		(layer "F.Cu")
		(net "GND")
	)
	(gr_poly
		(pts
			(arc
				(start 56.549798 -103.5431)
				(mid 56.340502 -103.5431)
				(end 56.549798 -103.5431)
			)
		)
		(stroke
			(width 0)
			(type solid)
		)
		(fill yes)
		(layer "F.Cu")
		(net "GND")
	)
	(gr_poly
		(pts
			(arc
				(start 62.410848 -113.2332)
				(mid 62.201552 -113.2332)
				(end 62.410848 -113.2332)
			)
		)
		(stroke
			(width 0)
			(type solid)
		)
		(fill yes)
		(layer "F.Cu")
		(net "GND")
	)
	(gr_poly
		(pts
			(arc
				(start 62.639448 -76.1238)
				(mid 62.430152 -76.1238)
				(end 62.639448 -76.1238)
			)
		)
		(stroke
			(width 0)
			(type solid)
		)
		(fill yes)
		(layer "F.Cu")
		(net "GND")
	)
	(gr_poly
		(pts
			(arc
				(start 67.719448 -76.327)
				(mid 67.510152 -76.327)
				(end 67.719448 -76.327)
			)
		)
		(stroke
			(width 0)
			(type solid)
		)
		(fill yes)
		(layer "F.Cu")
		(net "GND")
	)
	(gr_poly
		(pts
			(arc
				(start 67.744848 -110.7186)
				(mid 67.535552 -110.7186)
				(end 67.744848 -110.7186)
			)
		)
		(stroke
			(width 0)
			(type solid)
		)
		(fill yes)
		(layer "F.Cu")
		(net "GND")
	)
	(gr_poly
		(pts
			(arc
				(start 69.065648 -113.4872)
				(mid 68.856352 -113.4872)
				(end 69.065648 -113.4872)
			)
		)
		(stroke
			(width 0)
			(type solid)
		)
		(fill yes)
		(layer "F.Cu")
		(net "GND")
	)
	(gr_poly
		(pts
			(arc
				(start 69.218048 -100.6602)
				(mid 69.008752 -100.6602)
				(end 69.218048 -100.6602)
			)
		)
		(stroke
			(width 0)
			(type solid)
		)
		(fill yes)
		(layer "F.Cu")
		(net "GND")
	)
	(gr_poly
		(pts
			(arc
				(start 70.234048 -96.901)
				(mid 70.024752 -96.901)
				(end 70.234048 -96.901)
			)
		)
		(stroke
			(width 0)
			(type solid)
		)
		(fill yes)
		(layer "F.Cu")
		(net "GND")
	)
	(gr_poly
		(pts
			(arc
				(start 70.767448 -103.8098)
				(mid 70.558152 -103.8098)
				(end 70.767448 -103.8098)
			)
		)
		(stroke
			(width 0)
			(type solid)
		)
		(fill yes)
		(layer "F.Cu")
		(net "GND")
	)
	(gr_poly
		(pts
			(arc
				(start 71.554848 -106.5022)
				(mid 71.345552 -106.5022)
				(end 71.554848 -106.5022)
			)
		)
		(stroke
			(width 0)
			(type solid)
		)
		(fill yes)
		(layer "F.Cu")
		(net "GND")
	)
	(gr_poly
		(pts
			(arc
				(start 72.396604 -98.332544)
				(mid 72.187308 -98.332544)
				(end 72.396604 -98.332544)
			)
		)
		(stroke
			(width 0)
			(type solid)
		)
		(fill yes)
		(layer "F.Cu")
		(net "GND")
	)
	(gr_poly
		(pts
			(arc
				(start 73.967848 -111.3282)
				(mid 73.758552 -111.3282)
				(end 73.967848 -111.3282)
			)
		)
		(stroke
			(width 0)
			(type solid)
		)
		(fill yes)
		(layer "F.Cu")
		(net "GND")
	)
	(gr_poly
		(pts
			(arc
				(start 82.705448 -97.5106)
				(mid 82.496152 -97.5106)
				(end 82.705448 -97.5106)
			)
		)
		(stroke
			(width 0)
			(type solid)
		)
		(fill yes)
		(layer "F.Cu")
		(net "GND")
	)
	(gr_poly
		(pts
			(arc
				(start 85.321648 -92.2528)
				(mid 85.112352 -92.2528)
				(end 85.321648 -92.2528)
			)
		)
		(stroke
			(width 0)
			(type solid)
		)
		(fill yes)
		(layer "F.Cu")
		(net "GND")
	)
	(gr_poly
		(pts
			(arc
				(start 85.372448 -95.6056)
				(mid 85.163152 -95.6056)
				(end 85.372448 -95.6056)
			)
		)
		(stroke
			(width 0)
			(type solid)
		)
		(fill yes)
		(layer "F.Cu")
		(net "GND")
	)
	(gr_poly
		(pts
			(xy 19.442176 -32.489394) (xy 19.442176 -30.900116) (xy 20.080986 -30.261306) (xy 20.080986 -29.501338)
			(xy 20.31111 -29.271214) (xy 22.112986 -29.271214) (xy 22.225 -29.1592) (xy 22.7584 -29.1592) (xy 22.8346 -29.083)
			(xy 22.8346 -26.924) (xy 22.806152 -26.895552) (xy 17.902936 -26.895552) (xy 17.851374 -26.94686)
			(xy 17.851374 -30.086554) (xy 18.236692 -30.471872)
			(arc
				(start 18.564606 -30.471872)
				(mid 18.623615 -30.476463)
				(end 18.681192 -30.49016)
			)
			(xy 18.688812 -30.4927) (xy 18.980658 -30.4927) (xy 19.206464 -30.718506) (xy 19.206464 -32.483044)
			(xy 19.2278 -32.50438) (xy 19.42719 -32.50438)
		)
		(stroke
			(width 0)
			(type solid)
		)
		(fill yes)
		(layer "F.Cu")
		(net "SW_P1V0_AUX_SW")
	)
	(gr_poly
		(pts
			(xy 6.89102 -49.66208) (xy 6.89102 -49.215802) (xy 6.88467 -49.209452) (xy 6.91261 -49.181512) (xy 6.91261 -46.61535)
			(xy 7.25932 -46.26864) (xy 7.26186 -46.26864) (xy 7.29742 -46.23308) (xy 9.692894 -46.23308) (xy 9.951212 -46.491398)
			(xy 9.951212 -46.510194) (xy 9.95172 -46.510448) (xy 9.95172 -47.03064) (xy 9.992868 -47.071788)
			(xy 10.441432 -47.071788) (xy 10.691368 -46.822106) (xy 10.691368 -42.60723) (xy 10.518648 -42.43451)
			(xy 5.19049 -42.43451) (xy 5.050028 -42.574972) (xy 5.050028 -46.194472) (xy 5.920994 -47.065184)
			(xy 6.61035 -47.75454) (xy 6.61035 -49.66589) (xy 6.61162 -49.66716) (xy 6.88594 -49.66716)
		)
		(stroke
			(width 0)
			(type solid)
		)
		(fill yes)
		(layer "F.Cu")
		(net "SW_P5V_AUX_SW")
	)
	(gr_poly
		(pts
			(xy 9.0424 -70.0532) (xy 9.0424 -67.94373) (xy 8.9408 -67.84213) (xy 7.44093 -67.84213) (xy 7.3152 -67.7164)
			(xy 7.3152 -66.9798) (xy 7.41807 -66.87693) (xy 7.41807 -66.487802) (xy 7.417816 -66.4718) (xy 7.417816 -65.636902)
			(xy 7.41807 -65.6209) (xy 7.41807 -64.90589) (xy 7.4168 -64.90462) (xy 7.4168 -63.503048) (xy 7.37997 -63.466218)
			(xy 7.21741 -63.466218) (xy 7.18693 -63.496698) (xy 7.18693 -66.173858) (xy 6.911594 -66.449194)
			(xy 6.453124 -66.449194) (xy 6.1722 -66.730118) (xy 5.57657 -66.730118) (xy 5.38607 -66.920618) (xy 5.38607 -70.07987)
			(xy 5.461 -70.1548) (xy 8.9408 -70.1548)
		)
		(stroke
			(width 0)
			(type solid)
		)
		(fill yes)
		(layer "F.Cu")
		(net "SW_P3V3_AUX_SW")
	)
	(gr_poly
		(pts
			(arc
				(start 78.480412 -54.401212)
				(mid 78.217268 -54.401212)
				(end 78.480412 -54.401212)
			)
		)
		(stroke
			(width 0)
			(type solid)
		)
		(fill yes)
		(layer "F.Cu")
		(net "GND")
	)
	(gr_poly
		(pts
			(xy 8.86714 -48.257968) (xy 8.86714 -47.818802) (xy 9.697212 -46.98873) (xy 9.697212 -46.615858)
			(xy 9.643618 -46.562264) (xy 9.17321 -46.562264) (xy 9.119616 -46.615858) (xy 9.119616 -46.838616)
			(xy 8.828532 -47.1297)
			(arc
				(start 8.827516 -47.149004)
				(mid 8.789209 -47.305358)
				(end 8.697722 -47.437802)
			)
			(arc
				(start 8.422132 -47.713392)
				(mid 8.28967 -47.804839)
				(end 8.133334 -47.843186)
			)
			(xy 8.11403 -47.844202) (xy 7.9502 -48.008032) (xy 7.9502 -48.43526) (xy 8.689848 -48.43526)
		)
		(stroke
			(width 0)
			(type solid)
		)
		(fill yes)
		(layer "F.Cu")
		(net "SW_P5V_AUX_BST")
	)
	(gr_poly
		(pts
			(xy 16.788892 -70.612508) (xy 16.788892 -70.02399) (xy 17.11579 -69.697092) (xy 18.29181 -69.697092)
			(xy 18.44421 -69.849492) (xy 19.151854 -69.849492) (xy 19.252692 -69.748654) (xy 19.252692 -69.56679)
			(xy 19.2786 -69.541136) (xy 19.2786 -69.3166) (xy 19.4818 -69.1134) (xy 19.6088 -69.1134) (xy 19.684492 -69.037454)
			(xy 19.684492 -68.93179) (xy 19.7104 -68.906136) (xy 19.7104 -68.3895) (xy 19.562318 -68.241418)
			(arc
				(start 19.527774 -68.263516)
				(mid 19.446569 -68.300917)
				(end 19.358102 -68.313808)
			)
			(xy 16.268192 -68.313808) (xy 15.2908 -69.2912) (xy 15.2908 -70.5104) (xy 15.4178 -70.6374) (xy 16.764 -70.6374)
		)
		(stroke
			(width 0)
			(type solid)
		)
		(fill yes)
		(layer "F.Cu")
		(net "GND")
	)
	(gr_poly
		(pts
			(xy 22.702012 -78.86446) (xy 22.702012 -75.99934) (xy 22.13864 -75.435968)
			(arc
				(start 20.968462 -75.435968)
				(mid 20.905932 -75.430508)
				(end 20.845272 -75.414378)
			)
			(xy 20.83689 -75.41133) (xy 19.096228 -75.41133) (xy 19.039586 -75.467972)
			(arc
				(start 19.195034 -75.623166)
				(mid 19.26291 -75.724655)
				(end 19.286728 -75.8444)
			)
			(arc
				(start 19.286728 -76.835)
				(mid 19.262893 -76.954738)
				(end 19.195034 -77.056234)
			)
			(xy 18.927064 -77.324204) (xy 18.927064 -79.031592) (xy 19.408902 -79.51343) (xy 22.053296 -79.51343)
		)
		(stroke
			(width 0)
			(type solid)
		)
		(fill yes)
		(layer "F.Cu")
		(net "GND")
	)
	(gr_poly
		(pts
			(arc
				(start 60.754514 -59.856116)
				(mid 60.469526 -59.856116)
				(end 60.754514 -59.856116)
			)
		)
		(stroke
			(width 0)
			(type solid)
		)
		(fill yes)
		(layer "F.Cu")
		(net "GND")
	)
	(gr_poly
		(pts
			(arc
				(start 66.25082 -52.668932)
				(mid 65.965832 -52.668932)
				(end 66.25082 -52.668932)
			)
		)
		(stroke
			(width 0)
			(type solid)
		)
		(fill yes)
		(layer "F.Cu")
		(net "GND")
	)
	(gr_poly
		(pts
			(arc
				(start 66.50482 -54.522878)
				(mid 66.219832 -54.522878)
				(end 66.50482 -54.522878)
			)
		)
		(stroke
			(width 0)
			(type solid)
		)
		(fill yes)
		(layer "F.Cu")
		(net "GND")
	)
	(gr_poly
		(pts
			(arc
				(start 66.914014 -45.460158)
				(mid 66.629026 -45.460158)
				(end 66.914014 -45.460158)
			)
		)
		(stroke
			(width 0)
			(type solid)
		)
		(fill yes)
		(layer "F.Cu")
		(net "GND")
	)
	(gr_poly
		(pts
			(arc
				(start 68.313808 -52.644548)
				(mid 68.02882 -52.644548)
				(end 68.313808 -52.644548)
			)
		)
		(stroke
			(width 0)
			(type solid)
		)
		(fill yes)
		(layer "F.Cu")
		(net "GND")
	)
	(gr_poly
		(pts
			(arc
				(start 68.344034 -45.488352)
				(mid 68.059046 -45.488352)
				(end 68.344034 -45.488352)
			)
		)
		(stroke
			(width 0)
			(type solid)
		)
		(fill yes)
		(layer "F.Cu")
		(net "GND")
	)
	(gr_poly
		(pts
			(arc
				(start 68.567808 -54.506622)
				(mid 68.28282 -54.506622)
				(end 68.567808 -54.506622)
			)
		)
		(stroke
			(width 0)
			(type solid)
		)
		(fill yes)
		(layer "F.Cu")
		(net "GND")
	)
	(gr_poly
		(pts
			(arc
				(start 75.674982 -49.940464)
				(mid 75.389994 -49.940464)
				(end 75.674982 -49.940464)
			)
		)
		(stroke
			(width 0)
			(type solid)
		)
		(fill yes)
		(layer "F.Cu")
		(net "GND")
	)
	(gr_poly
		(pts
			(arc
				(start 77.343254 -54.016656)
				(mid 77.058266 -54.016656)
				(end 77.343254 -54.016656)
			)
		)
		(stroke
			(width 0)
			(type solid)
		)
		(fill yes)
		(layer "F.Cu")
		(net "GND")
	)
	(gr_poly
		(pts
			(arc
				(start 79.176626 -47.125636)
				(mid 78.891638 -47.125636)
				(end 79.176626 -47.125636)
			)
		)
		(stroke
			(width 0)
			(type solid)
		)
		(fill yes)
		(layer "F.Cu")
		(net "GND")
	)
	(gr_poly
		(pts
			(xy 8.0264 -57.7596) (xy 8.0264 -55.73141) (xy 7.51459 -55.2196) (xy 7.51459 -52.911502) (xy 7.51459 -52.409852)
			(xy 7.51459 -51.60264) (xy 7.51459 -47.32401) (xy 7.85876 -46.97984) (xy 7.85876 -46.56582) (xy 7.81812 -46.52518)
			(xy 7.38378 -46.52518) (xy 7.207504 -46.701456) (xy 7.207504 -47.192184) (xy 7.20471 -47.195232)
			(xy 7.20471 -49.34966) (xy 7.20471 -50.14341) (xy 7.08406 -50.26406) (xy 6.51764 -50.26406) (xy 6.381242 -50.400458)
			(xy 6.381242 -52.125118) (xy 5.993892 -52.512468) (xy 5.993892 -56.028082) (xy 5.996432 -56.030622)
			(xy 6.45668 -56.49087) (xy 7.1628 -57.19699) (xy 7.1628 -57.59958) (xy 7.1628 -57.7596) (xy 7.1882 -57.785)
			(xy 8.001 -57.785)
		)
		(stroke
			(width 0)
			(type solid)
		)
		(fill yes)
		(layer "F.Cu")
		(net "SW_P5V_AUX_FLT")
	)
	(gr_poly
		(pts
			(arc
				(start 21.053552 -113.181638)
				(mid 20.732496 -113.181638)
				(end 21.053552 -113.181638)
			)
		)
		(stroke
			(width 0)
			(type solid)
		)
		(fill yes)
		(layer "F.Cu")
		(net "GND")
	)
	(gr_poly
		(pts
			(arc
				(start 21.820632 -113.1697)
				(mid 21.499576 -113.1697)
				(end 21.820632 -113.1697)
			)
		)
		(stroke
			(width 0)
			(type solid)
		)
		(fill yes)
		(layer "F.Cu")
		(net "GND")
	)
	(gr_poly
		(pts
			(arc
				(start 23.528782 -114.402108)
				(mid 23.207726 -114.402108)
				(end 23.528782 -114.402108)
			)
		)
		(stroke
			(width 0)
			(type solid)
		)
		(fill yes)
		(layer "F.Cu")
		(net "GND")
	)
	(gr_poly
		(pts
			(arc
				(start 24.838152 -114.410998)
				(mid 24.517096 -114.410998)
				(end 24.838152 -114.410998)
			)
		)
		(stroke
			(width 0)
			(type solid)
		)
		(fill yes)
		(layer "F.Cu")
		(net "GND")
	)
	(gr_poly
		(pts
			(xy 7.95147 -64.787018) (xy 7.95147 -64.094614)
			(arc
				(start 7.947406 -64.085216)
				(mid 7.92514 -64.012661)
				(end 7.917688 -63.937134)
			)
			(arc
				(start 7.917688 -63.303912)
				(mid 7.92615 -63.22378)
				(end 7.951216 -63.147194)
			)
			(xy 7.955788 -63.137034) (xy 7.955788 -62.74181) (xy 8.818372 -61.878972) (xy 9.190228 -61.878972)
			(xy 10.0076 -61.0616) (xy 10.0076 -60.6044) (xy 9.445498 -60.042298) (xy 9.445498 -57.106058) (xy 9.356852 -57.017412)
			(xy 8.532622 -57.017412) (xy 8.478266 -57.071768) (xy 8.478266 -57.688734) (xy 7.407148 -58.759852)
			(xy 7.407148 -63.057024) (xy 7.671308 -63.321184) (xy 7.671308 -64.800988) (xy 7.682484 -64.812418)
			(xy 7.92607 -64.812418)
		)
		(stroke
			(width 0)
			(type solid)
		)
		(fill yes)
		(layer "F.Cu")
		(net "SW_P3V3_AUX_FLT")
	)
	(gr_poly
		(pts
			(xy 40.10533 -36.39947) (xy 40.10533 -36.138612)
			(arc
				(start 40.080438 -36.11372)
				(mid 39.986681 -35.973542)
				(end 39.953692 -35.808158)
			)
			(xy 39.953692 -34.29)
			(arc
				(start 39.9542 -34.271458)
				(mid 39.926018 -34.196776)
				(end 39.8526 -34.16554)
			)
			(xy 39.41826 -34.16554) (xy 38.8874 -34.6964) (xy 38.8874 -34.8996) (xy 39.201852 -35.214052) (xy 39.201852 -35.85845)
			(xy 39.124128 -35.936174) (xy 38.514528 -35.936174) (xy 38.45687 -35.993832) (xy 38.45687 -36.376356)
			(xy 38.526974 -36.44646) (xy 40.05834 -36.44646)
		)
		(stroke
			(width 0)
			(type solid)
		)
		(fill yes)
		(layer "F.Cu")
		(net "P1V8_AUX")
	)
	(gr_poly
		(pts
			(arc
				(start 40.528494 -23.869904)
				(mid 40.17899 -23.869904)
				(end 40.528494 -23.869904)
			)
		)
		(stroke
			(width 0)
			(type solid)
		)
		(fill yes)
		(layer "F.Cu")
		(net "GND")
	)
	(gr_poly
		(pts
			(arc
				(start 41.939718 -23.873714)
				(mid 41.590214 -23.873714)
				(end 41.939718 -23.873714)
			)
		)
		(stroke
			(width 0)
			(type solid)
		)
		(fill yes)
		(layer "F.Cu")
		(net "GND")
	)
	(gr_poly
		(pts
			(arc
				(start 42.92219 -23.869904)
				(mid 42.572686 -23.869904)
				(end 42.92219 -23.869904)
			)
		)
		(stroke
			(width 0)
			(type solid)
		)
		(fill yes)
		(layer "F.Cu")
		(net "GND")
	)
	(gr_poly
		(pts
			(arc
				(start 44.333414 -23.873714)
				(mid 43.98391 -23.873714)
				(end 44.333414 -23.873714)
			)
		)
		(stroke
			(width 0)
			(type solid)
		)
		(fill yes)
		(layer "F.Cu")
		(net "GND")
	)
	(gr_poly
		(pts
			(arc
				(start 45.979334 -29.030168)
				(mid 45.62983 -29.030168)
				(end 45.979334 -29.030168)
			)
		)
		(stroke
			(width 0)
			(type solid)
		)
		(fill yes)
		(layer "F.Cu")
		(net "GND")
	)
	(gr_poly
		(pts
			(arc
				(start 50.538126 -25.726644)
				(mid 50.188622 -25.726644)
				(end 50.538126 -25.726644)
			)
		)
		(stroke
			(width 0)
			(type solid)
		)
		(fill yes)
		(layer "F.Cu")
		(net "GND")
	)
	(gr_poly
		(pts
			(arc
				(start 95.338138 -96.259142)
				(mid 94.99219 -96.259142)
				(end 95.338138 -96.259142)
			)
		)
		(stroke
			(width 0)
			(type solid)
		)
		(fill yes)
		(layer "F.Cu")
		(net "GND_P1")
	)
	(gr_poly
		(pts
			(arc
				(start 95.416624 -18.075656)
				(mid 95.070676 -18.075656)
				(end 95.416624 -18.075656)
			)
		)
		(stroke
			(width 0)
			(type solid)
		)
		(fill yes)
		(layer "F.Cu")
		(net "GND_P1")
	)
	(gr_poly
		(pts
			(arc
				(start 96.767396 -96.22028)
				(mid 96.421448 -96.22028)
				(end 96.767396 -96.22028)
			)
		)
		(stroke
			(width 0)
			(type solid)
		)
		(fill yes)
		(layer "F.Cu")
		(net "GND_P1")
	)
	(gr_poly
		(pts
			(arc
				(start 96.845882 -18.036794)
				(mid 96.499934 -18.036794)
				(end 96.845882 -18.036794)
			)
		)
		(stroke
			(width 0)
			(type solid)
		)
		(fill yes)
		(layer "F.Cu")
		(net "GND_P1")
	)
	(gr_poly
		(pts
			(arc
				(start 95.355156 -2.464054)
				(mid 94.975172 -2.464054)
				(end 95.355156 -2.464054)
			)
		)
		(stroke
			(width 0)
			(type solid)
		)
		(fill yes)
		(layer "F.Cu")
		(net "GND_P1")
	)
	(gr_poly
		(pts
			(arc
				(start 95.355156 55.517034)
				(mid 94.975172 55.517034)
				(end 95.355156 55.517034)
			)
		)
		(stroke
			(width 0)
			(type solid)
		)
		(fill yes)
		(layer "F.Cu")
		(net "GND_P1")
	)
	(gr_poly
		(pts
			(arc
				(start 95.42653 39.905432)
				(mid 95.046546 39.905432)
				(end 95.42653 39.905432)
			)
		)
		(stroke
			(width 0)
			(type solid)
		)
		(fill yes)
		(layer "F.Cu")
		(net "GND_P1")
	)
	(gr_poly
		(pts
			(arc
				(start 95.433642 110.58652)
				(mid 95.053658 110.58652)
				(end 95.433642 110.58652)
			)
		)
		(stroke
			(width 0)
			(type solid)
		)
		(fill yes)
		(layer "F.Cu")
		(net "GND_P1")
	)
	(gr_poly
		(pts
			(arc
				(start 96.784414 -2.425192)
				(mid 96.40443 -2.425192)
				(end 96.784414 -2.425192)
			)
		)
		(stroke
			(width 0)
			(type solid)
		)
		(fill yes)
		(layer "F.Cu")
		(net "GND_P1")
	)
	(gr_poly
		(pts
			(arc
				(start 96.784414 55.555896)
				(mid 96.40443 55.555896)
				(end 96.784414 55.555896)
			)
		)
		(stroke
			(width 0)
			(type solid)
		)
		(fill yes)
		(layer "F.Cu")
		(net "GND_P1")
	)
	(gr_poly
		(pts
			(arc
				(start 96.855788 39.944294)
				(mid 96.475804 39.944294)
				(end 96.855788 39.944294)
			)
		)
		(stroke
			(width 0)
			(type solid)
		)
		(fill yes)
		(layer "F.Cu")
		(net "GND_P1")
	)
	(gr_poly
		(pts
			(arc
				(start 96.8629 110.625382)
				(mid 96.482916 110.625382)
				(end 96.8629 110.625382)
			)
		)
		(stroke
			(width 0)
			(type solid)
		)
		(fill yes)
		(layer "F.Cu")
		(net "GND_P1")
	)
	(gr_poly
		(pts
			(arc
				(start 100.71862 31.402782)
				(mid 100.338636 31.402782)
				(end 100.71862 31.402782)
			)
		)
		(stroke
			(width 0)
			(type solid)
		)
		(fill yes)
		(layer "F.Cu")
		(net "GND_P1")
	)
	(gr_poly
		(pts
			(arc
				(start 100.789994 117.206268)
				(mid 100.41001 117.206268)
				(end 100.789994 117.206268)
			)
		)
		(stroke
			(width 0)
			(type solid)
		)
		(fill yes)
		(layer "F.Cu")
		(net "GND_P1")
	)
	(gr_poly
		(pts
			(arc
				(start 102.147878 31.441644)
				(mid 101.767894 31.441644)
				(end 102.147878 31.441644)
			)
		)
		(stroke
			(width 0)
			(type solid)
		)
		(fill yes)
		(layer "F.Cu")
		(net "GND_P1")
	)
	(gr_poly
		(pts
			(arc
				(start 102.219252 117.24513)
				(mid 101.839268 117.24513)
				(end 102.219252 117.24513)
			)
		)
		(stroke
			(width 0)
			(type solid)
		)
		(fill yes)
		(layer "F.Cu")
		(net "GND_P1")
	)
	(gr_poly
		(pts
			(xy 5.714492 -56.032908) (xy 5.714492 -52.238148) (xy 6.08457 -51.86807) (xy 6.08457 -48.73752) (xy 6.059424 -48.712628)
			(xy 5.15747 -48.712628) (xy 5.154168 -48.709072) (xy 5.142992 -48.709072) (xy 4.95046 -48.51654)
			(xy 4.95046 -48.3235) (xy 4.75488 -48.12792) (xy 3.91541 -48.12792) (xy 3.910076 -48.122332) (xy 3.893566 -48.122332)
			(xy 3.741674 -47.97044) (xy 3.741674 -47.95393) (xy 3.710432 -47.922942) (xy 3.710432 -47.27575)
			(xy 3.741674 -47.244762) (xy 3.741674 -31.877762) (xy 3.928364 -31.691072) (xy 4.131564 -31.691072)
			(xy 4.145534 -31.676848) (xy 4.440682 -31.676848) (xy 4.442714 -31.674816) (xy 13.574268 -31.674816)
			(xy 13.730224 -31.51886) (xy 13.730224 -30.399228) (xy 13.569188 -30.238192) (xy 1.601216 -30.238192)
			(xy 1.371092 -30.468316) (xy 1.371092 -55.930292) (xy 1.4986 -56.0578) (xy 5.6896 -56.0578)
		)
		(stroke
			(width 0)
			(type solid)
		)
		(fill yes)
		(layer "F.Cu")
		(net "GND")
	)
	(gr_poly
		(pts
			(xy 7.2644 -79.6544) (xy 12.672568 -79.6544) (xy 13.0302 -79.296768) (xy 13.0302 -78.177644) (xy 12.950444 -78.097888)
			(arc
				(start 12.684252 -78.097888)
				(mid 12.634417 -78.095202)
				(end 12.585192 -78.086966)
			)
			(xy 12.579604 -78.085696) (xy 3.635248 -78.085696) (xy 3.634994 -78.085188) (xy 3.056128 -78.085188)
			(xy 3.046984 -78.076044) (xy 2.981706 -78.076044) (xy 2.6924 -77.786738) (xy 2.6924 -72.712326) (xy 3.343402 -72.061324)
			(xy 3.343402 -64.812164) (xy 3.713988 -64.441578) (xy 5.81025 -64.441578) (xy 6.01599 -64.647318)
			(xy 6.77037 -64.647318) (xy 6.91769 -64.499998) (xy 6.91769 -63.278258) (xy 7.15264 -63.043308) (xy 7.15264 -58.7502)
			(xy 7.05104 -58.6486) (xy 5.162804 -58.6486) (xy 4.838192 -58.973212) (xy 1.529588 -58.973212) (xy 1.405636 -59.097164)
			(xy 1.405636 -79.83982) (xy 1.580134 -80.014318) (xy 6.904482 -80.014318)
		)
		(stroke
			(width 0)
			(type solid)
		)
		(fill yes)
		(layer "F.Cu")
		(net "GND")
	)
	(gr_poly
		(pts
			(arc
				(start 75.686666 -38.665912)
				(mid 75.829677 -38.464588)
				(end 75.981306 -38.269672)
			)
			(xy 75.992736 -38.255702) (xy 75.992736 -37.04971) (xy 75.799696 -36.85667) (xy 74.35215 -36.85667)
			(xy 74.25563 -36.95319)
			(arc
				(start 74.25563 -38.248082)
				(mid 74.306302 -38.335996)
				(end 74.407776 -38.33622)
			)
			(arc
				(start 74.407776 -38.33622)
				(mid 74.499568 -38.298351)
				(end 74.598022 -38.28542)
			)
			(arc
				(start 74.598022 -38.28542)
				(mid 74.858552 -38.388136)
				(end 74.978768 -38.64102)
			)
			(xy 74.981816 -38.688264) (xy 75.671426 -38.688264)
		)
		(stroke
			(width 0)
			(type solid)
		)
		(fill yes)
		(layer "F.Cu")
		(net "P1V0_AUX")
	)
	(gr_poly
		(pts
			(xy 81.540096 -79.012796) (xy 81.540096 -73.232772) (xy 81.378552 -73.071228) (xy 81.378552 -72.97928)
			(xy 81.37652 -72.977502) (xy 81.37652 -72.703182) (xy 81.376012 -72.702674) (xy 81.376012 -72.493124)
			(xy 81.32064 -72.437752) (xy 81.045304 -72.437752) (xy 80.987392 -72.495664) (xy 80.987392 -73.10628)
			(xy 80.78724 -73.306432)
			(arc
				(start 80.358234 -73.306432)
				(mid 80.326221 -73.310583)
				(end 80.293972 -73.31202)
			)
			(xy 79.924656 -73.31202) (xy 79.915004 -73.321672) (xy 79.915004 -73.358756) (xy 79.576676 -73.697084)
			(xy 79.321406 -73.697084) (xy 79.03337 -73.98512) (xy 79.03337 -74.78141)
			(arc
				(start 79.034894 -74.787252)
				(mid 79.042745 -74.831521)
				(end 79.045308 -74.876406)
			)
			(arc
				(start 79.045308 -74.876406)
				(mid 79.042719 -74.921288)
				(end 79.034894 -74.96556)
			)
			(xy 79.03337 -74.971402) (xy 79.03337 -76.197206) (xy 79.03337 -78.70317) (xy 79.463392 -79.133192)
			(xy 79.68234 -79.133192) (xy 81.4197 -79.133192)
		)
		(stroke
			(width 0)
			(type solid)
		)
		(fill yes)
		(layer "F.Cu")
		(net "GND")
	)
	(gr_poly
		(pts
			(arc
				(start 39.80307 -58.494422)
				(mid 39.901776 -58.462341)
				(end 40.005 -58.451496)
			)
			(arc
				(start 40.005 -58.451496)
				(mid 40.084636 -58.457854)
				(end 40.162226 -58.476896)
			)
			(xy 40.191944 -58.487056) (xy 40.259 -58.42) (xy 40.259 -58.039) (xy 40.020748 -57.800748) (xy 40.020748 -57.75706)
			(xy 40.02024 -57.756806) (xy 40.02024 -56.608726) (xy 39.985696 -56.573928) (xy 39.105078 -56.573928)
			(xy 38.89248 -56.786526) (xy 38.816788 -56.786526)
			(arc
				(start 38.810438 -56.788304)
				(mid 38.764586 -56.797117)
				(end 38.717982 -56.799988)
			)
			(arc
				(start 38.218618 -56.799988)
				(mid 38.172014 -56.797121)
				(end 38.126162 -56.788304)
			)
			(xy 38.119812 -56.786526) (xy 37.767514 -56.786526) (xy 37.745924 -56.808116) (xy 37.745924 -57.277)
			(xy 37.744908 -57.278016) (xy 37.744908 -57.28081) (xy 37.719 -57.306718) (xy 37.719 -58.42) (xy 37.79774 -58.49874)
			(xy 39.793164 -58.49874)
		)
		(stroke
			(width 0)
			(type solid)
		)
		(fill yes)
		(layer "F.Cu")
		(net "PWRGD_P1V8_AUX_R")
	)
	(gr_poly
		(pts
			(xy 22.80158 -32.5755) (xy 22.80158 -31.65602) (xy 22.61616 -31.4706) (xy 21.646642 -31.4706)
			(arc
				(start 21.285454 -31.832042)
				(mid 21.264678 -31.851258)
				(end 21.242528 -31.868872)
			)
			(xy 21.209 -31.9024) (xy 21.18868 -31.9024)
			(arc
				(start 21.178266 -31.907226)
				(mid 21.098992 -31.934352)
				(end 21.015706 -31.943548)
			)
			(arc
				(start 20.770088 -31.943548)
				(mid 20.686793 -31.934395)
				(end 20.607528 -31.907226)
			)
			(xy 20.597114 -31.9024) (xy 20.4216 -31.9024) (xy 20.3962 -31.9278) (xy 20.3962 -32.1818) (xy 20.4216 -32.2072)
			(xy 20.630642 -32.2072)
			(arc
				(start 20.639024 -32.204152)
				(mid 20.703527 -32.186689)
				(end 20.770088 -32.180784)
			)
			(arc
				(start 21.360892 -32.180784)
				(mid 21.394294 -32.182249)
				(end 21.42744 -32.186626)
			)
			(xy 21.453348 -32.191452) (xy 21.5392 -32.1056) (xy 21.67128 -32.1056) (xy 22.27072 -32.70504) (xy 22.67204 -32.70504)
		)
		(stroke
			(width 0)
			(type solid)
		)
		(fill yes)
		(layer "F.Cu")
		(net "GND")
	)
	(gr_poly
		(pts
			(xy 11.746484 -67.247516) (xy 11.746484 -64.689736) (xy 11.61034 -64.553592) (xy 10.225024 -64.553592)
			(arc
				(start 9.97204 -64.80683)
				(mid 9.940144 -64.835386)
				(end 9.905238 -64.86017)
			)
			(xy 9.900158 -64.863218) (xy 9.865868 -64.897508) (xy 9.82726 -64.897508)
			(arc
				(start 9.81964 -64.900048)
				(mid 9.761682 -64.913777)
				(end 9.702292 -64.918336)
			)
			(arc
				(start 9.249156 -64.918336)
				(mid 9.189763 -64.913801)
				(end 9.131808 -64.900048)
			)
			(xy 9.124188 -64.897508) (xy 8.89254 -64.897508) (xy 8.86714 -64.922908) (xy 8.86714 -65.151508)
			(xy 8.89254 -65.176908) (xy 9.93394 -65.176908) (xy 10.29589 -65.538858) (xy 10.813034 -65.538858)
			(xy 10.91565 -65.641474)
			(arc
				(start 10.91565 -67.051428)
				(mid 10.964098 -67.150329)
				(end 10.980674 -67.2592)
			)
			(arc
				(start 10.980674 -67.2592)
				(mid 10.995553 -67.295121)
				(end 11.031474 -67.31)
			)
			(xy 11.684 -67.31)
		)
		(stroke
			(width 0)
			(type solid)
		)
		(fill yes)
		(layer "F.Cu")
		(net "GND")
	)
	(gr_poly
		(pts
			(arc
				(start 85.114892 -72.998076)
				(mid 85.167596 -72.988537)
				(end 85.221064 -72.985376)
			)
			(xy 85.586824 -72.985376) (xy 85.725 -72.8472) (xy 85.725 -72.5932) (xy 85.5472 -72.4154) (xy 84.1756 -72.4154)
			(xy 84.135468 -72.375268)
			(arc
				(start 83.819238 -72.375268)
				(mid 83.700366 -72.359098)
				(end 83.59013 -72.311768)
			)
			(arc
				(start 83.194144 -72.311768)
				(mid 83.13132 -72.306591)
				(end 83.070192 -72.291194)
			)
			(xy 83.062064 -72.2884) (xy 82.804 -72.2884) (xy 82.7786 -72.3138) (xy 82.7786 -72.5424) (xy 82.804 -72.5678)
			(xy 83.076034 -72.5678)
			(arc
				(start 83.083146 -72.565514)
				(mid 83.138034 -72.55315)
				(end 83.194144 -72.549004)
			)
			(arc
				(start 83.598766 -72.549004)
				(mid 83.654875 -72.553155)
				(end 83.709764 -72.565514)
			)
			(xy 83.716876 -72.5678) (xy 83.7438 -72.5678) (xy 83.76158 -72.58558)
			(arc
				(start 83.768946 -72.589136)
				(mid 83.821615 -72.620937)
				(end 83.868514 -72.660764)
			)
			(xy 84.207096 -72.9996) (xy 85.108796 -72.9996)
		)
		(stroke
			(width 0)
			(type solid)
		)
		(fill yes)
		(layer "F.Cu")
		(net "GND")
	)
	(gr_poly
		(pts
			(arc
				(start 77.25664 -63.79337)
				(mid 77.47 -63.728081)
				(end 77.68336 -63.79337)
			)
			(arc
				(start 77.883512 -63.79337)
				(mid 78.1304 -63.702708)
				(end 78.377288 -63.79337)
			)
			(xy 85.760052 -63.79337) (xy 86.160864 -63.392558) (xy 86.160864 -59.060588) (xy 86.143084 -59.042808)
			(xy 76.569824 -59.042808) (xy 76.210414 -59.402218)
			(arc
				(start 76.210414 -61.801502)
				(mid 76.36251 -62.106302)
				(end 76.210414 -62.411102)
			)
			(xy 76.210414 -63.320422) (xy 76.683362 -63.79337)
		)
		(stroke
			(width 0)
			(type solid)
		)
		(fill yes)
		(layer "F.Cu")
		(net "P1V2_AUX")
	)
	(gr_poly
		(pts
			(xy 17.7292 -39.624) (xy 18.868136 -39.624) (xy 18.86839 -39.623492) (xy 19.533108 -39.623492) (xy 19.582892 -39.573708)
			(xy 19.582892 -38.99281) (xy 19.139916 -38.549834) (xy 19.139916 -38.545516) (xy 19.11604 -38.52164)
			(xy 19.11604 -32.864552) (xy 18.954496 -32.703008) (xy 18.954496 -32.59074) (xy 18.951956 -32.588454)
			(xy 18.951956 -32.124904) (xy 18.896584 -32.069532) (xy 18.621248 -32.069532) (xy 18.563336 -32.127444)
			(xy 18.563336 -32.73806) (xy 18.363184 -32.938212) (xy 18.353024 -32.938212)
			(arc
				(start 18.353024 -33.189418)
				(mid 18.315662 -33.27949)
				(end 18.225516 -33.316672)
			)
			(xy 18.154904 -33.316672)
			(arc
				(start 18.139918 -33.331658)
				(mid 18.016069 -33.414538)
				(end 17.869916 -33.443672)
			)
			(xy 17.51457 -33.443672)
			(arc
				(start 17.234408 -33.724088)
				(mid 17.176498 -33.771467)
				(end 17.110456 -33.806638)
			)
			(xy 17.108932 -33.807146) (xy 17.0434 -33.872678) (xy 17.0434 -38.351714) (xy 16.609314 -38.7858)
			(xy 16.609314 -39.887906) (xy 16.717264 -39.995856) (xy 17.357344 -39.995856)
		)
		(stroke
			(width 0)
			(type solid)
		)
		(fill yes)
		(layer "F.Cu")
		(net "GND")
	)
	(gr_poly
		(pts
			(xy 75.25004 -117.341904) (xy 75.25131 -117.341904) (xy 75.25131 -117.291358) (xy 75.283314 -117.259354)
			(xy 75.440032 -117.259354) (xy 75.471528 -117.29085) (xy 75.471528 -119.526304) (xy 75.849988 -119.526304)
			(xy 75.849988 -117.341904) (xy 75.851512 -117.341904) (xy 75.851512 -117.278404) (xy 75.891898 -117.238018)
			(xy 76.204572 -117.238018) (xy 76.226416 -117.216174) (xy 76.226416 -113.810796) (xy 76.864972 -113.17224)
			(xy 83.351878 -113.17224) (xy 84.435442 -112.088676) (xy 84.435442 -110.130336)
			(arc
				(start 84.435188 -110.12805)
				(mid 84.428355 -110.030874)
				(end 84.426044 -109.933486)
			)
			(arc
				(start 84.426044 -109.933486)
				(mid 84.428355 -109.836098)
				(end 84.435188 -109.738922)
			)
			(xy 84.435442 -109.736636) (xy 84.435442 -108.604558) (xy 85.686138 -107.353862) (xy 85.686138 -103.108506)
			(xy 85.53831 -102.960678) (xy 80.398112 -102.960678) (xy 79.756 -103.60279) (xy 79.756 -109.310932)
			(xy 78.214982 -110.852204) (xy 75.249532 -110.852204) (xy 74.871072 -111.230664)
			(arc
				(start 74.871072 -112.73536)
				(mid 74.920101 -112.825866)
				(end 74.937112 -112.927384)
			)
			(arc
				(start 74.937112 -117.201442)
				(mid 74.920278 -117.302653)
				(end 74.87158 -117.392958)
			)
			(xy 74.87158 -119.526304) (xy 75.25004 -119.526304)
		)
		(stroke
			(width 0)
			(type solid)
		)
		(fill yes)
		(layer "F.Cu")
		(net "P12V_AUX")
	)
	(gr_poly
		(pts
			(xy 10.257028 -118.783354)
			(arc
				(start 10.257028 -114.799872)
				(mid 10.552301 -114.087273)
				(end 11.2649 -113.792)
			)
			(xy 11.677904 -113.792) (xy 11.769344 -113.70056) (xy 11.769344 -113.376456) (xy 11.677396 -113.284508)
			(arc
				(start 11.2649 -113.284508)
				(mid 10.193376 -113.728348)
				(end 9.749536 -114.799872)
			)
			(xy 9.749536 -118.76532) (xy 9.862312 -118.878096) (xy 10.162286 -118.878096)
		)
		(stroke
			(width 0)
			(type solid)
		)
		(fill yes)
		(layer "F.Cu")
		(net "GND")
	)
	(gr_poly
		(pts
			(xy 36.6522 -73.6092) (xy 36.6522 -71.749158)
			(arc
				(start 36.548568 -71.645272)
				(mid 36.452032 -71.501029)
				(end 36.418012 -71.33082)
			)
			(xy 36.418012 -70.5104) (xy 35.363404 -70.5104) (xy 35.197288 -70.676516)
			(arc
				(start 35.19424 -70.69201)
				(mid 35.063374 -70.916487)
				(end 34.819082 -71.004938)
			)
			(arc
				(start 34.819082 -71.004938)
				(mid 34.570341 -70.912698)
				(end 34.441892 -70.68058)
			)
			(xy 34.435288 -70.6374) (xy 34.163 -70.6374) (xy 34.162492 -70.637908)
			(arc
				(start 34.162492 -71.331582)
				(mid 34.156102 -71.394727)
				(end 34.137092 -71.45528)
			)
			(xy 34.12363 -71.48703) (xy 34.3408 -71.7042) (xy 34.6202 -71.7042) (xy 35.0774 -72.1614) (xy 35.0774 -73.8378)
			(xy 35.1028 -73.8632) (xy 35.1028 -74.168) (xy 35.1536 -74.2188) (xy 36.0426 -74.2188)
		)
		(stroke
			(width 0)
			(type solid)
		)
		(fill yes)
		(layer "F.Cu")
		(net "P3V3_AUX")
	)
	(gr_poly
		(pts
			(xy 84.328 -85.217) (xy 84.328 -81.1276) (xy 84.2772 -81.0768) (xy 83.5152 -81.0768) (xy 83.2104 -80.772)
			(xy 82.2706 -80.772) (xy 82.169 -80.8736) (xy 82.169 -82.042) (xy 81.534 -82.677) (xy 78.359 -82.677)
			(xy 77.724 -83.312)
			(arc
				(start 77.15885 -83.312)
				(mid 77.078768 -83.351074)
				(end 77.060298 -83.438238)
			)
			(arc
				(start 77.060298 -83.438238)
				(mid 77.063146 -83.453489)
				(end 77.064108 -83.468972)
			)
			(arc
				(start 77.064108 -84.484972)
				(mid 77.026762 -84.575134)
				(end 76.9366 -84.61248)
			)
			(arc
				(start 76.2254 -84.61248)
				(mid 76.135238 -84.575134)
				(end 76.097892 -84.484972)
			)
			(arc
				(start 76.097892 -83.468972)
				(mid 76.098866 -83.45349)
				(end 76.101702 -83.438238)
			)
			(arc
				(start 76.101702 -83.438238)
				(mid 76.08322 -83.351083)
				(end 76.00315 -83.312)
			)
			(xy 75.311 -83.312) (xy 74.803 -83.82) (xy 74.803 -85.598) (xy 75.057 -85.852) (xy 83.693 -85.852)
		)
		(stroke
			(width 0)
			(type solid)
		)
		(fill yes)
		(layer "F.Cu")
		(net "P12V_AUX")
	)
	(gr_poly
		(pts
			(arc
				(start 40.647874 -38.418516)
				(mid 40.726081 -38.381771)
				(end 40.747696 -38.29812)
			)
			(arc
				(start 40.747696 -38.29812)
				(mid 40.742732 -38.262715)
				(end 40.741092 -38.227)
			)
			(arc
				(start 40.741092 -38.227)
				(mid 40.814448 -38.002159)
				(end 41.006268 -37.86378)
			)
			(xy 41.041574 -37.85235) (xy 41.041574 -36.76777) (xy 40.97528 -36.701476) (xy 39.550086 -36.701476)
			(xy 39.484046 -36.767516) (xy 39.484046 -36.815014) (xy 39.4843 -36.8173) (xy 39.485824 -36.851844)
			(xy 39.4843 -36.886388) (xy 39.484046 -36.888674) (xy 39.484046 -37.0967) (xy 39.35349 -37.227256)
			(xy 39.172388 -37.227256)
			(arc
				(start 39.16807 -37.228018)
				(mid 39.136305 -37.232018)
				(end 39.104316 -37.233352)
			)
			(arc
				(start 39.104316 -37.233352)
				(mid 39.072326 -37.23203)
				(end 39.040562 -37.228018)
			)
			(xy 39.036244 -37.227256) (xy 38.207442 -37.227256)
			(arc
				(start 38.203124 -37.228018)
				(mid 38.171359 -37.232018)
				(end 38.13937 -37.233352)
			)
			(arc
				(start 38.13937 -37.233352)
				(mid 38.10738 -37.23203)
				(end 38.075616 -37.228018)
			)
			(xy 38.071298 -37.227256) (xy 37.588698 -37.227256) (xy 37.40785 -37.408104) (xy 37.40785 -38.351714)
			(xy 37.474652 -38.418516)
		)
		(stroke
			(width 0)
			(type solid)
		)
		(fill yes)
		(layer "F.Cu")
		(net "P3V3_P2V5_P1V8_RVDD")
	)
	(gr_poly
		(pts
			(xy 18.415 -74.1426) (xy 18.415 -72.0852) (xy 18.6436 -71.8566) (xy 19.048222 -71.8566) (xy 19.068933 -71.839743)
			(xy 19.114179 -71.811381) (xy 19.16294 -71.789611) (xy 19.214261 -71.774858) (xy 19.26714 -71.767411)
			(xy 19.29384 -71.766938) (xy 19.322077 -71.767423) (xy 19.37794 -71.775705) (xy 19.431968 -71.792141)
			(xy 19.482979 -71.81637) (xy 19.506692 -71.831708) (xy 20.152106 -71.186294) (xy 20.442428 -70.485254)
			(xy 20.458314 -70.448719) (xy 20.498851 -70.380135) (xy 20.5232 -70.348602) (xy 20.5232 -69.337428)
			(xy 20.372578 -69.186806) (xy 20.3465 -69.159832) (xy 20.300945 -69.100216) (xy 20.263643 -69.035117)
			(xy 20.24888 -69.000624) (xy 20.193 -69.000624) (xy 20.152958 -68.99997) (xy 20.073664 -68.988751)
			(xy 20.035012 -68.978272) (xy 20.00631 -68.96989) (xy 19.939 -69.0372) (xy 19.939 -69.2404) (xy 19.5072 -69.6722)
			(xy 19.5072 -70.0024) (xy 19.4056 -70.104) (xy 18.3388 -70.104) (xy 18.1864 -69.9516) (xy 17.2212 -69.9516)
			(xy 17.0434 -70.1294) (xy 17.0434 -71.23938) (xy 18.994118 -71.23938) (xy 18.998189 -71.183758) (xy 19.010315 -71.129321)
			(xy 19.030238 -71.07723) (xy 19.057534 -71.028595) (xy 19.09162 -70.984452) (xy 19.131769 -70.945743)
			(xy 19.177127 -70.913292) (xy 19.226727 -70.887791) (xy 19.279511 -70.869784) (xy 19.334354 -70.859654)
			(xy 19.390088 -70.857617) (xy 19.445525 -70.863717) (xy 19.499482 -70.877823) (xy 19.550811 -70.899635)
			(xy 19.598417 -70.928689) (xy 19.641285 -70.964364) (xy 19.678502 -71.005901) (xy 19.709275 -71.052414)
			(xy 19.732947 -71.102911) (xy 19.749015 -71.156318) (xy 19.757135 -71.211494) (xy 19.757644 -71.23938)
			(xy 19.757135 -71.267266) (xy 19.749015 -71.322442) (xy 19.732947 -71.375849) (xy 19.709275 -71.426346)
			(xy 19.678502 -71.472859) (xy 19.641285 -71.514396) (xy 19.598417 -71.550071) (xy 19.550811 -71.579125)
			(xy 19.499482 -71.600937) (xy 19.445525 -71.615043) (xy 19.390088 -71.621143) (xy 19.334354 -71.619106)
			(xy 19.279511 -71.608976) (xy 19.226727 -71.590969) (xy 19.177127 -71.565468) (xy 19.131769 -71.533017)
			(xy 19.09162 -71.494308) (xy 19.057534 -71.450165) (xy 19.030238 -71.40153) (xy 19.010315 -71.349439)
			(xy 18.998189 -71.295002) (xy 18.994118 -71.23938) (xy 17.0434 -71.23938) (xy 17.0434 -71.83628)
			(xy 17.047972 -71.846186) (xy 17.057104 -71.866817) (xy 17.069998 -71.910051) (xy 17.076531 -71.954692)
			(xy 17.076928 -71.97725) (xy 17.076928 -73.78446) (xy 17.22374 -73.931272) (xy 17.3736 -73.931272)
			(xy 17.398191 -73.931729) (xy 17.446768 -73.939425) (xy 17.493542 -73.954628) (xy 17.53736 -73.976962)
			(xy 17.577145 -74.005878) (xy 17.594834 -74.022966) (xy 17.816068 -74.2442) (xy 18.3134 -74.2442)
		)
		(stroke
			(width 0)
			(type solid)
		)
		(fill yes)
		(layer "F.Cu")
		(net "P3V3_AUX")
	)
	(gr_poly
		(pts
			(xy 29.0322 -24.4856) (xy 29.088842 -24.4856) (xy 29.161232 -24.41321) (xy 29.161232 -24.1046) (xy 29.161706 -24.07534)
			(xy 29.169407 -24.017329) (xy 29.184663 -23.960832) (xy 29.195522 -23.933658) (xy 29.199332 -23.92426)
			(xy 29.199332 -23.6982) (xy 29.199829 -23.681481) (xy 29.208485 -23.649182) (xy 29.225208 -23.620224)
			(xy 29.248856 -23.596583) (xy 29.277819 -23.57987) (xy 29.31012 -23.571224) (xy 29.32684 -23.570692)
			(xy 29.88564 -23.570692) (xy 29.902351 -23.571242) (xy 29.934634 -23.579901) (xy 29.963575 -23.596619)
			(xy 29.987205 -23.620257) (xy 30.003914 -23.649204) (xy 30.012563 -23.681488) (xy 30.013148 -23.6982)
			(xy 30.013148 -23.92426) (xy 30.016958 -23.933658) (xy 30.027787 -23.960843) (xy 30.043038 -24.017338)
			(xy 30.050769 -24.075342) (xy 30.051248 -24.1046) (xy 30.051248 -24.4856) (xy 30.353 -24.4856) (xy 30.5308 -24.6634)
			(xy 31.242 -24.6634) (xy 31.5468 -24.3586) (xy 31.5468 -22.126448) (xy 31.414212 -22.126448) (xy 31.3824 -22.126018)
			(xy 31.319176 -22.118891) (xy 31.257149 -22.104727) (xy 31.1971 -22.083702) (xy 31.139784 -22.056082)
			(xy 31.085923 -22.022215) (xy 31.036195 -21.982526) (xy 31.0134 -21.960332) (xy 30.016196 -20.963128)
			(xy 29.10078 -20.963128) (xy 29.069609 -20.962693) (xy 29.007647 -20.955824) (xy 28.946817 -20.942183)
			(xy 28.887855 -20.921936) (xy 28.85948 -20.909026) (xy 28.849066 -20.9042) (xy 28.6258 -20.9042)
			(xy 28.526486 -21.003514) (xy 28.522676 -21.011134) (xy 28.508408 -21.0384) (xy 28.472443 -21.08833)
			(xy 28.42893 -21.131843) (xy 28.379 -21.167808) (xy 28.351734 -21.182076) (xy 28.344114 -21.185886)
			(xy 27.5082 -22.0218) (xy 27.471116 -22.0218) (xy 27.457908 -22.031452) (xy 27.428888 -22.051576)
			(xy 27.366816 -22.085258) (xy 27.301044 -22.110979) (xy 27.23259 -22.128342) (xy 27.162511 -22.137078)
			(xy 27.1272 -22.137624) (xy 26.7716 -22.137624) (xy 26.7716 -22.517354) (xy 29.161232 -22.517354)
			(xy 29.161232 -21.704554) (xy 29.161729 -21.675297) (xy 29.169453 -21.617293) (xy 29.184697 -21.560797)
			(xy 29.195522 -21.533612) (xy 29.199332 -21.524214) (xy 29.199332 -21.298154) (xy 29.199804 -21.281444)
			(xy 29.208473 -21.249168) (xy 29.225209 -21.220239) (xy 29.248867 -21.196634) (xy 29.277833 -21.179963)
			(xy 29.310129 -21.171366) (xy 29.32684 -21.1709) (xy 29.88564 -21.1709) (xy 29.902336 -21.171399)
			(xy 29.934592 -21.18004) (xy 29.963518 -21.196724) (xy 29.98715 -21.220317) (xy 30.003881 -21.249217)
			(xy 30.012574 -21.281459) (xy 30.013148 -21.298154) (xy 30.013148 -21.524214) (xy 30.016958 -21.533612)
			(xy 30.027802 -21.560792) (xy 30.043064 -21.617286) (xy 30.050771 -21.675295) (xy 30.051248 -21.704554)
			(xy 30.051248 -22.517354) (xy 30.050729 -22.547758) (xy 30.042449 -22.607999) (xy 30.026044 -22.666552)
			(xy 30.001818 -22.722326) (xy 29.970223 -22.774281) (xy 29.931848 -22.821451) (xy 29.887407 -22.862955)
			(xy 29.837729 -22.898022) (xy 29.783739 -22.925997) (xy 29.726442 -22.946361) (xy 29.666906 -22.958732)
			(xy 29.60624 -22.962882) (xy 29.545574 -22.958732) (xy 29.486038 -22.946361) (xy 29.428741 -22.925997)
			(xy 29.374751 -22.898022) (xy 29.325073 -22.862955) (xy 29.280632 -22.821451) (xy 29.242257 -22.774281)
			(xy 29.210662 -22.722326) (xy 29.186436 -22.666552) (xy 29.170031 -22.607999) (xy 29.161751 -22.547758)
			(xy 29.161232 -22.517354) (xy 26.7716 -22.517354) (xy 26.7716 -22.724364) (xy 26.870406 -22.963124)
			(xy 26.90622 -22.9616) (xy 26.924 -22.961092) (xy 26.951251 -22.961578) (xy 27.005199 -22.969334)
			(xy 27.057494 -22.984689) (xy 27.107071 -23.007331) (xy 27.152921 -23.036797) (xy 27.194112 -23.072488)
			(xy 27.229803 -23.113679) (xy 27.259269 -23.159529) (xy 27.281911 -23.209106) (xy 27.297266 -23.261401)
			(xy 27.305022 -23.315349) (xy 27.305508 -23.3426) (xy 27.305113 -23.367618) (xy 27.298565 -23.417224)
			(xy 27.285582 -23.465547) (xy 27.266387 -23.511755) (xy 27.2542 -23.533608) (xy 27.2542 -23.88997)
			(xy 27.300936 -24.002492) (xy 27.314573 -24.037013) (xy 27.333785 -24.108709) (xy 27.343492 -24.182296)
			(xy 27.344116 -24.219408) (xy 27.34392 -24.23692) (xy 27.341634 -24.27187) (xy 27.339544 -24.289258)
			(xy 27.336496 -24.313896) (xy 27.7368 -24.7142) (xy 28.8036 -24.7142)
		)
		(stroke
			(width 0)
			(type solid)
		)
		(fill yes)
		(layer "F.Cu")
		(net "CRT_VCC5")
	)
	(gr_poly
		(pts
			(xy 68.48221 -39.164006)
			(arc
				(start 68.48221 -37.17036)
				(mid 68.44838 -37.094664)
				(end 68.369434 -37.069522)
			)
			(arc
				(start 68.369434 -37.069522)
				(mid 68.348257 -37.071253)
				(end 68.327016 -37.071808)
			)
			(arc
				(start 68.327016 -37.071808)
				(mid 68.057249 -36.960067)
				(end 67.945508 -36.6903)
			)
			(arc
				(start 67.945508 -36.6903)
				(mid 67.969781 -36.556438)
				(end 68.039488 -36.439602)
			)
			(arc
				(start 68.039488 -36.439602)
				(mid 68.064498 -36.3728)
				(end 68.039488 -36.305998)
			)
			(arc
				(start 68.039488 -36.305998)
				(mid 67.969755 -36.189172)
				(end 67.945508 -36.0553)
			)
			(arc
				(start 67.945508 -36.0553)
				(mid 68.016492 -35.833581)
				(end 68.203064 -35.694366)
			)
			(arc
				(start 68.203064 -35.694366)
				(mid 68.270504 -35.613062)
				(end 68.229226 -35.515804)
			)
			(arc
				(start 68.229226 -35.515804)
				(mid 68.111932 -35.379902)
				(end 68.069714 -35.205416)
			)
			(arc
				(start 68.069714 -35.205416)
				(mid 68.181455 -34.935649)
				(end 68.451222 -34.823908)
			)
			(arc
				(start 68.451222 -34.823908)
				(mid 68.698106 -34.914561)
				(end 68.82765 -35.14344)
			)
			(xy 68.830444 -35.159696) (xy 68.877688 -35.207194) (xy 68.94957 -35.135312) (xy 71.04126 -35.135312)
			(xy 71.564754 -34.611818) (xy 73.355962 -34.611818) (xy 73.575672 -34.831528) (xy 73.575672 -35.468052)
			(xy 73.606914 -35.499294) (xy 74.398378 -35.499294) (xy 74.39787 -35.498786) (xy 74.673206 -35.22345)
			(xy 74.673206 -33.929828) (xy 74.576432 -33.833308)
			(arc
				(start 73.140316 -33.833308)
				(mid 73.05811 -33.82429)
				(end 72.979788 -33.797748)
			)
			(xy 72.969628 -33.793176)
			(arc
				(start 72.46493 -33.793176)
				(mid 72.399561 -33.787446)
				(end 72.336152 -33.77057)
			)
			(xy 72.32777 -33.767776)
			(arc
				(start 72.315324 -33.767776)
				(mid 72.285223 -33.765968)
				(end 72.255634 -33.760156)
			)
			(xy 72.249284 -33.758378) (xy 71.18985 -33.758378) (xy 70.640702 -34.307526) (xy 66.491104 -34.307526)
			(xy 66.181732 -34.616644) (xy 66.181732 -37.980112)
			(arc
				(start 66.329814 -38.128194)
				(mid 66.41272 -38.15716)
				(end 66.487294 -38.110668)
			)
			(arc
				(start 66.487294 -38.110668)
				(mid 66.625699 -37.980661)
				(end 66.80962 -37.933376)
			)
			(arc
				(start 66.80962 -37.933376)
				(mid 67.079387 -38.045117)
				(end 67.191128 -38.314884)
			)
			(arc
				(start 67.191128 -38.314884)
				(mid 67.172604 -38.432064)
				(end 67.118992 -38.537896)
			)
			(arc
				(start 67.118992 -38.537896)
				(mid 67.100377 -38.607949)
				(end 67.133216 -38.672516)
			)
			(arc
				(start 67.133216 -38.672516)
				(mid 67.225526 -38.80054)
				(end 67.258184 -38.954964)
			)
			(arc
				(start 67.258184 -38.954964)
				(mid 67.256808 -38.987851)
				(end 67.252596 -39.020496)
			)
			(xy 67.248024 -39.046404) (xy 67.463924 -39.262304) (xy 68.383912 -39.262304)
		)
		(stroke
			(width 0)
			(type solid)
		)
		(fill yes)
		(layer "F.Cu")
		(net "P1V8_AUX")
	)
	(gr_poly
		(pts
			(xy 84.492084 -118.78056)
			(arc
				(start 84.492084 -114.799872)
				(mid 84.787357 -114.087273)
				(end 85.499956 -113.792)
			)
			(arc
				(start 88.000078 -113.792)
				(mid 89.055078 -113.355004)
				(end 89.492074 -112.300004)
			)
			(xy 89.492074 -85.508084)
			(arc
				(start 87.749888 -85.508084)
				(mid 87.037379 -85.212795)
				(end 86.742016 -84.500212)
			)
			(arc
				(start 86.742016 -81.999836)
				(mid 87.037289 -81.287237)
				(end 87.749888 -80.991964)
			)
			(xy 89.492074 -80.991964)
			(arc
				(start 89.492074 -1.999996)
				(mid 89.055078 -0.944996)
				(end 88.000078 -0.508)
			)
			(arc
				(start 1.999996 -0.508)
				(mid 0.944996 -0.944996)
				(end 0.508 -1.999996)
			)
			(xy 0.508 -80.991964)
			(arc
				(start 2.249932 -80.991964)
				(mid 2.962785 -81.287237)
				(end 3.258058 -82.00009)
			)
			(arc
				(start 3.258058 -84.499958)
				(mid 2.962785 -85.212811)
				(end 2.249932 -85.508084)
			)
			(xy 0.508 -85.508084)
			(arc
				(start 0.508 -112.300004)
				(mid 0.944996 -113.355004)
				(end 1.999996 -113.792)
			)
			(arc
				(start 4.500118 -113.792)
				(mid 5.212717 -114.087273)
				(end 5.50799 -114.799872)
			)
			(xy 5.50799 -118.71071) (xy 5.621528 -118.824248) (xy 5.936488 -118.824248) (xy 6.015228 -118.745508)
			(arc
				(start 6.015228 -114.799872)
				(mid 5.571478 -113.728438)
				(end 4.500118 -113.284508)
			)
			(arc
				(start 1.999996 -113.284508)
				(mid 1.303847 -112.996153)
				(end 1.015492 -112.300004)
			)
			(xy 1.015492 -86.015576)
			(arc
				(start 2.249932 -86.015576)
				(mid 3.321472 -85.571572)
				(end 3.765296 -84.499958)
			)
			(arc
				(start 3.765296 -81.999582)
				(mid 3.321366 -80.928222)
				(end 2.249932 -80.484472)
			)
			(xy 1.015492 -80.484472) (xy 1.015492 -3.937) (xy 1.262634 -3.689858) (xy 13.649198 -3.689858) (xy 14.76756 -2.571496)
			(xy 14.76756 -1.487932) (xy 15.24 -1.015492)
			(arc
				(start 88.000078 -1.015492)
				(mid 88.696317 -1.303831)
				(end 88.984836 -1.999996)
			)
			(xy 88.984836 -80.484472)
			(arc
				(start 87.749888 -80.484472)
				(mid 86.678438 -80.928386)
				(end 86.234524 -81.999836)
			)
			(arc
				(start 86.234524 -84.500212)
				(mid 86.678348 -85.571826)
				(end 87.749888 -86.015576)
			)
			(xy 88.984836 -86.015576)
			(arc
				(start 88.984836 -112.300004)
				(mid 88.696571 -112.996064)
				(end 88.000586 -113.284508)
			)
			(arc
				(start 85.499956 -113.284508)
				(mid 84.428432 -113.728348)
				(end 83.984592 -114.799872)
			)
			(xy 83.984592 -118.768114) (xy 84.094574 -118.878096) (xy 84.394548 -118.878096)
		)
		(stroke
			(width 0)
			(type solid)
		)
		(fill yes)
		(layer "F.Cu")
		(net "GND")
	)
	(gr_poly
		(pts
			(xy 47.9171 -51.200812) (xy 47.9171 -49.083468) (xy 47.516034 -49.083468) (xy 47.345854 -49.253648)
			(xy 47.345854 -51.169316) (xy 47.520098 -51.34356) (xy 47.774352 -51.34356)
		)
		(stroke
			(width 0)
			(type solid)
		)
		(fill yes)
		(layer "B.Cu")
		(net "P3V3_AUX")
	)
	(gr_poly
		(pts
			(xy 12.755118 -77.280516) (xy 12.755118 -76.277724) (xy 12.271248 -75.793854) (xy 3.259836 -75.793854)
			(xy 3.090418 -75.963272) (xy 3.090418 -77.601572) (xy 3.2639 -77.775054) (xy 12.26058 -77.775054)
		)
		(stroke
			(width 0)
			(type solid)
		)
		(fill yes)
		(layer "B.Cu")
		(net "P3V3_AUX")
	)
	(gr_poly
		(pts
			(xy 25.273 -23.495) (xy 25.273 -21.082) (xy 24.765 -20.574) (xy 17.018 -20.574) (xy 16.637 -20.955)
			(xy 16.637 -23.622) (xy 16.891 -23.876) (xy 24.892 -23.876)
		)
		(stroke
			(width 0)
			(type solid)
		)
		(fill yes)
		(layer "B.Cu")
		(net "P1V0_AUX")
	)
	(gr_poly
		(pts
			(xy 25.654 -25.273) (xy 25.654 -24.511) (xy 25.4 -24.257) (xy 16.764 -24.257) (xy 16.637 -24.384)
			(xy 16.637 -26.416) (xy 16.891 -26.67) (xy 24.257 -26.67)
		)
		(stroke
			(width 0)
			(type solid)
		)
		(fill yes)
		(layer "B.Cu")
		(net "GND")
	)
	(gr_poly
		(pts
			(xy 46.7868 -82.8294) (xy 46.7868 -82.0674) (xy 46.7614 -82.042) (xy 45.212 -82.042) (xy 45.0596 -82.1944)
			(xy 45.0596 -82.701892) (xy 45.441108 -83.0834) (xy 46.5328 -83.0834)
		)
		(stroke
			(width 0)
			(type solid)
		)
		(fill yes)
		(layer "B.Cu")
		(net "GND")
	)
	(gr_poly
		(pts
			(xy 50.333148 -45.5041) (xy 50.333148 -45.2755) (xy 50.118772 -45.061124) (xy 48.98898 -45.061124)
			(xy 48.904906 -45.145198) (xy 48.904906 -45.5295) (xy 48.967136 -45.591476) (xy 50.245772 -45.591476)
		)
		(stroke
			(width 0)
			(type solid)
		)
		(fill yes)
		(layer "B.Cu")
		(net "GND")
	)
	(gr_poly
		(pts
			(xy 57.44972 -46.358048) (xy 57.44972 -46.04004) (xy 57.31256 -45.90288) (xy 56.504332 -45.90288)
			(xy 56.460644 -45.946568) (xy 56.460644 -46.4185) (xy 56.49468 -46.452282) (xy 57.355486 -46.452282)
		)
		(stroke
			(width 0)
			(type solid)
		)
		(fill yes)
		(layer "B.Cu")
		(net "P3V3_RGM")
	)
	(gr_poly
		(pts
			(xy 58.348626 -51.134264) (xy 58.348626 -50.866802) (xy 58.16981 -50.687986) (xy 57.22874 -50.687986)
			(xy 57.142126 -50.7746) (xy 57.142126 -51.206146) (xy 57.219342 -51.283362) (xy 58.199528 -51.283362)
		)
		(stroke
			(width 0)
			(type solid)
		)
		(fill yes)
		(layer "B.Cu")
		(net "P1V0_AUX")
	)
	(gr_poly
		(pts
			(xy 69.587364 -65.004696) (xy 69.587364 -63.62319) (xy 69.327776 -63.363348) (xy 67.569588 -63.363348)
			(xy 67.309746 -63.62319) (xy 67.309746 -64.593216) (xy 67.81292 -65.09639) (xy 69.49567 -65.09639)
		)
		(stroke
			(width 0)
			(type solid)
		)
		(fill yes)
		(layer "B.Cu")
		(net "P1V8_STBY_RC_VCC18A")
	)
	(gr_poly
		(pts
			(xy 71.428864 -65.00495) (xy 71.428864 -63.07963) (xy 71.26859 -62.919356) (xy 69.977508 -62.919356)
			(xy 69.845428 -63.051436) (xy 69.845428 -64.990472) (xy 69.948298 -65.093342) (xy 71.340472 -65.093342)
		)
		(stroke
			(width 0)
			(type solid)
		)
		(fill yes)
		(layer "B.Cu")
		(net "P1V8_STBY_PE_VCC18A")
	)
	(gr_poly
		(pts
			(xy 80.255364 -118.737634) (xy 80.255364 -115.252754) (xy 80.174338 -115.171728) (xy 79.865474 -115.171728)
			(xy 79.748126 -115.289076) (xy 79.748126 -118.718584) (xy 79.85379 -118.824248) (xy 80.16875 -118.824248)
		)
		(stroke
			(width 0)
			(type solid)
		)
		(fill yes)
		(layer "B.Cu")
		(net "GND")
	)
	(gr_poly
		(pts
			(xy 83.217766 -32.401256) (xy 83.217766 -29.350462) (xy 82.99196 -29.124656) (xy 82.13598 -29.124656)
			(xy 82.023966 -29.23667) (xy 82.023966 -32.375856) (xy 82.100166 -32.452056) (xy 83.166966 -32.452056)
		)
		(stroke
			(width 0)
			(type solid)
		)
		(fill yes)
		(layer "B.Cu")
		(net "P3V3_AUX")
	)
	(gr_poly
		(pts
			(xy 84.836 -101.05644) (xy 84.836 -99.991164) (xy 84.582 -99.737164) (xy 79.822294 -99.737164) (xy 79.647796 -99.911662)
			(xy 79.647796 -101.099366) (xy 79.78267 -101.23424) (xy 84.6582 -101.23424)
		)
		(stroke
			(width 0)
			(type solid)
		)
		(fill yes)
		(layer "B.Cu")
		(net "GND")
	)
	(gr_poly
		(pts
			(xy 86.03107 -53.56606) (xy 86.03107 -51.166522) (xy 85.772244 -50.907696) (xy 84.263738 -50.907696)
			(xy 84.189062 -50.982372) (xy 84.189062 -53.681122) (xy 84.296504 -53.788564) (xy 85.808566 -53.788564)
		)
		(stroke
			(width 0)
			(type solid)
		)
		(fill yes)
		(layer "B.Cu")
		(net "GND")
	)
	(gr_poly
		(pts
			(xy 69.535294 -36.711128) (xy 69.535294 -35.907726) (xy 69.398642 -35.771074) (xy 67.34683 -35.771074)
			(xy 67.209416 -35.908488) (xy 67.209416 -35.97275) (xy 67.209416 -36.811712) (xy 67.291204 -36.8935)
			(xy 69.352922 -36.8935)
		)
		(stroke
			(width 0)
			(type solid)
		)
		(fill yes)
		(layer "B.Cu")
		(net "P1V8_STBY_AVDDPLL")
	)
	(gr_poly
		(pts
			(xy 9.2964 -61.4172) (xy 9.2964 -60.3504) (xy 9.144 -60.198) (xy 8.89 -60.198) (xy 8.6614 -60.4266)
			(xy 7.6454 -60.4266) (xy 7.5184 -60.5536) (xy 7.5184 -61.6712) (xy 7.5946 -61.7474) (xy 8.9662 -61.7474)
		)
		(stroke
			(width 0)
			(type solid)
		)
		(fill yes)
		(layer "B.Cu")
		(net "SW_P3V3_AUX_FLT")
	)
	(gr_poly
		(pts
			(xy 16.500856 -89.2302) (xy 16.894048 -89.2302) (xy 17.122648 -89.0016) (xy 17.122648 -88.496648)
			(xy 16.99133 -88.36533) (xy 16.12773 -88.36533) (xy 15.57274 -88.92032) (xy 15.57274 -89.06383) (xy 15.853156 -89.3445)
			(xy 16.386556 -89.3445)
		)
		(stroke
			(width 0)
			(type solid)
		)
		(fill yes)
		(layer "B.Cu")
		(net "GND")
	)
	(gr_poly
		(pts
			(xy 16.9926 -100.457) (xy 16.9926 -99.901248) (xy 15.495524 -98.404172) (xy 15.292324 -98.404172)
			(xy 14.913864 -98.782632) (xy 14.913864 -98.942652) (xy 15.7226 -99.751388) (xy 15.7226 -100.2792)
			(xy 16.3576 -100.9142) (xy 16.5354 -100.9142)
		)
		(stroke
			(width 0)
			(type solid)
		)
		(fill yes)
		(layer "B.Cu")
		(net "GND")
	)
	(gr_poly
		(pts
			(xy 38.17112 -33.086294) (xy 38.17112 -31.247588) (xy 37.919152 -30.99562) (xy 37.874702 -30.99562)
			(xy 37.873686 -30.994604) (xy 37.737796 -30.994604) (xy 37.20084 -31.53156) (xy 37.20084 -33.028382)
			(xy 37.341302 -33.168844) (xy 38.08857 -33.168844)
		)
		(stroke
			(width 0)
			(type solid)
		)
		(fill yes)
		(layer "B.Cu")
		(net "P1V2_AUX")
	)
	(gr_poly
		(pts
			(xy 50.854102 -69.267324) (xy 52.50688 -69.267324) (xy 52.53609 -69.23786) (xy 52.53609 -68.245228)
			(xy 52.33289 -68.042028) (xy 50.007266 -68.042028) (xy 49.830228 -68.219066) (xy 49.830228 -69.034152)
			(xy 50.064162 -69.268086) (xy 50.85334 -69.268086)
		)
		(stroke
			(width 0)
			(type solid)
		)
		(fill yes)
		(layer "B.Cu")
		(net "P3V3_SENSOR")
	)
	(gr_poly
		(pts
			(xy 51.937158 -55.240174) (xy 51.937158 -54.017926) (xy 51.824636 -53.905404) (xy 51.214274 -53.905404)
			(xy 51.210972 -53.90896) (xy 50.570384 -53.90896) (xy 50.370232 -54.108604) (xy 50.370232 -55.113174)
			(xy 50.554128 -55.29707) (xy 51.880262 -55.29707)
		)
		(stroke
			(width 0)
			(type solid)
		)
		(fill yes)
		(layer "B.Cu")
		(net "P3V3_AUX")
	)
	(gr_poly
		(pts
			(xy 70.8406 -35.2552) (xy 70.8406 -34.5186) (xy 70.6755 -34.3535) (xy 68.78701 -34.3535) (xy 68.6435 -34.49701)
			(xy 67.32397 -34.49701) (xy 67.211702 -34.609278) (xy 67.211702 -35.407854) (xy 67.320414 -35.516566)
			(xy 70.579234 -35.516566)
		)
		(stroke
			(width 0)
			(type solid)
		)
		(fill yes)
		(layer "B.Cu")
		(net "P3V3_BMC_USB2AV33")
	)
	(gr_poly
		(pts
			(xy 59.882786 -45.093382) (xy 60.051442 -44.924726) (xy 60.117482 -44.924726) (xy 60.149994 -44.89196)
			(xy 60.862464 -44.89196) (xy 60.862464 -44.355512) (xy 60.83681 -44.329858) (xy 59.545728 -44.329858)
			(xy 59.44489 -44.430696) (xy 59.44489 -45.45076) (xy 59.882786 -45.45076)
		)
		(stroke
			(width 0)
			(type solid)
		)
		(fill yes)
		(layer "B.Cu")
		(net "P1V8_AUX")
	)
	(gr_poly
		(pts
			(xy 80.971898 -35.412934) (xy 80.971898 -34.975292) (xy 80.315054 -34.318448) (xy 78.73365 -34.318448)
			(xy 78.731364 -34.318702) (xy 78.698852 -34.319972) (xy 75.294998 -34.319972) (xy 75.07605 -34.53892)
			(xy 75.07605 -35.390582) (xy 75.161394 -35.475926) (xy 80.908906 -35.475926)
		)
		(stroke
			(width 0)
			(type solid)
		)
		(fill yes)
		(layer "B.Cu")
		(net "GND")
	)
	(gr_poly
		(pts
			(xy 86.189566 -36.897056) (xy 86.189566 -34.839656) (xy 86.037166 -34.687256) (xy 82.582766 -34.687256)
			(xy 82.506566 -34.763456) (xy 82.506566 -36.008056) (xy 82.506566 -36.962588) (xy 82.593434 -37.049456)
			(xy 82.618834 -37.074856) (xy 83.852766 -37.074856) (xy 86.011766 -37.074856)
		)
		(stroke
			(width 0)
			(type solid)
		)
		(fill yes)
		(layer "B.Cu")
		(net "P2V5_AUX")
	)
	(gr_poly
		(pts
			(xy 15.7734 -101.2952) (xy 15.7734 -101.1936) (xy 15.4178 -100.838) (xy 15.4178 -99.822) (xy 14.7066 -99.1108)
			(xy 14.6558 -99.1108) (xy 13.8684 -99.8982) (xy 13.8684 -101.092) (xy 14.2748 -101.4984) (xy 14.8082 -101.4984)
			(xy 15.113 -101.8032) (xy 15.2654 -101.8032)
		)
		(stroke
			(width 0)
			(type solid)
		)
		(fill yes)
		(layer "B.Cu")
		(net "PVCCA_AUX_PLD")
	)
	(gr_poly
		(pts
			(xy 28.3972 -100.9396) (xy 28.3972 -99.7458) (xy 28.0416 -99.3902) (xy 27.92222 -99.3902) (xy 27.490166 -99.822508)
			(xy 27.09799 -99.822508) (xy 26.99639 -99.720908) (xy 26.72461 -99.720908) (xy 26.5938 -99.851464)
			(xy 26.5938 -101.164136) (xy 27.05481 -101.624892) (xy 27.711908 -101.624892)
		)
		(stroke
			(width 0)
			(type solid)
		)
		(fill yes)
		(layer "B.Cu")
		(net "PVCCA_AUX_PLD")
	)
	(gr_poly
		(pts
			(xy 52.625244 -73.314306) (xy 52.625244 -73.234296) (xy 52.761134 -73.098406) (xy 52.761134 -72.571864)
			(xy 52.718462 -72.529192) (xy 51.087274 -72.529192) (xy 50.981356 -72.63511) (xy 50.981356 -73.151492)
			(xy 50.46091 -73.671938) (xy 50.46091 -74.25055) (xy 50.718212 -74.507852) (xy 51.431698 -74.507852)
		)
		(stroke
			(width 0)
			(type solid)
		)
		(fill yes)
		(layer "B.Cu")
		(net "P1V8_AUX")
	)
	(gr_poly
		(pts
			(xy 55.831232 -47.987712) (xy 55.831232 -47.476918) (xy 55.828184 -47.47387) (xy 55.828184 -46.949868)
			(xy 55.113936 -46.23562) (xy 54.75351 -46.23562) (xy 54.57571 -46.41342) (xy 54.57571 -47.361094)
			(xy 54.944518 -47.729648) (xy 55.32882 -47.729648) (xy 55.632858 -48.03394) (xy 55.785004 -48.03394)
		)
		(stroke
			(width 0)
			(type solid)
		)
		(fill yes)
		(layer "B.Cu")
		(net "P1V8_AUX")
	)
	(gr_poly
		(pts
			(xy 56.71058 -47.429928) (xy 56.71058 -47.309024) (xy 56.81218 -47.207424) (xy 57.3913 -47.207424)
			(xy 57.508394 -47.09033) (xy 57.508394 -46.855126) (xy 57.36844 -46.715172) (xy 56.180736 -46.715172)
			(xy 56.082438 -46.81347) (xy 56.082438 -47.36846) (xy 56.162194 -47.448216) (xy 56.692292 -47.448216)
		)
		(stroke
			(width 0)
			(type solid)
		)
		(fill yes)
		(layer "B.Cu")
		(net "GND")
	)
	(gr_poly
		(pts
			(xy 68.6816 -34.098992) (xy 69.075554 -34.098992) (xy 69.1896 -33.9852) (xy 69.1896 -33.684464) (xy 69.189092 -33.68421)
			(xy 69.189092 -33.578292) (xy 68.524882 -32.914082) (xy 67.432936 -32.914082) (xy 67.337432 -33.009586)
			(xy 67.337432 -34.130742) (xy 67.449446 -34.242756) (xy 68.53809 -34.242756)
		)
		(stroke
			(width 0)
			(type solid)
		)
		(fill yes)
		(layer "B.Cu")
		(net "P3V3_AUX")
	)
	(gr_poly
		(pts
			(xy 73.787 -62.526164) (xy 73.787 -61.976) (xy 73.533 -61.722) (xy 73.533 -61.087) (xy 73.430892 -60.984892)
			(xy 72.573388 -60.984892) (xy 72.548496 -60.96) (xy 71.453248 -60.96) (xy 71.351648 -61.0616) (xy 71.351648 -62.37224)
			(xy 71.632572 -62.653164) (xy 73.66 -62.653164)
		)
		(stroke
			(width 0)
			(type solid)
		)
		(fill yes)
		(layer "B.Cu")
		(net "GND")
	)
	(gr_poly
		(pts
			(xy 74.019156 -65.253362) (xy 74.019156 -64.857376) (xy 73.265538 -64.103758) (xy 73.265538 -62.985396)
			(xy 73.18756 -62.907672) (xy 71.76897 -62.907672) (xy 71.68388 -62.992508) (xy 71.68388 -65.014094)
			(xy 71.763128 -65.093342) (xy 73.054972 -65.093342) (xy 73.329546 -65.367916) (xy 73.904856 -65.367916)
		)
		(stroke
			(width 0)
			(type solid)
		)
		(fill yes)
		(layer "B.Cu")
		(net "P1V8_STBY_DP_VCC18A")
	)
	(gr_poly
		(pts
			(xy 61.74232 -51.235356) (xy 61.74232 -50.0507) (xy 61.617352 -49.925732) (xy 61.174376 -49.925732)
			(xy 61.14288 -49.956974) (xy 61.044074 -50.05578) (xy 61.044074 -50.671476) (xy 60.897262 -50.818288)
			(xy 60.359544 -50.818288) (xy 60.297822 -50.88001) (xy 60.297822 -51.307238) (xy 60.349892 -51.359308)
			(xy 61.618368 -51.359308)
		)
		(stroke
			(width 0)
			(type solid)
		)
		(fill yes)
		(layer "B.Cu")
		(net "P1V2_AUX")
	)
	(gr_poly
		(pts
			(xy 39.628572 -36.214304) (xy 39.628572 -35.212274)
			(arc
				(start 39.446708 -35.030664)
				(mid 39.407774 -34.983216)
				(end 39.37889 -34.929064)
			)
			(xy 39.25697 -34.634424) (xy 38.694106 -34.634424) (xy 38.595554 -34.732976) (xy 38.595554 -35.365182)
			(xy 38.601396 -35.371024) (xy 38.601396 -36.170108) (xy 38.772846 -36.341304) (xy 39.501318 -36.341304)
		)
		(stroke
			(width 0)
			(type solid)
		)
		(fill yes)
		(layer "B.Cu")
		(net "P1V8_AUX")
	)
	(gr_poly
		(pts
			(xy 51.116484 -45.408088) (xy 51.116484 -44.916598) (xy 51.127152 -44.90593) (xy 51.127152 -44.378118)
			(xy 51.046634 -44.2976) (xy 49.941226 -44.2976) (xy 49.828196 -44.41063) (xy 49.828196 -44.699682)
			(xy 49.931066 -44.802552) (xy 50.225706 -44.802552) (xy 50.593752 -45.170598) (xy 50.593752 -45.386752)
			(xy 50.683922 -45.476922) (xy 51.047396 -45.476922)
		)
		(stroke
			(width 0)
			(type solid)
		)
		(fill yes)
		(layer "B.Cu")
		(net "P3V3_P1V8_SD2VDD")
	)
	(gr_poly
		(pts
			(xy 52.76088 -72.20331) (xy 52.76088 -70.39737) (xy 52.976272 -70.181978) (xy 53.492654 -70.181978)
			(xy 53.637688 -70.036944) (xy 53.637688 -69.567806) (xy 53.59146 -69.521578) (xy 50.959512 -69.521578)
			(xy 50.809652 -69.671438) (xy 50.809652 -70.27291) (xy 50.983388 -70.446646) (xy 50.983388 -72.224138)
			(xy 51.018694 -72.259444) (xy 52.704492 -72.259444)
		)
		(stroke
			(width 0)
			(type solid)
		)
		(fill yes)
		(layer "B.Cu")
		(net "GND")
	)
	(gr_poly
		(pts
			(xy 55.486808 -74.06259) (xy 55.486808 -73.523348) (xy 55.729886 -73.28027) (xy 56.66105 -73.28027)
			(xy 56.709564 -73.231756) (xy 56.709564 -72.620378) (xy 56.677052 -72.587866) (xy 55.760112 -72.587866)
			(xy 55.757572 -72.590406) (xy 54.868826 -72.590406) (xy 54.80431 -72.654922) (xy 54.80431 -74.074528)
			(xy 54.855364 -74.125582) (xy 55.423816 -74.125582)
		)
		(stroke
			(width 0)
			(type solid)
		)
		(fill yes)
		(layer "B.Cu")
		(net "P1V2_AUX")
	)
	(gr_poly
		(pts
			(xy 55.925212 -72.171306) (xy 55.925212 -70.75043) (xy 55.739284 -70.564756) (xy 55.023512 -70.564756)
			(xy 55.001922 -70.542912) (xy 54.090824 -70.542912) (xy 54.051708 -70.582028) (xy 54.051708 -71.052182)
			(xy 54.15534 -71.15556) (xy 54.56428 -71.15556) (xy 54.810152 -71.401432) (xy 54.810152 -72.19823)
			(xy 54.929532 -72.31761) (xy 55.779162 -72.31761)
		)
		(stroke
			(width 0)
			(type solid)
		)
		(fill yes)
		(layer "B.Cu")
		(net "P2V5_AUX")
	)
	(gr_poly
		(pts
			(xy 56.802528 -45.522388) (xy 56.802528 -45.13707) (xy 56.907176 -45.032422) (xy 56.907176 -44.325032)
			(xy 56.907176 -43.503596) (xy 56.39943 -43.503596) (xy 56.358028 -43.544998) (xy 56.358028 -44.292774)
			(xy 56.358028 -45.15993) (xy 56.256428 -45.26153) (xy 56.256428 -45.499274) (xy 56.311546 -45.554392)
			(xy 56.360314 -45.60316) (xy 56.721502 -45.60316)
		)
		(stroke
			(width 0)
			(type solid)
		)
		(fill yes)
		(layer "B.Cu")
		(net "P1V8_AUX")
	)
	(gr_poly
		(pts
			(xy 13.50772 -35.00628) (xy 13.50772 -32.399478) (xy 13.213842 -32.1056) (xy 4.449064 -32.1056) (xy 4.374896 -32.180022)
			(xy 4.343908 -32.21101) (xy 4.343908 -33.47339) (xy 4.99745 -34.126932) (xy 5.142992 -34.272474)
			(xy 5.32638 -34.456116) (xy 5.32638 -34.54654) (xy 5.603494 -34.8234) (xy 5.603494 -35.56127) (xy 5.768848 -35.726624)
			(xy 12.787376 -35.726624)
		)
		(stroke
			(width 0)
			(type solid)
		)
		(fill yes)
		(layer "B.Cu")
		(net "P5V_AUX")
	)
	(gr_poly
		(pts
			(xy 53.520594 -44.72432) (xy 53.520594 -44.397168) (xy 53.215032 -44.091606) (xy 53.215032 -43.54322)
			(xy 53.15077 -43.478958) (xy 51.78933 -43.478958) (xy 51.692048 -43.576494) (xy 51.692048 -44.066714)
			(xy 51.66868 -44.089828) (xy 51.66868 -44.313094) (xy 51.47056 -44.511214) (xy 51.47056 -44.69892)
			(xy 52.44846 -44.69892) (xy 52.537868 -44.788328) (xy 53.456586 -44.788328)
		)
		(stroke
			(width 0)
			(type solid)
		)
		(fill yes)
		(layer "B.Cu")
		(net "P3V3_AUX")
	)
	(gr_poly
		(pts
			(xy 20.176998 -38.882574) (xy 20.176998 -33.482026) (xy 19.975068 -33.280096) (xy 17.570196 -33.280096)
			(arc
				(start 17.296892 -33.5534)
				(mid 17.233332 -33.742033)
				(end 17.095724 -33.885886)
			)
			(xy 17.095724 -38.76294) (xy 17.291304 -38.95852) (xy 20.101052 -38.95852)
		)
		(stroke
			(width 0)
			(type solid)
		)
		(fill yes)
		(layer "B.Cu")
		(net "GND")
	)
	(gr_poly
		(pts
			(xy 56.7309 -72.30237) (xy 56.7309 -69.621654) (xy 56.769 -69.583554) (xy 56.769 -69.0626) (xy 56.55564 -68.84924)
			(xy 56.07304 -68.84924) (xy 55.079646 -69.842634) (xy 55.079646 -70.260972) (xy 55.128922 -70.310248)
			(xy 55.874666 -70.310248) (xy 56.107838 -70.54342) (xy 56.111394 -70.54342) (xy 56.219852 -70.651878)
			(xy 56.219852 -72.262746) (xy 56.290718 -72.333612) (xy 56.699912 -72.333612)
		)
		(stroke
			(width 0)
			(type solid)
		)
		(fill yes)
		(layer "B.Cu")
		(net "ADCVREFEXT0")
	)
	(gr_poly
		(pts
			(xy 61.701172 -46.890178) (xy 61.701172 -45.884592) (xy 61.53658 -45.72) (xy 61.53658 -43.588432)
			(xy 61.467492 -43.519344) (xy 61.177678 -43.519344) (xy 61.116718 -43.580304) (xy 61.116718 -45.049948)
			(xy 61.15558 -45.08881) (xy 61.15558 -46.730412) (xy 61.116718 -46.769274) (xy 61.116718 -46.773592)
			(xy 61.057282 -46.833028) (xy 61.057282 -47.155862) (xy 61.112146 -47.210726) (xy 61.380624 -47.210726)
		)
		(stroke
			(width 0)
			(type solid)
		)
		(fill yes)
		(layer "B.Cu")
		(net "P1V2_AUX")
	)
	(gr_poly
		(pts
			(xy 72.9234 -52.1716) (xy 72.9234 -51.7144) (xy 72.8472 -51.6382) (xy 72.709532 -51.6382)
			(arc
				(start 72.700134 -51.642264)
				(mid 72.615873 -51.668087)
				(end 72.528176 -51.676808)
			)
			(xy 72.504046 -51.676808) (xy 72.4662 -51.7144) (xy 71.4502 -51.7144) (xy 71.3994 -51.7652) (xy 71.3994 -52.2732)
			(xy 71.501 -52.3748) (xy 72.7202 -52.3748)
		)
		(stroke
			(width 0)
			(type solid)
		)
		(fill yes)
		(layer "B.Cu")
		(net "P1V2_AUX")
	)
	(gr_poly
		(pts
			(xy 82.176874 -50.6476) (xy 82.704178 -50.6476) (xy 82.83702 -50.515012) (xy 82.83702 -49.341278)
			(xy 82.676746 -49.181004) (xy 81.182718 -49.181004) (xy 80.9879 -49.375822) (xy 80.9879 -50.49774)
			(xy 81.136236 -50.646076) (xy 81.158588 -50.64506)
			(arc
				(start 81.178654 -50.644552)
				(mid 81.204865 -50.645429)
				(end 81.230978 -50.647854)
			)
			(xy 81.233772 -50.648108) (xy 82.17662 -50.648108)
		)
		(stroke
			(width 0)
			(type solid)
		)
		(fill yes)
		(layer "B.Cu")
		(net "P1V2_AUX")
	)
	(gr_poly
		(pts
			(xy 30.3784 -20.193) (xy 30.3784 -18.5674) (xy 30.226 -18.415) (xy 28.956 -18.415) (xy 28.7528 -18.6182)
			(xy 28.7528 -19.463004)
			(arc
				(start 28.753562 -19.467068)
				(mid 28.759085 -19.512385)
				(end 28.760928 -19.558)
			)
			(arc
				(start 28.760928 -19.558)
				(mid 28.75907 -19.603613)
				(end 28.753562 -19.648932)
			)
			(xy 28.7528 -19.652996) (xy 28.7528 -20.193) (xy 28.965906 -20.406106) (xy 30.165294 -20.406106)
		)
		(stroke
			(width 0)
			(type solid)
		)
		(fill yes)
		(layer "B.Cu")
		(net "P5V_AUX")
	)
	(gr_poly
		(pts
			(xy 58.241184 -46.597062) (xy 58.32602 -46.51248) (xy 58.32602 -46.219618)
			(arc
				(start 58.318654 -46.20768)
				(mid 58.294392 -46.150849)
				(end 58.286396 -46.08957)
			)
			(xy 58.286396 -46.0248) (xy 58.207402 -45.945806) (xy 57.888378 -45.945806) (xy 57.756298 -46.077886)
			(xy 57.756298 -46.743366) (xy 57.762648 -46.749716) (xy 57.762648 -47.208948) (xy 57.819544 -47.26559)
			(xy 58.241184 -47.26559)
		)
		(stroke
			(width 0)
			(type solid)
		)
		(fill yes)
		(layer "B.Cu")
		(net "P1V8_BMC_USB2AV18")
	)
	(gr_poly
		(pts
			(xy 69.556122 -39.63924) (xy 69.556122 -38.390322) (xy 69.704204 -38.24224) (xy 70.865746 -38.24224)
			(xy 70.93839 -38.16985) (xy 70.93966 -38.167564) (xy 70.93966 -37.319204) (xy 70.78853 -37.168074)
			(xy 68.727574 -37.168074) (xy 68.593716 -37.301932) (xy 68.593716 -37.886132) (xy 68.489576 -37.990272)
			(xy 67.503548 -37.990272) (xy 67.40906 -38.08476) (xy 67.40906 -39.147496) (xy 67.945254 -39.68369)
			(xy 69.511672 -39.68369)
		)
		(stroke
			(width 0)
			(type solid)
		)
		(fill yes)
		(layer "B.Cu")
		(net "P1V8_AUX")
	)
	(gr_poly
		(pts
			(xy 76.862432 -59.23026) (xy 76.862432 -58.788554) (xy 86.108286 -58.788554) (xy 86.143338 -58.753502)
			(xy 86.143338 -56.874664) (xy 85.860636 -56.592216) (xy 77.142594 -56.592216) (xy 76.77023 -56.219852)
			(xy 75.806808 -56.219852) (xy 75.79995 -56.22671) (xy 75.79995 -56.81599) (xy 75.395328 -57.220612)
			(xy 74.415396 -57.220612) (xy 74.3331 -57.302908) (xy 74.3331 -58.891678) (xy 74.89063 -59.449208)
			(xy 76.643484 -59.449208)
		)
		(stroke
			(width 0)
			(type solid)
		)
		(fill yes)
		(layer "B.Cu")
		(net "GND")
	)
	(gr_poly
		(pts
			(xy 24.129492 -94.513654) (xy 24.129492 -93.31579) (xy 24.58339 -92.861892) (xy 24.740108 -92.861892)
			(xy 24.887936 -92.71381) (xy 24.887936 -92.227908) (xy 24.408892 -92.227908) (xy 24.1046 -92.5322)
			(xy 24.057864 -92.5322) (xy 23.90521 -92.685108) (xy 22.800564 -92.685108) (xy 22.800564 -93.490288)
			(xy 22.844252 -93.518228) (xy 22.844252 -93.69425) (xy 22.800564 -93.72219) (xy 22.800564 -94.271846)
			(xy 23.168864 -94.6404) (xy 24.003 -94.6404)
		)
		(stroke
			(width 0)
			(type solid)
		)
		(fill yes)
		(layer "B.Cu")
		(net "VCCIO4")
	)
	(gr_poly
		(pts
			(xy 37.424614 -34.773616) (xy 37.424614 -33.700466) (xy 36.865052 -33.140904) (xy 36.865052 -32.335978)
			(xy 36.78174 -32.252666) (xy 34.574734 -32.252666) (xy 34.506154 -32.321246)
			(arc
				(start 34.511488 -32.347916)
				(mid 34.517197 -32.385571)
				(end 34.519108 -32.423608)
			)
			(arc
				(start 34.519108 -32.423608)
				(mid 34.513348 -32.489628)
				(end 34.496248 -32.553656)
			)
			(xy 34.4932 -32.562038) (xy 34.4932 -33.6042) (xy 35.926014 -35.037014) (xy 37.161216 -35.037014)
		)
		(stroke
			(width 0)
			(type solid)
		)
		(fill yes)
		(layer "B.Cu")
		(net "P3V3_STBY_PLLAHVDD")
	)
	(gr_poly
		(pts
			(xy 50.726848 -73.046082) (xy 50.726848 -72.5297) (xy 50.732944 -72.523858) (xy 50.732944 -72.333358)
			(xy 50.72888 -72.329548) (xy 50.72888 -70.552056) (xy 50.56251 -70.385432) (xy 50.193956 -70.385432)
			(xy 50.193448 -70.386194) (xy 49.77257 -70.386194) (xy 49.675796 -70.28942) (xy 48.78832 -70.28942)
			(xy 48.692054 -70.385686) (xy 48.692054 -70.757542) (xy 49.210722 -71.27621) (xy 49.210722 -73.03516)
			(xy 49.38903 -73.213468) (xy 50.559716 -73.213468)
		)
		(stroke
			(width 0)
			(type solid)
		)
		(fill yes)
		(layer "B.Cu")
		(net "P1V8_SENSOR")
	)
	(gr_poly
		(pts
			(xy 85.985858 -50.394616) (xy 85.985858 -49.632362) (xy 85.901022 -49.547526) (xy 85.869018 -49.547526)
			(arc
				(start 85.860128 -49.550828)
				(mid 85.6996 -49.580808)
				(end 85.539072 -49.550828)
			)
			(xy 85.530182 -49.547526) (xy 83.235546 -49.547526) (xy 83.126072 -49.657) (xy 83.126072 -50.471832)
			(xy 83.229196 -50.574956) (xy 85.805518 -50.574956)
		)
		(stroke
			(width 0)
			(type solid)
		)
		(fill yes)
		(layer "B.Cu")
		(net "GND")
	)
	(gr_poly
		(pts
			(xy 54.322726 -53.537104) (xy 54.322726 -53.064664) (xy 54.52491 -52.86248) (xy 55.174642 -52.86248)
			(xy 55.224172 -52.81295) (xy 55.224172 -50.854356) (xy 55.147718 -50.777648) (xy 54.663848 -50.777648)
			(xy 54.582822 -50.85842) (xy 54.582822 -51.9176) (xy 53.9242 -52.576222) (xy 53.9242 -52.91836) (xy 53.776372 -53.066188)
			(xy 53.210968 -53.066188) (xy 53.210968 -53.067204) (xy 53.060346 -53.217826) (xy 53.060346 -53.526436)
			(xy 53.195982 -53.662072) (xy 54.197758 -53.662072)
		)
		(stroke
			(width 0)
			(type solid)
		)
		(fill yes)
		(layer "B.Cu")
		(net "GND")
	)
	(gr_poly
		(pts
			(xy 74.049636 -117.341904) (xy 74.270108 -117.341904) (xy 74.270108 -119.526304) (xy 74.650092 -119.526304)
			(xy 74.650092 -117.341904) (xy 74.652378 -117.341904) (xy 74.652378 -115.061238) (xy 74.543158 -114.952018)
			(xy 73.754996 -114.952018) (xy 73.709784 -114.996976)
			(arc
				(start 73.709784 -117.265196)
				(mid 73.701338 -117.343352)
				(end 73.676256 -117.41785)
			)
			(xy 73.671684 -117.427756) (xy 73.671684 -119.522748) (xy 73.67524 -119.526304) (xy 74.049636 -119.526304)
		)
		(stroke
			(width 0)
			(type solid)
		)
		(fill yes)
		(layer "B.Cu")
		(net "GND")
	)
	(gr_poly
		(pts
			(xy 83.92795 -55.222648) (xy 83.92795 -51.122834) (xy 83.707224 -50.902108) (xy 82.282284 -50.902108)
			(xy 82.18932 -50.995072) (xy 82.18932 -52.86756) (xy 82.182716 -52.874164) (xy 82.182716 -53.0098)
			(xy 82.015584 -53.176932) (xy 81.821528 -53.176932)
			(arc
				(start 81.815432 -53.178456)
				(mid 81.762241 -53.188333)
				(end 81.708244 -53.191664)
			)
			(xy 81.31683 -53.191664) (xy 81.154016 -53.354224) (xy 81.154016 -55.203344) (xy 81.330292 -55.37962)
			(xy 83.770978 -55.37962)
		)
		(stroke
			(width 0)
			(type solid)
		)
		(fill yes)
		(layer "B.Cu")
		(net "P0V6_DDR_VREF_AUX")
	)
	(gr_poly
		(pts
			(arc
				(start 26.637488 -15.841726)
				(mid 26.486612 -15.841726)
				(end 26.637488 -15.841726)
			)
		)
		(stroke
			(width 0)
			(type solid)
		)
		(fill yes)
		(layer "B.Cu")
		(net "GND")
	)
	(gr_poly
		(pts
			(xy 27.3304 -96.52) (xy 27.3304 -96.447864) (xy 27.304492 -96.42221) (xy 27.304492 -95.71101) (xy 26.53919 -94.945708)
			(xy 25.424892 -94.945708) (xy 25.418796 -94.951804) (xy 25.418796 -95.616522) (xy 25.2984 -95.736664)
			(xy 25.2984 -95.98152) (xy 25.327864 -96.000316) (xy 25.327864 -96.176338) (xy 25.2984 -96.195134)
			(xy 25.2984 -96.5454) (xy 25.205436 -96.638618) (xy 25.205436 -96.85655) (xy 25.396444 -97.047558)
			(xy 25.396444 -97.04959) (xy 25.501092 -97.154492) (xy 26.695908 -97.154492)
		)
		(stroke
			(width 0)
			(type solid)
		)
		(fill yes)
		(layer "B.Cu")
		(net "VCCIO3")
	)
	(gr_poly
		(pts
			(xy 54.776624 -70.09892) (xy 54.776624 -69.804534) (xy 54.825392 -69.755766) (xy 54.825392 -69.737224)
			(xy 55.821834 -68.740782) (xy 55.821834 -68.418456) (xy 55.630572 -68.227194) (xy 54.901084 -68.227194)
			(xy 54.686962 -68.441316) (xy 53.021992 -68.441316) (xy 52.932584 -68.530724) (xy 52.932584 -69.203824)
			(xy 52.996084 -69.267324) (xy 53.69687 -69.267324) (xy 53.705252 -69.275706) (xy 53.722524 -69.275706)
			(xy 53.89753 -69.450712) (xy 53.89753 -70.234048) (xy 53.951886 -70.288404) (xy 54.58714 -70.288404)
		)
		(stroke
			(width 0)
			(type solid)
		)
		(fill yes)
		(layer "B.Cu")
		(net "P2V5_SENSOR")
	)
	(gr_poly
		(pts
			(xy 71.303896 -36.369244) (xy 72.015858 -36.369244) (xy 72.4154 -35.969702) (xy 72.4154 -34.3408)
			(xy 71.172324 -33.097724) (xy 69.594476 -33.097724) (xy 69.4436 -33.2486) (xy 69.4436 -33.5788) (xy 69.6849 -33.8201)
			(xy 70.8533 -33.8201) (xy 71.2216 -34.1884) (xy 71.2216 -35.4584) (xy 70.895972 -35.784028) (xy 70.503034 -35.784028)
			(xy 70.386194 -35.900868) (xy 70.207886 -35.900868) (xy 70.18274 -35.926014) (xy 70.18274 -36.717478)
			(xy 70.213474 -36.748212) (xy 70.924928 -36.748212)
		)
		(stroke
			(width 0)
			(type solid)
		)
		(fill yes)
		(layer "B.Cu")
		(net "GND")
	)
	(gr_poly
		(pts
			(arc
				(start 14.98092 -73.81367)
				(mid 14.815312 -73.81367)
				(end 14.98092 -73.81367)
			)
		)
		(stroke
			(width 0)
			(type solid)
		)
		(fill yes)
		(layer "B.Cu")
		(net "GND")
	)
	(gr_poly
		(pts
			(arc
				(start 26.644854 -17.165574)
				(mid 26.479246 -17.165574)
				(end 26.644854 -17.165574)
			)
		)
		(stroke
			(width 0)
			(type solid)
		)
		(fill yes)
		(layer "B.Cu")
		(net "GND")
	)
	(gr_poly
		(pts
			(xy 71.707756 -43.575732) (xy 72.121776 -43.575732) (xy 72.76846 -42.929302) (xy 72.76846 -42.621708)
			(xy 72.198738 -42.621708) (xy 72.136762 -42.68343) (xy 72.077834 -42.68343) (xy 71.96201 -42.799508)
			(xy 70.88759 -42.799508) (xy 70.771766 -42.68343) (xy 70.69963 -42.68343) (xy 70.5358 -42.5196) (xy 70.5358 -41.91)
			(xy 70.409054 -41.783508) (xy 69.79539 -41.783508) (xy 69.769736 -41.7576) (xy 69.723 -41.7576) (xy 69.596 -41.8846)
			(xy 69.596 -43.6118) (xy 69.749924 -43.765724) (xy 71.517764 -43.765724)
		)
		(stroke
			(width 0)
			(type solid)
		)
		(fill yes)
		(layer "B.Cu")
		(net "P1V2_AUX")
	)
	(gr_poly
		(pts
			(xy 87.757 -34.179256) (xy 87.757 -29.464) (xy 87.5284 -29.2354) (xy 85.6234 -29.2354) (xy 85.2678 -29.591)
			(xy 84.182966 -29.591) (xy 83.878166 -29.8958) (xy 83.878166 -30.928056) (xy 84.030566 -31.080456)
			(xy 84.513166 -31.080456) (xy 84.729066 -31.296356) (xy 84.729066 -32.490156) (xy 84.487766 -32.731456)
			(xy 81.3689 -32.731456) (xy 81.3308 -32.769556) (xy 81.3308 -34.274506) (xy 81.46415 -34.407856)
			(xy 85.911182 -34.407856) (xy 86.009988 -34.407856) (xy 86.122002 -34.407856) (xy 87.5284 -34.407856)
		)
		(stroke
			(width 0)
			(type solid)
		)
		(fill yes)
		(layer "B.Cu")
		(net "GND")
	)
	(gr_poly
		(pts
			(xy 73.63968 -60.684156) (xy 73.63968 -60.260992) (xy 73.558908 -60.18022) (xy 72.769984 -60.18022)
			(xy 72.564752 -59.974988) (xy 72.564752 -58.52668) (xy 72.40397 -58.365898) (xy 71.514208 -58.365898)
			(xy 71.367142 -58.512964) (xy 71.367142 -59.188858) (xy 71.12 -59.436) (xy 70.9422 -59.436) (xy 70.8406 -59.5376)
			(xy 70.8406 -59.922664) (xy 71.371968 -60.454032) (xy 71.508366 -60.590176) (xy 71.623936 -60.705492)
			(xy 72.653906 -60.705492) (xy 72.678798 -60.730384) (xy 73.536302 -60.730384) (xy 73.54951 -60.743846)
			(xy 73.57999 -60.743846)
		)
		(stroke
			(width 0)
			(type solid)
		)
		(fill yes)
		(layer "B.Cu")
		(net "P1V0_STBY_PE_VCC10A")
	)
	(gr_poly
		(pts
			(arc
				(start 75.312016 -37.097716)
				(mid 75.327329 -37.005993)
				(end 75.36434 -36.920678)
			)
			(xy 75.36434 -35.98037) (xy 75.259946 -35.875976) (xy 75.040998 -35.875976) (xy 74.490834 -35.325812)
			(xy 74.490834 -34.73577) (xy 74.399648 -34.644584) (xy 72.9742 -34.644584) (xy 72.669908 -34.948876)
			(xy 72.669908 -36.075112) (xy 72.266048 -36.478718) (xy 72.266048 -36.539678) (xy 72.179688 -36.626038)
			(xy 71.498968 -36.626038) (xy 71.464424 -36.660582) (xy 71.464424 -37.08908) (xy 71.521574 -37.146484)
			(xy 75.309984 -37.146484)
		)
		(stroke
			(width 0)
			(type solid)
		)
		(fill yes)
		(layer "B.Cu")
		(net "P1V2_AUX")
	)
	(gr_poly
		(pts
			(xy 54.779672 -44.9326) (xy 54.779672 -44.207938) (xy 54.998874 -43.988736) (xy 54.998874 -43.532044)
			(xy 54.951122 -43.484292) (xy 54.522624 -43.484292) (xy 54.094888 -43.912028)
			(arc
				(start 54.093364 -43.930824)
				(mid 54.027825 -44.072549)
				(end 53.8861 -44.138088)
			)
			(xy 53.867304 -44.139612) (xy 53.81498 -44.191936) (xy 53.81498 -44.8056) (xy 53.660802 -44.959778)
			(xy 53.660802 -45.483526) (xy 53.709824 -45.532548) (xy 54.179724 -45.532548)
		)
		(stroke
			(width 0)
			(type solid)
		)
		(fill yes)
		(layer "B.Cu")
		(net "P3V3_STBY_PLLAHVDD")
	)
	(gr_poly
		(pts
			(arc
				(start 31.104586 -19.802856)
				(mid 31.259371 -19.726508)
				(end 31.42996 -19.70024)
			)
			(xy 32.83839 -19.70024)
			(arc
				(start 32.898588 -19.639788)
				(mid 33.082468 -19.51686)
				(end 33.2994 -19.473672)
			)
			(xy 33.655 -19.473672) (xy 33.655 -18.034) (xy 32.766 -17.145) (xy 31.75 -17.145) (xy 30.861 -18.034)
			(xy 30.861 -19.685) (xy 30.988 -19.812) (xy 31.091378 -19.812)
		)
		(stroke
			(width 0)
			(type solid)
		)
		(fill yes)
		(layer "B.Cu")
		(net "CRT_VCC5_2_FUSE")
	)
	(gr_poly
		(pts
			(xy 73.337674 -67.949572) (xy 73.337674 -65.840356) (xy 73.224136 -65.726818) (xy 67.99453 -65.726818)
			(xy 67.437 -66.284348) (xy 67.437 -66.715132)
			(arc
				(start 67.582034 -66.860166)
				(mid 67.64991 -66.961655)
				(end 67.673728 -67.0814)
			)
			(xy 67.673728 -67.6656) (xy 67.672458 -67.692524) (xy 67.670426 -67.716146) (xy 67.84467 -67.89039)
			(arc
				(start 67.854576 -67.8942)
				(mid 67.970628 -67.965349)
				(end 68.05422 -68.072762)
			)
			(xy 73.214484 -68.072762)
		)
		(stroke
			(width 0)
			(type solid)
		)
		(fill yes)
		(layer "B.Cu")
		(net "P1V8_AUX")
	)
	(gr_poly
		(pts
			(arc
				(start 8.536432 -99.5934)
				(mid 8.278368 -99.5934)
				(end 8.536432 -99.5934)
			)
		)
		(stroke
			(width 0)
			(type solid)
		)
		(fill yes)
		(layer "B.Cu")
		(net "GND")
	)
	(gr_poly
		(pts
			(arc
				(start 8.841232 -95.25)
				(mid 8.583168 -95.25)
				(end 8.841232 -95.25)
			)
		)
		(stroke
			(width 0)
			(type solid)
		)
		(fill yes)
		(layer "B.Cu")
		(net "GND")
	)
	(gr_poly
		(pts
			(arc
				(start 13.218922 -108.342176)
				(mid 12.960858 -108.342176)
				(end 13.218922 -108.342176)
			)
		)
		(stroke
			(width 0)
			(type solid)
		)
		(fill yes)
		(layer "B.Cu")
		(net "GND")
	)
	(gr_poly
		(pts
			(arc
				(start 14.726412 -108.342176)
				(mid 14.468348 -108.342176)
				(end 14.726412 -108.342176)
			)
		)
		(stroke
			(width 0)
			(type solid)
		)
		(fill yes)
		(layer "B.Cu")
		(net "GND")
	)
	(gr_poly
		(pts
			(arc
				(start 15.13967 -110.109508)
				(mid 14.881606 -110.109508)
				(end 15.13967 -110.109508)
			)
		)
		(stroke
			(width 0)
			(type solid)
		)
		(fill yes)
		(layer "B.Cu")
		(net "GND")
	)
	(gr_poly
		(pts
			(arc
				(start 15.343632 -50.7746)
				(mid 15.085568 -50.7746)
				(end 15.343632 -50.7746)
			)
		)
		(stroke
			(width 0)
			(type solid)
		)
		(fill yes)
		(layer "B.Cu")
		(net "GND")
	)
	(gr_poly
		(pts
			(arc
				(start 16.96847 -109.982508)
				(mid 16.710406 -109.982508)
				(end 16.96847 -109.982508)
			)
		)
		(stroke
			(width 0)
			(type solid)
		)
		(fill yes)
		(layer "B.Cu")
		(net "GND")
	)
	(gr_poly
		(pts
			(arc
				(start 18.171922 -108.341922)
				(mid 17.913858 -108.341922)
				(end 18.171922 -108.341922)
			)
		)
		(stroke
			(width 0)
			(type solid)
		)
		(fill yes)
		(layer "B.Cu")
		(net "GND")
	)
	(gr_poly
		(pts
			(arc
				(start 19.628612 -108.341922)
				(mid 19.370548 -108.341922)
				(end 19.628612 -108.341922)
			)
		)
		(stroke
			(width 0)
			(type solid)
		)
		(fill yes)
		(layer "B.Cu")
		(net "GND")
	)
	(gr_poly
		(pts
			(arc
				(start 20.906232 -47.879)
				(mid 20.648168 -47.879)
				(end 20.906232 -47.879)
			)
		)
		(stroke
			(width 0)
			(type solid)
		)
		(fill yes)
		(layer "B.Cu")
		(net "GND")
	)
	(gr_poly
		(pts
			(arc
				(start 22.049232 -100.9904)
				(mid 21.791168 -100.9904)
				(end 22.049232 -100.9904)
			)
		)
		(stroke
			(width 0)
			(type solid)
		)
		(fill yes)
		(layer "B.Cu")
		(net "GND")
	)
	(gr_poly
		(pts
			(arc
				(start 26.799032 -79.2226)
				(mid 26.540968 -79.2226)
				(end 26.799032 -79.2226)
			)
		)
		(stroke
			(width 0)
			(type solid)
		)
		(fill yes)
		(layer "B.Cu")
		(net "GND")
	)
	(gr_poly
		(pts
			(arc
				(start 28.36799 -74.541634)
				(mid 28.109926 -74.541634)
				(end 28.36799 -74.541634)
			)
		)
		(stroke
			(width 0)
			(type solid)
		)
		(fill yes)
		(layer "B.Cu")
		(net "GND")
	)
	(gr_poly
		(pts
			(arc
				(start 42.088308 -108.886752)
				(mid 41.830244 -108.886752)
				(end 42.088308 -108.886752)
			)
		)
		(stroke
			(width 0)
			(type solid)
		)
		(fill yes)
		(layer "B.Cu")
		(net "GND")
	)
	(gr_poly
		(pts
			(arc
				(start 44.294552 -79.35722)
				(mid 44.036488 -79.35722)
				(end 44.294552 -79.35722)
			)
		)
		(stroke
			(width 0)
			(type solid)
		)
		(fill yes)
		(layer "B.Cu")
		(net "GND")
	)
	(gr_poly
		(pts
			(arc
				(start 47.714408 -33.63595)
				(mid 47.464472 -33.63595)
				(end 47.714408 -33.63595)
			)
		)
		(stroke
			(width 0)
			(type solid)
		)
		(fill yes)
		(layer "B.Cu")
		(net "GND")
	)
	(gr_poly
		(pts
			(arc
				(start 51.933348 -31.877)
				(mid 51.683412 -31.877)
				(end 51.933348 -31.877)
			)
		)
		(stroke
			(width 0)
			(type solid)
		)
		(fill yes)
		(layer "B.Cu")
		(net "GND")
	)
	(gr_poly
		(pts
			(arc
				(start 52.884832 -15.0114)
				(mid 52.626768 -15.0114)
				(end 52.884832 -15.0114)
			)
		)
		(stroke
			(width 0)
			(type solid)
		)
		(fill yes)
		(layer "B.Cu")
		(net "GND")
	)
	(gr_poly
		(pts
			(arc
				(start 53.769768 -35.690302)
				(mid 53.519832 -35.690302)
				(end 53.769768 -35.690302)
			)
		)
		(stroke
			(width 0)
			(type solid)
		)
		(fill yes)
		(layer "B.Cu")
		(net "GND")
	)
	(gr_poly
		(pts
			(arc
				(start 56.385968 -31.7754)
				(mid 56.136032 -31.7754)
				(end 56.385968 -31.7754)
			)
		)
		(stroke
			(width 0)
			(type solid)
		)
		(fill yes)
		(layer "B.Cu")
		(net "GND")
	)
	(gr_poly
		(pts
			(arc
				(start 62.35573 -26.296112)
				(mid 62.097666 -26.296112)
				(end 62.35573 -26.296112)
			)
		)
		(stroke
			(width 0)
			(type solid)
		)
		(fill yes)
		(layer "B.Cu")
		(net "GND")
	)
	(gr_poly
		(pts
			(arc
				(start 63.298832 -19.2786)
				(mid 63.040768 -19.2786)
				(end 63.298832 -19.2786)
			)
		)
		(stroke
			(width 0)
			(type solid)
		)
		(fill yes)
		(layer "B.Cu")
		(net "GND")
	)
	(gr_poly
		(pts
			(arc
				(start 63.911734 -26.141426)
				(mid 63.65367 -26.141426)
				(end 63.911734 -26.141426)
			)
		)
		(stroke
			(width 0)
			(type solid)
		)
		(fill yes)
		(layer "B.Cu")
		(net "GND")
	)
	(gr_poly
		(pts
			(arc
				(start 64.74587 -26.339038)
				(mid 64.487806 -26.339038)
				(end 64.74587 -26.339038)
			)
		)
		(stroke
			(width 0)
			(type solid)
		)
		(fill yes)
		(layer "B.Cu")
		(net "GND")
	)
	(gr_poly
		(pts
			(arc
				(start 66.107818 -26.327354)
				(mid 65.849754 -26.327354)
				(end 66.107818 -26.327354)
			)
		)
		(stroke
			(width 0)
			(type solid)
		)
		(fill yes)
		(layer "B.Cu")
		(net "GND")
	)
	(gr_poly
		(pts
			(xy 68.920614 -56.008778) (xy 70.485762 -56.008778) (xy 70.572884 -55.921656) (xy 70.572884 -55.2196)
			(xy 70.488048 -55.134764) (xy 69.73189 -55.134764) (xy 69.498972 -55.367682) (xy 69.11721 -55.367682)
			(arc
				(start 69.108574 -55.370984)
				(mid 69.032224 -55.391882)
				(end 68.95338 -55.398924)
			)
			(arc
				(start 68.872608 -55.398924)
				(mid 68.793763 -55.391884)
				(end 68.717414 -55.370984)
			)
			(xy 68.708778 -55.367682) (xy 68.63842 -55.367682) (xy 68.53301 -55.262272) (xy 67.285616 -55.262272)
			(xy 67.123056 -55.424578) (xy 67.123056 -56.379872) (xy 67.418966 -56.675782) (xy 68.25361 -56.675782)
		)
		(stroke
			(width 0)
			(type solid)
		)
		(fill yes)
		(layer "B.Cu")
		(net "P1V0_STBY_RC_VCC10A")
	)
	(gr_poly
		(pts
			(arc
				(start 87.225632 -16.7894)
				(mid 86.967568 -16.7894)
				(end 87.225632 -16.7894)
			)
		)
		(stroke
			(width 0)
			(type solid)
		)
		(fill yes)
		(layer "B.Cu")
		(net "GND")
	)
	(gr_poly
		(pts
			(arc
				(start 30.385004 -50.72253)
				(mid 30.097476 -50.72253)
				(end 30.385004 -50.72253)
			)
		)
		(stroke
			(width 0)
			(type solid)
		)
		(fill yes)
		(layer "B.Cu")
		(net "GND")
	)
	(gr_poly
		(pts
			(xy 40.8432 -54.864) (xy 40.8432 -54.5084) (xy 41.060624 -54.290976) (xy 41.40454 -54.290976) (xy 41.587928 -54.107588)
			(xy 41.587928 -53.16601) (xy 41.282366 -52.860448) (xy 38.398704 -52.860448) (xy 38.215062 -53.04409)
			(xy 38.215062 -53.747416)
			(arc
				(start 38.33241 -53.864764)
				(mid 38.449057 -53.795412)
				(end 38.5826 -53.771292)
			)
			(arc
				(start 38.5826 -53.771292)
				(mid 38.718998 -53.796508)
				(end 38.837362 -53.868828)
			)
			(xy 39.054278 -53.868828) (xy 39.476426 -54.290976) (xy 39.476426 -54.919626) (xy 39.5986 -55.0418)
			(xy 40.6654 -55.0418)
		)
		(stroke
			(width 0)
			(type solid)
		)
		(fill yes)
		(layer "B.Cu")
		(net "P1V2_P1V0_I3C_VDDL1")
	)
	(gr_poly
		(pts
			(xy 86.160864 -64.116966) (xy 86.160864 -59.060588) (xy 86.143084 -59.042808) (xy 78.414118 -59.042808)
			(xy 78.199996 -59.25693) (xy 78.199996 -63.707264)
			(arc
				(start 78.236572 -63.717678)
				(mid 78.435461 -63.854966)
				(end 78.511908 -64.0842)
			)
			(arc
				(start 78.511908 -64.0842)
				(mid 78.506852 -64.146103)
				(end 78.491842 -64.206374)
			)
			(xy 78.481682 -64.236092) (xy 78.575662 -64.330072)
			(arc
				(start 80.1116 -64.330072)
				(mid 80.160725 -64.333992)
				(end 80.208628 -64.345566)
			)
			(xy 80.216248 -64.348106) (xy 85.929724 -64.348106)
		)
		(stroke
			(width 0)
			(type solid)
		)
		(fill yes)
		(layer "B.Cu")
		(net "P1V2_AUX")
	)
	(gr_poly
		(pts
			(arc
				(start 24.178768 -112.594898)
				(mid 23.857712 -112.594898)
				(end 24.178768 -112.594898)
			)
		)
		(stroke
			(width 0)
			(type solid)
		)
		(fill yes)
		(layer "B.Cu")
		(net "GND")
	)
	(gr_poly
		(pts
			(arc
				(start 25.617678 -112.554258)
				(mid 25.296622 -112.554258)
				(end 25.617678 -112.554258)
			)
		)
		(stroke
			(width 0)
			(type solid)
		)
		(fill yes)
		(layer "B.Cu")
		(net "GND")
	)
	(gr_poly
		(pts
			(xy 33.4518 -40.767) (xy 33.4518 -40.665654)
			(arc
				(start 33.44672 -40.65524)
				(mid 33.404644 -40.53523)
				(end 33.390332 -40.40886)
			)
			(arc
				(start 33.390332 -40.1574)
				(mid 33.405948 -40.025509)
				(end 33.4518 -39.90086)
			)
			(xy 33.4518 -39.1922) (xy 33.274 -39.0144) (xy 32.5628 -39.0144) (xy 31.8516 -38.3032) (xy 28.0924 -38.3032)
			(xy 27.9908 -38.4048) (xy 27.9908 -39.9542) (xy 28.4226 -40.386) (xy 28.829 -40.386) (xy 29.1338 -40.0812)
			(xy 29.718 -40.0812) (xy 30.1244 -40.4876) (xy 30.1244 -41.0972) (xy 30.3276 -41.3004) (xy 32.9184 -41.3004)
		)
		(stroke
			(width 0)
			(type solid)
		)
		(fill yes)
		(layer "B.Cu")
		(net "P5V_AUX")
	)
	(gr_poly
		(pts
			(xy 42.7101 -52.415694) (xy 42.7101 -51.6255) (xy 43.29684 -51.03876)
			(arc
				(start 43.293538 -51.013868)
				(mid 43.291101 -50.990174)
				(end 43.290236 -50.96637)
			)
			(arc
				(start 43.290236 -50.96637)
				(mid 43.293955 -50.915292)
				(end 43.304968 -50.865278)
			)
			(xy 43.307 -50.858166) (xy 43.307 -50.476404)
			(arc
				(start 43.304968 -50.469292)
				(mid 43.293961 -50.419277)
				(end 43.290236 -50.3682)
			)
			(arc
				(start 43.290236 -50.3682)
				(mid 43.293955 -50.317122)
				(end 43.304968 -50.267108)
			)
			(xy 43.307 -50.259996) (xy 43.307 -50.0126) (xy 43.1546 -49.8602) (xy 41.402 -49.8602) (xy 41.223438 -50.038762)
			(xy 41.223438 -52.534058) (xy 41.29532 -52.60594) (xy 41.387776 -52.60594) (xy 41.438576 -52.656994)
			(xy 42.4688 -52.656994)
		)
		(stroke
			(width 0)
			(type solid)
		)
		(fill yes)
		(layer "B.Cu")
		(net "P1V2_P1V0_I3C_VDDL2")
	)
	(gr_poly
		(pts
			(xy 60.65266 -47.71136) (xy 60.771024 -47.592996) (xy 60.771024 -46.755304) (xy 60.901326 -46.625002)
			(xy 60.901326 -45.19422) (xy 60.853574 -45.146468) (xy 60.255404 -45.146468) (xy 60.172346 -45.229526)
			(xy 60.172346 -45.616876) (xy 60.084208 -45.705014) (xy 59.724544 -45.705014) (xy 59.722258 -45.705268)
			(xy 59.690254 -45.706792) (xy 59.65825 -45.705268) (xy 59.655964 -45.705014) (xy 59.210448 -45.705014)
			(xy 59.150758 -45.764704) (xy 59.150758 -46.429676) (xy 59.013598 -46.566836) (xy 58.631328 -46.566836)
			(xy 58.495692 -46.702472) (xy 58.495692 -47.16399) (xy 58.624216 -47.29226) (xy 59.897772 -47.29226)
			(xy 59.904884 -47.299626) (xy 60.07735 -47.299626) (xy 60.132976 -47.355252) (xy 60.188348 -47.41037)
			(xy 60.188348 -47.58182) (xy 60.326524 -47.719996) (xy 60.65266 -47.719996)
		)
		(stroke
			(width 0)
			(type solid)
		)
		(fill yes)
		(layer "B.Cu")
		(net "GND")
	)
	(gr_poly
		(pts
			(xy 33.872424 -60.183776) (xy 35.588448 -60.183776) (xy 35.837368 -59.934856) (xy 35.837368 -59.433968)
			(xy 35.637216 -59.233816)
			(arc
				(start 35.28695 -59.233816)
				(mid 35.176232 -59.293848)
				(end 35.052 -59.314588)
			)
			(arc
				(start 35.052 -59.314588)
				(mid 34.818846 -59.235052)
				(end 34.682938 -59.0296)
			)
			(xy 33.3502 -59.0296) (xy 32.8676 -58.547) (xy 32.131 -58.547) (xy 32.067754 -58.610246)
			(arc
				(start 32.067754 -60.767976)
				(mid 32.086179 -60.783135)
				(end 32.103568 -60.799472)
			)
			(xy 32.147002 -60.842652) (xy 33.213548 -60.842652)
		)
		(stroke
			(width 0)
			(type solid)
		)
		(fill yes)
		(layer "B.Cu")
		(net "P12V_SENSOR")
	)
	(gr_poly
		(pts
			(xy 35.8902 -31.4706) (xy 36.9062 -31.4706) (xy 36.946332 -31.430468) (xy 36.946332 -31.42615) (xy 37.084 -31.288736)
			(xy 37.084 -30.9372) (xy 36.8808 -30.734) (xy 36.146486 -30.734)
			(arc
				(start 36.133532 -30.765496)
				(mid 35.780726 -31.001444)
				(end 35.42792 -30.765496)
			)
			(xy 35.414966 -30.734) (xy 34.671 -30.734) (xy 34.4932 -30.9118) (xy 34.4932 -31.6484) (xy 34.5694 -31.7246)
			(xy 35.6362 -31.7246)
		)
		(stroke
			(width 0)
			(type solid)
		)
		(fill yes)
		(layer "B.Cu")
		(net "P3V3_AUX")
	)
	(gr_poly
		(pts
			(arc
				(start 48.85563 -52.920392)
				(mid 48.912691 -52.895066)
				(end 48.974502 -52.886356)
			)
			(xy 49.241964 -52.886356) (xy 49.241964 -52.928012) (xy 49.364138 -52.928012) (xy 49.389792 -52.902104)
			(xy 49.389792 -52.775358) (xy 49.418748 -52.746402) (xy 49.418748 -52.401724) (xy 49.33569 -52.318412)
			(xy 49.08804 -52.318412) (xy 48.82896 -52.059332) (xy 48.82896 -51.63566) (xy 48.70704 -51.51374)
			(xy 48.37938 -51.51374) (xy 48.256444 -51.636676) (xy 48.256444 -51.883564) (xy 48.247808 -51.883564)
			(xy 48.247808 -52.408836) (xy 48.256444 -52.408836)
			(arc
				(start 48.256444 -52.676298)
				(mid 48.254589 -52.704202)
				(end 48.249332 -52.73167)
			)
			(xy 48.247808 -52.73802) (xy 48.247808 -52.770532) (xy 48.362616 -52.88534) (xy 48.73371 -52.88534)
			(xy 48.776382 -52.928012) (xy 48.843184 -52.928012)
		)
		(stroke
			(width 0)
			(type solid)
		)
		(fill yes)
		(layer "B.Cu")
		(net "P1V2_P1V0_I3C_VDDL2")
	)
	(gr_poly
		(pts
			(xy 60.160408 -50.227484)
			(arc
				(start 60.160408 -50.181764)
				(mid 60.186918 -50.075797)
				(end 60.259976 -49.994566)
			)
			(xy 60.259976 -48.906684) (xy 59.955176 -48.601884) (xy 59.955176 -47.709582) (xy 59.792362 -47.546768)
			(xy 58.688732 -47.546768) (xy 58.570876 -47.664624) (xy 58.570876 -48.162464) (xy 58.622946 -48.214534)
			(xy 59.136534 -48.214534) (xy 59.352434 -48.430434) (xy 59.352434 -48.60544) (xy 59.675014 -48.92802)
			(xy 59.675014 -49.482248) (xy 59.673236 -49.48428) (xy 59.673236 -49.522126) (xy 59.425586 -49.769776)
			(arc
				(start 59.425586 -50.029364)
				(mid 59.470584 -50.100689)
				(end 59.486292 -50.183542)
			)
			(xy 59.486292 -50.30216) (xy 59.591956 -50.40757) (xy 59.890914 -50.40757)
		)
		(stroke
			(width 0)
			(type solid)
		)
		(fill yes)
		(layer "B.Cu")
		(net "P1V0_AUX")
	)
	(gr_poly
		(pts
			(xy 51.43754 -43.961304) (xy 51.43754 -43.471084) (xy 51.684174 -43.22445) (xy 52.606194 -43.22445)
			(xy 52.787804 -43.04284) (xy 52.787804 -42.604436) (xy 52.687728 -42.50436) (xy 52.53863 -42.50436)
			(xy 52.535836 -42.504614) (xy 52.499768 -42.506646) (xy 52.4637 -42.504614) (xy 52.460906 -42.50436)
			(xy 51.785266 -42.50436) (xy 51.6128 -42.676826) (xy 51.60518 -42.676826)
			(arc
				(start 51.492404 -42.789602)
				(mid 51.399161 -42.851842)
				(end 51.289204 -42.873676)
			)
			(xy 50.66792 -42.873676) (xy 50.638202 -42.903648) (xy 50.638202 -43.096434) (xy 50.634646 -43.09999)
			(xy 50.634646 -43.163236) (xy 50.374804 -43.423078) (xy 49.972468 -43.423078) (xy 49.89703 -43.498516)
			(xy 49.89703 -43.923458) (xy 49.990756 -44.017184) (xy 51.238658 -44.017184) (xy 51.238658 -44.017692)
			(xy 51.381152 -44.017692)
		)
		(stroke
			(width 0)
			(type solid)
		)
		(fill yes)
		(layer "B.Cu")
		(net "GND")
	)
	(gr_poly
		(pts
			(xy 84.47278 -78.83398) (xy 84.47278 -72.96658) (xy 84.114132 -72.607932)
			(arc
				(start 79.502 -72.607932)
				(mid 79.361557 -72.757132)
				(end 79.16418 -72.812148)
			)
			(arc
				(start 79.16418 -72.812148)
				(mid 79.108595 -72.80804)
				(end 79.054198 -72.795892)
			)
			(xy 79.024988 -72.787256) (xy 78.898242 -72.914002)
			(arc
				(start 78.898242 -74.575416)
				(mid 79.045321 -74.876406)
				(end 78.898242 -75.177396)
			)
			(xy 78.898242 -78.994762) (xy 79.01178 -79.1083) (xy 84.19846 -79.1083)
		)
		(stroke
			(width 0)
			(type solid)
		)
		(fill yes)
		(layer "B.Cu")
		(net "GND")
	)
	(gr_poly
		(pts
			(xy 48.878744 -51.12258) (xy 48.878744 -49.860454) (xy 49.07153 -49.667668) (xy 50.832258 -49.667668)
			(xy 50.88509 -49.614836) (xy 50.88509 -49.119028) (xy 50.819812 -49.05375) (xy 48.955706 -49.05375)
			(xy 48.708818 -48.806862) (xy 48.708818 -48.80356) (xy 48.688244 -48.78324) (xy 48.688244 -47.79899)
			(xy 48.708818 -47.77867) (xy 48.708818 -47.778162) (xy 48.953928 -47.533052) (xy 50.168556 -47.533052)
			(xy 50.18786 -47.513748) (xy 50.188368 -47.514256) (xy 51.177952 -47.514256) (xy 51.206654 -47.485808)
			(xy 52.797456 -47.485808) (xy 52.8193 -47.463964) (xy 52.8193 -46.108112) (xy 52.774088 -46.063154)
			(xy 52.655216 -45.944028) (xy 52.197254 -45.944028) (xy 51.390042 -46.75124) (xy 48.42002 -46.75124)
			(xy 48.171354 -46.999906) (xy 48.171354 -51.03876)
			(arc
				(start 48.176434 -51.049174)
				(mid 48.190174 -51.081931)
				(end 48.20031 -51.115976)
			)
			(xy 48.203612 -51.129692) (xy 48.28032 -51.2064) (xy 48.794924 -51.2064)
		)
		(stroke
			(width 0)
			(type solid)
		)
		(fill yes)
		(layer "B.Cu")
		(net "P1V2_AUX")
	)
	(gr_poly
		(pts
			(xy 63.367158 -50.241454)
			(arc
				(start 63.363348 -50.216054)
				(mid 63.360513 -50.191361)
				(end 63.359538 -50.166524)
			)
			(arc
				(start 63.359538 -50.166524)
				(mid 63.4564 -49.932678)
				(end 63.690246 -49.835816)
			)
			(arc
				(start 63.690246 -49.835816)
				(mid 63.715083 -49.836788)
				(end 63.739776 -49.839626)
			)
			(xy 63.765176 -49.843436) (xy 63.77686 -49.831752) (xy 64.69761 -49.831752) (xy 64.873632 -49.65573)
			(xy 64.873632 -48.384968) (xy 64.222884 -48.384968) (xy 64.177672 -48.383698) (xy 64.15532 -48.382428)
			(xy 64.104774 -48.432974) (xy 64.104774 -49.115472) (xy 63.938404 -49.281842) (xy 63.294006 -49.281842)
			(xy 63.25616 -49.319688) (xy 63.25616 -49.681384) (xy 63.255652 -49.681892) (xy 63.255652 -49.856644)
			(xy 63.15964 -49.952656) (xy 62.798452 -49.952656) (xy 62.65799 -50.093118) (xy 62.65799 -50.291492)
			(xy 62.776608 -50.409856)
			(arc
				(start 63.11392 -50.409856)
				(mid 63.135452 -50.411341)
				(end 63.156592 -50.415698)
			)
			(xy 63.18504 -50.423572)
		)
		(stroke
			(width 0)
			(type solid)
		)
		(fill yes)
		(layer "B.Cu")
		(net "GND")
	)
	(gr_poly
		(pts
			(xy 32.0294 -58.2676) (xy 32.587946 -58.2676) (xy 32.639 -58.2168) (xy 32.639 -56.642) (xy 32.4612 -56.4642)
			(xy 32.1818 -56.4642)
			(arc
				(start 31.841186 -56.804814)
				(mid 31.81145 -56.87391)
				(end 31.837376 -56.944514)
			)
			(arc
				(start 31.837376 -56.944514)
				(mid 31.90969 -57.06288)
				(end 31.934912 -57.199276)
			)
			(arc
				(start 31.934912 -57.199276)
				(mid 31.823171 -57.469043)
				(end 31.553404 -57.580784)
			)
			(arc
				(start 31.553404 -57.580784)
				(mid 31.468465 -57.571202)
				(end 31.387796 -57.542938)
			)
			(arc
				(start 31.387796 -57.542938)
				(mid 31.289628 -57.548346)
				(end 31.242 -57.634378)
			)
			(xy 31.242 -58.5216) (xy 31.369 -58.6486) (xy 31.6484 -58.6486)
		)
		(stroke
			(width 0)
			(type solid)
		)
		(fill yes)
		(layer "B.Cu")
		(net "P12V_AUX")
	)
	(gr_poly
		(pts
			(xy 57.780936 -74.042016) (xy 57.780936 -72.334628) (xy 57.781952 -72.333866) (xy 57.781952 -71.493634)
			(xy 57.900062 -71.375524) (xy 58.71718 -71.375524) (xy 58.764932 -71.327772) (xy 58.764932 -69.866256)
			(xy 58.650124 -69.751448)
			(arc
				(start 58.382662 -69.751448)
				(mid 58.299104 -69.795251)
				(end 58.287666 -69.888862)
			)
			(arc
				(start 58.287666 -69.888862)
				(mid 58.309168 -69.966299)
				(end 58.316368 -70.046342)
			)
			(arc
				(start 58.316368 -70.046342)
				(mid 58.186103 -70.360831)
				(end 57.871614 -70.491096)
			)
			(xy 57.448704 -70.491096) (xy 57.427622 -70.512432) (xy 57.097676 -70.512432) (xy 56.987694 -70.622414)
			(xy 56.987694 -73.31583) (xy 56.750966 -73.552558) (xy 55.881524 -73.552558) (xy 55.847234 -73.586848)
			(xy 55.847234 -74.074782) (xy 55.90159 -74.129138) (xy 57.694068 -74.129138)
		)
		(stroke
			(width 0)
			(type solid)
		)
		(fill yes)
		(layer "B.Cu")
		(net "GND")
	)
	(gr_poly
		(pts
			(xy 75.849988 -117.341904) (xy 75.851512 -117.341904) (xy 75.851512 -117.279166) (xy 75.892152 -117.238526)
			(xy 76.205842 -117.238526) (xy 76.22032 -117.224048) (xy 76.22032 -114.266472) (xy 76.778612 -113.70818)
			(xy 83.90382 -113.70818) (xy 84.42071 -113.19129) (xy 84.42071 -108.61929) (xy 85.4964 -107.5436)
			(xy 88.109298 -107.5436) (xy 88.636348 -107.01655) (xy 88.636348 -88.509348) (xy 85.52688 -85.39988)
			(xy 85.52688 -82.09788) (xy 85.217 -81.788) (xy 82.423 -81.788) (xy 82.169 -82.042) (xy 82.169 -87.122)
			(xy 86.203536 -91.156536) (xy 86.203536 -101.074474) (xy 85.444584 -101.833426) (xy 80.208374 -101.833426)
			(xy 80.0862 -101.9556) (xy 80.0862 -109.1946) (xy 78.0034 -111.2774) (xy 75.0316 -111.2774) (xy 74.871072 -111.437928)
			(xy 74.871072 -114.920268) (xy 74.906632 -114.955828) (xy 74.906632 -117.596412) (xy 74.9046 -117.596412)
			(xy 74.9046 -119.122952) (xy 75.24242 -119.122952) (xy 75.25004 -119.115332) (xy 75.25004 -117.341904)
			(xy 75.25131 -117.341904) (xy 75.25131 -117.291612) (xy 75.283568 -117.259354) (xy 75.440286 -117.259354)
			(xy 75.470512 -117.28958) (xy 75.470512 -119.525288) (xy 75.471528 -119.526304) (xy 75.849988 -119.526304)
		)
		(stroke
			(width 0)
			(type solid)
		)
		(fill yes)
		(layer "B.Cu")
		(net "P12V_AUX")
	)
	(gr_poly
		(pts
			(xy 73.861676 -57.647332) (xy 73.861676 -57.307988) (xy 74.451464 -56.7182) (xy 75.062334 -56.7182)
			(xy 75.41006 -56.370474) (xy 75.41006 -56.199278) (xy 75.714606 -55.894732) (xy 76.820522 -55.894732)
			(xy 77.26172 -56.33593) (xy 78.979776 -56.33593) (xy 79.12354 -56.192166) (xy 79.12354 -55.441596)
			(arc
				(start 78.909164 -55.22722)
				(mid 78.889259 -55.209533)
				(end 78.871572 -55.189628)
			)
			(xy 78.409292 -54.727348)
			(arc
				(start 78.38948 -54.72938)
				(mid 78.369199 -54.731275)
				(end 78.34884 -54.73192)
			)
			(arc
				(start 78.34884 -54.73192)
				(mid 78.323366 -54.730996)
				(end 78.29804 -54.72811)
			)
			(arc
				(start 78.29804 -54.72811)
				(mid 78.099505 -54.61864)
				(end 78.018132 -54.407054)
			)
			(xy 78.01737 -54.356508) (xy 75.284584 -54.356508) (xy 74.129646 -55.511446) (xy 72.488552 -55.511446)
			(xy 72.128126 -55.15102) (xy 71.215758 -55.15102) (xy 71.188072 -55.178706) (xy 71.188072 -56.156352)
			(xy 70.893432 -56.450992) (xy 70.105524 -56.450992) (xy 70.105524 -57.417462) (xy 70.537324 -57.849262)
			(xy 73.659746 -57.849262)
		)
		(stroke
			(width 0)
			(type solid)
		)
		(fill yes)
		(layer "B.Cu")
		(net "P1V0_AUX")
	)
	(gr_poly
		(pts
			(xy 65.1002 -100.3554) (xy 65.1002 -98.74758) (xy 65.74028 -98.1075) (xy 65.74028 -97.2439) (xy 66.46672 -96.51746)
			(xy 66.46672 -93.0656) (xy 66.64452 -92.8878) (xy 67.3862 -92.8878) (xy 68.0212 -93.5228) (xy 68.960492 -93.5228)
			(xy 68.960492 -92.597732)
			(arc
				(start 68.74383 -92.38107)
				(mid 68.670357 -92.28655)
				(end 68.622418 -92.176854)
			)
			(xy 68.618862 -92.164662) (xy 68.5292 -92.075) (xy 68.5292 -91.5162) (xy 68.73748 -91.30792) (xy 70.42912 -91.30792)
			(xy 70.69074 -91.0463) (xy 70.69074 -90.13952) (xy 70.61454 -90.06332) (xy 70.18782 -90.06332) (xy 69.79412 -90.45702)
			(xy 66.46418 -90.45702) (xy 65.367408 -91.554046)
			(arc
				(start 65.367408 -91.644724)
				(mid 65.366739 -91.667871)
				(end 65.364868 -91.690952)
			)
			(arc
				(start 65.36309 -91.70797)
				(mid 65.354368 -91.760365)
				(end 65.339468 -91.811348)
			)
			(arc
				(start 65.338198 -91.814904)
				(mid 65.330091 -91.835951)
				(end 65.320926 -91.85656)
			)
			(xy 65.3161 -91.866974) (xy 65.3161 -92.23756) (xy 64.25438 -93.29928) (xy 64.25438 -97.7011) (xy 63.64224 -98.31324)
			(xy 63.64224 -100.49256) (xy 63.80988 -100.6602) (xy 64.7954 -100.6602)
		)
		(stroke
			(width 0)
			(type solid)
		)
		(fill yes)
		(layer "B.Cu")
		(net "PGPPA_BMC_AUX_L")
	)
	(gr_poly
		(pts
			(xy 83.82 -44.683426) (xy 83.82 -44.562522)
			(arc
				(start 83.817206 -44.554394)
				(mid 83.800881 -44.491823)
				(end 83.795362 -44.427394)
			)
			(arc
				(start 83.795362 -44.427394)
				(mid 83.800885 -44.362966)
				(end 83.817206 -44.300394)
			)
			(xy 83.82 -44.292266) (xy 83.82 -44.2722) (xy 83.835748 -44.256452)
			(arc
				(start 83.839304 -44.249594)
				(mid 83.907089 -44.157613)
				(end 83.99907 -44.089828)
			)
			(xy 84.005928 -44.086272) (xy 84.0232 -44.069) (xy 84.045806 -44.069)
			(arc
				(start 84.05368 -44.066206)
				(mid 84.114437 -44.050958)
				(end 84.17687 -44.045886)
			)
			(arc
				(start 84.17687 -44.045886)
				(mid 84.227089 -44.049206)
				(end 84.276438 -44.059094)
			)
			(xy 84.304886 -44.066714) (xy 84.4296 -43.942) (xy 84.4296 -43.561) (xy 84.361528 -43.492928)
			(arc
				(start 84.329778 -43.506898)
				(mid 84.254981 -43.530817)
				(end 84.17687 -43.538902)
			)
			(arc
				(start 84.17687 -43.538902)
				(mid 84.081387 -43.52676)
				(end 83.991958 -43.49115)
			)
			(xy 83.980528 -43.4848) (xy 83.947 -43.4848) (xy 83.7184 -43.2562) (xy 83.4136 -43.2562) (xy 83.2866 -43.3832)
			(xy 83.2866 -44.7548) (xy 83.3374 -44.8056) (xy 83.62442 -44.8056)
		)
		(stroke
			(width 0)
			(type solid)
		)
		(fill yes)
		(layer "B.Cu")
		(net "P1V2_AUX")
	)
	(gr_poly
		(pts
			(xy 52.789582 -53.416708) (xy 52.789582 -52.95265) (xy 52.940458 -52.801774) (xy 53.588666 -52.801774)
			(xy 53.668676 -52.721764) (xy 53.668676 -52.472336) (xy 53.669692 -52.47132) (xy 53.669692 -52.470812)
			(xy 54.328568 -51.81219) (xy 54.328568 -50.752756) (xy 54.329838 -50.751486) (xy 54.329838 -49.817274)
			(xy 54.657752 -49.48936) (xy 54.760368 -49.48936) (xy 54.788816 -49.460912) (xy 54.788816 -49.019968)
			(xy 53.841904 -48.073056) (xy 53.40731 -48.073056) (xy 53.296312 -48.184308) (xy 53.296312 -48.8442)
			(xy 53.294534 -48.845724) (xy 53.294534 -48.884586) (xy 53.129688 -49.049432) (xy 53.129688 -49.595024)
			(xy 53.208428 -49.673764) (xy 53.639212 -49.673764) (xy 53.75783 -49.792382) (xy 53.75783 -51.28895)
			(xy 53.6448 -51.40198) (xy 53.615844 -51.40198) (xy 53.54447 -51.473608) (xy 53.21173 -51.473608)
			(xy 53.200808 -51.48453) (xy 53.200808 -51.96967) (xy 52.96535 -52.205128) (xy 51.36261 -52.205128)
			(xy 51.291236 -52.1335) (xy 51.2445 -52.1335) (xy 51.17592 -52.06492) (xy 51.17592 -52.018184) (xy 51.172872 -52.01539)
			(xy 51.172872 -51.535584) (xy 50.616612 -51.535584) (xy 50.616612 -52.753768) (xy 51.136042 -52.753768)
			(xy 51.184048 -52.801774) (xy 52.058062 -52.801774) (xy 52.18303 -52.926742) (xy 52.18303 -53.353462)
			(xy 52.352448 -53.52288) (xy 52.68341 -53.52288)
		)
		(stroke
			(width 0)
			(type solid)
		)
		(fill yes)
		(layer "B.Cu")
		(net "P1V2_AUX")
	)
	(gr_poly
		(pts
			(arc
				(start 57.580276 -29.328364)
				(mid 57.635312 -29.283059)
				(end 57.698132 -29.24937)
			)
			(arc
				(start 58.297826 -29.000958)
				(mid 58.366059 -28.98026)
				(end 58.437018 -28.973272)
			)
			(xy 58.781442 -28.973272) (xy 58.781442 -28.524708)
			(arc
				(start 58.74004 -28.516834)
				(mid 58.366698 -28.067)
				(end 58.74004 -27.617166)
			)
			(xy 58.781442 -27.609292) (xy 58.781442 -26.951432) (xy 58.552588 -26.722578) (xy 55.598314 -26.722578)
			(xy 55.409592 -26.9113)
			(arc
				(start 55.414926 -26.937716)
				(mid 55.421234 -26.981456)
				(end 55.423308 -27.0256)
			)
			(arc
				(start 55.423308 -27.0256)
				(mid 55.420176 -27.078797)
				(end 55.410862 -27.131264)
			)
			(xy 55.409592 -27.136852) (xy 55.409592 -29.02966) (xy 55.758588 -29.378656) (xy 57.529984 -29.378656)
		)
		(stroke
			(width 0)
			(type solid)
		)
		(fill yes)
		(layer "B.Cu")
		(net "GND")
	)
	(gr_poly
		(pts
			(xy 73.03516 -40.015922) (xy 73.122536 -39.928292) (xy 73.122536 -38.637972) (xy 72.980804 -38.49624)
			(xy 72.390762 -38.49624)
			(arc
				(start 72.376538 -38.523418)
				(mid 72.236078 -38.67297)
				(end 72.038464 -38.728142)
			)
			(arc
				(start 72.038464 -38.728142)
				(mid 71.870968 -38.689407)
				(end 71.737474 -38.581076)
			)
			(arc
				(start 71.737474 -38.581076)
				(mid 71.657464 -38.542042)
				(end 71.577454 -38.581076)
			)
			(arc
				(start 71.577454 -38.581076)
				(mid 71.443966 -38.689419)
				(end 71.276464 -38.728142)
			)
			(arc
				(start 71.276464 -38.728142)
				(mid 71.079092 -38.673119)
				(end 70.938644 -38.523926)
			)
			(xy 70.92442 -38.496748) (xy 70.209664 -38.496748) (xy 70.075044 -38.631114) (xy 70.075044 -40.128444)
			(xy 71.0184 -41.0718) (xy 71.979282 -41.0718)
		)
		(stroke
			(width 0)
			(type solid)
		)
		(fill yes)
		(layer "B.Cu")
		(net "P1V8_BMC_USB2AV18")
	)
	(gr_poly
		(pts
			(xy 10.257028 -118.783354)
			(arc
				(start 10.257028 -114.799872)
				(mid 10.552301 -114.087273)
				(end 11.2649 -113.792)
			)
			(xy 11.677904 -113.792) (xy 11.769344 -113.70056) (xy 11.769344 -113.376456) (xy 11.677396 -113.284508)
			(arc
				(start 11.2649 -113.284508)
				(mid 10.193376 -113.728348)
				(end 9.749536 -114.799872)
			)
			(xy 9.749536 -118.76532) (xy 9.862312 -118.878096) (xy 10.162286 -118.878096)
		)
		(stroke
			(width 0)
			(type solid)
		)
		(fill yes)
		(layer "B.Cu")
		(net "GND")
	)
	(gr_poly
		(pts
			(arc
				(start 26.787856 -88.596216)
				(mid 26.905062 -88.496784)
				(end 27.054556 -88.461088)
			)
			(arc
				(start 27.054556 -88.461088)
				(mid 27.130648 -88.469961)
				(end 27.202638 -88.49614)
			)
			(xy 27.235404 -88.512396) (xy 27.3685 -88.3793) (xy 27.3685 -87.884) (xy 27.1653 -87.6808)
			(arc
				(start 26.632916 -87.6808)
				(mid 26.545375 -87.730833)
				(end 26.544016 -87.831676)
			)
			(arc
				(start 26.544016 -87.831676)
				(mid 26.574897 -87.909183)
				(end 26.585418 -87.99195)
			)
			(arc
				(start 26.585418 -87.99195)
				(mid 26.531554 -88.172775)
				(end 26.387552 -88.294718)
			)
			(arc
				(start 26.387552 -88.294718)
				(mid 26.328627 -88.368951)
				(end 26.356564 -88.459564)
			)
			(xy 26.373836 -88.476836)
			(arc
				(start 26.383488 -88.480646)
				(mid 26.464697 -88.527952)
				(end 26.529284 -88.596216)
			)
		)
		(stroke
			(width 0)
			(type solid)
		)
		(fill yes)
		(layer "B.Cu")
		(net "PVCCA_AUX_PLD")
	)
	(gr_poly
		(pts
			(xy 39.007288 -57.886092)
			(arc
				(start 39.196264 -57.697116)
				(mid 39.321821 -57.602477)
				(end 39.468552 -57.545986)
			)
			(xy 39.482522 -57.542684) (xy 39.99738 -57.027826) (xy 39.99738 -56.94934)
			(arc
				(start 39.995856 -56.943244)
				(mid 39.985979 -56.890053)
				(end 39.982648 -56.836056)
			)
			(arc
				(start 39.982648 -56.836056)
				(mid 39.985998 -56.782062)
				(end 39.995856 -56.728868)
			)
			(xy 39.99738 -56.722772) (xy 39.99738 -56.55564) (xy 40.110156 -56.442864) (xy 40.110156 -56.43372)
			(xy 40.1193 -56.43372) (xy 40.166798 -56.386222) (xy 40.816022 -56.386222) (xy 40.880792 -56.450992)
			(arc
				(start 40.964612 -56.450992)
				(mid 41.095793 -56.470845)
				(end 41.21531 -56.528462)
			)
			(xy 41.228264 -56.537352) (xy 41.425368 -56.537352) (xy 41.5544 -56.40832) (xy 41.5544 -56.138572)
			(xy 41.484804 -56.068976)
			(arc
				(start 41.313862 -56.068976)
				(mid 41.219459 -56.059708)
				(end 41.128696 -56.032146)
			)
			(xy 41.119298 -56.028336) (xy 41.055544 -56.028336) (xy 40.785796 -55.758588) (xy 38.805612 -55.758588)
			(xy 38.735 -55.8292) (xy 38.735 -56.5404) (xy 38.32606 -56.94934) (xy 38.32606 -57.73674) (xy 38.49624 -57.90692)
			(xy 38.987476 -57.90692)
		)
		(stroke
			(width 0)
			(type solid)
		)
		(fill yes)
		(layer "B.Cu")
		(net "PVCCIO_PECI_BMC")
	)
	(gr_poly
		(pts
			(xy 59.695334 -73.695052) (xy 64.3382 -73.695052) (xy 64.457072 -73.575926) (xy 64.457072 -72.396096)
			(arc
				(start 64.089788 -72.028812)
				(mid 64.024976 -71.951145)
				(end 63.97498 -71.863204)
			)
			(arc
				(start 63.97498 -71.863204)
				(mid 63.914767 -71.809003)
				(end 63.83401 -71.81596)
			)
			(arc
				(start 63.83401 -71.81596)
				(mid 63.703286 -71.867084)
				(end 63.564008 -71.88454)
			)
			(arc
				(start 62.08903 -71.88454)
				(mid 61.973846 -71.87261)
				(end 61.863478 -71.83755)
			)
			(arc
				(start 61.863478 -71.83755)
				(mid 61.778128 -71.83967)
				(end 61.72454 -71.90613)
			)
			(arc
				(start 61.72454 -71.90613)
				(mid 61.562037 -72.155166)
				(end 61.280802 -72.251824)
			)
			(arc
				(start 61.280802 -72.251824)
				(mid 61.122121 -72.223454)
				(end 60.983114 -72.141842)
			)
			(xy 60.9473 -72.111362) (xy 60.423044 -72.635618) (xy 58.774584 -72.635618) (xy 58.529982 -72.391016)
			(xy 58.084466 -72.391016) (xy 58.035444 -72.440038) (xy 58.035444 -74.879708) (xy 58.071512 -74.915776)
			(xy 58.47461 -74.915776)
		)
		(stroke
			(width 0)
			(type solid)
		)
		(fill yes)
		(layer "B.Cu")
		(net "P5V_SENSOR")
	)
	(gr_poly
		(pts
			(xy 26.6192 -99.4664) (xy 27.1018 -99.4664) (xy 27.2034 -99.568) (xy 27.384756 -99.568) (xy 27.743404 -99.209352)
			(xy 27.743404 -97.568004) (xy 27.5844 -97.409) (xy 25.313386 -97.409) (xy 25.207468 -97.515172) (xy 25.207468 -97.687384)
			(xy 25.14854 -97.777808) (xy 24.996648 -97.777808)
			(arc
				(start 24.823166 -97.95129)
				(mid 24.794074 -98.033007)
				(end 24.83866 -98.1075)
			)
			(arc
				(start 24.83866 -98.1075)
				(mid 24.946448 -98.226543)
				(end 24.985472 -98.382328)
			)
			(xy 24.985472 -98.4377) (xy 25.123902 -98.4377) (xy 25.123902 -98.386392)
			(arc
				(start 25.123902 -98.382328)
				(mid 25.45461 -98.05162)
				(end 25.785318 -98.382328)
			)
			(arc
				(start 25.785318 -98.382328)
				(mid 25.739537 -98.550209)
				(end 25.614884 -98.671634)
			)
			(xy 25.614884 -98.776028) (xy 25.848056 -99.0092) (xy 25.848056 -99.5172) (xy 26.102056 -99.7712)
			(xy 26.3144 -99.7712)
		)
		(stroke
			(width 0)
			(type solid)
		)
		(fill yes)
		(layer "B.Cu")
		(net "GND")
	)
	(gr_poly
		(pts
			(xy 60.6171 -72.071738) (xy 60.6171 -71.464678) (xy 60.798456 -71.283322)
			(arc
				(start 60.777882 -71.249032)
				(mid 60.716034 -71.107306)
				(end 60.694824 -70.954138)
			)
			(arc
				(start 60.694824 -70.954138)
				(mid 60.860889 -70.553349)
				(end 61.261752 -70.387464)
			)
			(arc
				(start 61.725556 -70.387464)
				(mid 61.942466 -70.430517)
				(end 62.126368 -70.553326)
			)
			(xy 62.24651 -70.673468) (xy 63.696088 -70.673468) (xy 63.79718 -70.572122)
			(arc
				(start 63.79718 -70.296024)
				(mid 63.829708 -70.107005)
				(end 63.923418 -69.939662)
			)
			(xy 63.923418 -69.591174)
			(arc
				(start 63.922656 -69.586602)
				(mid 63.91737 -69.547643)
				(end 63.915544 -69.50837)
			)
			(arc
				(start 63.915544 -69.50837)
				(mid 63.916681 -69.478071)
				(end 63.919862 -69.447918)
			)
			(xy 63.923164 -69.423026) (xy 63.726568 -69.22643)
			(arc
				(start 61.74486 -69.22643)
				(mid 61.490098 -69.32396)
				(end 61.235336 -69.22643)
			)
			(xy 60.864242 -69.22643) (xy 59.84494 -70.245732) (xy 59.84494 -70.300596) (xy 59.8424 -70.303136)
			(xy 59.8424 -70.673722) (xy 59.83478 -70.681342) (xy 59.83478 -72.342756) (xy 59.863736 -72.371712)
			(xy 60.317126 -72.371712)
		)
		(stroke
			(width 0)
			(type solid)
		)
		(fill yes)
		(layer "B.Cu")
		(net "PGPPA_BMC_AUX")
	)
	(gr_poly
		(pts
			(xy 16.02232 -88.111076) (xy 16.3068 -87.826596) (xy 16.3068 -87.733886)
			(arc
				(start 16.293338 -87.719408)
				(mid 16.23132 -87.632464)
				(end 16.1925 -87.532972)
			)
			(arc
				(start 16.1925 -87.532972)
				(mid 16.131774 -87.463704)
				(end 16.0401 -87.472012)
			)
			(arc
				(start 16.0401 -87.472012)
				(mid 15.955776 -87.509661)
				(end 15.864332 -87.522558)
			)
			(arc
				(start 15.864332 -87.522558)
				(mid 15.630486 -87.425696)
				(end 15.533624 -87.19185)
			)
			(arc
				(start 15.533624 -87.19185)
				(mid 15.588929 -87.00884)
				(end 15.736316 -86.88705)
			)
			(arc
				(start 15.736316 -86.88705)
				(mid 15.796701 -86.812909)
				(end 15.768828 -86.721442)
			)
			(arc
				(start 15.552166 -86.505034)
				(mid 15.48429 -86.403545)
				(end 15.460472 -86.2838)
			)
			(xy 15.460472 -86.1568) (xy 15.1638 -86.1568) (xy 14.7574 -86.5632)
			(arc
				(start 14.7574 -87.42299)
				(mid 14.935764 -87.7316)
				(end 14.7574 -88.04021)
			)
			(xy 14.7574 -88.209374) (xy 15.243048 -88.695022) (xy 15.438374 -88.695022)
		)
		(stroke
			(width 0)
			(type solid)
		)
		(fill yes)
		(layer "B.Cu")
		(net "PVCCA_AUX_PLD")
	)
	(gr_poly
		(pts
			(xy 39.13886 -52.44338) (xy 39.13886 -51.69662) (xy 39.344092 -51.491388) (xy 39.358277 -51.463939)
			(xy 39.393098 -51.412899) (xy 39.434647 -51.367169) (xy 39.482126 -51.327629) (xy 39.534619 -51.295042)
			(xy 39.591118 -51.270033) (xy 39.650535 -51.253084) (xy 39.711725 -51.244521) (xy 39.742618 -51.243992)
			(xy 39.771601 -51.24446) (xy 39.829077 -51.251993) (xy 39.885087 -51.266928) (xy 39.938682 -51.289012)
			(xy 39.988954 -51.317871) (xy 40.035052 -51.353016) (xy 40.076193 -51.393852) (xy 40.111681 -51.439686)
			(xy 40.140914 -51.489741) (xy 40.152574 -51.51628) (xy 40.156384 -51.525424) (xy 40.32504 -51.69408)
			(xy 40.887396 -51.69408) (xy 40.887396 -51.068224) (xy 40.969184 -51.068224) (xy 40.969184 -50.682144)
			(xy 40.90924 -50.6222) (xy 40.61714 -50.6222) (xy 39.81958 -49.82464) (xy 38.51402 -49.82464) (xy 38.04666 -50.292)
			(xy 38.04666 -50.673) (xy 38.352982 -50.673) (xy 38.357053 -50.617378) (xy 38.369179 -50.562941)
			(xy 38.389102 -50.51085) (xy 38.416398 -50.462215) (xy 38.450484 -50.418072) (xy 38.490633 -50.379363)
			(xy 38.535991 -50.346912) (xy 38.585591 -50.321411) (xy 38.638375 -50.303404) (xy 38.693218 -50.293274)
			(xy 38.748952 -50.291237) (xy 38.804389 -50.297337) (xy 38.858346 -50.311443) (xy 38.909675 -50.333255)
			(xy 38.957281 -50.362309) (xy 39.000149 -50.397984) (xy 39.037366 -50.439521) (xy 39.068139 -50.486034)
			(xy 39.091811 -50.536531) (xy 39.107879 -50.589938) (xy 39.115999 -50.645114) (xy 39.116508 -50.673)
			(xy 39.115999 -50.700886) (xy 39.107879 -50.756062) (xy 39.091811 -50.809469) (xy 39.068139 -50.859966)
			(xy 39.037366 -50.906479) (xy 39.000149 -50.948016) (xy 38.957281 -50.983691) (xy 38.909675 -51.012745)
			(xy 38.858346 -51.034557) (xy 38.804389 -51.048663) (xy 38.748952 -51.054763) (xy 38.693218 -51.052726)
			(xy 38.638375 -51.042596) (xy 38.585591 -51.024589) (xy 38.535991 -50.999088) (xy 38.490633 -50.966637)
			(xy 38.450484 -50.927928) (xy 38.416398 -50.883785) (xy 38.389102 -50.83515) (xy 38.369179 -50.783059)
			(xy 38.357053 -50.728622) (xy 38.352982 -50.673) (xy 38.04666 -50.673) (xy 38.04666 -52.3748) (xy 38.2778 -52.60594)
			(xy 38.9763 -52.60594)
		)
		(stroke
			(width 0)
			(type solid)
		)
		(fill yes)
		(layer "B.Cu")
		(net "P1V2_AUX")
	)
	(gr_poly
		(pts
			(xy 72.0344 -42.3672) (xy 72.7456 -42.3672) (xy 72.852788 -42.260012) (xy 72.852788 -41.610788) (xy 73.102978 -41.360344)
			(xy 73.857104 -40.606218)
			(arc
				(start 73.859136 -40.588946)
				(mid 73.989599 -40.322661)
				(end 74.255884 -40.192198)
			)
			(xy 74.273156 -40.190166) (xy 75.322684 -39.140638) (xy 75.322684 -38.474904)
			(arc
				(start 75.321414 -38.469062)
				(mid 75.314185 -38.426789)
				(end 75.311762 -38.383972)
			)
			(arc
				(start 75.311762 -38.383972)
				(mid 75.314201 -38.341157)
				(end 75.321414 -38.298882)
			)
			(xy 75.322684 -38.29304) (xy 75.322684 -37.839904)
			(arc
				(start 75.321414 -37.834062)
				(mid 75.314185 -37.791789)
				(end 75.311762 -37.748972)
			)
			(arc
				(start 75.311762 -37.748972)
				(mid 75.314201 -37.706157)
				(end 75.321414 -37.663882)
			)
			(xy 75.322684 -37.65804) (xy 75.322684 -37.446458) (xy 75.277218 -37.400992) (xy 71.585582 -37.400992)
			(xy 71.45909 -37.527484) (xy 71.45909 -37.899848) (xy 71.524368 -37.965126) (xy 72.83577 -37.965126)
			(xy 72.837548 -37.966904) (xy 72.90943 -37.966904) (xy 73.387458 -38.444932) (xy 73.387458 -40.028622)
			(xy 72.19188 -41.2242) (xy 72.186546 -41.2242) (xy 72.084692 -41.326308) (xy 70.91299 -41.326308)
			(xy 70.912736 -41.3258) (xy 70.891908 -41.3258) (xy 69.5706 -40.004492) (xy 67.780408 -40.004492)
			(xy 67.158108 -39.382192) (xy 67.158108 -39.256208) (xy 67.154552 -39.252906) (xy 67.154552 -37.97935)
			(xy 67.158108 -37.976048) (xy 67.158108 -37.841174) (xy 67.311524 -37.687758) (xy 67.774566 -37.687758)
			(xy 67.869054 -37.59327) (xy 67.869054 -37.269166) (xy 67.747642 -37.148008) (xy 67.185794 -37.148008)
			(xy 67.18427 -37.14623) (xy 66.370708 -37.14623) (xy 65.6971 -37.819838) (xy 65.6971 -40.586914)
			(xy 65.860676 -40.750744) (xy 69.04101 -40.750744) (xy 69.062092 -40.771826) (xy 69.143626 -40.771826)
			(xy 69.9008 -41.529) (xy 70.5358 -41.529) (xy 70.9168 -41.91) (xy 70.9168 -42.4688) (xy 70.993 -42.545)
			(xy 71.8566 -42.545)
		)
		(stroke
			(width 0)
			(type solid)
		)
		(fill yes)
		(layer "B.Cu")
		(net "GND")
	)
	(gr_poly
		(pts
			(xy 24.257 -91.9734) (xy 24.7396 -91.9734) (xy 24.887936 -91.82481) (xy 24.887936 -91.1352) (xy 24.616664 -91.1352)
			(xy 24.422608 -91.32951) (xy 24.422608 -91.48191) (xy 24.18461 -91.719908) (xy 23.44039 -91.719908)
			(xy 23.207472 -91.48699) (xy 23.176484 -91.499182) (xy 23.147182 -91.510053) (xy 23.085809 -91.521817)
			(xy 23.054564 -91.52255) (xy 23.029989 -91.522099) (xy 22.98138 -91.514827) (xy 22.93438 -91.500448)
			(xy 22.890023 -91.479278) (xy 22.869398 -91.465908) (xy 22.439884 -91.465908) (xy 22.419264 -91.479286)
			(xy 22.374906 -91.500457) (xy 22.327904 -91.514835) (xy 22.279294 -91.522105) (xy 22.230142 -91.522105)
			(xy 22.181532 -91.514835) (xy 22.13453 -91.500457) (xy 22.090172 -91.479286) (xy 22.069552 -91.465908)
			(xy 21.86559 -91.465908) (xy 21.789136 -91.3892) (xy 21.7678 -91.3892) (xy 21.425408 -91.046808)
			(xy 21.222462 -91.046808) (xy 21.221954 -91.046046) (xy 20.8788 -91.3892) (xy 20.857464 -91.3892)
			(xy 20.78101 -91.465908) (xy 20.522692 -91.465908) (xy 20.3962 -91.5924) (xy 20.3962 -92.017929)
			(xy 22.724366 -92.017929) (xy 22.724366 -91.965955) (xy 22.732496 -91.91462) (xy 22.748557 -91.86519)
			(xy 22.772153 -91.81888) (xy 22.802703 -91.776832) (xy 22.839454 -91.740081) (xy 22.881502 -91.709531)
			(xy 22.927812 -91.685935) (xy 22.977242 -91.669874) (xy 23.028577 -91.661744) (xy 23.080551 -91.661744)
			(xy 23.131886 -91.669874) (xy 23.181316 -91.685935) (xy 23.227626 -91.709531) (xy 23.269674 -91.740081)
			(xy 23.306425 -91.776832) (xy 23.336975 -91.81888) (xy 23.360571 -91.86519) (xy 23.376632 -91.91462)
			(xy 23.384762 -91.965955) (xy 23.385272 -91.991942) (xy 23.384762 -92.017929) (xy 23.376632 -92.069264)
			(xy 23.360571 -92.118694) (xy 23.336975 -92.165004) (xy 23.306425 -92.207052) (xy 23.269674 -92.243803)
			(xy 23.227626 -92.274353) (xy 23.181316 -92.297949) (xy 23.131886 -92.31401) (xy 23.080551 -92.32214)
			(xy 23.028577 -92.32214) (xy 22.977242 -92.31401) (xy 22.927812 -92.297949) (xy 22.881502 -92.274353)
			(xy 22.839454 -92.243803) (xy 22.802703 -92.207052) (xy 22.772153 -92.165004) (xy 22.748557 -92.118694)
			(xy 22.732496 -92.069264) (xy 22.724366 -92.017929) (xy 20.3962 -92.017929) (xy 20.3962 -92.050616)
			(xy 20.62353 -92.277692) (xy 21.189188 -92.277692) (xy 21.213572 -92.239592) (xy 21.389594 -92.239592)
			(xy 21.413978 -92.277692) (xy 22.499066 -92.277692) (xy 22.65172 -92.4306) (xy 23.7998 -92.4306)
		)
		(stroke
			(width 0)
			(type solid)
		)
		(fill yes)
		(layer "B.Cu")
		(net "VCCIO0")
	)
	(gr_poly
		(pts
			(xy 58.008266 -55.420006) (xy 58.028479 -55.415516) (xy 58.069604 -55.41068) (xy 58.090308 -55.410354)
			(xy 58.111013 -55.410657) (xy 58.15214 -55.415496) (xy 58.17235 -55.420006) (xy 58.177938 -55.421276)
			(xy 59.602624 -55.421276) (xy 59.608212 -55.420006) (xy 59.628425 -55.415513) (xy 59.66955 -55.410671)
			(xy 59.690254 -55.410354) (xy 59.710959 -55.410654) (xy 59.752088 -55.415487) (xy 59.772296 -55.420006)
			(xy 59.777884 -55.421276) (xy 60.40247 -55.421276) (xy 60.408058 -55.420006) (xy 60.428271 -55.415515)
			(xy 60.469396 -55.410679) (xy 60.4901 -55.410354) (xy 60.510805 -55.410657) (xy 60.551932 -55.415494)
			(xy 60.572142 -55.420006) (xy 60.57773 -55.421276) (xy 62.180724 -55.421276) (xy 62.389258 -55.212742)
			(xy 62.389258 -54.667658) (xy 62.33414 -54.61254) (xy 61.77534 -54.61254) (xy 61.6966 -54.5338) (xy 61.6966 -54.032658)
			(xy 61.569092 -53.90515) (xy 61.36386 -53.90515) (xy 61.107066 -53.648356) (xy 60.536328 -53.648356)
			(xy 60.282836 -53.901848) (xy 60.282836 -54.180232) (xy 60.047378 -54.41569) (xy 59.972956 -54.41569)
			(xy 59.972956 -54.418484) (xy 59.388756 -54.418484) (xy 59.388756 -54.41569) (xy 58.99658 -54.41569)
			(xy 58.99658 -54.418484) (xy 58.34888 -54.418484) (xy 58.300366 -54.370224) (xy 58.300366 -54.005988)
			(xy 58.23712 -53.942742) (xy 57.137046 -53.942742) (xy 57.061608 -54.01818) (xy 57.061608 -55.002001)
			(xy 57.769508 -55.002001) (xy 57.769508 -54.950027) (xy 57.777638 -54.898692) (xy 57.793699 -54.849262)
			(xy 57.817295 -54.802952) (xy 57.847845 -54.760904) (xy 57.884596 -54.724153) (xy 57.926644 -54.693603)
			(xy 57.972954 -54.670007) (xy 58.022384 -54.653946) (xy 58.073719 -54.645816) (xy 58.125693 -54.645816)
			(xy 58.177028 -54.653946) (xy 58.226458 -54.670007) (xy 58.272768 -54.693603) (xy 58.314816 -54.724153)
			(xy 58.351567 -54.760904) (xy 58.382117 -54.802952) (xy 58.405713 -54.849262) (xy 58.421774 -54.898692)
			(xy 58.429904 -54.950027) (xy 58.430414 -54.976014) (xy 58.429904 -55.002001) (xy 58.421774 -55.053336)
			(xy 58.405713 -55.102766) (xy 58.382117 -55.149076) (xy 58.351567 -55.191124) (xy 58.314816 -55.227875)
			(xy 58.272768 -55.258425) (xy 58.226458 -55.282021) (xy 58.177028 -55.298082) (xy 58.125693 -55.306212)
			(xy 58.073719 -55.306212) (xy 58.022384 -55.298082) (xy 57.972954 -55.282021) (xy 57.926644 -55.258425)
			(xy 57.884596 -55.227875) (xy 57.847845 -55.191124) (xy 57.817295 -55.149076) (xy 57.793699 -55.102766)
			(xy 57.777638 -55.053336) (xy 57.769508 -55.002001) (xy 57.061608 -55.002001) (xy 57.061608 -55.207662)
			(xy 57.275222 -55.421276) (xy 58.002678 -55.421276)
		)
		(stroke
			(width 0)
			(type solid)
		)
		(fill yes)
		(layer "B.Cu")
		(net "GND")
	)
	(gr_poly
		(pts
			(arc
				(start 23.576026 -97.404174)
				(mid 23.617314 -97.351892)
				(end 23.668228 -97.308924)
			)
			(arc
				(start 23.668228 -97.055686)
				(mid 23.562224 -96.936909)
				(end 23.523956 -96.782382)
			)
			(arc
				(start 23.523956 -96.782382)
				(mid 23.620818 -96.548536)
				(end 23.854664 -96.451674)
			)
			(arc
				(start 23.854664 -96.451674)
				(mid 23.995058 -96.482927)
				(end 24.108918 -96.5708)
			)
			(xy 24.170132 -96.5708) (xy 24.564594 -96.965262) (xy 24.742394 -96.965262) (xy 24.950928 -96.756728)
			(xy 24.950928 -96.17964) (xy 24.945848 -96.176084) (xy 24.945848 -96.000316) (xy 24.950928 -95.99676)
			(xy 24.950928 -95.724472) (xy 25.164288 -95.511112) (xy 25.164288 -94.088712) (xy 25.4508 -93.8022)
			(xy 25.4508 -93.218) (xy 25.3492 -93.1164) (xy 24.6888 -93.1164) (xy 24.572468 -93.232732) (xy 24.575008 -93.257116)
			(xy 24.575008 -93.432884) (xy 24.484584 -93.491304) (xy 24.384 -93.491304) (xy 24.384 -94.087188)
			(xy 24.484584 -94.087188) (xy 24.575008 -94.146116) (xy 24.575008 -94.321884) (xy 24.484584 -94.380304)
			(xy 24.384 -94.380304) (xy 24.384 -95.035878) (xy 24.393652 -95.042228) (xy 24.393652 -95.217996)
			(xy 24.384 -95.224346) (xy 24.384 -95.25) (xy 23.9522 -95.6818)
			(arc
				(start 23.438358 -95.6818)
				(mid 23.351546 -95.730615)
				(end 23.348188 -95.830136)
			)
			(arc
				(start 23.348188 -95.830136)
				(mid 23.375862 -95.903983)
				(end 23.385272 -95.982282)
			)
			(arc
				(start 23.385272 -95.982282)
				(mid 23.333465 -96.159995)
				(end 23.194264 -96.282002)
			)
			(xy 23.1648 -96.295718) (xy 23.1648 -96.468946)
			(arc
				(start 23.194264 -96.482662)
				(mid 23.385242 -96.782382)
				(end 23.194264 -97.082102)
			)
			(xy 23.1648 -97.095818) (xy 23.1648 -97.268792)
			(arc
				(start 23.194264 -97.282508)
				(mid 23.274541 -97.335331)
				(end 23.33625 -97.409)
			)
			(xy 23.5712 -97.409)
		)
		(stroke
			(width 0)
			(type solid)
		)
		(fill yes)
		(layer "B.Cu")
		(net "GND")
	)
	(gr_poly
		(pts
			(xy 33.3756 -38.5064) (xy 33.3756 -37.47897) (xy 33.372806 -37.471096) (xy 33.363069 -37.441426)
			(xy 33.349399 -37.380492) (xy 33.342512 -37.318424) (xy 33.342072 -37.2872) (xy 33.342516 -37.255976)
			(xy 33.349409 -37.19391) (xy 33.363077 -37.132977) (xy 33.372806 -37.103304) (xy 33.3756 -37.09543)
			(xy 33.3756 -36.3474) (xy 33.3248 -36.2966) (xy 32.6644 -36.2966) (xy 32.1564 -35.7886) (xy 32.1564 -34.671)
			(xy 32.556704 -34.270696) (xy 32.556704 -34.206688) (xy 32.556933 -34.189404) (xy 32.559734 -34.154949)
			(xy 32.562292 -34.137854) (xy 32.5628 -34.134044) (xy 32.5628 -33.5534) (xy 32.3342 -33.3248) (xy 30.861 -33.3248)
			(xy 30.790388 -33.395412) (xy 30.790388 -33.42132) (xy 30.78989 -33.455581) (xy 30.781628 -33.523603)
			(xy 30.765227 -33.590134) (xy 30.740926 -33.654202) (xy 30.709079 -33.714874) (xy 30.670151 -33.771265)
			(xy 30.62471 -33.822552) (xy 30.573418 -33.867988) (xy 30.517023 -33.90691) (xy 30.456348 -33.93875)
			(xy 30.392277 -33.963045) (xy 30.325744 -33.979439) (xy 30.257721 -33.987694) (xy 30.22346 -33.988248)
			(xy 30.190275 -33.987779) (xy 30.124359 -33.980033) (xy 30.059799 -33.964642) (xy 29.997479 -33.941815)
			(xy 29.938251 -33.911866) (xy 29.882927 -33.875203) (xy 29.832264 -33.83233) (xy 29.786955 -33.783832)
			(xy 29.747621 -33.730374) (xy 29.714801 -33.672688) (xy 29.688943 -33.611563) (xy 29.670401 -33.547836)
			(xy 29.65943 -33.48238) (xy 29.657294 -33.44926) (xy 29.655008 -33.401) (xy 28.9814 -33.401) (xy 28.956 -33.4264)
			(xy 28.956 -33.7566) (xy 28.575 -33.7566) (xy 28.3464 -33.9852) (xy 28.3464 -34.875216) (xy 29.76575 -34.875216)
			(xy 29.769821 -34.819594) (xy 29.781947 -34.765157) (xy 29.80187 -34.713066) (xy 29.829166 -34.664431)
			(xy 29.863252 -34.620288) (xy 29.903401 -34.581579) (xy 29.948759 -34.549128) (xy 29.998359 -34.523627)
			(xy 30.051143 -34.50562) (xy 30.105986 -34.49549) (xy 30.16172 -34.493453) (xy 30.217157 -34.499553)
			(xy 30.271114 -34.513659) (xy 30.322443 -34.535471) (xy 30.370049 -34.564525) (xy 30.412917 -34.6002)
			(xy 30.450134 -34.641737) (xy 30.480907 -34.68825) (xy 30.504579 -34.738747) (xy 30.520647 -34.792154)
			(xy 30.528767 -34.84733) (xy 30.529276 -34.875216) (xy 30.528767 -34.903102) (xy 30.520647 -34.958278)
			(xy 30.504579 -35.011685) (xy 30.480907 -35.062182) (xy 30.450134 -35.108695) (xy 30.412917 -35.150232)
			(xy 30.370049 -35.185907) (xy 30.322443 -35.214961) (xy 30.271114 -35.236773) (xy 30.217157 -35.250879)
			(xy 30.16172 -35.256979) (xy 30.105986 -35.254942) (xy 30.051143 -35.244812) (xy 29.998359 -35.226805)
			(xy 29.948759 -35.201304) (xy 29.903401 -35.168853) (xy 29.863252 -35.130144) (xy 29.829166 -35.086001)
			(xy 29.80187 -35.037366) (xy 29.781947 -34.985275) (xy 29.769821 -34.930838) (xy 29.76575 -34.875216)
			(xy 28.3464 -34.875216) (xy 28.3464 -35.1028) (xy 28.067508 -35.381692) (xy 28.067508 -37.668708)
			(xy 28.3718 -37.973) (xy 31.9532 -37.973) (xy 32.5628 -38.5826) (xy 33.2994 -38.5826)
		)
		(stroke
			(width 0)
			(type solid)
		)
		(fill yes)
		(layer "B.Cu")
		(net "CRT_VCC5")
	)
	(gr_poly
		(pts
			(xy 37.923978 -56.533034) (xy 38.158166 -56.533034) (xy 38.29304 -56.39816) (xy 38.29304 -55.50916)
			(xy 37.737034 -54.9529) (xy 37.737034 -52.478686) (xy 37.425122 -52.166774) (xy 33.93186 -52.166774)
			(xy 33.786318 -52.312316) (xy 33.786318 -54.2544) (xy 34.695382 -54.2544) (xy 34.699453 -54.198778)
			(xy 34.711579 -54.144341) (xy 34.731502 -54.09225) (xy 34.758798 -54.043615) (xy 34.792884 -53.999472)
			(xy 34.833033 -53.960763) (xy 34.878391 -53.928312) (xy 34.927991 -53.902811) (xy 34.980775 -53.884804)
			(xy 35.035618 -53.874674) (xy 35.091352 -53.872637) (xy 35.146789 -53.878737) (xy 35.200746 -53.892843)
			(xy 35.252075 -53.914655) (xy 35.299681 -53.943709) (xy 35.342549 -53.979384) (xy 35.379766 -54.020921)
			(xy 35.410539 -54.067434) (xy 35.434211 -54.117931) (xy 35.450279 -54.171338) (xy 35.458399 -54.226514)
			(xy 35.458908 -54.2544) (xy 35.458399 -54.282286) (xy 35.450279 -54.337462) (xy 35.434211 -54.390869)
			(xy 35.410539 -54.441366) (xy 35.379766 -54.487879) (xy 35.342549 -54.529416) (xy 35.299681 -54.565091)
			(xy 35.252075 -54.594145) (xy 35.200746 -54.615957) (xy 35.146789 -54.630063) (xy 35.091352 -54.636163)
			(xy 35.035618 -54.634126) (xy 34.980775 -54.623996) (xy 34.927991 -54.605989) (xy 34.878391 -54.580488)
			(xy 34.833033 -54.548037) (xy 34.792884 -54.509328) (xy 34.758798 -54.465185) (xy 34.731502 -54.41655)
			(xy 34.711579 -54.364459) (xy 34.699453 -54.310022) (xy 34.695382 -54.2544) (xy 33.786318 -54.2544)
			(xy 33.786318 -56.002936) (xy 33.812226 -56.014874) (xy 33.81883 -56.018176) (xy 33.830514 -56.023764)
			(xy 33.844341 -56.030342) (xy 33.874467 -56.035752) (xy 33.904845 -56.032017) (xy 33.932762 -56.019469)
			(xy 33.955724 -55.999231) (xy 33.964118 -55.986426) (xy 33.97905 -55.962831) (xy 34.014726 -55.919877)
			(xy 34.056282 -55.882582) (xy 34.10283 -55.851743) (xy 34.153376 -55.828018) (xy 34.20684 -55.811914)
			(xy 34.262081 -55.803775) (xy 34.29 -55.803292) (xy 34.317251 -55.803778) (xy 34.371199 -55.811534)
			(xy 34.423494 -55.826889) (xy 34.473071 -55.849531) (xy 34.518921 -55.878997) (xy 34.560112 -55.914688)
			(xy 34.595803 -55.955879) (xy 34.625269 -56.001729) (xy 34.647911 -56.051306) (xy 34.663266 -56.103601)
			(xy 34.671022 -56.157549) (xy 34.671022 -56.212051) (xy 34.663266 -56.265999) (xy 34.647911 -56.318294)
			(xy 34.625269 -56.367871) (xy 34.595803 -56.413721) (xy 34.560112 -56.454912) (xy 34.518921 -56.490603)
			(xy 34.473071 -56.520069) (xy 34.423494 -56.542711) (xy 34.371199 -56.558066) (xy 34.317251 -56.565822)
			(xy 34.29 -56.566308) (xy 34.270882 -56.566072) (xy 34.232838 -56.562253) (xy 34.214054 -56.558688)
			(xy 34.159444 -56.613044) (xy 34.282126 -56.735726) (xy 34.300668 -56.73725) (xy 34.329731 -56.740157)
			(xy 34.386839 -56.752417) (xy 34.441924 -56.771841) (xy 34.49409 -56.798115) (xy 34.54249 -56.830812)
			(xy 34.586337 -56.8694) (xy 34.62492 -56.913251) (xy 34.657611 -56.961655) (xy 34.683879 -57.013824)
			(xy 34.703298 -57.068911) (xy 34.715551 -57.12602) (xy 34.718498 -57.15508) (xy 34.720022 -57.173622)
			(xy 34.765488 -57.219088) (xy 37.237924 -57.219088)
		)
		(stroke
			(width 0)
			(type solid)
		)
		(fill yes)
		(layer "B.Cu")
		(net "GND")
	)
	(gr_poly
		(pts
			(xy 59.580272 -72.360028) (xy 59.580272 -70.575932) (xy 59.587892 -70.568312) (xy 59.587892 -70.190614)
			(xy 59.590686 -70.188074) (xy 59.590686 -69.854826) (xy 60.44438 -69.001132)
			(arc
				(start 60.44438 -68.584572)
				(mid 60.323991 -68.2752)
				(end 60.44438 -67.965828)
			)
			(xy 60.44438 -67.17792)
			(arc
				(start 60.416186 -67.16395)
				(mid 60.262304 -67.023193)
				(end 60.205366 -66.822574)
			)
			(arc
				(start 60.205366 -66.822574)
				(mid 60.227936 -66.693255)
				(end 60.292996 -66.579242)
			)
			(arc
				(start 60.292996 -66.579242)
				(mid 60.304694 -66.544482)
				(end 60.289948 -66.510916)
			)
			(xy 60.134754 -66.355722) (xy 59.45124 -66.355722)
			(arc
				(start 59.445652 -66.400172)
				(mid 59.298572 -66.678403)
				(end 59.0042 -66.789808)
			)
			(arc
				(start 59.0042 -66.789808)
				(mid 58.930669 -66.783648)
				(end 58.859166 -66.765424)
			)
			(arc
				(start 58.859166 -66.765424)
				(mid 58.767171 -66.778789)
				(end 58.724546 -66.861436)
			)
			(arc
				(start 58.724546 -67.55892)
				(mid 58.847567 -67.68077)
				(end 58.91657 -67.83959)
			)
			(xy 58.919618 -67.853814) (xy 59.029346 -67.963542)
			(arc
				(start 59.029346 -67.97802)
				(mid 59.058656 -68.049412)
				(end 59.129676 -68.07962)
			)
			(arc
				(start 59.129676 -68.07962)
				(mid 59.396015 -68.193227)
				(end 59.50585 -68.461128)
			)
			(arc
				(start 59.50585 -68.461128)
				(mid 59.426709 -68.69377)
				(end 59.222132 -68.829936)
			)
			(arc
				(start 59.222132 -68.829936)
				(mid 59.150069 -68.901115)
				(end 59.175396 -68.9991)
			)
			(arc
				(start 59.175396 -68.9991)
				(mid 59.255884 -69.121798)
				(end 59.284108 -69.2658)
			)
			(arc
				(start 59.284108 -69.2658)
				(mid 59.223009 -69.472815)
				(end 59.059318 -69.613526)
			)
			(xy 59.029346 -69.627242) (xy 59.029346 -72.327516) (xy 59.083194 -72.381364) (xy 59.558936 -72.381364)
		)
		(stroke
			(width 0)
			(type solid)
		)
		(fill yes)
		(layer "B.Cu")
		(net "PGPPA_BMC_AUX_SENSOR")
	)
	(gr_poly
		(pts
			(xy 49.4157 -44.666916) (xy 49.4157 -44.143168) (xy 49.33442 -44.061888) (xy 48.88611 -44.061888)
			(xy 48.7299 -43.905678) (xy 48.7299 -43.663362) (xy 48.723296 -43.656504) (xy 48.723296 -43.389296)
			(xy 48.619664 -43.285664) (xy 48.590962 -43.294046) (xy 48.568636 -43.299991) (xy 48.522877 -43.306366)
			(xy 48.499776 -43.306746) (xy 48.469557 -43.306075) (xy 48.410127 -43.295081) (xy 48.381666 -43.284902)
			(xy 48.37303 -43.2816) (xy 48.3616 -43.2816) (xy 48.351948 -43.271948) (xy 48.345344 -43.268392)
			(xy 48.323654 -43.256436) (xy 48.283802 -43.227031) (xy 48.248781 -43.192012) (xy 48.219374 -43.152162)
			(xy 48.207422 -43.13047) (xy 48.203866 -43.123866) (xy 48.133 -43.053) (xy 48.023272 -43.053) (xy 48.011334 -43.086782)
			(xy 48.002382 -43.110584) (xy 47.978222 -43.15533) (xy 47.947495 -43.195848) (xy 47.910926 -43.231184)
			(xy 47.869378 -43.260504) (xy 47.82383 -43.283116) (xy 47.775357 -43.298487) (xy 47.725102 -43.306254)
			(xy 47.699676 -43.306746) (xy 47.67311 -43.306222) (xy 47.62066 -43.297735) (xy 47.570244 -43.280968)
			(xy 47.523159 -43.256351) (xy 47.480617 -43.22452) (xy 47.443716 -43.186294) (xy 47.42815 -43.16476)
			(xy 47.419246 -43.1529) (xy 47.396011 -43.134492) (xy 47.368471 -43.123522) (xy 47.338943 -43.120912)
			(xy 47.309906 -43.126882) (xy 47.283802 -43.14093) (xy 47.272956 -43.151044) (xy 47.2186 -43.2054)
			(xy 47.2186 -43.687746) (xy 47.220124 -43.694096) (xy 47.224968 -43.714261) (xy 47.230187 -43.755403)
			(xy 47.230538 -43.776138) (xy 47.230198 -43.796874) (xy 47.229531 -43.802125) (xy 47.369478 -43.802125)
			(xy 47.369478 -43.750151) (xy 47.377608 -43.698816) (xy 47.393669 -43.649386) (xy 47.417265 -43.603076)
			(xy 47.447815 -43.561028) (xy 47.484566 -43.524277) (xy 47.526614 -43.493727) (xy 47.572924 -43.470131)
			(xy 47.622354 -43.45407) (xy 47.673689 -43.44594) (xy 47.725663 -43.44594) (xy 47.776998 -43.45407)
			(xy 47.826428 -43.470131) (xy 47.872738 -43.493727) (xy 47.914786 -43.524277) (xy 47.951537 -43.561028)
			(xy 47.982087 -43.603076) (xy 48.005683 -43.649386) (xy 48.021744 -43.698816) (xy 48.029874 -43.750151)
			(xy 48.030384 -43.776138) (xy 48.029874 -43.802125) (xy 48.021744 -43.85346) (xy 48.005683 -43.90289)
			(xy 47.982087 -43.9492) (xy 47.951537 -43.991248) (xy 47.914786 -44.027999) (xy 47.872738 -44.058549)
			(xy 47.826428 -44.082145) (xy 47.776998 -44.098206) (xy 47.725663 -44.106336) (xy 47.673689 -44.106336)
			(xy 47.622354 -44.098206) (xy 47.572924 -44.082145) (xy 47.526614 -44.058549) (xy 47.484566 -44.027999)
			(xy 47.447815 -43.991248) (xy 47.417265 -43.9492) (xy 47.393669 -43.90289) (xy 47.377608 -43.85346)
			(xy 47.369478 -43.802125) (xy 47.229531 -43.802125) (xy 47.224972 -43.838016) (xy 47.220124 -43.85818)
			(xy 47.2186 -43.86453) (xy 47.2186 -44.3738) (xy 47.262034 -44.417234) (xy 47.273138 -44.427718)
			(xy 47.300069 -44.44209) (xy 47.330045 -44.447852) (xy 47.360385 -44.444489) (xy 47.388372 -44.432301)
			(xy 47.411501 -44.412381) (xy 47.420022 -44.399708) (xy 47.435319 -44.376486) (xy 47.472401 -44.335054)
			(xy 47.515893 -44.300412) (xy 47.564569 -44.273537) (xy 47.617057 -44.255186) (xy 47.671875 -44.245877)
			(xy 47.699676 -44.245276) (xy 47.724379 -44.24574) (xy 47.773236 -44.253097) (xy 47.820455 -44.267636)
			(xy 47.864988 -44.289033) (xy 47.905845 -44.316814) (xy 47.942117 -44.350361) (xy 47.972999 -44.388928)
			(xy 47.997804 -44.431657) (xy 48.015979 -44.477599) (xy 48.022002 -44.501562) (xy 48.025304 -44.515786)
			(xy 48.060864 -44.5516) (xy 48.118268 -44.5516) (xy 48.361092 -44.794424) (xy 49.288192 -44.794424)
		)
		(stroke
			(width 0)
			(type solid)
		)
		(fill yes)
		(layer "B.Cu")
		(net "P3V3_P1V8_SD1VDD")
	)
	(gr_poly
		(pts
			(xy 56.8071 -55.187088) (xy 56.8071 -54.620668) (xy 56.721756 -54.53507) (xy 56.368696 -54.53507)
			(xy 56.2102 -54.376574) (xy 56.2102 -54.343046)
			(arc
				(start 56.203342 -54.331362)
				(mid 56.170528 -54.251825)
				(end 56.1594 -54.166516)
			)
			(arc
				(start 56.1594 -54.166516)
				(mid 56.172351 -54.074911)
				(end 56.2102 -53.990494)
			)
			(arc
				(start 56.2102 -52.742592)
				(mid 56.159415 -52.56657)
				(end 56.2102 -52.390548)
			)
			(xy 56.2102 -52.19446)
			(arc
				(start 56.207152 -52.186078)
				(mid 56.196592 -52.146955)
				(end 56.193182 -52.106576)
			)
			(xy 56.193436 -52.106576) (xy 56.193436 -51.807364)
			(arc
				(start 56.193182 -51.807364)
				(mid 56.196587 -51.766984)
				(end 56.207152 -51.727862)
			)
			(xy 56.2102 -51.71948) (xy 56.2102 -50.748946) (xy 56.409082 -50.550064) (xy 56.703976 -50.550064)
			(xy 56.807354 -50.446686) (xy 56.807354 -50.101246) (xy 57.44337 -49.46523) (xy 58.365644 -49.46523)
			(xy 58.478928 -49.351946) (xy 58.478928 -49.067466) (xy 58.316114 -48.904652) (xy 58.126884 -48.904652)
			(xy 58.124344 -48.904906) (xy 58.090308 -48.906684) (xy 58.056272 -48.904906) (xy 58.053732 -48.904652)
			(xy 57.902856 -48.904652)
			(arc
				(start 57.729628 -48.731424)
				(mid 57.645975 -48.702333)
				(end 57.571386 -48.749966)
			)
			(arc
				(start 57.571386 -48.749966)
				(mid 57.451147 -48.864822)
				(end 57.290208 -48.906684)
			)
			(arc
				(start 57.290208 -48.906684)
				(mid 57.056362 -48.809822)
				(end 56.9595 -48.575976)
			)
			(arc
				(start 56.9595 -48.575976)
				(mid 56.96543 -48.513377)
				(end 56.983122 -48.45304)
			)
			(arc
				(start 56.983122 -48.45304)
				(mid 56.973018 -48.358321)
				(end 56.888888 -48.313594)
			)
			(xy 56.729376 -48.313594)
			(arc
				(start 56.716422 -48.322738)
				(mid 56.654272 -48.353052)
				(end 56.585866 -48.363124)
			)
			(xy 56.353964 -48.363124) (xy 56.23687 -48.479964) (xy 56.23687 -48.669956) (xy 56.291988 -48.725328)
			(xy 56.574436 -48.725328) (xy 56.816752 -48.96739) (xy 56.816752 -48.97628) (xy 56.818784 -48.978566)
			(xy 56.818784 -49.50079) (xy 56.816752 -49.503076) (xy 56.816752 -49.509426) (xy 56.552592 -49.773332)
			(xy 56.545988 -49.773332) (xy 56.503062 -49.816512) (xy 54.802532 -49.816512) (xy 54.597046 -50.021998)
			(xy 54.597046 -50.490628) (xy 54.621684 -50.515266) (xy 55.257192 -50.515266) (xy 55.479442 -50.737516)
			(xy 55.479442 -52.930298) (xy 55.288942 -53.120798) (xy 54.62778 -53.120798) (xy 54.57698 -53.171344)
			(xy 54.57698 -53.642514) (xy 54.507638 -53.711856) (xy 54.507638 -53.751988) (xy 54.35727 -53.902356)
			(xy 54.317138 -53.902356) (xy 54.303168 -53.91658) (xy 53.991764 -53.91658) (xy 53.853588 -54.054756)
			(xy 53.853588 -54.285134) (xy 53.97754 -54.409086) (xy 54.40172 -54.409086) (xy 54.40553 -54.412896)
			(xy 55.13705 -54.412896) (xy 55.237888 -54.513734) (xy 55.237888 -55.278274) (xy 55.386732 -55.427118)
			(xy 56.56707 -55.427118)
		)
		(stroke
			(width 0)
			(type solid)
		)
		(fill yes)
		(layer "B.Cu")
		(net "P1V8_AUX")
	)
	(gr_poly
		(pts
			(xy 77.69987 -62.096904) (xy 77.69987 -59.887866) (xy 77.523086 -59.711082)
			(arc
				(start 76.966318 -59.711082)
				(mid 76.891831 -59.743586)
				(end 76.864972 -59.820302)
			)
			(arc
				(start 76.865988 -59.849004)
				(mid 76.821917 -60.026942)
				(end 76.699872 -60.16371)
			)
			(arc
				(start 76.699872 -60.16371)
				(mid 76.655474 -60.247712)
				(end 76.699872 -60.331604)
			)
			(arc
				(start 76.699872 -60.331604)
				(mid 76.821882 -60.468391)
				(end 76.865988 -60.64631)
			)
			(arc
				(start 76.865988 -60.64631)
				(mid 76.48448 -61.027818)
				(end 76.102972 -60.64631)
			)
			(arc
				(start 76.102972 -60.64631)
				(mid 76.147043 -60.468372)
				(end 76.269088 -60.331604)
			)
			(arc
				(start 76.269088 -60.331604)
				(mid 76.313276 -60.247712)
				(end 76.269088 -60.16371)
			)
			(arc
				(start 76.269088 -60.16371)
				(mid 76.147078 -60.026923)
				(end 76.102972 -59.849004)
			)
			(arc
				(start 76.103988 -59.820302)
				(mid 76.077152 -59.743564)
				(end 76.002642 -59.711082)
			)
			(xy 74.79284 -59.711082) (xy 74.01687 -58.935112) (xy 74.01687 -58.60796) (xy 73.731628 -58.322718)
			(xy 73.128124 -58.322718) (xy 73.125076 -58.325766) (xy 72.90562 -58.325766) (xy 72.814688 -58.416698)
			(xy 72.81926 -58.42127) (xy 72.81926 -59.85764) (xy 72.838056 -59.87669) (xy 73.68286 -59.87669)
			(arc
				(start 75.6412 -61.83503)
				(mid 75.677014 -61.849791)
				(end 75.712828 -61.83503)
			)
			(arc
				(start 75.712828 -61.83503)
				(mid 75.836059 -61.753443)
				(end 75.981052 -61.724794)
			)
			(arc
				(start 75.981052 -61.724794)
				(mid 76.250819 -61.836535)
				(end 76.36256 -62.106302)
			)
			(arc
				(start 76.36256 -62.106302)
				(mid 76.361793 -62.130227)
				(end 76.359512 -62.154054)
			)
			(arc
				(start 76.359512 -62.154054)
				(mid 76.384125 -62.233981)
				(end 76.46035 -62.268354)
			)
			(xy 77.52842 -62.268354)
		)
		(stroke
			(width 0)
			(type solid)
		)
		(fill yes)
		(layer "B.Cu")
		(net "P1V0_STBY_DP_VCC10A")
	)
	(gr_poly
		(pts
			(xy 39.189914 -38.483286) (xy 40.1828 -38.483286) (xy 40.326056 -38.34003) (xy 40.326056 -37.286438)
			(xy 39.720012 -36.680394) (xy 39.70262 -36.662227) (xy 39.673269 -36.621389) (xy 39.661592 -36.599114)
			(xy 38.853364 -36.599114) (xy 38.852856 -36.59886) (xy 38.613334 -36.59886) (xy 38.347142 -36.332668)
			(xy 38.347142 -35.476434) (xy 38.263576 -35.392868) (xy 38.239738 -35.408451) (xy 38.188414 -35.43313)
			(xy 38.133989 -35.449895) (xy 38.077674 -35.458371) (xy 38.0492 -35.458908) (xy 38.020532 -35.458393)
			(xy 37.963841 -35.449815) (xy 37.909071 -35.432852) (xy 37.857456 -35.407887) (xy 37.810156 -35.37548)
			(xy 37.78885 -35.356292) (xy 36.409376 -35.356292) (xy 36.233354 -35.532314) (xy 36.233354 -36.740084)
			(xy 36.257283 -36.752115) (xy 36.301812 -36.781877) (xy 36.341744 -36.817569) (xy 36.376298 -36.858491)
			(xy 36.404795 -36.90384) (xy 36.426675 -36.952726) (xy 36.441509 -37.004189) (xy 36.449007 -37.057221)
			(xy 36.449508 -37.084) (xy 36.449436 -37.095074) (xy 36.448168 -37.117187) (xy 36.446968 -37.128196)
			(xy 36.444174 -37.152834) (xy 36.832536 -37.541196) (xy 37.243748 -37.541196) (xy 37.243748 -37.48126)
			(xy 37.251571 -37.421838) (xy 37.267084 -37.363945) (xy 37.29002 -37.308572) (xy 37.319987 -37.256666)
			(xy 37.356474 -37.209116) (xy 37.398854 -37.166736) (xy 37.446404 -37.130249) (xy 37.49831 -37.100282)
			(xy 37.553683 -37.077346) (xy 37.611576 -37.061833) (xy 37.670998 -37.05401) (xy 37.730934 -37.05401)
			(xy 37.790356 -37.061833) (xy 37.848249 -37.077346) (xy 37.903622 -37.100282) (xy 37.955528 -37.130249)
			(xy 38.003078 -37.166736) (xy 38.045458 -37.209116) (xy 38.081945 -37.256666) (xy 38.111912 -37.308572)
			(xy 38.134848 -37.363945) (xy 38.150361 -37.421838) (xy 38.158184 -37.48126) (xy 38.158674 -37.511228)
			(xy 38.15867 -37.511482) (xy 38.367206 -37.511482) (xy 38.371277 -37.45586) (xy 38.383403 -37.401423)
			(xy 38.403326 -37.349332) (xy 38.430622 -37.300697) (xy 38.464708 -37.256554) (xy 38.504857 -37.217845)
			(xy 38.550215 -37.185394) (xy 38.599815 -37.159893) (xy 38.652599 -37.141886) (xy 38.707442 -37.131756)
			(xy 38.763176 -37.129719) (xy 38.818613 -37.135819) (xy 38.87257 -37.149925) (xy 38.923899 -37.171737)
			(xy 38.971505 -37.200791) (xy 39.014373 -37.236466) (xy 39.05159 -37.278003) (xy 39.082363 -37.324516)
			(xy 39.106035 -37.375013) (xy 39.122103 -37.42842) (xy 39.130223 -37.483596) (xy 39.130732 -37.511482)
			(xy 39.130223 -37.539368) (xy 39.122103 -37.594544) (xy 39.106035 -37.647951) (xy 39.082363 -37.698448)
			(xy 39.05159 -37.744961) (xy 39.014373 -37.786498) (xy 38.971505 -37.822173) (xy 38.923899 -37.851227)
			(xy 38.87257 -37.873039) (xy 38.818613 -37.887145) (xy 38.763176 -37.893245) (xy 38.707442 -37.891208)
			(xy 38.652599 -37.881078) (xy 38.599815 -37.863071) (xy 38.550215 -37.83757) (xy 38.504857 -37.805119)
			(xy 38.464708 -37.76641) (xy 38.430622 -37.722267) (xy 38.403326 -37.673632) (xy 38.383403 -37.621541)
			(xy 38.371277 -37.567104) (xy 38.367206 -37.511482) (xy 38.15867 -37.511482) (xy 38.158184 -37.541196)
			(xy 38.150361 -37.600618) (xy 38.134848 -37.658511) (xy 38.111912 -37.713884) (xy 38.081945 -37.76579)
			(xy 38.045458 -37.81334) (xy 38.003078 -37.85572) (xy 37.955528 -37.892207) (xy 37.903622 -37.922174)
			(xy 37.848249 -37.94511) (xy 37.790356 -37.960623) (xy 37.730934 -37.968446) (xy 37.670998 -37.968446)
			(xy 37.611576 -37.960623) (xy 37.553683 -37.94511) (xy 37.49831 -37.922174) (xy 37.446404 -37.892207)
			(xy 37.398854 -37.85572) (xy 37.356474 -37.81334) (xy 37.319987 -37.76579) (xy 37.29002 -37.713884)
			(xy 37.267084 -37.658511) (xy 37.251571 -37.600618) (xy 37.243748 -37.541196) (xy 36.832536 -37.541196)
			(xy 36.95192 -37.66058) (xy 36.95192 -38.180264) (xy 37.252656 -38.480746) (xy 37.260784 -38.489128)
			(xy 37.27577 -38.504876) (xy 37.313616 -38.504876) (xy 37.313616 -38.554914) (xy 37.321236 -38.56736)
			(xy 37.332817 -38.586519) (xy 37.352787 -38.626589) (xy 37.361114 -38.64737) (xy 37.365178 -38.65753)
			(xy 37.4142 -38.706552) (xy 37.4142 -39.0144) (xy 37.4904 -39.0906) (xy 38.5826 -39.0906)
		)
		(stroke
			(width 0)
			(type solid)
		)
		(fill yes)
		(layer "B.Cu")
		(net "P3V3_P1V8_SD1VDD")
	)
	(gr_poly
		(pts
			(xy 45.724572 -51.2826) (xy 45.739782 -51.28204) (xy 45.768857 -51.273091) (xy 45.794009 -51.25598)
			(xy 45.813008 -51.232221) (xy 45.824169 -51.203923) (xy 45.826505 -51.173592) (xy 45.819807 -51.143918)
			(xy 45.81271 -51.130454) (xy 45.799005 -51.105298) (xy 45.779534 -51.05143) (xy 45.769644 -50.99501)
			(xy 45.769022 -50.96637) (xy 45.769532 -50.940383) (xy 45.777662 -50.889048) (xy 45.793723 -50.839618)
			(xy 45.817319 -50.793308) (xy 45.847869 -50.75126) (xy 45.88462 -50.714509) (xy 45.926668 -50.683959)
			(xy 45.972978 -50.660363) (xy 46.022408 -50.644302) (xy 46.073743 -50.636172) (xy 46.125717 -50.636172)
			(xy 46.177052 -50.644302) (xy 46.226482 -50.660363) (xy 46.272792 -50.683959) (xy 46.31484 -50.714509)
			(xy 46.351591 -50.75126) (xy 46.382141 -50.793308) (xy 46.405737 -50.839618) (xy 46.421798 -50.889048)
			(xy 46.429928 -50.940383) (xy 46.430438 -50.96637) (xy 46.430137 -50.986321) (xy 46.425298 -51.025928)
			(xy 46.420786 -51.045364) (xy 46.413928 -51.07305) (xy 46.470316 -51.129184) (xy 46.573694 -51.025806)
			(xy 46.5709 -51.001676) (xy 46.569122 -50.96637) (xy 46.569651 -50.939463) (xy 46.578364 -50.88636)
			(xy 46.595556 -50.835367) (xy 46.620773 -50.787828) (xy 46.65335 -50.744996) (xy 46.6725 -50.726086)
			(xy 46.6725 -50.406808) (xy 46.653326 -50.387922) (xy 46.620755 -50.345082) (xy 46.595543 -50.297536)
			(xy 46.578356 -50.246539) (xy 46.569646 -50.193432) (xy 46.569122 -50.166524) (xy 46.569584 -50.141459)
			(xy 46.577149 -50.091903) (xy 46.59211 -50.044057) (xy 46.614124 -49.999019) (xy 46.642685 -49.957821)
			(xy 46.677139 -49.921407) (xy 46.716697 -49.890613) (xy 46.76045 -49.866145) (xy 46.783752 -49.856898)
			(xy 46.793912 -49.853088) (xy 47.0916 -49.5554) (xy 47.0916 -49.05248) (xy 47.11954 -49.02454) (xy 47.0535 -48.9585)
			(xy 45.9105 -48.9585) (xy 45.085 -49.784) (xy 45.085 -49.8729) (xy 45.14723 -49.8729) (xy 45.157644 -49.868074)
			(xy 45.179966 -49.857913) (xy 45.226861 -49.84356) (xy 45.275363 -49.836295) (xy 45.299884 -49.835816)
			(xy 45.325872 -49.836298) (xy 45.377209 -49.844427) (xy 45.426642 -49.860486) (xy 45.472954 -49.884081)
			(xy 45.515005 -49.914631) (xy 45.551759 -49.951383) (xy 45.58231 -49.993432) (xy 45.605908 -50.039743)
			(xy 45.62197 -50.089175) (xy 45.630101 -50.140512) (xy 45.630101 -50.192488) (xy 45.630097 -50.192511)
			(xy 45.769532 -50.192511) (xy 45.769532 -50.140537) (xy 45.777662 -50.089202) (xy 45.793723 -50.039772)
			(xy 45.817319 -49.993462) (xy 45.847869 -49.951414) (xy 45.88462 -49.914663) (xy 45.926668 -49.884113)
			(xy 45.972978 -49.860517) (xy 46.022408 -49.844456) (xy 46.073743 -49.836326) (xy 46.125717 -49.836326)
			(xy 46.177052 -49.844456) (xy 46.226482 -49.860517) (xy 46.272792 -49.884113) (xy 46.31484 -49.914663)
			(xy 46.351591 -49.951414) (xy 46.382141 -49.993462) (xy 46.405737 -50.039772) (xy 46.421798 -50.089202)
			(xy 46.429928 -50.140537) (xy 46.430438 -50.166524) (xy 46.429928 -50.192511) (xy 46.421798 -50.243846)
			(xy 46.405737 -50.293276) (xy 46.382141 -50.339586) (xy 46.351591 -50.381634) (xy 46.31484 -50.418385)
			(xy 46.272792 -50.448935) (xy 46.226482 -50.472531) (xy 46.177052 -50.488592) (xy 46.125717 -50.496722)
			(xy 46.073743 -50.496722) (xy 46.022408 -50.488592) (xy 45.972978 -50.472531) (xy 45.926668 -50.448935)
			(xy 45.88462 -50.418385) (xy 45.847869 -50.381634) (xy 45.817319 -50.339586) (xy 45.793723 -50.293276)
			(xy 45.777662 -50.243846) (xy 45.769532 -50.192511) (xy 45.630097 -50.192511) (xy 45.62197 -50.243825)
			(xy 45.605908 -50.293257) (xy 45.58231 -50.339568) (xy 45.551759 -50.381617) (xy 45.515005 -50.418369)
			(xy 45.472954 -50.448919) (xy 45.426642 -50.472514) (xy 45.377209 -50.488573) (xy 45.325872 -50.496702)
			(xy 45.299884 -50.497232) (xy 45.277963 -50.496841) (xy 45.234512 -50.490976) (xy 45.21327 -50.485548)
			(xy 45.200281 -50.482429) (xy 45.173576 -50.482342) (xy 45.147763 -50.489184) (xy 45.124607 -50.502485)
			(xy 45.105692 -50.521337) (xy 45.092313 -50.544449) (xy 45.085386 -50.57024) (xy 45.085 -50.583592)
			(xy 45.085 -51.1048) (xy 45.2628 -51.2826)
		)
		(stroke
			(width 0)
			(type solid)
		)
		(fill yes)
		(layer "B.Cu")
		(net "GND")
	)
	(gr_poly
		(pts
			(xy 37.6428 -61.0362) (xy 39.3446 -61.0362) (xy 39.583614 -60.797186) (xy 39.587424 -60.789566) (xy 39.600596 -60.764364)
			(xy 39.633268 -60.717823) (xy 39.672484 -60.676644) (xy 39.717374 -60.64174) (xy 39.766947 -60.613881)
			(xy 39.820103 -60.593685) (xy 39.847774 -60.587128) (xy 39.862506 -60.58408) (xy 39.914576 -60.531756)
			(xy 39.93229 -60.514707) (xy 39.972079 -60.485835) (xy 40.015898 -60.463546) (xy 40.062666 -60.448392)
			(xy 40.111229 -60.440744) (xy 40.13581 -60.440316) (xy 40.30472 -60.440316) (xy 40.30472 -60.3504)
			(xy 40.939212 -60.3504) (xy 41.128442 -60.16117) (xy 41.562274 -60.16117) (xy 41.577208 -60.160651)
			(xy 41.605803 -60.152027) (xy 41.630686 -60.135508) (xy 41.649733 -60.112503) (xy 41.66132 -60.084974)
			(xy 41.664457 -60.055272) (xy 41.662096 -60.04052) (xy 41.658992 -60.022904) (xy 41.655683 -59.987286)
			(xy 41.655492 -59.9694) (xy 41.655978 -59.942149) (xy 41.663734 -59.888201) (xy 41.679089 -59.835906)
			(xy 41.701731 -59.786329) (xy 41.731197 -59.740479) (xy 41.766888 -59.699288) (xy 41.808079 -59.663597)
			(xy 41.853929 -59.634131) (xy 41.903506 -59.611489) (xy 41.955801 -59.596134) (xy 42.009749 -59.588378)
			(xy 42.037 -59.587892) (xy 42.050059 -59.588005) (xy 42.076117 -59.589783) (xy 42.08907 -59.591448)
			(xy 42.103488 -59.592929) (xy 42.132145 -59.588683) (xy 42.158457 -59.576562) (xy 42.180307 -59.55754)
			(xy 42.195936 -59.533148) (xy 42.204088 -59.505349) (xy 42.20464 -59.490864) (xy 42.20464 -58.870342)
			(xy 42.102532 -58.768234) (xy 41.641776 -58.768234) (xy 41.63695 -58.76925) (xy 41.610228 -58.77412)
			(xy 41.55616 -58.779333) (xy 41.529 -58.779664) (xy 40.934386 -58.779664) (xy 40.907227 -58.779331)
			(xy 40.853158 -58.774115) (xy 40.826436 -58.76925) (xy 40.82161 -58.768234) (xy 40.088566 -58.768234)
			(xy 39.9796 -58.8772) (xy 39.9796 -59.6392) (xy 39.951152 -59.667648) (xy 39.948358 -59.683142) (xy 39.943098 -59.709107)
			(xy 39.926354 -59.759368) (xy 39.902817 -59.80683) (xy 39.87294 -59.850578) (xy 39.837297 -59.889772)
			(xy 39.796574 -59.923657) (xy 39.751555 -59.951583) (xy 39.703105 -59.973011) (xy 39.652156 -59.987529)
			(xy 39.599689 -59.994859) (xy 39.5732 -59.995308) (xy 39.544461 -59.994787) (xy 39.487633 -59.986165)
			(xy 39.432742 -59.969115) (xy 39.381029 -59.944023) (xy 39.333666 -59.911458) (xy 39.312342 -59.892184)
			(xy 39.302292 -59.883291) (xy 39.278635 -59.87064) (xy 39.252498 -59.864598) (xy 39.225689 -59.865582)
			(xy 39.200065 -59.873523) (xy 39.177399 -59.887873) (xy 39.16807 -59.897518) (xy 39.149947 -59.91658)
			(xy 39.109366 -59.950038) (xy 39.064569 -59.977599) (xy 39.016407 -59.998737) (xy 38.965796 -60.013051)
			(xy 38.913698 -60.02027) (xy 38.8874 -60.020708) (xy 38.860574 -60.020253) (xy 38.80745 -60.01274)
			(xy 38.755902 -59.997862) (xy 38.706945 -59.975912) (xy 38.661544 -59.947322) (xy 38.620594 -59.912657)
			(xy 38.584902 -59.872599) (xy 38.569646 -59.850528) (xy 36.950142 -59.850528) (xy 36.381511 -60.41898)
			(xy 37.982142 -60.41898) (xy 37.986213 -60.363358) (xy 37.998339 -60.308921) (xy 38.018262 -60.25683)
			(xy 38.045558 -60.208195) (xy 38.079644 -60.164052) (xy 38.119793 -60.125343) (xy 38.165151 -60.092892)
			(xy 38.214751 -60.067391) (xy 38.267535 -60.049384) (xy 38.322378 -60.039254) (xy 38.378112 -60.037217)
			(xy 38.433549 -60.043317) (xy 38.487506 -60.057423) (xy 38.538835 -60.079235) (xy 38.586441 -60.108289)
			(xy 38.629309 -60.143964) (xy 38.666526 -60.185501) (xy 38.697299 -60.232014) (xy 38.720971 -60.282511)
			(xy 38.737039 -60.335918) (xy 38.745159 -60.391094) (xy 38.745668 -60.41898) (xy 38.745159 -60.446866)
			(xy 38.737039 -60.502042) (xy 38.720971 -60.555449) (xy 38.697299 -60.605946) (xy 38.666526 -60.652459)
			(xy 38.629309 -60.693996) (xy 38.586441 -60.729671) (xy 38.538835 -60.758725) (xy 38.487506 -60.780537)
			(xy 38.433549 -60.794643) (xy 38.378112 -60.800743) (xy 38.322378 -60.798706) (xy 38.267535 -60.788576)
			(xy 38.214751 -60.770569) (xy 38.165151 -60.745068) (xy 38.119793 -60.712617) (xy 38.079644 -60.673908)
			(xy 38.045558 -60.629765) (xy 38.018262 -60.58113) (xy 37.998339 -60.529039) (xy 37.986213 -60.474602)
			(xy 37.982142 -60.41898) (xy 36.381511 -60.41898) (xy 36.1442 -60.656216) (xy 36.1442 -60.9092) (xy 36.4744 -61.2394)
			(xy 37.4396 -61.2394)
		)
		(stroke
			(width 0)
			(type solid)
		)
		(fill yes)
		(layer "B.Cu")
		(net "P3V3_AUX")
	)
	(gr_poly
		(pts
			(xy 47.913036 -47.782734) (xy 47.913036 -46.902624) (xy 47.9171 -46.89856) (xy 47.9171 -46.894496)
			(xy 48.31461 -46.496732) (xy 48.31842 -46.496732) (xy 48.33239 -46.482762) (xy 50.315114 -46.482762)
			(xy 50.374804 -46.423072) (xy 50.374804 -45.898816) (xy 50.32375 -45.848016) (xy 48.871632 -45.848016)
			(xy 48.8696 -45.845984) (xy 48.86198 -45.845984) (xy 48.650652 -45.635164) (xy 48.650652 -45.170852)
			(xy 48.5648 -45.085) (xy 48.2346 -45.085) (xy 47.981362 -44.831762) (xy 47.974385 -44.825357) (xy 47.957043 -44.817775)
			(xy 47.938133 -44.816992) (xy 47.920224 -44.823114) (xy 47.912782 -44.828968) (xy 47.890237 -44.847161)
			(xy 47.840103 -44.87618) (xy 47.785683 -44.896031) (xy 47.72864 -44.906108) (xy 47.699676 -44.906692)
			(xy 47.672115 -44.906147) (xy 47.617755 -44.897014) (xy 47.565664 -44.87899) (xy 47.517285 -44.852572)
			(xy 47.47396 -44.818495) (xy 47.436888 -44.777702) (xy 47.421546 -44.7548) (xy 47.3456 -44.7548)
			(xy 47.1424 -44.958) (xy 47.1424 -45.151294) (xy 47.15887 -45.169746) (xy 47.186709 -45.210623) (xy 47.208151 -45.255191)
			(xy 47.222717 -45.302454) (xy 47.230084 -45.35136) (xy 47.230085 -45.400817) (xy 47.229896 -45.402071)
			(xy 47.369478 -45.402071) (xy 47.369478 -45.350097) (xy 47.377608 -45.298762) (xy 47.393669 -45.249332)
			(xy 47.417265 -45.203022) (xy 47.447815 -45.160974) (xy 47.484566 -45.124223) (xy 47.526614 -45.093673)
			(xy 47.572924 -45.070077) (xy 47.622354 -45.054016) (xy 47.673689 -45.045886) (xy 47.725663 -45.045886)
			(xy 47.776998 -45.054016) (xy 47.826428 -45.070077) (xy 47.872738 -45.093673) (xy 47.914786 -45.124223)
			(xy 47.951537 -45.160974) (xy 47.982087 -45.203022) (xy 48.005683 -45.249332) (xy 48.021744 -45.298762)
			(xy 48.029874 -45.350097) (xy 48.030384 -45.376084) (xy 48.029874 -45.402071) (xy 48.021744 -45.453406)
			(xy 48.005683 -45.502836) (xy 47.982087 -45.549146) (xy 47.951537 -45.591194) (xy 47.914786 -45.627945)
			(xy 47.872738 -45.658495) (xy 47.826428 -45.682091) (xy 47.776998 -45.698152) (xy 47.725663 -45.706282)
			(xy 47.673689 -45.706282) (xy 47.622354 -45.698152) (xy 47.572924 -45.682091) (xy 47.526614 -45.658495)
			(xy 47.484566 -45.627945) (xy 47.447815 -45.591194) (xy 47.417265 -45.549146) (xy 47.393669 -45.502836)
			(xy 47.377608 -45.453406) (xy 47.369478 -45.402071) (xy 47.229896 -45.402071) (xy 47.222723 -45.449723)
			(xy 47.208159 -45.496987) (xy 47.186721 -45.541556) (xy 47.158884 -45.582436) (xy 47.1424 -45.600874)
			(xy 47.1424 -45.95114) (xy 47.158866 -45.969591) (xy 47.186699 -46.010468) (xy 47.208134 -46.055034)
			(xy 47.222694 -46.102294) (xy 47.230055 -46.151196) (xy 47.230052 -46.200648) (xy 47.229861 -46.201917)
			(xy 47.369478 -46.201917) (xy 47.369478 -46.149943) (xy 47.377608 -46.098608) (xy 47.393669 -46.049178)
			(xy 47.417265 -46.002868) (xy 47.447815 -45.96082) (xy 47.484566 -45.924069) (xy 47.526614 -45.893519)
			(xy 47.572924 -45.869923) (xy 47.622354 -45.853862) (xy 47.673689 -45.845732) (xy 47.725663 -45.845732)
			(xy 47.776998 -45.853862) (xy 47.826428 -45.869923) (xy 47.872738 -45.893519) (xy 47.914786 -45.924069)
			(xy 47.951537 -45.96082) (xy 47.982087 -46.002868) (xy 48.005683 -46.049178) (xy 48.021744 -46.098608)
			(xy 48.029874 -46.149943) (xy 48.030384 -46.17593) (xy 48.029874 -46.201917) (xy 48.021744 -46.253252)
			(xy 48.005683 -46.302682) (xy 47.982087 -46.348992) (xy 47.951537 -46.39104) (xy 47.914786 -46.427791)
			(xy 47.872738 -46.458341) (xy 47.826428 -46.481937) (xy 47.776998 -46.497998) (xy 47.725663 -46.506128)
			(xy 47.673689 -46.506128) (xy 47.622354 -46.497998) (xy 47.572924 -46.481937) (xy 47.526614 -46.458341)
			(xy 47.484566 -46.427791) (xy 47.447815 -46.39104) (xy 47.417265 -46.348992) (xy 47.393669 -46.302682)
			(xy 47.377608 -46.253252) (xy 47.369478 -46.201917) (xy 47.229861 -46.201917) (xy 47.222685 -46.249549)
			(xy 47.208118 -46.296807) (xy 47.186677 -46.34137) (xy 47.158839 -46.382243) (xy 47.1424 -46.40072)
			(xy 47.1424 -46.75124) (xy 47.158871 -46.76969) (xy 47.186713 -46.810566) (xy 47.208155 -46.855132)
			(xy 47.22272 -46.902396) (xy 47.230082 -46.951302) (xy 47.230538 -46.97603) (xy 47.229867 -47.006515)
			(xy 47.218752 -47.066461) (xy 47.20844 -47.095156) (xy 47.196502 -47.12589) (xy 47.416212 -47.3456)
			(xy 47.416212 -47.808388) (xy 47.45355 -47.845726) (xy 47.850044 -47.845726)
		)
		(stroke
			(width 0)
			(type solid)
		)
		(fill yes)
		(layer "B.Cu")
		(net "P3V3_P2V5_P1V8_RVDD")
	)
	(gr_poly
		(pts
			(arc
				(start 46.328076 -69.68744)
				(mid 46.276853 -69.583511)
				(end 46.259242 -69.469)
			)
			(arc
				(start 46.259242 -69.469)
				(mid 46.351163 -69.220724)
				(end 46.582584 -69.092064)
			)
			(arc
				(start 46.582584 -69.092064)
				(mid 46.658249 -69.036414)
				(end 46.65599 -68.942458)
			)
			(arc
				(start 46.65599 -68.942458)
				(mid 46.62057 -68.853392)
				(end 46.608492 -68.758308)
			)
			(arc
				(start 46.608492 -68.7578)
				(mid 46.99 -68.376292)
				(end 47.371508 -68.7578)
			)
			(arc
				(start 47.371508 -68.7578)
				(mid 47.279587 -69.006076)
				(end 47.048166 -69.134736)
			)
			(arc
				(start 47.048166 -69.134736)
				(mid 46.972501 -69.190386)
				(end 46.97476 -69.284342)
			)
			(arc
				(start 46.97476 -69.284342)
				(mid 47.01018 -69.373408)
				(end 47.022258 -69.468492)
			)
			(arc
				(start 47.022258 -69.469)
				(mid 47.004592 -69.583494)
				(end 46.953424 -69.68744)
			)
			(xy 46.953424 -70.4088) (xy 48.326802 -70.4088) (xy 48.4378 -70.297802) (xy 48.4378 -70.280276) (xy 48.68291 -70.034912)
			(xy 49.781206 -70.034912) (xy 49.789842 -70.043802) (xy 50.455322 -70.043802) (xy 50.510186 -69.988938)
			(xy 50.510186 -69.59727) (xy 50.435256 -69.52234) (xy 49.958752 -69.52234) (xy 49.954942 -69.51853)
			(xy 49.954434 -69.51853) (xy 49.62652 -69.190616) (xy 49.284382 -69.190616) (xy 48.288956 -68.195444)
			(xy 48.189896 -68.195444) (xy 48.189896 -68.1355) (xy 47.92472 -68.1355) (xy 47.92472 -67.5005) (xy 48.014636 -67.5005)
			(xy 48.014636 -67.05981)
			(arc
				(start 47.846488 -66.654426)
				(mid 47.828664 -66.595784)
				(end 47.822612 -66.534792)
			)
			(xy 47.822612 -66.41846) (xy 47.3202 -66.41846)
			(arc
				(start 46.948598 -66.790062)
				(mid 46.920019 -66.876013)
				(end 46.971458 -66.95059)
			)
			(arc
				(start 46.971458 -66.95059)
				(mid 47.115446 -67.090745)
				(end 47.168308 -67.2846)
			)
			(arc
				(start 47.168308 -67.2846)
				(mid 46.7868 -67.666108)
				(end 46.405292 -67.2846)
			)
			(arc
				(start 46.405292 -67.2846)
				(mid 46.406509 -67.254405)
				(end 46.410118 -67.224402)
			)
			(arc
				(start 46.410118 -67.224402)
				(mid 46.387079 -67.142459)
				(end 46.309788 -67.1068)
			)
			(xy 45.72 -67.1068) (xy 45.6184 -67.2084) (xy 45.6184 -68.77558) (xy 45.339 -69.05498) (xy 45.339 -70.0532)
			(xy 45.68571 -70.39991) (xy 45.703236 -70.4088) (xy 46.328076 -70.4088)
		)
		(stroke
			(width 0)
			(type solid)
		)
		(fill yes)
		(layer "B.Cu")
		(net "P3V3_AUX")
	)
	(gr_poly
		(pts
			(xy 50.40503 -55.960518) (xy 50.40503 -55.507636) (xy 50.385472 -55.488332) (xy 50.238152 -55.488332)
			(xy 50.238152 -55.341012) (xy 50.115978 -55.218584) (xy 50.115978 -53.99532) (xy 50.456846 -53.654452)
			(xy 51.105562 -53.654452) (xy 51.227228 -53.532786) (xy 51.227228 -53.204618) (xy 51.030632 -53.008022)
			(xy 50.461418 -53.008022) (xy 50.362104 -52.908708) (xy 50.362104 -51.369976) (xy 50.45075 -51.28133)
			(xy 51.36769 -51.28133) (xy 51.42738 -51.34102) (xy 51.42738 -51.90998) (xy 51.46802 -51.95062) (xy 52.85994 -51.95062)
			(xy 52.9463 -51.86426) (xy 52.9463 -51.37912) (xy 53.10632 -51.2191) (xy 53.43906 -51.2191) (xy 53.49748 -51.16068)
			(xy 53.49748 -49.988724) (xy 53.450744 -49.941988) (xy 53.110892 -49.941988) (xy 52.871878 -49.702974)
			(xy 52.871878 -48.908716) (xy 53.041804 -48.73879) (xy 53.041804 -48.078898) (xy 53.3019 -47.818802)
			(xy 53.947822 -47.818802) (xy 55.043324 -48.914304) (xy 55.043324 -49.46777) (xy 55.094632 -49.519078)
			(xy 56.447182 -49.519078) (xy 56.562244 -49.404016) (xy 56.562244 -49.0728) (xy 56.469026 -48.979582)
			(xy 56.044846 -48.979582) (xy 55.926482 -48.861218) (xy 55.926482 -48.491648) (xy 55.742078 -48.307244)
			(xy 55.59171 -48.307244) (xy 55.591202 -48.306736) (xy 55.54599 -48.306736) (xy 55.22341 -47.984156)
			(xy 54.839108 -47.984156) (xy 54.209696 -47.354744) (xy 54.209696 -47.302166) (xy 54.154832 -47.302166)
			(arc
				(start 54.151022 -47.302674)
				(mid 54.125447 -47.305696)
				(end 54.099714 -47.306738)
			)
			(arc
				(start 54.099714 -47.306738)
				(mid 53.769006 -46.97603)
				(end 54.099714 -46.645322)
			)
			(arc
				(start 54.106064 -46.645322)
				(mid 54.17923 -46.616293)
				(end 54.209696 -46.543722)
			)
			(xy 54.209696 -46.412912) (xy 54.27345 -46.349158) (xy 54.27345 -46.348142) (xy 54.691534 -45.930058)
			(xy 55.170578 -45.930058) (xy 55.705248 -46.464728) (xy 56.130952 -46.464728) (xy 56.20639 -46.38929)
			(xy 56.20639 -45.811186) (xy 55.98668 -45.591476) (xy 55.98668 -45.162724) (xy 56.103266 -45.046138)
			(xy 56.103266 -43.501564) (xy 56.065674 -43.463972) (xy 55.66156 -43.463972) (xy 55.544974 -43.580558)
			(xy 55.544974 -43.806618) (xy 55.044594 -44.306998) (xy 55.044594 -45.034708) (xy 54.285388 -45.793914)
			(xy 53.564536 -45.793914) (xy 53.382926 -45.612304) (xy 53.382926 -45.094906) (xy 53.337714 -45.049694)
			(xy 52.43957 -45.049694) (xy 52.34305 -44.953174) (xy 51.439572 -44.953174) (xy 51.370738 -45.022008)
			(xy 51.370738 -45.66158) (xy 51.177444 -45.854874) (xy 50.775362 -45.854874) (xy 50.629058 -46.001178)
			(xy 50.629058 -46.397164) (xy 50.703226 -46.471332) (xy 51.22418 -46.471332) (xy 52.02301 -45.672248)
			(xy 52.75961 -45.672248) (xy 53.073554 -45.986192) (xy 53.073554 -47.038768)
			(arc
				(start 53.07457 -47.043594)
				(mid 53.077776 -47.065207)
				(end 53.078888 -47.087028)
			)
			(xy 53.078888 -47.354744) (xy 53.073554 -47.354744) (xy 53.073554 -47.569374) (xy 52.902866 -47.740062)
			(xy 51.312064 -47.740062) (xy 51.283362 -47.768764) (xy 50.294286 -47.768764) (xy 50.269902 -47.793148)
			(xy 49.054004 -47.793148) (xy 48.942752 -47.9044) (xy 48.942752 -48.67783) (xy 49.063402 -48.79848)
			(xy 50.934112 -48.79848) (xy 51.140106 -49.004474) (xy 51.140106 -49.795684) (xy 51.011582 -49.924208)
			(xy 49.23536 -49.924208) (xy 49.133252 -50.026316) (xy 49.133252 -51.89728) (xy 49.233328 -51.997356)
			(xy 49.241964 -51.997356) (xy 49.241964 -52.005992) (xy 49.245012 -52.00904) (xy 49.424082 -52.00904)
			(xy 49.472596 -52.0573) (xy 49.50714 -52.0573) (xy 49.50714 -52.091844) (xy 49.673256 -52.258214)
			(xy 49.673256 -52.851812) (xy 49.6443 -52.880768) (xy 49.6443 -54.620922) (xy 49.362868 -54.902354)
			(xy 48.665638 -54.902354) (xy 48.586898 -54.981094) (xy 48.586898 -55.311802) (xy 48.634142 -55.359046)
			(xy 49.655984 -55.359046) (xy 49.877218 -55.58028) (xy 49.877218 -55.984648) (xy 49.989486 -56.096916)
			(xy 50.268632 -56.096916)
		)
		(stroke
			(width 0)
			(type solid)
		)
		(fill yes)
		(layer "B.Cu")
		(net "GND")
	)
	(gr_poly
		(pts
			(xy 18.775172 -95.0214) (xy 18.787797 -94.999665) (xy 18.818594 -94.959943) (xy 18.855046 -94.925338)
			(xy 18.896314 -94.896646) (xy 18.941448 -94.874529) (xy 18.989409 -94.859495) (xy 19.039093 -94.85189)
			(xy 19.089355 -94.85189) (xy 19.139039 -94.859495) (xy 19.187 -94.874529) (xy 19.232134 -94.896646)
			(xy 19.273402 -94.925338) (xy 19.309854 -94.959943) (xy 19.340651 -94.999665) (xy 19.353276 -95.0214)
			(xy 19.575272 -95.0214) (xy 19.587897 -94.999665) (xy 19.618694 -94.959943) (xy 19.655146 -94.925338)
			(xy 19.696414 -94.896646) (xy 19.741548 -94.874529) (xy 19.789509 -94.859495) (xy 19.839193 -94.85189)
			(xy 19.889455 -94.85189) (xy 19.939139 -94.859495) (xy 19.9871 -94.874529) (xy 20.032234 -94.896646)
			(xy 20.073502 -94.925338) (xy 20.109954 -94.959943) (xy 20.140751 -94.999665) (xy 20.153376 -95.0214)
			(xy 20.375118 -95.0214) (xy 20.387739 -94.999663) (xy 20.41853 -94.959938) (xy 20.454981 -94.925333)
			(xy 20.496251 -94.896645) (xy 20.541389 -94.874537) (xy 20.589353 -94.859518) (xy 20.639039 -94.851933)
			(xy 20.66417 -94.851474) (xy 20.690996 -94.851993) (xy 20.743943 -94.860651) (xy 20.794799 -94.877744)
			(xy 20.842227 -94.902824) (xy 20.884983 -94.935233) (xy 20.921945 -94.97412) (xy 20.937474 -94.996)
			(xy 21.147278 -94.996) (xy 21.163788 -95.0214) (xy 21.7551 -95.0214) (xy 21.77161 -94.996) (xy 21.981414 -94.996)
			(xy 21.995717 -94.975786) (xy 22.029386 -94.939476) (xy 22.068093 -94.908592) (xy 22.110971 -94.883824)
			(xy 22.157063 -94.865726) (xy 22.205339 -94.854703) (xy 22.254718 -94.851001) (xy 22.304097 -94.854703)
			(xy 22.352373 -94.865726) (xy 22.398465 -94.883824) (xy 22.441343 -94.908592) (xy 22.48005 -94.939476)
			(xy 22.513719 -94.975786) (xy 22.528022 -94.996) (xy 22.78126 -94.996) (xy 22.797971 -94.972456)
			(xy 22.838222 -94.931071) (xy 22.885062 -94.897321) (xy 22.9108 -94.88424) (xy 22.9108 -94.742) (xy 22.546056 -94.377256)
			(xy 22.546056 -93.748352) (xy 22.462236 -93.693996) (xy 22.462236 -93.518228) (xy 22.546056 -93.463872)
			(xy 22.546056 -92.6846) (xy 22.393656 -92.5322) (xy 21.447506 -92.5322) (xy 21.38934 -92.621608)
			(xy 21.213572 -92.621608) (xy 21.15566 -92.5322) (xy 20.618196 -92.5322) (xy 20.618196 -92.550996)
			(xy 20.42922 -92.739972) (xy 20.42922 -92.912184) (xy 20.370292 -93.002608) (xy 20.119086 -93.002608)
			(xy 20.103299 -93.02102) (xy 20.067256 -93.053472) (xy 20.02686 -93.080314) (xy 19.982979 -93.10097)
			(xy 19.936552 -93.114998) (xy 19.888574 -93.122097) (xy 19.864324 -93.122496) (xy 19.838669 -93.122014)
			(xy 19.787975 -93.114093) (xy 19.739113 -93.098438) (xy 19.693255 -93.075423) (xy 19.651502 -93.045602)
			(xy 19.614855 -93.009689) (xy 19.599148 -92.9894) (xy 19.3548 -92.9894) (xy 19.2532 -93.091) (xy 19.2532 -93.218)
			(xy 18.481802 -93.989398) (xy 18.472381 -93.999448) (xy 18.458805 -94.023405) (xy 18.452125 -94.050118)
			(xy 18.452828 -94.077645) (xy 18.460862 -94.103982) (xy 18.470539 -94.119192) (xy 19.118072 -94.119192)
			(xy 19.118072 -93.840808) (xy 19.314414 -93.644212) (xy 19.593052 -93.644212) (xy 19.782028 -93.833188)
			(xy 19.95424 -93.833188) (xy 20.044664 -93.892116) (xy 20.044664 -94.105222) (xy 20.06734 -94.120621)
			(xy 20.107731 -94.157671) (xy 20.141459 -94.200874) (xy 20.1676 -94.249048) (xy 20.18544 -94.300874)
			(xy 20.194489 -94.354931) (xy 20.195032 -94.382336) (xy 20.194532 -94.408323) (xy 20.186397 -94.459656)
			(xy 20.170332 -94.509085) (xy 20.146734 -94.555393) (xy 20.116183 -94.59744) (xy 20.079431 -94.634191)
			(xy 20.037383 -94.66474) (xy 19.991074 -94.688337) (xy 19.941645 -94.704399) (xy 19.890311 -94.712533)
			(xy 19.864324 -94.713044) (xy 19.836983 -94.712522) (xy 19.783046 -94.70353) (xy 19.731323 -94.685787)
			(xy 19.683224 -94.659777) (xy 19.640059 -94.626209) (xy 19.603005 -94.585996) (xy 19.573071 -94.540236)
			(xy 19.561556 -94.515432) (xy 19.557746 -94.506796) (xy 19.366738 -94.315788) (xy 19.314414 -94.315788)
			(xy 19.118072 -94.119192) (xy 18.470539 -94.119192) (xy 18.475643 -94.127215) (xy 18.485612 -94.136718)
			(xy 18.505808 -94.155684) (xy 18.540194 -94.19912) (xy 18.566857 -94.247681) (xy 18.58505 -94.300008)
			(xy 18.594264 -94.354636) (xy 18.594832 -94.382336) (xy 18.594311 -94.409147) (xy 18.585663 -94.462066)
			(xy 18.568598 -94.5129) (xy 18.543564 -94.560318) (xy 18.511214 -94.603082) (xy 18.472395 -94.640072)
			(xy 18.45056 -94.65564) (xy 18.45056 -94.908878) (xy 18.471451 -94.923725) (xy 18.508813 -94.958806)
			(xy 18.540318 -94.999229) (xy 18.553176 -95.0214)
		)
		(stroke
			(width 0)
			(type solid)
		)
		(fill yes)
		(layer "B.Cu")
		(net "GND")
	)
	(gr_poly
		(pts
			(arc
				(start 57.769506 -76.72451)
				(mid 58.1152 -76.504331)
				(end 58.460894 -76.72451)
			)
			(xy 60.653422 -76.72451)
			(arc
				(start 60.738766 -76.639166)
				(mid 60.840255 -76.57129)
				(end 60.96 -76.547472)
			)
			(arc
				(start 62.174882 -76.547472)
				(mid 62.267609 -76.487397)
				(end 62.250574 -76.378308)
			)
			(arc
				(start 62.250574 -76.378308)
				(mid 62.178431 -76.260036)
				(end 62.153292 -76.1238)
			)
			(arc
				(start 62.153292 -76.1238)
				(mid 62.265033 -75.854033)
				(end 62.5348 -75.742292)
			)
			(arc
				(start 62.5348 -75.742292)
				(mid 62.673617 -75.768462)
				(end 62.793372 -75.843384)
			)
			(arc
				(start 62.793372 -75.843384)
				(mid 62.903089 -75.861677)
				(end 62.963806 -75.768454)
			)
			(xy 62.963806 -74.120502) (xy 62.846712 -74.003408) (xy 59.76366 -74.003408)
			(arc
				(start 59.716924 -74.050144)
				(mid 59.688278 -74.137129)
				(end 59.741308 -74.211688)
			)
			(arc
				(start 59.741308 -74.211688)
				(mid 59.889806 -74.352097)
				(end 59.944508 -74.549)
			)
			(arc
				(start 59.944508 -74.549)
				(mid 59.832767 -74.818767)
				(end 59.563 -74.930508)
			)
			(arc
				(start 59.563 -74.930508)
				(mid 59.366114 -74.875779)
				(end 59.225688 -74.727308)
			)
			(arc
				(start 59.225688 -74.727308)
				(mid 59.151101 -74.674466)
				(end 59.064144 -74.702924)
			)
			(xy 58.65876 -75.108308) (xy 58.641742 -75.108308) (xy 58.58002 -75.170284) (xy 57.966102 -75.170284)
			(xy 57.90438 -75.108308) (xy 57.552844 -75.108308)
			(arc
				(start 57.550558 -75.108562)
				(mid 57.528615 -75.110243)
				(end 57.506616 -75.110848)
			)
			(arc
				(start 56.806084 -75.110848)
				(mid 56.784084 -75.110254)
				(end 56.762142 -75.108562)
			)
			(xy 56.759856 -75.108308) (xy 53.699156 -75.108308) (xy 53.51018 -74.919332) (xy 53.51018 -74.385424)
			(xy 53.71211 -74.183494) (xy 54.313582 -74.183494) (xy 54.54904 -73.948036) (xy 54.54904 -71.501762)
			(xy 54.46776 -71.420482) (xy 53.964078 -71.420482) (xy 53.799232 -71.255636) (xy 53.799232 -71.159624)
			(xy 53.7972 -71.157846) (xy 53.7972 -70.530974) (xy 53.735986 -70.469506) (xy 53.122068 -70.469506)
			(xy 53.017928 -70.573646) (xy 53.017928 -73.502012) (xy 52.25288 -74.26706)
			(arc
				(start 52.25288 -75.370182)
				(mid 52.266433 -75.404727)
				(end 52.29987 -75.420728)
			)
			(arc
				(start 52.29987 -75.420728)
				(mid 52.406526 -75.448446)
				(end 52.496974 -75.511406)
			)
			(arc
				(start 52.500022 -75.514454)
				(mid 52.725689 -75.64507)
				(end 52.814728 -75.89012)
			)
			(arc
				(start 52.814728 -75.89012)
				(mid 52.806736 -75.967548)
				(end 52.783232 -76.041758)
			)
			(arc
				(start 52.783232 -76.041758)
				(mid 52.780115 -76.113822)
				(end 52.82565 -76.169774)
			)
			(arc
				(start 52.82565 -76.169774)
				(mid 52.964567 -76.309416)
				(end 53.015388 -76.49972)
			)
			(arc
				(start 53.015388 -76.49972)
				(mid 53.012188 -76.548773)
				(end 53.002688 -76.597002)
			)
			(arc
				(start 53.002688 -76.597002)
				(mid 53.020465 -76.684959)
				(end 53.100986 -76.72451)
			)
		)
		(stroke
			(width 0)
			(type solid)
		)
		(fill yes)
		(layer "B.Cu")
		(net "ADCVREFEXT1")
	)
	(gr_poly
		(pts
			(xy 59.03722 -44.15282) (xy 59.363102 -44.15282) (xy 59.440318 -44.075604) (xy 59.886596 -44.075604)
			(xy 59.9694 -43.9928) (xy 59.9694 -42.9768) (xy 60.6552 -42.291) (xy 61.4934 -42.291) (xy 61.595 -42.1894)
			(xy 61.595 -41.7068) (xy 61.4934 -41.6052) (xy 60.728606 -41.6052) (xy 60.709755 -41.624051) (xy 60.667138 -41.656073)
			(xy 60.619935 -41.680845) (xy 60.569371 -41.697725) (xy 60.516754 -41.706276) (xy 60.463446 -41.706276)
			(xy 60.410829 -41.697725) (xy 60.360265 -41.680845) (xy 60.313062 -41.656073) (xy 60.270445 -41.624051)
			(xy 60.251594 -41.6052) (xy 59.92876 -41.6052) (xy 59.909909 -41.624051) (xy 59.867292 -41.656073)
			(xy 59.820089 -41.680845) (xy 59.769525 -41.697725) (xy 59.716908 -41.706276) (xy 59.6636 -41.706276)
			(xy 59.610983 -41.697725) (xy 59.560419 -41.680845) (xy 59.513216 -41.656073) (xy 59.470599 -41.624051)
			(xy 59.451748 -41.6052) (xy 59.12866 -41.6052) (xy 59.109809 -41.624051) (xy 59.067192 -41.656073)
			(xy 59.019989 -41.680845) (xy 58.969425 -41.697725) (xy 58.916808 -41.706276) (xy 58.8635 -41.706276)
			(xy 58.810883 -41.697725) (xy 58.760319 -41.680845) (xy 58.713116 -41.656073) (xy 58.670499 -41.624051)
			(xy 58.651648 -41.6052) (xy 58.42 -41.6052) (xy 58.271664 -41.753536) (xy 58.261612 -41.764246) (xy 58.247581 -41.790036)
			(xy 58.241474 -41.818754) (xy 58.243796 -41.848022) (xy 58.254356 -41.875417) (xy 58.272278 -41.898671)
			(xy 58.283856 -41.907714) (xy 58.304707 -41.923385) (xy 58.34167 -41.960186) (xy 58.372406 -42.002326)
			(xy 58.396155 -42.048763) (xy 58.412331 -42.09835) (xy 58.420533 -42.149859) (xy 58.421016 -42.175938)
			(xy 58.420504 -42.201923) (xy 58.420504 -42.201925) (xy 59.360056 -42.201925) (xy 59.360056 -42.149951)
			(xy 59.368186 -42.098616) (xy 59.384247 -42.049186) (xy 59.407843 -42.002876) (xy 59.438393 -41.960828)
			(xy 59.475144 -41.924077) (xy 59.517192 -41.893527) (xy 59.563502 -41.869931) (xy 59.612932 -41.85387)
			(xy 59.664267 -41.84574) (xy 59.716241 -41.84574) (xy 59.767576 -41.85387) (xy 59.817006 -41.869931)
			(xy 59.863316 -41.893527) (xy 59.905364 -41.924077) (xy 59.942115 -41.960828) (xy 59.972665 -42.002876)
			(xy 59.996261 -42.049186) (xy 60.012322 -42.098616) (xy 60.020452 -42.149951) (xy 60.020962 -42.175938)
			(xy 60.020452 -42.201925) (xy 60.012322 -42.25326) (xy 59.996261 -42.30269) (xy 59.972665 -42.349)
			(xy 59.942115 -42.391048) (xy 59.905364 -42.427799) (xy 59.863316 -42.458349) (xy 59.817006 -42.481945)
			(xy 59.767576 -42.498006) (xy 59.716241 -42.506136) (xy 59.664267 -42.506136) (xy 59.612932 -42.498006)
			(xy 59.563502 -42.481945) (xy 59.517192 -42.458349) (xy 59.475144 -42.427799) (xy 59.438393 -42.391048)
			(xy 59.407843 -42.349) (xy 59.384247 -42.30269) (xy 59.368186 -42.25326) (xy 59.360056 -42.201925)
			(xy 58.420504 -42.201925) (xy 58.412368 -42.253254) (xy 58.396304 -42.30268) (xy 58.372706 -42.348985)
			(xy 58.342156 -42.391028) (xy 58.305405 -42.427776) (xy 58.263359 -42.458322) (xy 58.217052 -42.481916)
			(xy 58.167625 -42.497975) (xy 58.116294 -42.506106) (xy 58.090308 -42.506646) (xy 58.064229 -42.506157)
			(xy 58.012716 -42.497971) (xy 57.963127 -42.481802) (xy 57.91669 -42.45805) (xy 57.874557 -42.427304)
			(xy 57.837772 -42.390326) (xy 57.822084 -42.369486) (xy 57.813089 -42.357865) (xy 57.789823 -42.339934)
			(xy 57.762413 -42.329371) (xy 57.73313 -42.327053) (xy 57.7044 -42.33317) (xy 57.678602 -42.347217)
			(xy 57.667906 -42.357294) (xy 57.471564 -42.553636) (xy 57.461512 -42.564346) (xy 57.447481 -42.590136)
			(xy 57.441374 -42.618854) (xy 57.443696 -42.648122) (xy 57.454256 -42.675517) (xy 57.472178 -42.698771)
			(xy 57.483756 -42.707814) (xy 57.504607 -42.723485) (xy 57.54157 -42.760286) (xy 57.572306 -42.802426)
			(xy 57.596055 -42.848863) (xy 57.612231 -42.89845) (xy 57.620433 -42.949959) (xy 57.620916 -42.976038)
			(xy 57.620494 -43.000309) (xy 57.620241 -43.002025) (xy 57.76011 -43.002025) (xy 57.76011 -42.950051)
			(xy 57.76824 -42.898716) (xy 57.784301 -42.849286) (xy 57.807897 -42.802976) (xy 57.838447 -42.760928)
			(xy 57.875198 -42.724177) (xy 57.917246 -42.693627) (xy 57.963556 -42.670031) (xy 58.012986 -42.65397)
			(xy 58.064321 -42.64584) (xy 58.116295 -42.64584) (xy 58.16763 -42.65397) (xy 58.21706 -42.670031)
			(xy 58.26337 -42.693627) (xy 58.305418 -42.724177) (xy 58.342169 -42.760928) (xy 58.372719 -42.802976)
			(xy 58.396315 -42.849286) (xy 58.412376 -42.898716) (xy 58.420506 -42.950051) (xy 58.421016 -42.976038)
			(xy 58.420506 -43.002025) (xy 58.412376 -43.05336) (xy 58.396315 -43.10279) (xy 58.372719 -43.1491)
			(xy 58.342169 -43.191148) (xy 58.305418 -43.227899) (xy 58.26337 -43.258449) (xy 58.21706 -43.282045)
			(xy 58.16763 -43.298106) (xy 58.116295 -43.306236) (xy 58.064321 -43.306236) (xy 58.012986 -43.298106)
			(xy 57.963556 -43.282045) (xy 57.917246 -43.258449) (xy 57.875198 -43.227899) (xy 57.838447 -43.191148)
			(xy 57.807897 -43.1491) (xy 57.784301 -43.10279) (xy 57.76824 -43.05336) (xy 57.76011 -43.002025)
			(xy 57.620241 -43.002025) (xy 57.61341 -43.048331) (xy 57.599383 -43.094803) (xy 57.578716 -43.138725)
			(xy 57.551853 -43.179156) (xy 57.519369 -43.215228) (xy 57.481963 -43.246165) (xy 57.440438 -43.271303)
			(xy 57.418224 -43.281092) (xy 57.386982 -43.294046) (xy 57.386982 -44.190666) (xy 57.501536 -44.30522)
			(xy 58.884566 -44.30522)
		)
		(stroke
			(width 0)
			(type solid)
		)
		(fill yes)
		(layer "B.Cu")
		(net "P1V0_STBY_PLAVDD")
	)
	(gr_poly
		(pts
			(xy 18.4404 -96.901) (xy 18.4404 -96.637602) (xy 18.32864 -96.526096) (xy 18.32864 -96.413066) (xy 18.328139 -96.397944)
			(xy 18.31937 -96.369002) (xy 18.302493 -96.343909) (xy 18.278996 -96.324872) (xy 18.250948 -96.313568)
			(xy 18.23593 -96.31172) (xy 18.21149 -96.309173) (xy 18.163694 -96.297776) (xy 18.11811 -96.279433)
			(xy 18.075742 -96.254547) (xy 18.037522 -96.223667) (xy 18.004291 -96.187473) (xy 17.976781 -96.14676)
			(xy 17.955598 -96.102425) (xy 17.941206 -96.055443) (xy 17.933925 -96.00685) (xy 17.933416 -95.982282)
			(xy 17.933913 -95.956461) (xy 17.941937 -95.905446) (xy 17.957786 -95.856296) (xy 17.981077 -95.810204)
			(xy 18.011243 -95.768289) (xy 18.047554 -95.731567) (xy 18.068036 -95.715836) (xy 18.068036 -95.448628)
			(xy 18.047545 -95.43291) (xy 18.011237 -95.396186) (xy 17.981074 -95.354269) (xy 17.957787 -95.308176)
			(xy 17.941942 -95.259025) (xy 17.933922 -95.20801) (xy 17.933924 -95.156369) (xy 17.941947 -95.105354)
			(xy 17.957795 -95.056204) (xy 17.981085 -95.010113) (xy 18.011251 -94.968198) (xy 18.047561 -94.931476)
			(xy 18.068036 -94.915736) (xy 18.068036 -94.648782) (xy 18.045581 -94.631499) (xy 18.006384 -94.590587)
			(xy 17.974741 -94.543587) (xy 17.962626 -94.517972) (xy 17.94891 -94.488) (xy 17.779492 -94.488)
			(xy 17.765776 -94.517972) (xy 17.754165 -94.542502) (xy 17.724149 -94.587714) (xy 17.687148 -94.627412)
			(xy 17.644155 -94.660528) (xy 17.596329 -94.686172) (xy 17.544954 -94.703654) (xy 17.491412 -94.712504)
			(xy 17.464278 -94.713044) (xy 17.436383 -94.712464) (xy 17.381385 -94.7031) (xy 17.328737 -94.684641)
			(xy 17.279933 -94.657611) (xy 17.257776 -94.640654) (xy 17.22247 -94.61246) (xy 16.928592 -94.906338)
			(xy 16.926814 -94.907862) (xy 16.920417 -94.914722) (xy 16.912648 -94.931777) (xy 16.911541 -94.950484)
			(xy 16.917246 -94.968336) (xy 16.92275 -94.975934) (xy 16.939654 -94.998075) (xy 16.966578 -95.046837)
			(xy 16.984961 -95.099417) (xy 16.994286 -95.154332) (xy 16.994886 -95.182182) (xy 16.994404 -95.208169)
			(xy 17.13408 -95.208169) (xy 17.13408 -95.156195) (xy 17.14221 -95.10486) (xy 17.158271 -95.05543)
			(xy 17.181867 -95.00912) (xy 17.212417 -94.967072) (xy 17.249168 -94.930321) (xy 17.291216 -94.899771)
			(xy 17.337526 -94.876175) (xy 17.386956 -94.860114) (xy 17.438291 -94.851984) (xy 17.490265 -94.851984)
			(xy 17.5416 -94.860114) (xy 17.59103 -94.876175) (xy 17.63734 -94.899771) (xy 17.679388 -94.930321)
			(xy 17.716139 -94.967072) (xy 17.746689 -95.00912) (xy 17.770285 -95.05543) (xy 17.786346 -95.10486)
			(xy 17.794476 -95.156195) (xy 17.794986 -95.182182) (xy 17.794476 -95.208169) (xy 17.786346 -95.259504)
			(xy 17.770285 -95.308934) (xy 17.746689 -95.355244) (xy 17.716139 -95.397292) (xy 17.679388 -95.434043)
			(xy 17.63734 -95.464593) (xy 17.59103 -95.488189) (xy 17.5416 -95.50425) (xy 17.490265 -95.51238)
			(xy 17.438291 -95.51238) (xy 17.386956 -95.50425) (xy 17.337526 -95.488189) (xy 17.291216 -95.464593)
			(xy 17.249168 -95.434043) (xy 17.212417 -95.397292) (xy 17.181867 -95.355244) (xy 17.158271 -95.308934)
			(xy 17.14221 -95.259504) (xy 17.13408 -95.208169) (xy 16.994404 -95.208169) (xy 16.994404 -95.208172)
			(xy 16.986275 -95.259511) (xy 16.970214 -95.308947) (xy 16.946617 -95.355261) (xy 16.916065 -95.397313)
			(xy 16.87931 -95.434067) (xy 16.837257 -95.464619) (xy 16.790943 -95.488216) (xy 16.741507 -95.504276)
			(xy 16.690168 -95.512405) (xy 16.664178 -95.51289) (xy 16.638461 -95.5124) (xy 16.587647 -95.504433)
			(xy 16.538679 -95.488695) (xy 16.492738 -95.465564) (xy 16.450933 -95.4356) (xy 16.432276 -95.417894)
			(xy 16.422528 -95.408885) (xy 16.399471 -95.395755) (xy 16.37381 -95.389009) (xy 16.347277 -95.389102)
			(xy 16.321664 -95.396029) (xy 16.2987 -95.40932) (xy 16.28902 -95.418402) (xy 16.002 -95.705422)
			(xy 16.002 -96.008269) (xy 17.13408 -96.008269) (xy 17.13408 -95.956295) (xy 17.14221 -95.90496)
			(xy 17.158271 -95.85553) (xy 17.181867 -95.80922) (xy 17.212417 -95.767172) (xy 17.249168 -95.730421)
			(xy 17.291216 -95.699871) (xy 17.337526 -95.676275) (xy 17.386956 -95.660214) (xy 17.438291 -95.652084)
			(xy 17.490265 -95.652084) (xy 17.5416 -95.660214) (xy 17.59103 -95.676275) (xy 17.63734 -95.699871)
			(xy 17.679388 -95.730421) (xy 17.716139 -95.767172) (xy 17.746689 -95.80922) (xy 17.770285 -95.85553)
			(xy 17.786346 -95.90496) (xy 17.794476 -95.956295) (xy 17.794986 -95.982282) (xy 17.794476 -96.008269)
			(xy 17.786346 -96.059604) (xy 17.770285 -96.109034) (xy 17.746689 -96.155344) (xy 17.716139 -96.197392)
			(xy 17.679388 -96.234143) (xy 17.63734 -96.264693) (xy 17.59103 -96.288289) (xy 17.5416 -96.30435)
			(xy 17.490265 -96.31248) (xy 17.438291 -96.31248) (xy 17.386956 -96.30435) (xy 17.337526 -96.288289)
			(xy 17.291216 -96.264693) (xy 17.249168 -96.234143) (xy 17.212417 -96.197392) (xy 17.181867 -96.155344)
			(xy 17.158271 -96.109034) (xy 17.14221 -96.059604) (xy 17.13408 -96.008269) (xy 16.002 -96.008269)
			(xy 16.002 -96.4184) (xy 16.219424 -96.635824) (xy 16.229113 -96.644923) (xy 16.252101 -96.658244)
			(xy 16.27775 -96.665174) (xy 16.304319 -96.665244) (xy 16.330004 -96.658449) (xy 16.353062 -96.645249)
			(xy 16.371927 -96.626541) (xy 16.378936 -96.61525) (xy 16.391746 -96.594251) (xy 16.422606 -96.555949)
			(xy 16.458803 -96.522645) (xy 16.499538 -96.495076) (xy 16.54391 -96.47385) (xy 16.590939 -96.459438)
			(xy 16.639584 -96.452157) (xy 16.664178 -96.451674) (xy 16.690169 -96.452155) (xy 16.741511 -96.460284)
			(xy 16.79095 -96.476344) (xy 16.837267 -96.49994) (xy 16.879323 -96.530492) (xy 16.916082 -96.567246)
			(xy 16.946639 -96.609298) (xy 16.970241 -96.655613) (xy 16.986307 -96.70505) (xy 16.994441 -96.756391)
			(xy 16.994886 -96.782382) (xy 16.994245 -96.81226) (xy 16.98351 -96.871045) (xy 16.97355 -96.899222)
			(xy 16.961866 -96.929956) (xy 17.021048 -96.989138) (xy 17.135856 -96.87433) (xy 17.130522 -96.84766)
			(xy 17.127449 -96.831515) (xy 17.124137 -96.798815) (xy 17.123918 -96.782382) (xy 17.124402 -96.756394)
			(xy 17.132536 -96.70506) (xy 17.1486 -96.655629) (xy 17.172199 -96.60932) (xy 17.202752 -96.567273)
			(xy 17.239507 -96.530524) (xy 17.281558 -96.499976) (xy 17.32787 -96.476383) (xy 17.377302 -96.460326)
			(xy 17.428638 -96.452199) (xy 17.454626 -96.451674) (xy 17.480934 -96.452178) (xy 17.532886 -96.460501)
			(xy 17.582864 -96.476951) (xy 17.629605 -96.50111) (xy 17.671927 -96.532369) (xy 17.708763 -96.569939)
			(xy 17.724374 -96.59112) (xy 17.952466 -96.59112) (xy 18.01114 -96.682814) (xy 18.01114 -96.85401)
			(xy 18.159476 -97.0026) (xy 18.3388 -97.0026)
		)
		(stroke
			(width 0)
			(type solid)
		)
		(fill yes)
		(layer "B.Cu")
		(net "VCCIO1")
	)
	(gr_poly
		(pts
			(xy 30.607 -103.632) (xy 30.607 -103.092758) (xy 30.394148 -102.879652) (xy 30.373668 -102.858519)
			(xy 30.337884 -102.811799) (xy 30.308574 -102.760768) (xy 30.28625 -102.706317) (xy 30.278324 -102.677976)
			(xy 30.274768 -102.664768) (xy 29.8704 -102.2604) (xy 29.8704 -99.131374) (xy 29.867606 -99.1235)
			(xy 29.856814 -99.089588) (xy 29.845197 -99.019381) (xy 29.844492 -98.9838) (xy 29.845192 -98.948218)
			(xy 29.856806 -98.87801) (xy 29.867606 -98.8441) (xy 29.8704 -98.836226) (xy 29.8704 -97.346008)
			(xy 29.869919 -97.336031) (xy 29.862308 -97.317585) (xy 29.848235 -97.303439) (xy 29.829829 -97.295733)
			(xy 29.819854 -97.295208) (xy 29.790418 -97.294558) (xy 29.732127 -97.286264) (xy 29.675501 -97.270136)
			(xy 29.621588 -97.246471) (xy 29.571385 -97.215709) (xy 29.525822 -97.178418) (xy 29.485741 -97.135288)
			(xy 29.451885 -97.087117) (xy 29.42488 -97.034797) (xy 29.405226 -96.979297) (xy 29.393286 -96.921642)
			(xy 29.389281 -96.8629) (xy 29.393286 -96.804158) (xy 29.405226 -96.746503) (xy 29.42488 -96.691003)
			(xy 29.451885 -96.638683) (xy 29.485741 -96.590512) (xy 29.525822 -96.547382) (xy 29.571385 -96.510091)
			(xy 29.621588 -96.479329) (xy 29.675501 -96.455664) (xy 29.732127 -96.439536) (xy 29.790418 -96.431242)
			(xy 29.819854 -96.430592) (xy 29.829827 -96.43006) (xy 29.848231 -96.422355) (xy 29.862302 -96.408211)
			(xy 29.869912 -96.389768) (xy 29.8704 -96.379792) (xy 29.8704 -96.2152) (xy 28.367228 -94.712028)
			(xy 28.351988 -94.70898) (xy 28.322869 -94.702754) (xy 28.266569 -94.683368) (xy 28.213462 -94.656437)
			(xy 28.164554 -94.622472) (xy 28.12077 -94.582117) (xy 28.082939 -94.536133) (xy 28.051778 -94.485393)
			(xy 28.027876 -94.430856) (xy 28.011686 -94.373554) (xy 28.003513 -94.314573) (xy 28.002992 -94.2848)
			(xy 28.003368 -94.25951) (xy 28.009299 -94.209278) (xy 28.021044 -94.16008) (xy 28.029408 -94.13621)
			(xy 28.032456 -94.127574) (xy 28.032456 -92.111576) (xy 28.014234 -92.087756) (xy 27.985206 -92.035282)
			(xy 27.965386 -91.978684) (xy 27.955335 -91.919564) (xy 27.954732 -91.88958) (xy 27.955254 -91.861597)
			(xy 27.964013 -91.80632) (xy 27.981311 -91.753094) (xy 28.006723 -91.703229) (xy 28.039622 -91.657954)
			(xy 28.0792 -91.618383) (xy 28.124481 -91.585491) (xy 28.174349 -91.560088) (xy 28.227578 -91.542799)
			(xy 28.282857 -91.534049) (xy 28.31084 -91.533472) (xy 28.336024 -91.533903) (xy 28.385891 -91.540989)
			(xy 28.434263 -91.55503) (xy 28.480175 -91.575743) (xy 28.522711 -91.602718) (xy 28.561024 -91.635415)
			(xy 28.594349 -91.673183) (xy 28.608528 -91.694) (xy 28.9306 -91.694) (xy 29.3624 -91.2622) (xy 29.3624 -90.1573)
			(xy 29.06014 -89.85504) (xy 27.64028 -89.85504) (xy 27.247596 -90.247724) (xy 27.267408 -90.281506)
			(xy 27.2773 -90.299235) (xy 27.291347 -90.337321) (xy 27.298466 -90.377286) (xy 27.298904 -90.397584)
			(xy 27.298904 -90.558874) (xy 27.405584 -90.665554) (xy 27.405584 -90.907849) (xy 27.92221 -90.907849)
			(xy 27.92221 -90.854551) (xy 27.930153 -90.801847) (xy 27.945863 -90.750917) (xy 27.968989 -90.702896)
			(xy 27.999013 -90.658859) (xy 28.035265 -90.619788) (xy 28.076936 -90.586557) (xy 28.123094 -90.559908)
			(xy 28.172708 -90.540436) (xy 28.22467 -90.528576) (xy 28.27782 -90.524593) (xy 28.33097 -90.528576)
			(xy 28.382932 -90.540436) (xy 28.432546 -90.559908) (xy 28.478704 -90.586557) (xy 28.520375 -90.619788)
			(xy 28.556627 -90.658859) (xy 28.586651 -90.702896) (xy 28.609777 -90.750917) (xy 28.625487 -90.801847)
			(xy 28.63343 -90.854551) (xy 28.633928 -90.8812) (xy 28.63343 -90.907849) (xy 28.625487 -90.960553)
			(xy 28.609777 -91.011483) (xy 28.586651 -91.059504) (xy 28.556627 -91.103541) (xy 28.520375 -91.142612)
			(xy 28.478704 -91.175843) (xy 28.432546 -91.202492) (xy 28.382932 -91.221964) (xy 28.33097 -91.233824)
			(xy 28.27782 -91.237808) (xy 28.22467 -91.233824) (xy 28.172708 -91.221964) (xy 28.123094 -91.202492)
			(xy 28.076936 -91.175843) (xy 28.035265 -91.142612) (xy 27.999013 -91.103541) (xy 27.968989 -91.059504)
			(xy 27.945863 -91.011483) (xy 27.930153 -90.960553) (xy 27.92221 -90.907849) (xy 27.405584 -90.907849)
			(xy 27.405584 -90.944192) (xy 27.209242 -91.140788) (xy 26.930858 -91.140788) (xy 26.773124 -90.9828)
			(xy 26.566876 -90.9828) (xy 26.498804 -91.050872) (xy 26.498804 -91.319096) (xy 26.565606 -91.319096)
			(xy 26.565606 -91.318842) (xy 26.587937 -91.319184) (xy 26.631793 -91.327592) (xy 26.67315 -91.344435)
			(xy 26.710401 -91.369059) (xy 26.742102 -91.400509) (xy 26.767021 -91.437565) (xy 26.784191 -91.478786)
			(xy 26.792946 -91.522575) (xy 26.793444 -91.544902) (xy 26.793444 -91.812364) (xy 26.7335 -91.812364)
			(xy 26.7335 -92.07754) (xy 26.0985 -92.07754) (xy 26.0985 -91.812364) (xy 26.038556 -91.812364) (xy 26.038556 -91.544902)
			(xy 26.040588 -91.515946) (xy 26.041096 -91.512898) (xy 26.041096 -91.050872) (xy 26.024078 -91.034108)
			(xy 25.867868 -91.034108) (xy 25.848341 -91.033686) (xy 25.809859 -91.027015) (xy 25.773064 -91.013923)
			(xy 25.739017 -90.994787) (xy 25.723596 -90.9828) (xy 25.294844 -90.9828) (xy 25.142444 -91.1352)
			(xy 25.142444 -92.757244) (xy 25.247092 -92.861892) (xy 25.45461 -92.861892) (xy 25.705308 -93.11259)
			(xy 25.705308 -93.90761) (xy 25.4254 -94.187264) (xy 25.4254 -94.6404) (xy 25.4762 -94.6912) (xy 26.6446 -94.6912)
			(xy 27.559 -95.6056) (xy 27.559 -96.165649) (xy 27.81299 -96.165649) (xy 27.81299 -96.112351) (xy 27.820933 -96.059647)
			(xy 27.836643 -96.008717) (xy 27.859769 -95.960696) (xy 27.889793 -95.916659) (xy 27.926045 -95.877588)
			(xy 27.967716 -95.844357) (xy 28.013874 -95.817708) (xy 28.063488 -95.798236) (xy 28.11545 -95.786376)
			(xy 28.1686 -95.782393) (xy 28.22175 -95.786376) (xy 28.273712 -95.798236) (xy 28.323326 -95.817708)
			(xy 28.369484 -95.844357) (xy 28.411155 -95.877588) (xy 28.447407 -95.916659) (xy 28.477431 -95.960696)
			(xy 28.500557 -96.008717) (xy 28.516267 -96.059647) (xy 28.52421 -96.112351) (xy 28.524708 -96.139)
			(xy 28.52421 -96.165649) (xy 28.516267 -96.218353) (xy 28.500557 -96.269283) (xy 28.477431 -96.317304)
			(xy 28.447407 -96.361341) (xy 28.411155 -96.400412) (xy 28.369484 -96.433643) (xy 28.323326 -96.460292)
			(xy 28.273712 -96.479764) (xy 28.22175 -96.491624) (xy 28.1686 -96.495608) (xy 28.11545 -96.491624)
			(xy 28.063488 -96.479764) (xy 28.013874 -96.460292) (xy 27.967716 -96.433643) (xy 27.926045 -96.400412)
			(xy 27.889793 -96.361341) (xy 27.859769 -96.317304) (xy 27.836643 -96.269283) (xy 27.820933 -96.218353)
			(xy 27.81299 -96.165649) (xy 27.559 -96.165649) (xy 27.559 -96.3168) (xy 28.8036 -97.5614) (xy 28.8036 -101.2444)
			(xy 28.1686 -101.8794) (xy 26.9494 -101.8794) (xy 26.3652 -101.2952) (xy 25.7556 -101.2952) (xy 25.654 -101.3968)
			(xy 25.654 -101.7778) (xy 25.8318 -101.9556) (xy 26.2636 -101.9556) (xy 26.28646 -101.97846) (xy 26.3525 -101.97846)
			(xy 26.3525 -102.044246) (xy 26.6954 -102.3874) (xy 26.6954 -102.864158) (xy 27.056842 -103.2256)
			(xy 28.6766 -103.2256) (xy 29.3116 -103.8606) (xy 30.3784 -103.8606)
		)
		(stroke
			(width 0)
			(type solid)
		)
		(fill yes)
		(layer "B.Cu")
		(net "P3V3_AUX")
	)
	(gr_poly
		(pts
			(xy 84.492084 -118.78056)
			(arc
				(start 84.492084 -114.799872)
				(mid 84.787357 -114.087273)
				(end 85.499956 -113.792)
			)
			(arc
				(start 88.000078 -113.792)
				(mid 89.055078 -113.355004)
				(end 89.492074 -112.300004)
			)
			(xy 89.492074 -85.508084)
			(arc
				(start 87.749888 -85.508084)
				(mid 87.037379 -85.212795)
				(end 86.742016 -84.500212)
			)
			(arc
				(start 86.742016 -81.999836)
				(mid 87.037289 -81.287237)
				(end 87.749888 -80.991964)
			)
			(xy 89.492074 -80.991964)
			(arc
				(start 89.492074 -1.999996)
				(mid 89.055078 -0.944996)
				(end 88.000078 -0.508)
			)
			(arc
				(start 1.999996 -0.508)
				(mid 0.944996 -0.944996)
				(end 0.508 -1.999996)
			)
			(xy 0.508 -80.991964)
			(arc
				(start 2.249932 -80.991964)
				(mid 2.962785 -81.287237)
				(end 3.258058 -82.00009)
			)
			(arc
				(start 3.258058 -84.499958)
				(mid 2.962785 -85.212811)
				(end 2.249932 -85.508084)
			)
			(xy 0.508 -85.508084)
			(arc
				(start 0.508 -112.300004)
				(mid 0.944996 -113.355004)
				(end 1.999996 -113.792)
			)
			(arc
				(start 4.500118 -113.792)
				(mid 5.212717 -114.087273)
				(end 5.50799 -114.799872)
			)
			(xy 5.50799 -118.71071) (xy 5.621528 -118.824248) (xy 5.936488 -118.824248) (xy 6.015228 -118.745508)
			(arc
				(start 6.015228 -114.799872)
				(mid 5.571478 -113.728438)
				(end 4.500118 -113.284508)
			)
			(arc
				(start 1.999996 -113.284508)
				(mid 1.303847 -112.996153)
				(end 1.015492 -112.300004)
			)
			(xy 1.015492 -86.015576)
			(arc
				(start 2.249932 -86.015576)
				(mid 3.321472 -85.571572)
				(end 3.765296 -84.499958)
			)
			(arc
				(start 3.765296 -81.999582)
				(mid 3.321366 -80.928222)
				(end 2.249932 -80.484472)
			)
			(xy 1.015492 -80.484472)
			(arc
				(start 1.015492 -1.999996)
				(mid 1.303847 -1.303847)
				(end 1.999996 -1.015492)
			)
			(xy 63.699136 -1.015492) (xy 76.6064 -1.015492)
			(arc
				(start 88.000078 -1.015492)
				(mid 88.696317 -1.303831)
				(end 88.984836 -1.999996)
			)
			(xy 88.984836 -80.484472)
			(arc
				(start 87.749888 -80.484472)
				(mid 86.678438 -80.928386)
				(end 86.234524 -81.999836)
			)
			(arc
				(start 86.234524 -84.500212)
				(mid 86.678348 -85.571826)
				(end 87.749888 -86.015576)
			)
			(xy 88.984836 -86.015576)
			(arc
				(start 88.984836 -112.300004)
				(mid 88.696571 -112.996064)
				(end 88.000586 -113.284508)
			)
			(arc
				(start 85.499956 -113.284508)
				(mid 84.428432 -113.728348)
				(end 83.984592 -114.799872)
			)
			(xy 83.984592 -118.768114) (xy 84.094574 -118.878096) (xy 84.394548 -118.878096)
		)
		(stroke
			(width 0)
			(type solid)
		)
		(fill yes)
		(layer "B.Cu")
		(net "GND")
	)
	(gr_poly
		(pts
			(xy 43.586654 -55.734712) (xy 43.609559 -55.720869) (xy 43.658418 -55.699031) (xy 43.709848 -55.68423)
			(xy 43.762841 -55.676756) (xy 43.7896 -55.676292) (xy 43.81469 -55.67669) (xy 43.864436 -55.68327)
			(xy 43.912891 -55.696317) (xy 43.959215 -55.715606) (xy 43.981116 -55.727854) (xy 43.993054 -55.734712)
			(xy 44.049188 -55.734712) (xy 44.064316 -55.734148) (xy 44.093241 -55.725272) (xy 44.118304 -55.708321)
			(xy 44.137312 -55.68478) (xy 44.148601 -55.656709) (xy 44.151184 -55.626562) (xy 44.144834 -55.59698)
			(xy 44.130108 -55.570548) (xy 44.119546 -55.559706) (xy 44.100644 -55.540888) (xy 44.06856 -55.498283)
			(xy 44.04373 -55.451081) (xy 44.026799 -55.400505) (xy 44.018206 -55.347867) (xy 44.017692 -55.3212)
			(xy 44.018202 -55.295213) (xy 44.026332 -55.243878) (xy 44.042393 -55.194448) (xy 44.065989 -55.148138)
			(xy 44.096539 -55.10609) (xy 44.13329 -55.069339) (xy 44.175338 -55.038789) (xy 44.221648 -55.015193)
			(xy 44.271078 -54.999132) (xy 44.322413 -54.991002) (xy 44.3484 -54.990492) (xy 44.371972 -54.990949)
			(xy 44.41863 -54.997708) (xy 44.441364 -55.003954) (xy 44.47032 -55.012336) (xy 44.54779 -54.934612)
			(xy 44.562869 -54.920484) (xy 44.59858 -54.899725) (xy 44.638397 -54.888731) (xy 44.659042 -54.887876)
			(xy 44.662203 -54.867707) (xy 44.674831 -54.828887) (xy 44.69422 -54.792964) (xy 44.719739 -54.761103)
			(xy 44.750562 -54.734338) (xy 44.785687 -54.713538) (xy 44.823974 -54.699379) (xy 44.864181 -54.692319)
			(xy 44.884594 -54.692042) (xy 44.884594 -54.692296) (xy 45.183806 -54.692296) (xy 45.183806 -54.692042)
			(xy 45.20466 -54.69238) (xy 45.245707 -54.699743) (xy 45.284713 -54.714496) (xy 45.32036 -54.73614)
			(xy 45.336206 -54.7497) (xy 45.849794 -54.7497) (xy 45.867054 -54.730562) (xy 45.906458 -54.697348)
			(xy 45.950533 -54.670644) (xy 45.998215 -54.651094) (xy 46.048352 -54.639172) (xy 46.09973 -54.635166)
			(xy 46.151108 -54.639172) (xy 46.201245 -54.651094) (xy 46.248927 -54.670644) (xy 46.293002 -54.697348)
			(xy 46.332406 -54.730562) (xy 46.349666 -54.7497) (xy 48.458628 -54.7497) (xy 48.560228 -54.6481)
			(xy 49.257458 -54.6481) (xy 49.385728 -54.51983) (xy 49.385728 -53.805328) (xy 49.22139 -53.641244)
			(xy 48.974502 -53.641244) (xy 48.95273 -53.640697) (xy 48.910009 -53.632259) (xy 48.889666 -53.62448)
			(xy 48.880522 -53.620924) (xy 48.711104 -53.620924) (xy 48.688642 -53.638745) (xy 48.638857 -53.667179)
			(xy 48.58492 -53.686619) (xy 48.528442 -53.696484) (xy 48.499776 -53.697124) (xy 48.472906 -53.696598)
			(xy 48.419872 -53.687908) (xy 48.36894 -53.67076) (xy 48.32145 -53.645605) (xy 48.27865 -53.613105)
			(xy 48.259746 -53.594) (xy 47.939706 -53.594) (xy 47.926212 -53.607805) (xy 47.896545 -53.632506)
			(xy 47.880524 -53.643276) (xy 47.874936 -53.648864) (xy 47.872142 -53.648864) (xy 47.860712 -53.655214)
			(xy 47.835922 -53.668353) (xy 47.783018 -53.687018) (xy 47.727726 -53.69651) (xy 47.699676 -53.697124)
			(xy 47.671621 -53.696568) (xy 47.616317 -53.68709) (xy 47.563412 -53.668396) (xy 47.53864 -53.655214)
			(xy 47.52721 -53.648864) (xy 47.072296 -53.648864) (xy 47.060866 -53.655214) (xy 47.036076 -53.66835)
			(xy 46.98317 -53.687007) (xy 46.927879 -53.696491) (xy 46.89983 -53.697124) (xy 46.871774 -53.696572)
			(xy 46.816466 -53.687103) (xy 46.763556 -53.668416) (xy 46.738794 -53.655214) (xy 46.727364 -53.648864)
			(xy 46.42866 -53.648864) (xy 46.42866 -54.016656) (xy 46.488604 -54.016656) (xy 46.488604 -54.09184)
			(xy 46.575726 -54.09184) (xy 46.58741 -54.057804) (xy 46.59628 -54.033829) (xy 46.620342 -53.988728)
			(xy 46.65105 -53.947862) (xy 46.687674 -53.912201) (xy 46.729344 -53.882593) (xy 46.77507 -53.859742)
			(xy 46.823765 -53.84419) (xy 46.874271 -53.836307) (xy 46.89983 -53.835808) (xy 46.925814 -53.83632)
			(xy 46.977143 -53.844454) (xy 47.026567 -53.860516) (xy 47.07287 -53.884113) (xy 47.114912 -53.914662)
			(xy 47.151658 -53.951411) (xy 47.182203 -53.993456) (xy 47.205795 -54.039761) (xy 47.221853 -54.089186)
			(xy 47.229983 -54.140516) (xy 47.229983 -54.192484) (xy 47.22998 -54.192503) (xy 47.369478 -54.192503)
			(xy 47.369478 -54.140529) (xy 47.377608 -54.089194) (xy 47.393669 -54.039764) (xy 47.417265 -53.993454)
			(xy 47.447815 -53.951406) (xy 47.484566 -53.914655) (xy 47.526614 -53.884105) (xy 47.572924 -53.860509)
			(xy 47.622354 -53.844448) (xy 47.673689 -53.836318) (xy 47.725663 -53.836318) (xy 47.776998 -53.844448)
			(xy 47.826428 -53.860509) (xy 47.872738 -53.884105) (xy 47.914786 -53.914655) (xy 47.951537 -53.951406)
			(xy 47.982087 -53.993454) (xy 48.005683 -54.039764) (xy 48.021744 -54.089194) (xy 48.029874 -54.140529)
			(xy 48.030384 -54.166516) (xy 48.029874 -54.192503) (xy 48.021744 -54.243838) (xy 48.005683 -54.293268)
			(xy 47.982087 -54.339578) (xy 47.951537 -54.381626) (xy 47.914786 -54.418377) (xy 47.872738 -54.448927)
			(xy 47.826428 -54.472523) (xy 47.776998 -54.488584) (xy 47.725663 -54.496714) (xy 47.673689 -54.496714)
			(xy 47.622354 -54.488584) (xy 47.572924 -54.472523) (xy 47.526614 -54.448927) (xy 47.484566 -54.418377)
			(xy 47.447815 -54.381626) (xy 47.417265 -54.339578) (xy 47.393669 -54.293268) (xy 47.377608 -54.243838)
			(xy 47.369478 -54.192503) (xy 47.22998 -54.192503) (xy 47.221853 -54.243814) (xy 47.205795 -54.293239)
			(xy 47.182203 -54.339544) (xy 47.151658 -54.381589) (xy 47.114912 -54.418338) (xy 47.07287 -54.448887)
			(xy 47.026567 -54.472484) (xy 46.977143 -54.488546) (xy 46.925814 -54.49668) (xy 46.89983 -54.497224)
			(xy 46.874526 -54.496744) (xy 46.824507 -54.489034) (xy 46.776249 -54.473788) (xy 46.73088 -54.451364)
			(xy 46.689458 -54.422286) (xy 46.652954 -54.387234) (xy 46.637194 -54.36743) (xy 46.627817 -54.356046)
			(xy 46.603926 -54.338774) (xy 46.576099 -54.329038) (xy 46.546652 -54.327647) (xy 46.518031 -54.334716)
			(xy 46.492617 -54.349657) (xy 46.472524 -54.371229) (xy 46.46549 -54.384194) (xy 46.455744 -54.402951)
			(xy 46.430379 -54.436757) (xy 46.39917 -54.465259) (xy 46.363207 -54.487461) (xy 46.323744 -54.502591)
			(xy 46.282155 -54.510121) (xy 46.26102 -54.510432) (xy 45.961808 -54.510432) (xy 45.939872 -54.510056)
			(xy 45.896772 -54.501893) (xy 45.856045 -54.485599) (xy 45.819207 -54.461782) (xy 45.803058 -54.446932)
			(xy 45.475906 -54.446932) (xy 45.464222 -54.453536) (xy 45.439022 -54.467244) (xy 45.385067 -54.486714)
			(xy 45.328564 -54.496595) (xy 45.299884 -54.497224) (xy 45.273896 -54.496713) (xy 45.222561 -54.48858)
			(xy 45.173131 -54.472517) (xy 45.126821 -54.448919) (xy 45.084773 -54.418368) (xy 45.048022 -54.381615)
			(xy 45.017472 -54.339565) (xy 44.993877 -54.293255) (xy 44.977816 -54.243823) (xy 44.969686 -54.192488)
			(xy 44.969686 -54.140512) (xy 44.977816 -54.089177) (xy 44.993877 -54.039745) (xy 45.017472 -53.993435)
			(xy 45.048022 -53.951385) (xy 45.084773 -53.914632) (xy 45.126821 -53.884081) (xy 45.173131 -53.860483)
			(xy 45.222561 -53.84442) (xy 45.273896 -53.836287) (xy 45.299884 -53.835808) (xy 45.33065 -53.836485)
			(xy 45.391121 -53.847856) (xy 45.420026 -53.858414) (xy 45.428916 -53.861716) (xy 45.794168 -53.861716)
			(xy 45.794168 -53.491892) (xy 45.734224 -53.491892) (xy 45.734224 -53.224176) (xy 45.734599 -53.205577)
			(xy 45.740695 -53.168882) (xy 45.752734 -53.133686) (xy 45.770388 -53.100944) (xy 45.781468 -53.086)
			(xy 45.786778 -53.07847) (xy 45.792153 -53.060861) (xy 45.790979 -53.042488) (xy 45.783405 -53.025707)
			(xy 45.77715 -53.018944) (xy 45.665898 -52.907692) (xy 44.45 -52.907692) (xy 44.432982 -52.890674)
			(xy 44.41952 -52.887372) (xy 44.394865 -52.880712) (xy 44.34782 -52.860844) (xy 44.304388 -52.83398)
			(xy 44.265603 -52.800757) (xy 44.232387 -52.761967) (xy 44.20553 -52.718531) (xy 44.18567 -52.671482)
			(xy 44.178982 -52.646834) (xy 44.17568 -52.633372) (xy 44.1706 -52.628292) (xy 44.1706 -52.59832)
			(xy 44.170346 -52.596034) (xy 44.169076 -52.56657) (xy 44.170346 -52.537106) (xy 44.1706 -52.53482)
			(xy 44.1706 -51.8922) (xy 43.8404 -51.562) (xy 43.18 -51.562) (xy 43.0022 -51.7398) (xy 43.0022 -53.215286)
			(xy 43.179317 -53.392403) (xy 44.169586 -53.392403) (xy 44.169586 -53.340429) (xy 44.177716 -53.289094)
			(xy 44.193777 -53.239664) (xy 44.217373 -53.193354) (xy 44.247923 -53.151306) (xy 44.284674 -53.114555)
			(xy 44.326722 -53.084005) (xy 44.373032 -53.060409) (xy 44.422462 -53.044348) (xy 44.473797 -53.036218)
			(xy 44.525771 -53.036218) (xy 44.577106 -53.044348) (xy 44.626536 -53.060409) (xy 44.672846 -53.084005)
			(xy 44.714894 -53.114555) (xy 44.751645 -53.151306) (xy 44.782195 -53.193354) (xy 44.805791 -53.239664)
			(xy 44.821852 -53.289094) (xy 44.829982 -53.340429) (xy 44.830492 -53.366416) (xy 44.829982 -53.392403)
			(xy 44.969686 -53.392403) (xy 44.969686 -53.340429) (xy 44.977816 -53.289094) (xy 44.993877 -53.239664)
			(xy 45.017473 -53.193354) (xy 45.048023 -53.151306) (xy 45.084774 -53.114555) (xy 45.126822 -53.084005)
			(xy 45.173132 -53.060409) (xy 45.222562 -53.044348) (xy 45.273897 -53.036218) (xy 45.325871 -53.036218)
			(xy 45.377206 -53.044348) (xy 45.426636 -53.060409) (xy 45.472946 -53.084005) (xy 45.514994 -53.114555)
			(xy 45.551745 -53.151306) (xy 45.582295 -53.193354) (xy 45.605891 -53.239664) (xy 45.621952 -53.289094)
			(xy 45.630082 -53.340429) (xy 45.630592 -53.366416) (xy 45.630082 -53.392403) (xy 45.621952 -53.443738)
			(xy 45.605891 -53.493168) (xy 45.582295 -53.539478) (xy 45.551745 -53.581526) (xy 45.514994 -53.618277)
			(xy 45.472946 -53.648827) (xy 45.426636 -53.672423) (xy 45.377206 -53.688484) (xy 45.325871 -53.696614)
			(xy 45.273897 -53.696614) (xy 45.222562 -53.688484) (xy 45.173132 -53.672423) (xy 45.126822 -53.648827)
			(xy 45.084774 -53.618277) (xy 45.048023 -53.581526) (xy 45.017473 -53.539478) (xy 44.993877 -53.493168)
			(xy 44.977816 -53.443738) (xy 44.969686 -53.392403) (xy 44.829982 -53.392403) (xy 44.821852 -53.443738)
			(xy 44.805791 -53.493168) (xy 44.782195 -53.539478) (xy 44.751645 -53.581526) (xy 44.714894 -53.618277)
			(xy 44.672846 -53.648827) (xy 44.626536 -53.672423) (xy 44.577106 -53.688484) (xy 44.525771 -53.696614)
			(xy 44.473797 -53.696614) (xy 44.422462 -53.688484) (xy 44.373032 -53.672423) (xy 44.326722 -53.648827)
			(xy 44.284674 -53.618277) (xy 44.247923 -53.581526) (xy 44.217373 -53.539478) (xy 44.193777 -53.493168)
			(xy 44.177716 -53.443738) (xy 44.169586 -53.392403) (xy 43.179317 -53.392403) (xy 43.3832 -53.596286)
			(xy 43.3832 -54.164484) (xy 43.415966 -54.176676) (xy 43.442822 -54.187345) (xy 43.452019 -54.192503)
			(xy 44.169586 -54.192503) (xy 44.169586 -54.140529) (xy 44.177716 -54.089194) (xy 44.193777 -54.039764)
			(xy 44.217373 -53.993454) (xy 44.247923 -53.951406) (xy 44.284674 -53.914655) (xy 44.326722 -53.884105)
			(xy 44.373032 -53.860509) (xy 44.422462 -53.844448) (xy 44.473797 -53.836318) (xy 44.525771 -53.836318)
			(xy 44.577106 -53.844448) (xy 44.626536 -53.860509) (xy 44.672846 -53.884105) (xy 44.714894 -53.914655)
			(xy 44.751645 -53.951406) (xy 44.782195 -53.993454) (xy 44.805791 -54.039764) (xy 44.821852 -54.089194)
			(xy 44.829982 -54.140529) (xy 44.830492 -54.166516) (xy 44.829982 -54.192503) (xy 44.821852 -54.243838)
			(xy 44.805791 -54.293268) (xy 44.782195 -54.339578) (xy 44.751645 -54.381626) (xy 44.714894 -54.418377)
			(xy 44.672846 -54.448927) (xy 44.626536 -54.472523) (xy 44.577106 -54.488584) (xy 44.525771 -54.496714)
			(xy 44.473797 -54.496714) (xy 44.422462 -54.488584) (xy 44.373032 -54.472523) (xy 44.326722 -54.448927)
			(xy 44.284674 -54.418377) (xy 44.247923 -54.381626) (xy 44.217373 -54.339578) (xy 44.193777 -54.293268)
			(xy 44.177716 -54.243838) (xy 44.169586 -54.192503) (xy 43.452019 -54.192503) (xy 43.493223 -54.215612)
			(xy 43.538784 -54.251158) (xy 43.578461 -54.293169) (xy 43.611347 -54.340685) (xy 43.63669 -54.392618)
			(xy 43.653909 -54.447779) (xy 43.662611 -54.504907) (xy 43.663108 -54.5338) (xy 43.662622 -54.561051)
			(xy 43.654866 -54.614999) (xy 43.639511 -54.667294) (xy 43.616869 -54.716871) (xy 43.587403 -54.762721)
			(xy 43.551712 -54.803912) (xy 43.510521 -54.839603) (xy 43.464671 -54.869069) (xy 43.415094 -54.891711)
			(xy 43.362799 -54.907066) (xy 43.308851 -54.914822) (xy 43.2816 -54.915308) (xy 43.248601 -54.914612)
			(xy 43.18359 -54.903247) (xy 43.152314 -54.892702) (xy 43.139051 -54.888402) (xy 43.11125 -54.886432)
			(xy 43.083952 -54.892053) (xy 43.059191 -54.904848) (xy 43.038813 -54.923862) (xy 43.024337 -54.947679)
			(xy 43.016842 -54.974524) (xy 43.016424 -54.98846) (xy 43.016424 -55.583328) (xy 43.167808 -55.734712)
		)
		(stroke
			(width 0)
			(type solid)
		)
		(fill yes)
		(layer "B.Cu")
		(net "P3V3_STBY_DACAV33")
	)
	(gr_poly
		(pts
			(xy 24.1681 -91.3765) (xy 24.1681 -91.2241) (xy 24.892 -90.5002) (xy 24.892 -90.2208) (xy 24.5872 -89.916)
			(xy 23.920704 -89.916) (xy 23.915878 -89.916762) (xy 23.900719 -89.919473) (xy 23.870062 -89.922395)
			(xy 23.854664 -89.922604) (xy 23.839266 -89.922392) (xy 23.80861 -89.919467) (xy 23.79345 -89.916762)
			(xy 23.788624 -89.916) (xy 23.120604 -89.916) (xy 23.115778 -89.916762) (xy 23.100619 -89.919473)
			(xy 23.069962 -89.922395) (xy 23.054564 -89.922604) (xy 23.039166 -89.922392) (xy 23.00851 -89.919467)
			(xy 22.99335 -89.916762) (xy 22.988524 -89.916) (xy 22.320758 -89.916) (xy 22.315932 -89.916762)
			(xy 22.300774 -89.919476) (xy 22.270116 -89.922403) (xy 22.254718 -89.922604) (xy 22.239321 -89.92239)
			(xy 22.208665 -89.919461) (xy 22.193504 -89.916762) (xy 22.188678 -89.916) (xy 20.343368 -89.916)
			(xy 20.165568 -90.094054) (xy 20.16379 -90.095578) (xy 20.154279 -90.105418) (xy 20.140404 -90.128995)
			(xy 20.13329 -90.155411) (xy 20.13345 -90.182768) (xy 20.14087 -90.209099) (xy 20.147534 -90.221054)
			(xy 20.16244 -90.247004) (xy 20.183633 -90.302963) (xy 20.194412 -90.361823) (xy 20.195032 -90.391742)
			(xy 20.194522 -90.417729) (xy 20.333972 -90.417729) (xy 20.333972 -90.365755) (xy 20.342102 -90.31442)
			(xy 20.358163 -90.26499) (xy 20.381759 -90.21868) (xy 20.412309 -90.176632) (xy 20.44906 -90.139881)
			(xy 20.491108 -90.109331) (xy 20.537418 -90.085735) (xy 20.586848 -90.069674) (xy 20.638183 -90.061544)
			(xy 20.690157 -90.061544) (xy 20.741492 -90.069674) (xy 20.790922 -90.085735) (xy 20.837232 -90.109331)
			(xy 20.87928 -90.139881) (xy 20.916031 -90.176632) (xy 20.946581 -90.21868) (xy 20.970177 -90.26499)
			(xy 20.986238 -90.31442) (xy 20.994368 -90.365755) (xy 20.994878 -90.391742) (xy 20.994368 -90.417729)
			(xy 21.92452 -90.417729) (xy 21.92452 -90.365755) (xy 21.93265 -90.31442) (xy 21.948711 -90.26499)
			(xy 21.972307 -90.21868) (xy 22.002857 -90.176632) (xy 22.039608 -90.139881) (xy 22.081656 -90.109331)
			(xy 22.127966 -90.085735) (xy 22.177396 -90.069674) (xy 22.228731 -90.061544) (xy 22.280705 -90.061544)
			(xy 22.33204 -90.069674) (xy 22.38147 -90.085735) (xy 22.42778 -90.109331) (xy 22.469828 -90.139881)
			(xy 22.506579 -90.176632) (xy 22.537129 -90.21868) (xy 22.560725 -90.26499) (xy 22.576786 -90.31442)
			(xy 22.584916 -90.365755) (xy 22.585426 -90.391742) (xy 22.584916 -90.417729) (xy 22.724366 -90.417729)
			(xy 22.724366 -90.365755) (xy 22.732496 -90.31442) (xy 22.748557 -90.26499) (xy 22.772153 -90.21868)
			(xy 22.802703 -90.176632) (xy 22.839454 -90.139881) (xy 22.881502 -90.109331) (xy 22.927812 -90.085735)
			(xy 22.977242 -90.069674) (xy 23.028577 -90.061544) (xy 23.080551 -90.061544) (xy 23.131886 -90.069674)
			(xy 23.181316 -90.085735) (xy 23.227626 -90.109331) (xy 23.269674 -90.139881) (xy 23.306425 -90.176632)
			(xy 23.336975 -90.21868) (xy 23.360571 -90.26499) (xy 23.376632 -90.31442) (xy 23.384762 -90.365755)
			(xy 23.385272 -90.391742) (xy 23.384762 -90.417729) (xy 23.524466 -90.417729) (xy 23.524466 -90.365755)
			(xy 23.532596 -90.31442) (xy 23.548657 -90.26499) (xy 23.572253 -90.21868) (xy 23.602803 -90.176632)
			(xy 23.639554 -90.139881) (xy 23.681602 -90.109331) (xy 23.727912 -90.085735) (xy 23.777342 -90.069674)
			(xy 23.828677 -90.061544) (xy 23.880651 -90.061544) (xy 23.931986 -90.069674) (xy 23.981416 -90.085735)
			(xy 24.027726 -90.109331) (xy 24.069774 -90.139881) (xy 24.106525 -90.176632) (xy 24.137075 -90.21868)
			(xy 24.160671 -90.26499) (xy 24.176732 -90.31442) (xy 24.184862 -90.365755) (xy 24.185372 -90.391742)
			(xy 24.184862 -90.417729) (xy 24.176732 -90.469064) (xy 24.160671 -90.518494) (xy 24.137075 -90.564804)
			(xy 24.106525 -90.606852) (xy 24.069774 -90.643603) (xy 24.027726 -90.674153) (xy 23.981416 -90.697749)
			(xy 23.931986 -90.71381) (xy 23.880651 -90.72194) (xy 23.828677 -90.72194) (xy 23.777342 -90.71381)
			(xy 23.727912 -90.697749) (xy 23.681602 -90.674153) (xy 23.639554 -90.643603) (xy 23.602803 -90.606852)
			(xy 23.572253 -90.564804) (xy 23.548657 -90.518494) (xy 23.532596 -90.469064) (xy 23.524466 -90.417729)
			(xy 23.384762 -90.417729) (xy 23.376632 -90.469064) (xy 23.360571 -90.518494) (xy 23.336975 -90.564804)
			(xy 23.306425 -90.606852) (xy 23.269674 -90.643603) (xy 23.227626 -90.674153) (xy 23.181316 -90.697749)
			(xy 23.131886 -90.71381) (xy 23.080551 -90.72194) (xy 23.028577 -90.72194) (xy 22.977242 -90.71381)
			(xy 22.927812 -90.697749) (xy 22.881502 -90.674153) (xy 22.839454 -90.643603) (xy 22.802703 -90.606852)
			(xy 22.772153 -90.564804) (xy 22.748557 -90.518494) (xy 22.732496 -90.469064) (xy 22.724366 -90.417729)
			(xy 22.584916 -90.417729) (xy 22.576786 -90.469064) (xy 22.560725 -90.518494) (xy 22.537129 -90.564804)
			(xy 22.506579 -90.606852) (xy 22.469828 -90.643603) (xy 22.42778 -90.674153) (xy 22.38147 -90.697749)
			(xy 22.33204 -90.71381) (xy 22.280705 -90.72194) (xy 22.228731 -90.72194) (xy 22.177396 -90.71381)
			(xy 22.127966 -90.697749) (xy 22.081656 -90.674153) (xy 22.039608 -90.643603) (xy 22.002857 -90.606852)
			(xy 21.972307 -90.564804) (xy 21.948711 -90.518494) (xy 21.93265 -90.469064) (xy 21.92452 -90.417729)
			(xy 20.994368 -90.417729) (xy 20.986238 -90.469064) (xy 20.970177 -90.518494) (xy 20.946581 -90.564804)
			(xy 20.916031 -90.606852) (xy 20.87928 -90.643603) (xy 20.837232 -90.674153) (xy 20.790922 -90.697749)
			(xy 20.741492 -90.71381) (xy 20.690157 -90.72194) (xy 20.638183 -90.72194) (xy 20.586848 -90.71381)
			(xy 20.537418 -90.697749) (xy 20.491108 -90.674153) (xy 20.44906 -90.643603) (xy 20.412309 -90.606852)
			(xy 20.381759 -90.564804) (xy 20.358163 -90.518494) (xy 20.342102 -90.469064) (xy 20.333972 -90.417729)
			(xy 20.194522 -90.417729) (xy 20.186392 -90.469064) (xy 20.170331 -90.518494) (xy 20.146735 -90.564804)
			(xy 20.116185 -90.606852) (xy 20.079434 -90.643603) (xy 20.037386 -90.674153) (xy 19.991076 -90.697749)
			(xy 19.941646 -90.71381) (xy 19.890311 -90.72194) (xy 19.838337 -90.72194) (xy 19.787002 -90.71381)
			(xy 19.737572 -90.697749) (xy 19.691262 -90.674153) (xy 19.649214 -90.643603) (xy 19.612463 -90.606852)
			(xy 19.581913 -90.564804) (xy 19.558317 -90.518494) (xy 19.542256 -90.469064) (xy 19.534126 -90.417729)
			(xy 19.533616 -90.391742) (xy 19.534093 -90.366562) (xy 19.54174 -90.316787) (xy 19.556847 -90.268748)
			(xy 19.579066 -90.223555) (xy 19.607883 -90.182255) (xy 19.642629 -90.145804) (xy 19.682503 -90.115044)
			(xy 19.704304 -90.102436) (xy 19.703796 -90.092022) (xy 19.704254 -90.075059) (xy 19.711417 -90.041894)
			(xy 19.725347 -90.010957) (xy 19.735038 -89.997026) (xy 19.744944 -89.983564) (xy 19.744944 -89.916)
			(xy 19.7104 -89.916) (xy 19.5326 -89.7382) (xy 19.5326 -89.3064) (xy 19.275552 -89.049352) (xy 19.241262 -89.071196)
			(xy 19.221344 -89.083351) (xy 19.178814 -89.102544) (xy 19.134004 -89.115554) (xy 19.087808 -89.122123)
			(xy 19.064478 -89.122504) (xy 19.064224 -89.122504) (xy 19.039015 -89.122032) (xy 18.989181 -89.114382)
			(xy 18.941085 -89.099257) (xy 18.895843 -89.077007) (xy 18.854502 -89.048147) (xy 18.818021 -89.013347)
			(xy 18.787245 -88.973412) (xy 18.774664 -88.951562) (xy 18.760186 -88.9254) (xy 18.568162 -88.9254)
			(xy 18.553684 -88.951562) (xy 18.540807 -88.973939) (xy 18.509186 -89.014747) (xy 18.471598 -89.050135)
			(xy 18.45056 -89.0651) (xy 18.45056 -89.318592) (xy 18.472404 -89.334145) (xy 18.511221 -89.371137)
			(xy 18.543566 -89.413904) (xy 18.568591 -89.461327) (xy 18.585642 -89.512164) (xy 18.594273 -89.565085)
			(xy 18.594832 -89.591896) (xy 18.594329 -89.617883) (xy 18.734026 -89.617883) (xy 18.734026 -89.565909)
			(xy 18.742156 -89.514574) (xy 18.758217 -89.465144) (xy 18.781813 -89.418834) (xy 18.812363 -89.376786)
			(xy 18.849114 -89.340035) (xy 18.891162 -89.309485) (xy 18.937472 -89.285889) (xy 18.986902 -89.269828)
			(xy 19.038237 -89.261698) (xy 19.090211 -89.261698) (xy 19.141546 -89.269828) (xy 19.190976 -89.285889)
			(xy 19.237286 -89.309485) (xy 19.279334 -89.340035) (xy 19.316085 -89.376786) (xy 19.346635 -89.418834)
			(xy 19.370231 -89.465144) (xy 19.386292 -89.514574) (xy 19.394422 -89.565909) (xy 19.394932 -89.591896)
			(xy 19.394422 -89.617883) (xy 19.386292 -89.669218) (xy 19.370231 -89.718648) (xy 19.346635 -89.764958)
			(xy 19.316085 -89.807006) (xy 19.279334 -89.843757) (xy 19.237286 -89.874307) (xy 19.190976 -89.897903)
			(xy 19.141546 -89.913964) (xy 19.090211 -89.922094) (xy 19.038237 -89.922094) (xy 18.986902 -89.913964)
			(xy 18.937472 -89.897903) (xy 18.891162 -89.874307) (xy 18.849114 -89.843757) (xy 18.812363 -89.807006)
			(xy 18.781813 -89.764958) (xy 18.758217 -89.718648) (xy 18.742156 -89.669218) (xy 18.734026 -89.617883)
			(xy 18.594329 -89.617883) (xy 18.594313 -89.618691) (xy 18.585671 -89.67158) (xy 18.568612 -89.722383)
			(xy 18.543583 -89.76977) (xy 18.511239 -89.812499) (xy 18.472427 -89.849453) (xy 18.45056 -89.864946)
			(xy 18.45056 -90.075004) (xy 18.360136 -90.133424) (xy 18.187924 -90.133424) (xy 18.034 -90.287348)
			(xy 18.034 -90.417729) (xy 18.734026 -90.417729) (xy 18.734026 -90.365755) (xy 18.742156 -90.31442)
			(xy 18.758217 -90.26499) (xy 18.781813 -90.21868) (xy 18.812363 -90.176632) (xy 18.849114 -90.139881)
			(xy 18.891162 -90.109331) (xy 18.937472 -90.085735) (xy 18.986902 -90.069674) (xy 19.038237 -90.061544)
			(xy 19.090211 -90.061544) (xy 19.141546 -90.069674) (xy 19.190976 -90.085735) (xy 19.237286 -90.109331)
			(xy 19.279334 -90.139881) (xy 19.316085 -90.176632) (xy 19.346635 -90.21868) (xy 19.370231 -90.26499)
			(xy 19.386292 -90.31442) (xy 19.394422 -90.365755) (xy 19.394932 -90.391742) (xy 19.394422 -90.417729)
			(xy 19.386292 -90.469064) (xy 19.370231 -90.518494) (xy 19.346635 -90.564804) (xy 19.316085 -90.606852)
			(xy 19.279334 -90.643603) (xy 19.237286 -90.674153) (xy 19.190976 -90.697749) (xy 19.141546 -90.71381)
			(xy 19.090211 -90.72194) (xy 19.038237 -90.72194) (xy 18.986902 -90.71381) (xy 18.937472 -90.697749)
			(xy 18.891162 -90.674153) (xy 18.849114 -90.643603) (xy 18.812363 -90.606852) (xy 18.781813 -90.564804)
			(xy 18.758217 -90.518494) (xy 18.742156 -90.469064) (xy 18.734026 -90.417729) (xy 18.034 -90.417729)
			(xy 18.034 -90.486484) (xy 18.187924 -90.640408) (xy 18.360136 -90.640408) (xy 18.45056 -90.699082)
			(xy 18.45056 -90.918792) (xy 18.47241 -90.934313) (xy 18.511245 -90.971248) (xy 18.543608 -91.013967)
			(xy 18.568652 -91.061349) (xy 18.58572 -91.112153) (xy 18.594364 -91.165045) (xy 18.594832 -91.191842)
			(xy 18.59407 -91.213686) (xy 18.592546 -91.236546) (xy 18.796 -91.44) (xy 19.2532 -91.44) (xy 19.4818 -91.2114)
			(xy 19.530822 -91.2114) (xy 19.534632 -91.164664) (xy 19.537265 -91.138862) (xy 19.54954 -91.088474)
			(xy 19.569526 -91.040619) (xy 19.596736 -90.996469) (xy 19.630502 -90.957105) (xy 19.669997 -90.923493)
			(xy 19.714253 -90.896456) (xy 19.762186 -90.876656) (xy 19.812622 -90.864579) (xy 19.864324 -90.86052)
			(xy 19.916026 -90.864579) (xy 19.966462 -90.876656) (xy 20.014395 -90.896456) (xy 20.058651 -90.923493)
			(xy 20.098146 -90.957105) (xy 20.131912 -90.996469) (xy 20.159122 -91.040619) (xy 20.179108 -91.088474)
			(xy 20.191383 -91.138862) (xy 20.194016 -91.164664) (xy 20.197826 -91.2114) (xy 20.6756 -91.2114)
			(xy 21.209 -90.678) (xy 21.21408 -90.678) (xy 21.222716 -90.664792) (xy 21.398484 -90.664792) (xy 21.40712 -90.678)
			(xy 21.4376 -90.678) (xy 21.808186 -91.048586) (xy 21.817934 -91.057649) (xy 21.841023 -91.070873)
			(xy 21.866743 -91.077683) (xy 21.89335 -91.077618) (xy 21.919037 -91.070683) (xy 21.942061 -91.057347)
			(xy 21.960858 -91.038516) (xy 21.967952 -91.02725) (xy 21.980671 -91.005944) (xy 22.0115 -90.967063)
			(xy 22.047799 -90.933232) (xy 22.08875 -90.905213) (xy 22.133433 -90.883635) (xy 22.180841 -90.868986)
			(xy 22.229908 -90.861595) (xy 22.254718 -90.861134) (xy 22.280555 -90.861626) (xy 22.331601 -90.869654)
			(xy 22.380777 -90.885527) (xy 22.426884 -90.908859) (xy 22.468798 -90.93908) (xy 22.5055 -90.975456)
			(xy 22.521164 -90.996008) (xy 22.788118 -90.996008) (xy 22.803821 -90.975489) (xy 22.840524 -90.939124)
			(xy 22.882434 -90.908907) (xy 22.928531 -90.885571) (xy 22.977695 -90.869684) (xy 23.028731 -90.861632)
			(xy 23.054564 -90.861134) (xy 23.080554 -90.861614) (xy 23.131894 -90.869742) (xy 23.181331 -90.885801)
			(xy 23.227646 -90.909398) (xy 23.269699 -90.93995) (xy 23.306454 -90.976705) (xy 23.337006 -91.018759)
			(xy 23.360601 -91.065075) (xy 23.37666 -91.114511) (xy 23.384786 -91.165852) (xy 23.385272 -91.191842)
			(xy 23.385272 -91.192096) (xy 23.385032 -91.210152) (xy 23.381086 -91.246047) (xy 23.377398 -91.263724)
			(xy 23.371302 -91.290902) (xy 23.5458 -91.4654) (xy 24.0792 -91.4654)
		)
		(stroke
			(width 0)
			(type solid)
		)
		(fill yes)
		(layer "B.Cu")
		(net "GND")
	)
	(gr_poly
		(pts
			(xy 69.60362 -57.6199) (xy 69.60362 -56.546242) (xy 69.57949 -56.522112) (xy 68.788026 -56.522112)
			(xy 68.379848 -56.93029) (xy 67.295268 -56.93029) (xy 66.737484 -56.372506) (xy 66.737484 -54.824122)
			(xy 66.715457 -54.808867) (xy 66.675501 -54.773171) (xy 66.640932 -54.732235) (xy 66.612428 -54.686867)
			(xy 66.590552 -54.637957) (xy 66.575733 -54.586468) (xy 66.568263 -54.533412) (xy 66.567812 -54.506622)
			(xy 66.568243 -54.479829) (xy 66.575699 -54.426765) (xy 66.59051 -54.375266) (xy 66.612383 -54.326348)
			(xy 66.640887 -54.280974) (xy 66.675463 -54.240035) (xy 66.715429 -54.20434) (xy 66.737484 -54.189122)
			(xy 66.737484 -53.076856) (xy 66.737013 -53.066981) (xy 66.729533 -53.048702) (xy 66.715699 -53.034605)
			(xy 66.697563 -53.026782) (xy 66.6877 -53.026056) (xy 66.659518 -53.024988) (xy 66.603912 -53.015579)
			(xy 66.550297 -52.99809) (xy 66.49984 -52.9729) (xy 66.453638 -52.940559) (xy 66.4127 -52.901771)
			(xy 66.377915 -52.857381) (xy 66.350042 -52.808355) (xy 66.329687 -52.75576) (xy 66.317295 -52.700743)
			(xy 66.313133 -52.644501) (xy 66.317294 -52.588259) (xy 66.329687 -52.533242) (xy 66.350041 -52.480647)
			(xy 66.377914 -52.431621) (xy 66.412698 -52.38723) (xy 66.453637 -52.348442) (xy 66.499838 -52.316101)
			(xy 66.550295 -52.290911) (xy 66.603911 -52.273421) (xy 66.659516 -52.264012) (xy 66.6877 -52.26304)
			(xy 66.69757 -52.262381) (xy 66.715713 -52.254543) (xy 66.72954 -52.240424) (xy 66.736997 -52.222122)
			(xy 66.737484 -52.21224) (xy 66.737484 -51.642264) (xy 65.72631 -50.63109) (xy 65.65392 -50.63109)
			(xy 65.640302 -50.631534) (xy 65.614038 -50.63875) (xy 65.590613 -50.652647) (xy 65.571692 -50.672238)
			(xy 65.558617 -50.696132) (xy 65.552319 -50.722631) (xy 65.553245 -50.749852) (xy 65.561328 -50.775862)
			(xy 65.568322 -50.787554) (xy 65.580767 -50.807644) (xy 65.600414 -50.850625) (xy 65.61374 -50.895965)
			(xy 65.620474 -50.942741) (xy 65.6209 -50.96637) (xy 65.62039 -50.992357) (xy 65.61226 -51.043692)
			(xy 65.596199 -51.093122) (xy 65.572603 -51.139432) (xy 65.542053 -51.18148) (xy 65.505302 -51.218231)
			(xy 65.463254 -51.248781) (xy 65.416944 -51.272377) (xy 65.367514 -51.288438) (xy 65.316179 -51.296568)
			(xy 65.264205 -51.296568) (xy 65.21287 -51.288438) (xy 65.16344 -51.272377) (xy 65.11713 -51.248781)
			(xy 65.075082 -51.218231) (xy 65.038331 -51.18148) (xy 65.007781 -51.139432) (xy 64.984185 -51.093122)
			(xy 64.968124 -51.043692) (xy 64.959994 -50.992357) (xy 64.959484 -50.96637) (xy 64.959882 -50.942738)
			(xy 64.966609 -50.895957) (xy 64.979934 -50.850611) (xy 64.999586 -50.807628) (xy 65.012062 -50.787554)
			(xy 65.019049 -50.775849) (xy 65.027166 -50.749836) (xy 65.028113 -50.722603) (xy 65.021825 -50.696088)
			(xy 65.008748 -50.672181) (xy 64.989814 -50.652584) (xy 64.966371 -50.638692) (xy 64.940089 -50.631495)
			(xy 64.926464 -50.63109) (xy 64.306196 -50.63109) (xy 64.184276 -50.75301) (xy 64.184276 -51.039268)
			(xy 64.344804 -51.199796) (xy 64.570102 -51.199796) (xy 64.639698 -51.269392) (xy 64.664844 -51.269392)
			(xy 64.664844 -51.294284) (xy 64.723518 -51.353212) (xy 64.723518 -51.882294) (xy 64.15151 -52.454302)
			(xy 64.1223 -52.454302) (xy 64.108787 -52.454762) (xy 64.082724 -52.461926) (xy 64.059452 -52.475673)
			(xy 64.040599 -52.495042) (xy 64.027485 -52.518676) (xy 64.021026 -52.544922) (xy 64.020954 -52.558442)
			(xy 64.020954 -52.56657) (xy 64.020444 -52.592557) (xy 64.959994 -52.592557) (xy 64.959994 -52.540583)
			(xy 64.968124 -52.489248) (xy 64.984185 -52.439818) (xy 65.007781 -52.393508) (xy 65.038331 -52.35146)
			(xy 65.075082 -52.314709) (xy 65.11713 -52.284159) (xy 65.16344 -52.260563) (xy 65.21287 -52.244502)
			(xy 65.264205 -52.236372) (xy 65.316179 -52.236372) (xy 65.367514 -52.244502) (xy 65.416944 -52.260563)
			(xy 65.463254 -52.284159) (xy 65.505302 -52.314709) (xy 65.542053 -52.35146) (xy 65.572603 -52.393508)
			(xy 65.596199 -52.439818) (xy 65.61226 -52.489248) (xy 65.62039 -52.540583) (xy 65.6209 -52.56657)
			(xy 65.62039 -52.592557) (xy 65.61226 -52.643892) (xy 65.596199 -52.693322) (xy 65.572603 -52.739632)
			(xy 65.542053 -52.78168) (xy 65.505302 -52.818431) (xy 65.463254 -52.848981) (xy 65.416944 -52.872577)
			(xy 65.367514 -52.888638) (xy 65.316179 -52.896768) (xy 65.264205 -52.896768) (xy 65.21287 -52.888638)
			(xy 65.16344 -52.872577) (xy 65.11713 -52.848981) (xy 65.075082 -52.818431) (xy 65.038331 -52.78168)
			(xy 65.007781 -52.739632) (xy 64.984185 -52.693322) (xy 64.968124 -52.643892) (xy 64.959994 -52.592557)
			(xy 64.020444 -52.592557) (xy 64.012314 -52.643892) (xy 63.996253 -52.693322) (xy 63.972657 -52.739632)
			(xy 63.942107 -52.78168) (xy 63.905356 -52.818431) (xy 63.863308 -52.848981) (xy 63.816998 -52.872577)
			(xy 63.767568 -52.888638) (xy 63.716233 -52.896768) (xy 63.664259 -52.896768) (xy 63.612924 -52.888638)
			(xy 63.563494 -52.872577) (xy 63.517184 -52.848981) (xy 63.475136 -52.818431) (xy 63.438385 -52.78168)
			(xy 63.407835 -52.739632) (xy 63.384239 -52.693322) (xy 63.368178 -52.643892) (xy 63.360048 -52.592557)
			(xy 63.359538 -52.56657) (xy 63.359671 -52.553175) (xy 63.361829 -52.526472) (xy 63.363856 -52.51323)
			(xy 63.364618 -52.509166) (xy 63.364618 -52.454302) (xy 63.215774 -52.454302) (xy 63.215774 -52.509166)
			(xy 63.216536 -52.51323) (xy 63.218564 -52.526471) (xy 63.220723 -52.553175) (xy 63.220854 -52.56657)
			(xy 63.220347 -52.59256) (xy 63.21222 -52.643901) (xy 63.196162 -52.693338) (xy 63.172569 -52.739655)
			(xy 63.14202 -52.781711) (xy 63.105269 -52.818471) (xy 63.06322 -52.849029) (xy 63.016909 -52.872633)
			(xy 62.967475 -52.888702) (xy 62.916136 -52.896841) (xy 62.890146 -52.897278) (xy 62.864323 -52.896776)
			(xy 62.813306 -52.888736) (xy 62.764161 -52.87286) (xy 62.718082 -52.849534) (xy 62.676191 -52.819327)
			(xy 62.657482 -52.80152) (xy 62.647743 -52.792511) (xy 62.624707 -52.779373) (xy 62.599067 -52.772601)
			(xy 62.572548 -52.772651) (xy 62.546934 -52.77952) (xy 62.523948 -52.792746) (xy 62.514226 -52.801774)
			(xy 62.4078 -52.9082) (xy 61.8998 -52.9082) (xy 61.849 -52.959) (xy 61.849 -53.392403) (xy 62.559948 -53.392403)
			(xy 62.559948 -53.340429) (xy 62.568078 -53.289094) (xy 62.584139 -53.239664) (xy 62.607735 -53.193354)
			(xy 62.638285 -53.151306) (xy 62.675036 -53.114555) (xy 62.717084 -53.084005) (xy 62.763394 -53.060409)
			(xy 62.812824 -53.044348) (xy 62.864159 -53.036218) (xy 62.916133 -53.036218) (xy 62.967468 -53.044348)
			(xy 63.016898 -53.060409) (xy 63.063208 -53.084005) (xy 63.105256 -53.114555) (xy 63.142007 -53.151306)
			(xy 63.172557 -53.193354) (xy 63.196153 -53.239664) (xy 63.212214 -53.289094) (xy 63.220344 -53.340429)
			(xy 63.220854 -53.366416) (xy 63.220344 -53.392403) (xy 63.360048 -53.392403) (xy 63.360048 -53.340429)
			(xy 63.368178 -53.289094) (xy 63.384239 -53.239664) (xy 63.407835 -53.193354) (xy 63.438385 -53.151306)
			(xy 63.475136 -53.114555) (xy 63.517184 -53.084005) (xy 63.563494 -53.060409) (xy 63.612924 -53.044348)
			(xy 63.664259 -53.036218) (xy 63.716233 -53.036218) (xy 63.767568 -53.044348) (xy 63.816998 -53.060409)
			(xy 63.863308 -53.084005) (xy 63.905356 -53.114555) (xy 63.942107 -53.151306) (xy 63.972657 -53.193354)
			(xy 63.996253 -53.239664) (xy 64.012314 -53.289094) (xy 64.020444 -53.340429) (xy 64.020954 -53.366416)
			(xy 64.020444 -53.392403) (xy 64.012314 -53.443738) (xy 63.996253 -53.493168) (xy 63.972657 -53.539478)
			(xy 63.942107 -53.581526) (xy 63.905356 -53.618277) (xy 63.863308 -53.648827) (xy 63.816998 -53.672423)
			(xy 63.767568 -53.688484) (xy 63.716233 -53.696614) (xy 63.664259 -53.696614) (xy 63.612924 -53.688484)
			(xy 63.563494 -53.672423) (xy 63.517184 -53.648827) (xy 63.475136 -53.618277) (xy 63.438385 -53.581526)
			(xy 63.407835 -53.539478) (xy 63.384239 -53.493168) (xy 63.368178 -53.443738) (xy 63.360048 -53.392403)
			(xy 63.220344 -53.392403) (xy 63.212214 -53.443738) (xy 63.196153 -53.493168) (xy 63.172557 -53.539478)
			(xy 63.142007 -53.581526) (xy 63.105256 -53.618277) (xy 63.063208 -53.648827) (xy 63.016898 -53.672423)
			(xy 62.967468 -53.688484) (xy 62.916133 -53.696614) (xy 62.864159 -53.696614) (xy 62.812824 -53.688484)
			(xy 62.763394 -53.672423) (xy 62.717084 -53.648827) (xy 62.675036 -53.618277) (xy 62.638285 -53.581526)
			(xy 62.607735 -53.539478) (xy 62.584139 -53.493168) (xy 62.568078 -53.443738) (xy 62.559948 -53.392403)
			(xy 61.849 -53.392403) (xy 61.849 -53.4162) (xy 62.288928 -53.856128) (xy 62.303406 -53.85943) (xy 62.325033 -53.864787)
			(xy 62.365778 -53.882804) (xy 62.402221 -53.908429) (xy 62.41796 -53.9242) (xy 62.665102 -53.9242)
			(xy 62.683548 -53.90767) (xy 62.724461 -53.879754) (xy 62.769079 -53.858252) (xy 62.816406 -53.843644)
			(xy 62.865381 -53.836258) (xy 62.914911 -53.836258) (xy 62.963886 -53.843644) (xy 63.011213 -53.858252)
			(xy 63.055831 -53.879754) (xy 63.096744 -53.90767) (xy 63.11519 -53.9242) (xy 63.465202 -53.9242)
			(xy 63.483649 -53.907671) (xy 63.524562 -53.879755) (xy 63.569181 -53.858251) (xy 63.616506 -53.84364)
			(xy 63.665481 -53.836247) (xy 63.690246 -53.835808) (xy 63.71623 -53.836321) (xy 63.767558 -53.844457)
			(xy 63.816982 -53.860523) (xy 63.863284 -53.884121) (xy 63.905324 -53.914672) (xy 63.942068 -53.951423)
			(xy 63.972611 -53.993469) (xy 63.996201 -54.039776) (xy 64.012257 -54.089202) (xy 64.020384 -54.140532)
			(xy 64.020954 -54.166516) (xy 64.020737 -54.184049) (xy 64.017042 -54.218921) (xy 64.013588 -54.236112)
			(xy 64.007746 -54.263036) (xy 64.144398 -54.399688) (xy 64.205358 -54.338474) (xy 64.190372 -54.306216)
			(xy 64.180598 -54.284237) (xy 64.166798 -54.238159) (xy 64.159823 -54.190566) (xy 64.159384 -54.166516)
			(xy 64.159866 -54.140526) (xy 64.167995 -54.089185) (xy 64.184056 -54.039748) (xy 64.207653 -53.993432)
			(xy 64.238204 -53.951377) (xy 64.274959 -53.91462) (xy 64.317011 -53.884065) (xy 64.363325 -53.860465)
			(xy 64.412761 -53.844401) (xy 64.464102 -53.836268) (xy 64.516082 -53.836267) (xy 64.567423 -53.844397)
			(xy 64.61686 -53.860459) (xy 64.663175 -53.884057) (xy 64.705229 -53.91461) (xy 64.741985 -53.951365)
			(xy 64.772539 -53.993418) (xy 64.796138 -54.039733) (xy 64.812201 -54.089169) (xy 64.820333 -54.14051)
			(xy 64.820333 -54.19249) (xy 64.820331 -54.192503) (xy 64.959994 -54.192503) (xy 64.959994 -54.140529)
			(xy 64.968124 -54.089194) (xy 64.984185 -54.039764) (xy 65.007781 -53.993454) (xy 65.038331 -53.951406)
			(xy 65.075082 -53.914655) (xy 65.11713 -53.884105) (xy 65.16344 -53.860509) (xy 65.21287 -53.844448)
			(xy 65.264205 -53.836318) (xy 65.316179 -53.836318) (xy 65.367514 -53.844448) (xy 65.416944 -53.860509)
			(xy 65.463254 -53.884105) (xy 65.505302 -53.914655) (xy 65.542053 -53.951406) (xy 65.572603 -53.993454)
			(xy 65.596199 -54.039764) (xy 65.61226 -54.089194) (xy 65.62039 -54.140529) (xy 65.6209 -54.166516)
			(xy 65.62039 -54.192503) (xy 65.61226 -54.243838) (xy 65.596199 -54.293268) (xy 65.572603 -54.339578)
			(xy 65.542053 -54.381626) (xy 65.505302 -54.418377) (xy 65.463254 -54.448927) (xy 65.416944 -54.472523)
			(xy 65.367514 -54.488584) (xy 65.316179 -54.496714) (xy 65.264205 -54.496714) (xy 65.21287 -54.488584)
			(xy 65.16344 -54.472523) (xy 65.11713 -54.448927) (xy 65.075082 -54.418377) (xy 65.038331 -54.381626)
			(xy 65.007781 -54.339578) (xy 64.984185 -54.293268) (xy 64.968124 -54.243838) (xy 64.959994 -54.192503)
			(xy 64.820331 -54.192503) (xy 64.812201 -54.243831) (xy 64.796138 -54.293267) (xy 64.772539 -54.339582)
			(xy 64.741985 -54.381635) (xy 64.705229 -54.41839) (xy 64.663175 -54.448943) (xy 64.61686 -54.472541)
			(xy 64.567423 -54.488603) (xy 64.516082 -54.496733) (xy 64.490092 -54.497224) (xy 64.46609 -54.496796)
			(xy 64.418589 -54.489861) (xy 64.372587 -54.476137) (xy 64.329051 -54.455912) (xy 64.308736 -54.443122)
			(xy 64.297061 -54.436006) (xy 64.271041 -54.427641) (xy 64.243734 -54.426482) (xy 64.217099 -54.432613)
			(xy 64.193047 -54.445593) (xy 64.173302 -54.464491) (xy 64.159281 -54.487952) (xy 64.15199 -54.514293)
			(xy 64.15151 -54.527958) (xy 64.15151 -55.40502) (xy 64.151992 -55.418678) (xy 64.159314 -55.444997)
			(xy 64.173349 -55.468436) (xy 64.193093 -55.487317) (xy 64.217134 -55.500291) (xy 64.243754 -55.506431)
			(xy 64.271049 -55.505297) (xy 64.297069 -55.496971) (xy 64.308736 -55.489856) (xy 64.329047 -55.477057)
			(xy 64.372582 -55.456821) (xy 64.418584 -55.44309) (xy 64.466088 -55.436151) (xy 64.490092 -55.435754)
			(xy 64.516085 -55.436237) (xy 64.56743 -55.444368) (xy 64.616871 -55.460431) (xy 64.663191 -55.484031)
			(xy 64.705248 -55.514587) (xy 64.742008 -55.551346) (xy 64.772565 -55.593402) (xy 64.796166 -55.639721)
			(xy 64.81223 -55.689162) (xy 64.820363 -55.740507) (xy 64.820363 -55.792493) (xy 64.81223 -55.843838)
			(xy 64.796166 -55.893279) (xy 64.772565 -55.939598) (xy 64.742008 -55.981654) (xy 64.705248 -56.018413)
			(xy 64.663191 -56.048969) (xy 64.616871 -56.072569) (xy 64.56743 -56.088632) (xy 64.516085 -56.096763)
			(xy 64.490092 -56.09717) (xy 64.467053 -56.096806) (xy 64.421419 -56.090426) (xy 64.39916 -56.08447)
			(xy 64.389065 -56.082155) (xy 64.368559 -56.084905) (xy 64.350801 -56.095523) (xy 64.338672 -56.112285)
			(xy 64.33414 -56.132473) (xy 64.33794 -56.152811) (xy 64.34328 -56.161686) (xy 64.351219 -56.173738)
			(xy 64.365083 -56.199053) (xy 64.370966 -56.212232) (xy 64.375991 -56.222625) (xy 64.393407 -56.237739)
			(xy 64.415689 -56.243679) (xy 64.4271 -56.24195) (xy 64.442692 -56.239103) (xy 64.474243 -56.236053)
			(xy 64.490092 -56.235854) (xy 64.516081 -56.236363) (xy 64.567418 -56.244492) (xy 64.616852 -56.260552)
			(xy 64.663166 -56.284147) (xy 64.705218 -56.314696) (xy 64.741974 -56.351447) (xy 64.772529 -56.393495)
			(xy 64.79613 -56.439805) (xy 64.812197 -56.489237) (xy 64.820333 -56.540573) (xy 64.8208 -56.566562)
			(xy 64.820244 -56.593845) (xy 64.81129 -56.64767) (xy 64.793619 -56.699295) (xy 64.767711 -56.747317)
			(xy 64.734269 -56.790433) (xy 64.694201 -56.827473) (xy 64.671702 -56.842914) (xy 64.659439 -56.851648)
			(xy 64.640231 -56.874811) (xy 64.628596 -56.902562) (xy 64.625541 -56.932497) (xy 64.63133 -56.962026)
			(xy 64.645463 -56.988592) (xy 64.6557 -56.999632) (xy 65.28054 -57.624472) (xy 65.7352 -57.624472)
			(xy 65.759791 -57.624929) (xy 65.808368 -57.632625) (xy 65.855142 -57.647828) (xy 65.89896 -57.670162)
			(xy 65.938745 -57.699078) (xy 65.956434 -57.716166) (xy 66.104008 -57.86374) (xy 69.35978 -57.86374)
		)
		(stroke
			(width 0)
			(type solid)
		)
		(fill yes)
		(layer "B.Cu")
		(net "GND")
	)
	(gr_poly
		(pts
			(xy 42.782236 -59.581034) (xy 42.782729 -59.59141) (xy 42.790927 -59.610473) (xy 42.805979 -59.624758)
			(xy 42.825446 -59.631947) (xy 42.83583 -59.631834) (xy 42.853864 -59.631072) (xy 43.43146 -59.631072)
			(xy 43.502072 -59.56046) (xy 43.502072 -59.3598) (xy 43.502529 -59.335209) (xy 43.510225 -59.286632)
			(xy 43.525428 -59.239858) (xy 43.547762 -59.19604) (xy 43.576678 -59.156255) (xy 43.593766 -59.138566)
			(xy 43.806364 -58.925968) (xy 43.824077 -58.908918) (xy 43.863866 -58.880043) (xy 43.907685 -58.857752)
			(xy 43.954452 -58.842595) (xy 44.003016 -58.834945) (xy 44.027598 -58.834528) (xy 44.442126 -58.834528)
			(xy 44.462282 -58.815868) (xy 44.506491 -58.78327) (xy 44.554475 -58.756538) (xy 44.605461 -58.736106)
			(xy 44.658626 -58.722301) (xy 44.713112 -58.715348) (xy 44.740576 -58.714894) (xy 44.772838 -58.71549)
			(xy 44.836645 -58.725079) (xy 44.898318 -58.744047) (xy 44.956485 -58.771973) (xy 45.009854 -58.808237)
			(xy 45.033946 -58.829702) (xy 45.048424 -58.843164) (xy 45.093636 -58.843164) (xy 45.27677 -58.66003)
			(xy 45.286071 -58.650128) (xy 45.299537 -58.626546) (xy 45.306304 -58.600246) (xy 45.305893 -58.573093)
			(xy 45.298333 -58.54701) (xy 45.284159 -58.523846) (xy 45.264377 -58.505242) (xy 45.240387 -58.492516)
			(xy 45.22724 -58.489088) (xy 45.203141 -58.483207) (xy 45.156918 -58.465206) (xy 45.113901 -58.440505)
			(xy 45.075055 -58.409657) (xy 45.041251 -58.373354) (xy 45.013247 -58.33241) (xy 44.991671 -58.287744)
			(xy 44.977007 -58.240356) (xy 44.969584 -58.19131) (xy 44.969176 -58.166508) (xy 44.969685 -58.14052)
			(xy 44.977814 -58.089184) (xy 44.993874 -58.039751) (xy 45.01747 -57.993439) (xy 45.048019 -57.951389)
			(xy 45.08477 -57.914635) (xy 45.126819 -57.884082) (xy 45.173129 -57.860484) (xy 45.22256 -57.84442)
			(xy 45.273896 -57.836287) (xy 45.299884 -57.8358) (xy 45.325899 -57.836284) (xy 45.377286 -57.844426)
			(xy 45.426766 -57.860512) (xy 45.473118 -57.884146) (xy 45.494448 -57.899046) (xy 45.5295 -57.9247)
			(xy 45.857922 -57.596278) (xy 45.832522 -57.561226) (xy 45.817566 -57.539883) (xy 45.793846 -57.49348)
			(xy 45.777694 -57.443932) (xy 45.769508 -57.392465) (xy 45.769022 -57.366408) (xy 45.769532 -57.340421)
			(xy 45.777662 -57.289086) (xy 45.793723 -57.239656) (xy 45.817319 -57.193346) (xy 45.847869 -57.151298)
			(xy 45.88462 -57.114547) (xy 45.926668 -57.083997) (xy 45.972978 -57.060401) (xy 46.022408 -57.04434)
			(xy 46.073743 -57.03621) (xy 46.125717 -57.03621) (xy 46.177052 -57.04434) (xy 46.226482 -57.060401)
			(xy 46.272792 -57.083997) (xy 46.31484 -57.114547) (xy 46.351591 -57.151298) (xy 46.382141 -57.193346)
			(xy 46.405737 -57.239656) (xy 46.421798 -57.289086) (xy 46.429928 -57.340421) (xy 46.430438 -57.366408)
			(xy 46.430184 -57.381902) (xy 46.428914 -57.404254) (xy 46.48073 -57.45607) (xy 46.568614 -57.368186)
			(xy 46.56963 -57.348882) (xy 46.571585 -57.322024) (xy 46.583114 -57.269426) (xy 46.603013 -57.21939)
			(xy 46.630758 -57.173241) (xy 46.665614 -57.132197) (xy 46.70666 -57.097344) (xy 46.752811 -57.069603)
			(xy 46.802848 -57.049707) (xy 46.855447 -57.038182) (xy 46.882304 -57.036208) (xy 46.901608 -57.035192)
			(xy 46.989238 -56.947562) (xy 46.937422 -56.896) (xy 46.91507 -56.897016) (xy 46.89983 -56.89727)
			(xy 46.873846 -56.896762) (xy 46.822517 -56.888638) (xy 46.773091 -56.872583) (xy 46.726785 -56.848994)
			(xy 46.684739 -56.818452) (xy 46.647988 -56.781709) (xy 46.617438 -56.739669) (xy 46.593841 -56.693367)
			(xy 46.577777 -56.643944) (xy 46.569642 -56.592617) (xy 46.569637 -56.540649) (xy 46.577762 -56.48932)
			(xy 46.593816 -56.439893) (xy 46.617404 -56.393587) (xy 46.647946 -56.351541) (xy 46.684689 -56.31479)
			(xy 46.726729 -56.28424) (xy 46.77303 -56.260642) (xy 46.822453 -56.244578) (xy 46.873781 -56.236443)
			(xy 46.925749 -56.236437) (xy 46.977078 -56.244561) (xy 47.026504 -56.260615) (xy 47.072811 -56.284203)
			(xy 47.114857 -56.314744) (xy 47.151608 -56.351487) (xy 47.182159 -56.393527) (xy 47.205757 -56.439828)
			(xy 47.221822 -56.489251) (xy 47.229957 -56.540578) (xy 47.230538 -56.566562) (xy 47.230284 -56.581802)
			(xy 47.229268 -56.604154) (xy 47.28083 -56.65597) (xy 47.36846 -56.56834) (xy 47.369476 -56.549036)
			(xy 47.371275 -56.523988) (xy 47.38149 -56.474821) (xy 47.399019 -56.427764) (xy 47.42346 -56.383896)
			(xy 47.45425 -56.344227) (xy 47.490682 -56.309667) (xy 47.53192 -56.281011) (xy 47.577015 -56.258918)
			(xy 47.624931 -56.243894) (xy 47.674568 -56.236285) (xy 47.699676 -56.235854) (xy 47.725946 -56.236365)
			(xy 47.777822 -56.244683) (xy 47.827732 -56.261098) (xy 47.851314 -56.272684) (xy 47.862236 -56.278272)
			(xy 47.9552 -56.278272) (xy 48.115728 -56.4388) (xy 48.193198 -56.4388) (xy 48.207422 -56.411622)
			(xy 48.21983 -56.389193) (xy 48.250497 -56.348125) (xy 48.287135 -56.312281) (xy 48.328865 -56.28252)
			(xy 48.374687 -56.259556) (xy 48.423505 -56.243937) (xy 48.474148 -56.236039) (xy 48.499776 -56.2356)
			(xy 48.525314 -56.236074) (xy 48.575782 -56.243928) (xy 48.624441 -56.259452) (xy 48.670133 -56.282278)
			(xy 48.711769 -56.311861) (xy 48.730408 -56.329326) (xy 48.766222 -56.364378) (xy 48.8442 -56.2864)
			(xy 48.8442 -55.619904) (xy 48.837596 -55.6133) (xy 48.528732 -55.6133) (xy 48.332644 -55.417212)
			(xy 48.332644 -55.004208) (xy 46.430692 -55.004208) (xy 46.421294 -55.04307) (xy 46.414803 -55.06827)
			(xy 46.394983 -55.116383) (xy 46.367869 -55.160796) (xy 46.334131 -55.200412) (xy 46.294602 -55.234252)
			(xy 46.250259 -55.261481) (xy 46.202198 -55.281425) (xy 46.151605 -55.293592) (xy 46.09973 -55.297681)
			(xy 46.047855 -55.293592) (xy 45.997262 -55.281425) (xy 45.949201 -55.261481) (xy 45.904858 -55.234252)
			(xy 45.865329 -55.200412) (xy 45.831591 -55.160796) (xy 45.804477 -55.116383) (xy 45.784657 -55.06827)
			(xy 45.778166 -55.04307) (xy 45.768768 -55.004208) (xy 45.489114 -55.004208) (xy 45.411644 -55.081678)
			(xy 45.411644 -55.185564) (xy 45.3517 -55.185564) (xy 45.3517 -55.710836) (xy 45.411644 -55.710836)
			(xy 45.411644 -55.792449) (xy 45.769532 -55.792449) (xy 45.769532 -55.740475) (xy 45.777662 -55.68914)
			(xy 45.793723 -55.63971) (xy 45.817319 -55.5934) (xy 45.847869 -55.551352) (xy 45.88462 -55.514601)
			(xy 45.926668 -55.484051) (xy 45.972978 -55.460455) (xy 46.022408 -55.444394) (xy 46.073743 -55.436264)
			(xy 46.125717 -55.436264) (xy 46.177052 -55.444394) (xy 46.226482 -55.460455) (xy 46.272792 -55.484051)
			(xy 46.31484 -55.514601) (xy 46.351591 -55.551352) (xy 46.382141 -55.5934) (xy 46.405737 -55.63971)
			(xy 46.421798 -55.68914) (xy 46.429928 -55.740475) (xy 46.430438 -55.766462) (xy 46.429928 -55.792449)
			(xy 46.569632 -55.792449) (xy 46.569632 -55.740475) (xy 46.577762 -55.68914) (xy 46.593823 -55.63971)
			(xy 46.617419 -55.5934) (xy 46.647969 -55.551352) (xy 46.68472 -55.514601) (xy 46.726768 -55.484051)
			(xy 46.773078 -55.460455) (xy 46.822508 -55.444394) (xy 46.873843 -55.436264) (xy 46.925817 -55.436264)
			(xy 46.977152 -55.444394) (xy 47.026582 -55.460455) (xy 47.072892 -55.484051) (xy 47.11494 -55.514601)
			(xy 47.151691 -55.551352) (xy 47.182241 -55.5934) (xy 47.205837 -55.63971) (xy 47.221898 -55.68914)
			(xy 47.230028 -55.740475) (xy 47.230538 -55.766462) (xy 47.230028 -55.792449) (xy 47.369478 -55.792449)
			(xy 47.369478 -55.740475) (xy 47.377608 -55.68914) (xy 47.393669 -55.63971) (xy 47.417265 -55.5934)
			(xy 47.447815 -55.551352) (xy 47.484566 -55.514601) (xy 47.526614 -55.484051) (xy 47.572924 -55.460455)
			(xy 47.622354 -55.444394) (xy 47.673689 -55.436264) (xy 47.725663 -55.436264) (xy 47.776998 -55.444394)
			(xy 47.826428 -55.460455) (xy 47.872738 -55.484051) (xy 47.914786 -55.514601) (xy 47.951537 -55.551352)
			(xy 47.982087 -55.5934) (xy 48.005683 -55.63971) (xy 48.021744 -55.68914) (xy 48.029874 -55.740475)
			(xy 48.030384 -55.766462) (xy 48.029874 -55.792449) (xy 48.021744 -55.843784) (xy 48.005683 -55.893214)
			(xy 47.982087 -55.939524) (xy 47.951537 -55.981572) (xy 47.914786 -56.018323) (xy 47.872738 -56.048873)
			(xy 47.826428 -56.072469) (xy 47.776998 -56.08853) (xy 47.725663 -56.09666) (xy 47.673689 -56.09666)
			(xy 47.622354 -56.08853) (xy 47.572924 -56.072469) (xy 47.526614 -56.048873) (xy 47.484566 -56.018323)
			(xy 47.447815 -55.981572) (xy 47.417265 -55.939524) (xy 47.393669 -55.893214) (xy 47.377608 -55.843784)
			(xy 47.369478 -55.792449) (xy 47.230028 -55.792449) (xy 47.221898 -55.843784) (xy 47.205837 -55.893214)
			(xy 47.182241 -55.939524) (xy 47.151691 -55.981572) (xy 47.11494 -56.018323) (xy 47.072892 -56.048873)
			(xy 47.026582 -56.072469) (xy 46.977152 -56.08853) (xy 46.925817 -56.09666) (xy 46.873843 -56.09666)
			(xy 46.822508 -56.08853) (xy 46.773078 -56.072469) (xy 46.726768 -56.048873) (xy 46.68472 -56.018323)
			(xy 46.647969 -55.981572) (xy 46.617419 -55.939524) (xy 46.593823 -55.893214) (xy 46.577762 -55.843784)
			(xy 46.569632 -55.792449) (xy 46.429928 -55.792449) (xy 46.421798 -55.843784) (xy 46.405737 -55.893214)
			(xy 46.382141 -55.939524) (xy 46.351591 -55.981572) (xy 46.31484 -56.018323) (xy 46.272792 -56.048873)
			(xy 46.226482 -56.072469) (xy 46.177052 -56.08853) (xy 46.125717 -56.09666) (xy 46.073743 -56.09666)
			(xy 46.022408 -56.08853) (xy 45.972978 -56.072469) (xy 45.926668 -56.048873) (xy 45.88462 -56.018323)
			(xy 45.847869 -55.981572) (xy 45.817319 -55.939524) (xy 45.793723 -55.893214) (xy 45.777662 -55.843784)
			(xy 45.769532 -55.792449) (xy 45.411644 -55.792449) (xy 45.411644 -55.978298) (xy 45.411125 -56.000623)
			(xy 45.402371 -56.044407) (xy 45.385202 -56.085625) (xy 45.360286 -56.122677) (xy 45.328588 -56.154125)
			(xy 45.29134 -56.178747) (xy 45.249987 -56.195588) (xy 45.206135 -56.203995) (xy 45.183806 -56.204358)
			(xy 45.183806 -56.204104) (xy 44.962318 -56.204104) (xy 44.574023 -56.592549) (xy 45.769532 -56.592549)
			(xy 45.769532 -56.540575) (xy 45.777662 -56.48924) (xy 45.793723 -56.43981) (xy 45.817319 -56.3935)
			(xy 45.847869 -56.351452) (xy 45.88462 -56.314701) (xy 45.926668 -56.284151) (xy 45.972978 -56.260555)
			(xy 46.022408 -56.244494) (xy 46.073743 -56.236364) (xy 46.125717 -56.236364) (xy 46.177052 -56.244494)
			(xy 46.226482 -56.260555) (xy 46.272792 -56.284151) (xy 46.31484 -56.314701) (xy 46.351591 -56.351452)
			(xy 46.382141 -56.3935) (xy 46.405737 -56.43981) (xy 46.421798 -56.48924) (xy 46.429928 -56.540575)
			(xy 46.430438 -56.566562) (xy 46.429928 -56.592549) (xy 46.421798 -56.643884) (xy 46.405737 -56.693314)
			(xy 46.382141 -56.739624) (xy 46.351591 -56.781672) (xy 46.31484 -56.818423) (xy 46.272792 -56.848973)
			(xy 46.226482 -56.872569) (xy 46.177052 -56.88863) (xy 46.125717 -56.89676) (xy 46.073743 -56.89676)
			(xy 46.022408 -56.88863) (xy 45.972978 -56.872569) (xy 45.926668 -56.848973) (xy 45.88462 -56.818423)
			(xy 45.847869 -56.781672) (xy 45.817319 -56.739624) (xy 45.793723 -56.693314) (xy 45.777662 -56.643884)
			(xy 45.769532 -56.592549) (xy 44.574023 -56.592549) (xy 44.305728 -56.860948) (xy 44.305728 -56.933592)
			(xy 44.330554 -56.946733) (xy 44.376087 -56.979625) (xy 44.415898 -57.019251) (xy 44.449001 -57.064631)
			(xy 44.474577 -57.11464) (xy 44.491993 -57.168042) (xy 44.500818 -57.223515) (xy 44.501308 -57.2516)
			(xy 44.50081 -57.278249) (xy 44.492867 -57.330953) (xy 44.477157 -57.381883) (xy 44.472095 -57.392395)
			(xy 44.969686 -57.392395) (xy 44.969686 -57.340421) (xy 44.977816 -57.289086) (xy 44.993877 -57.239656)
			(xy 45.017473 -57.193346) (xy 45.048023 -57.151298) (xy 45.084774 -57.114547) (xy 45.126822 -57.083997)
			(xy 45.173132 -57.060401) (xy 45.222562 -57.04434) (xy 45.273897 -57.03621) (xy 45.325871 -57.03621)
			(xy 45.377206 -57.04434) (xy 45.426636 -57.060401) (xy 45.472946 -57.083997) (xy 45.514994 -57.114547)
			(xy 45.551745 -57.151298) (xy 45.582295 -57.193346) (xy 45.605891 -57.239656) (xy 45.621952 -57.289086)
			(xy 45.630082 -57.340421) (xy 45.630592 -57.366408) (xy 45.630082 -57.392395) (xy 45.621952 -57.44373)
			(xy 45.605891 -57.49316) (xy 45.582295 -57.53947) (xy 45.551745 -57.581518) (xy 45.514994 -57.618269)
			(xy 45.472946 -57.648819) (xy 45.426636 -57.672415) (xy 45.377206 -57.688476) (xy 45.325871 -57.696606)
			(xy 45.273897 -57.696606) (xy 45.222562 -57.688476) (xy 45.173132 -57.672415) (xy 45.126822 -57.648819)
			(xy 45.084774 -57.618269) (xy 45.048023 -57.581518) (xy 45.017473 -57.53947) (xy 44.993877 -57.49316)
			(xy 44.977816 -57.44373) (xy 44.969686 -57.392395) (xy 44.472095 -57.392395) (xy 44.454031 -57.429904)
			(xy 44.424007 -57.473941) (xy 44.387755 -57.513012) (xy 44.346084 -57.546243) (xy 44.299926 -57.572892)
			(xy 44.250312 -57.592364) (xy 44.19835 -57.604224) (xy 44.1452 -57.608208) (xy 44.09205 -57.604224)
			(xy 44.040088 -57.592364) (xy 43.990474 -57.572892) (xy 43.944316 -57.546243) (xy 43.902645 -57.513012)
			(xy 43.866393 -57.473941) (xy 43.836369 -57.429904) (xy 43.813243 -57.381883) (xy 43.797533 -57.330953)
			(xy 43.78959 -57.278249) (xy 43.789092 -57.2516) (xy 43.789619 -57.223516) (xy 43.798432 -57.168044)
			(xy 43.815838 -57.114641) (xy 43.841408 -57.06463) (xy 43.874508 -57.019251) (xy 43.914317 -56.979627)
			(xy 43.95985 -56.94674) (xy 43.984672 -56.933592) (xy 43.984672 -56.7944) (xy 43.985058 -56.778627)
			(xy 43.991213 -56.747688) (xy 44.003284 -56.718544) (xy 44.02081 -56.692316) (xy 44.031662 -56.680862)
			(xy 44.151296 -56.561482) (xy 44.161533 -56.550504) (xy 44.175686 -56.524051) (xy 44.181546 -56.494628)
			(xy 44.178607 -56.464771) (xy 44.167123 -56.437055) (xy 44.148083 -56.41387) (xy 44.12313 -56.397215)
			(xy 44.094415 -56.388525) (xy 44.079414 -56.388) (xy 43.981116 -56.388) (xy 43.96994 -56.394096)
			(xy 43.942031 -56.408322) (xy 43.882722 -56.428477) (xy 43.82092 -56.438682) (xy 43.7896 -56.439308)
			(xy 43.764582 -56.438913) (xy 43.714976 -56.432365) (xy 43.666653 -56.419382) (xy 43.620445 -56.400187)
			(xy 43.598592 -56.388) (xy 43.053 -56.388) (xy 42.846752 -56.594248) (xy 42.843958 -56.609742) (xy 42.838606 -56.636162)
			(xy 42.82144 -56.687261) (xy 42.797234 -56.735425) (xy 42.782236 -56.757824) (xy 42.782236 -58.192495)
			(xy 44.169586 -58.192495) (xy 44.169586 -58.140521) (xy 44.177716 -58.089186) (xy 44.193777 -58.039756)
			(xy 44.217373 -57.993446) (xy 44.247923 -57.951398) (xy 44.284674 -57.914647) (xy 44.326722 -57.884097)
			(xy 44.373032 -57.860501) (xy 44.422462 -57.84444) (xy 44.473797 -57.83631) (xy 44.525771 -57.83631)
			(xy 44.577106 -57.84444) (xy 44.626536 -57.860501) (xy 44.672846 -57.884097) (xy 44.714894 -57.914647)
			(xy 44.751645 -57.951398) (xy 44.782195 -57.993446) (xy 44.805791 -58.039756) (xy 44.821852 -58.089186)
			(xy 44.829982 -58.140521) (xy 44.830492 -58.166508) (xy 44.829982 -58.192495) (xy 44.821852 -58.24383)
			(xy 44.805791 -58.29326) (xy 44.782195 -58.33957) (xy 44.751645 -58.381618) (xy 44.714894 -58.418369)
			(xy 44.672846 -58.448919) (xy 44.626536 -58.472515) (xy 44.577106 -58.488576) (xy 44.525771 -58.496706)
			(xy 44.473797 -58.496706) (xy 44.422462 -58.488576) (xy 44.373032 -58.472515) (xy 44.326722 -58.448919)
			(xy 44.284674 -58.418369) (xy 44.247923 -58.381618) (xy 44.217373 -58.33957) (xy 44.193777 -58.29326)
			(xy 44.177716 -58.24383) (xy 44.169586 -58.192495) (xy 42.782236 -58.192495)
		)
		(stroke
			(width 0)
			(type solid)
		)
		(fill yes)
		(layer "B.Cu")
		(net "A_BMC_ADCAV33")
	)
	(gr_poly
		(pts
			(xy 2.725674 -79.758794) (xy 7.747254 -79.758794) (xy 7.77519 -79.755566) (xy 7.831419 -79.756378)
			(xy 7.886919 -79.765434) (xy 7.94049 -79.782539) (xy 7.99097 -79.80732) (xy 8.037265 -79.839243)
			(xy 8.078375 -79.877614) (xy 8.113407 -79.921604) (xy 8.141603 -79.970259) (xy 8.162353 -80.022525)
			(xy 8.175207 -80.077271) (xy 8.178038 -80.10525) (xy 8.179835 -80.120284) (xy 8.191057 -80.148388)
			(xy 8.210026 -80.171967) (xy 8.235073 -80.188949) (xy 8.263999 -80.197841) (xy 8.27913 -80.198468)
			(xy 10.885678 -80.198468) (xy 10.89533 -80.19415) (xy 10.919653 -80.183957) (xy 10.970396 -80.169595)
			(xy 11.022632 -80.162339) (xy 11.049 -80.161892) (xy 11.056874 -80.161892) (xy 11.078464 -80.1624)
			(xy 11.808968 -79.431896) (xy 12.201906 -79.431896) (xy 12.29868 -79.335122) (xy 12.29868 -78.259432)
			(xy 12.102338 -78.06309) (xy 3.189478 -78.06309) (xy 3.183382 -78.069186) (xy 3.153156 -78.069186)
			(xy 2.830068 -77.746098) (xy 2.830068 -75.737212) (xy 3.265932 -75.301348) (xy 11.729974 -75.301348)
			(xy 12.470638 -74.560684) (xy 12.470638 -65.51676) (xy 11.29411 -64.340232) (xy 11.29411 -60.0964)
			(xy 8.03783 -56.84012) (xy 8.03783 -50.623978) (xy 5.46354 -48.049688) (xy 4.959096 -48.049688) (xy 4.953508 -48.050958)
			(xy 4.928324 -48.05633) (xy 4.877148 -48.062055) (xy 4.8514 -48.062388) (xy 4.821432 -48.061898)
			(xy 4.76201 -48.054075) (xy 4.704117 -48.038562) (xy 4.648744 -48.015626) (xy 4.596838 -47.985659)
			(xy 4.549288 -47.949172) (xy 4.506908 -47.906792) (xy 4.470421 -47.859242) (xy 4.440454 -47.807336)
			(xy 4.417518 -47.751963) (xy 4.402005 -47.69407) (xy 4.394182 -47.634648) (xy 4.394182 -47.574712)
			(xy 4.402005 -47.51529) (xy 4.417518 -47.457397) (xy 4.440454 -47.402024) (xy 4.470421 -47.350118)
			(xy 4.506908 -47.302568) (xy 4.549288 -47.260188) (xy 4.596838 -47.223701) (xy 4.648744 -47.193734)
			(xy 4.704117 -47.170798) (xy 4.76201 -47.155285) (xy 4.821432 -47.147462) (xy 4.8514 -47.146972)
			(xy 4.877149 -47.147291) (xy 4.928327 -47.153015) (xy 4.953508 -47.158402) (xy 4.959096 -47.159672)
			(xy 5.64769 -47.159672) (xy 5.676574 -47.160128) (xy 5.733855 -47.167605) (xy 5.789683 -47.182448)
			(xy 5.843115 -47.204405) (xy 5.868416 -47.218346) (xy 6.1468 -47.218346) (xy 8.739882 -49.811428)
			(xy 9.552414 -49.811428) (xy 9.552414 -49.751492) (xy 9.560237 -49.69207) (xy 9.57575 -49.634177)
			(xy 9.598686 -49.578804) (xy 9.628653 -49.526898) (xy 9.66514 -49.479348) (xy 9.70752 -49.436968)
			(xy 9.75507 -49.400481) (xy 9.806976 -49.370514) (xy 9.862349 -49.347578) (xy 9.920242 -49.332065)
			(xy 9.979664 -49.324242) (xy 10.0396 -49.324242) (xy 10.099022 -49.332065) (xy 10.156915 -49.347578)
			(xy 10.212288 -49.370514) (xy 10.264194 -49.400481) (xy 10.311744 -49.436968) (xy 10.354124 -49.479348)
			(xy 10.390611 -49.526898) (xy 10.420578 -49.578804) (xy 10.443514 -49.634177) (xy 10.459027 -49.69207)
			(xy 10.46685 -49.751492) (xy 10.46734 -49.78146) (xy 10.46685 -49.811428) (xy 10.459027 -49.87085)
			(xy 10.443514 -49.928743) (xy 10.420578 -49.984116) (xy 10.390611 -50.036022) (xy 10.354124 -50.083572)
			(xy 10.311744 -50.125952) (xy 10.264194 -50.162439) (xy 10.212288 -50.192406) (xy 10.156915 -50.215342)
			(xy 10.099022 -50.230855) (xy 10.0396 -50.238678) (xy 9.979664 -50.238678) (xy 9.920242 -50.230855)
			(xy 9.862349 -50.215342) (xy 9.806976 -50.192406) (xy 9.75507 -50.162439) (xy 9.70752 -50.125952)
			(xy 9.66514 -50.083572) (xy 9.628653 -50.036022) (xy 9.598686 -49.984116) (xy 9.57575 -49.928743)
			(xy 9.560237 -49.87085) (xy 9.552414 -49.811428) (xy 8.739882 -49.811428) (xy 9.40308 -50.474626)
			(xy 11.56716 -50.474626) (xy 12.86002 -49.18202) (xy 12.86002 -47.543974) (xy 12.859512 -47.540164)
			(xy 12.857142 -47.523373) (xy 12.854599 -47.489556) (xy 12.854432 -47.4726) (xy 12.85461 -47.455644)
			(xy 12.857155 -47.421828) (xy 12.859512 -47.405036) (xy 12.86002 -47.401226) (xy 12.86002 -47.161958)
			(xy 13.793978 -46.228) (xy 13.793978 -37.415978) (xy 12.609068 -36.231068) (xy 5.408422 -36.231068)
			(xy 5.072126 -35.894772) (xy 5.072126 -34.561526) (xy 4.0894 -33.5788) (xy 4.0894 -32.1056) (xy 4.407662 -31.787338)
			(xy 13.441934 -31.787338) (xy 13.530072 -31.6992) (xy 13.530072 -30.613604) (xy 13.445998 -30.52953)
			(xy 12.248134 -30.52953) (xy 12.116054 -30.39745) (xy 1.696212 -30.39745) (xy 1.288542 -30.80512)
			(xy 1.288542 -57.700672) (xy 3.66268 -57.700672) (xy 3.663192 -57.671933) (xy 3.671818 -57.615105)
			(xy 3.688871 -57.560214) (xy 3.713965 -57.508503) (xy 3.746532 -57.461141) (xy 3.765804 -57.439814)
			(xy 3.7759 -57.428301) (xy 3.789235 -57.400746) (xy 3.793813 -57.370479) (xy 3.789223 -57.340214)
			(xy 3.775877 -57.312665) (xy 3.765804 -57.30113) (xy 3.746531 -57.279804) (xy 3.713963 -57.232443)
			(xy 3.68887 -57.180731) (xy 3.67182 -57.12584) (xy 3.6632 -57.069011) (xy 3.66268 -57.040272) (xy 3.663152 -57.013021)
			(xy 3.670912 -56.959073) (xy 3.68627 -56.906779) (xy 3.708913 -56.857202) (xy 3.738381 -56.811353)
			(xy 3.774074 -56.770163) (xy 3.815265 -56.734472) (xy 3.861116 -56.705006) (xy 3.910694 -56.682364)
			(xy 3.962989 -56.667008) (xy 4.016937 -56.659251) (xy 4.044188 -56.658764) (xy 4.071559 -56.659221)
			(xy 4.125739 -56.667039) (xy 4.178243 -56.682529) (xy 4.227989 -56.705373) (xy 4.273955 -56.735101)
			(xy 4.294886 -56.752744) (xy 4.306214 -56.76198) (xy 4.332771 -56.774156) (xy 4.361688 -56.778329)
			(xy 4.390605 -56.774156) (xy 4.417162 -56.76198) (xy 4.42849 -56.752744) (xy 4.449421 -56.735103)
			(xy 4.495393 -56.70539) (xy 4.545141 -56.682554) (xy 4.597642 -56.667063) (xy 4.651819 -56.659237)
			(xy 4.679188 -56.658764) (xy 4.706616 -56.659242) (xy 4.760907 -56.667089) (xy 4.813517 -56.682621)
			(xy 4.863364 -56.705521) (xy 4.909422 -56.735316) (xy 4.930394 -56.752998) (xy 4.942157 -56.76259)
			(xy 4.969832 -56.775014) (xy 4.999938 -56.778749) (xy 5.02981 -56.773463) (xy 5.056805 -56.759623)
			(xy 5.068062 -56.749442) (xy 5.089545 -56.729303) (xy 5.137575 -56.695239) (xy 5.190269 -56.668958)
			(xy 5.246373 -56.651083) (xy 5.304558 -56.642038) (xy 5.334 -56.641492) (xy 5.361251 -56.641978)
			(xy 5.415199 -56.649734) (xy 5.467494 -56.665089) (xy 5.517071 -56.687731) (xy 5.562921 -56.717197)
			(xy 5.604112 -56.752888) (xy 5.639803 -56.794079) (xy 5.669269 -56.839929) (xy 5.691911 -56.889506)
			(xy 5.707266 -56.941801) (xy 5.715022 -56.995749) (xy 5.715508 -57.023) (xy 5.71504 -57.05037) (xy 5.707222 -57.104549)
			(xy 5.691734 -57.157052) (xy 5.668892 -57.206799) (xy 5.639169 -57.252766) (xy 5.621528 -57.273698)
			(xy 5.612289 -57.285024) (xy 5.600108 -57.311582) (xy 5.595934 -57.3405) (xy 5.600108 -57.369418)
			(xy 5.612289 -57.395976) (xy 5.621528 -57.407302) (xy 5.639186 -57.428219) (xy 5.668894 -57.474196)
			(xy 5.691726 -57.523948) (xy 5.707213 -57.576452) (xy 5.715036 -57.63063) (xy 5.715508 -57.658) (xy 5.715022 -57.685251)
			(xy 5.707266 -57.739199) (xy 5.691911 -57.791494) (xy 5.669269 -57.841071) (xy 5.639803 -57.886921)
			(xy 5.604112 -57.928112) (xy 5.562921 -57.963803) (xy 5.517071 -57.993269) (xy 5.467494 -58.015911)
			(xy 5.415199 -58.031266) (xy 5.361251 -58.039022) (xy 5.334 -58.039508) (xy 5.307991 -58.039038)
			(xy 5.256457 -58.031952) (xy 5.206365 -58.017926) (xy 5.158645 -57.99722) (xy 5.114183 -57.970219)
			(xy 5.093716 -57.954164) (xy 5.081511 -57.945108) (xy 5.053316 -57.933818) (xy 5.023049 -57.931302)
			(xy 4.993377 -57.937782) (xy 4.966914 -57.952685) (xy 4.956048 -57.963308) (xy 4.937987 -57.981766)
			(xy 4.89769 -58.014066) (xy 4.85341 -58.040642) (xy 4.805952 -58.06101) (xy 4.756183 -58.074798)
			(xy 4.70501 -58.081755) (xy 4.679188 -58.08218) (xy 4.651817 -58.081726) (xy 4.597637 -58.073906)
			(xy 4.545134 -58.058414) (xy 4.495387 -58.03557) (xy 4.449421 -58.005843) (xy 4.42849 -57.9882) (xy 4.417162 -57.978964)
			(xy 4.390605 -57.966788) (xy 4.361688 -57.962615) (xy 4.332771 -57.966788) (xy 4.306214 -57.978964)
			(xy 4.294886 -57.9882) (xy 4.273932 -58.005812) (xy 4.227965 -58.035528) (xy 4.178223 -58.058369)
			(xy 4.125728 -58.073867) (xy 4.071556 -58.081702) (xy 4.044188 -58.08218) (xy 4.016937 -58.081694)
			(xy 3.962989 -58.073937) (xy 3.910695 -58.058582) (xy 3.861117 -58.035941) (xy 3.815267 -58.006475)
			(xy 3.774077 -57.970783) (xy 3.738385 -57.929593) (xy 3.708919 -57.883743) (xy 3.686278 -57.834165)
			(xy 3.670923 -57.781871) (xy 3.663166 -57.727923) (xy 3.66268 -57.700672) (xy 1.288542 -57.700672)
			(xy 1.288542 -61.77661) (xy 7.263892 -61.77661) (xy 7.263892 -60.44819) (xy 7.53999 -60.172092) (xy 8.55599 -60.172092)
			(xy 8.78459 -59.943492) (xy 9.24941 -59.943492) (xy 9.550908 -60.24499) (xy 9.550908 -61.52261) (xy 9.07161 -62.001908)
			(xy 7.48919 -62.001908) (xy 7.263892 -61.77661) (xy 1.288542 -61.77661) (xy 1.288542 -63.250568)
			(xy 9.982182 -63.250568) (xy 9.982182 -63.190632) (xy 9.990005 -63.13121) (xy 10.005518 -63.073317)
			(xy 10.028454 -63.017944) (xy 10.058421 -62.966038) (xy 10.094908 -62.918488) (xy 10.137288 -62.876108)
			(xy 10.184838 -62.839621) (xy 10.236744 -62.809654) (xy 10.292117 -62.786718) (xy 10.35001 -62.771205)
			(xy 10.409432 -62.763382) (xy 10.469368 -62.763382) (xy 10.52879 -62.771205) (xy 10.586683 -62.786718)
			(xy 10.642056 -62.809654) (xy 10.693962 -62.839621) (xy 10.741512 -62.876108) (xy 10.783892 -62.918488)
			(xy 10.820379 -62.966038) (xy 10.850346 -63.017944) (xy 10.873282 -63.073317) (xy 10.888795 -63.13121)
			(xy 10.896618 -63.190632) (xy 10.897108 -63.2206) (xy 10.896618 -63.250568) (xy 10.888795 -63.30999)
			(xy 10.873282 -63.367883) (xy 10.850346 -63.423256) (xy 10.820379 -63.475162) (xy 10.783892 -63.522712)
			(xy 10.741512 -63.565092) (xy 10.693962 -63.601579) (xy 10.642056 -63.631546) (xy 10.586683 -63.654482)
			(xy 10.52879 -63.669995) (xy 10.469368 -63.677818) (xy 10.409432 -63.677818) (xy 10.35001 -63.669995)
			(xy 10.292117 -63.654482) (xy 10.236744 -63.631546) (xy 10.184838 -63.601579) (xy 10.137288 -63.565092)
			(xy 10.094908 -63.522712) (xy 10.058421 -63.475162) (xy 10.028454 -63.423256) (xy 10.005518 -63.367883)
			(xy 9.990005 -63.30999) (xy 9.982182 -63.250568) (xy 1.288542 -63.250568) (xy 1.288542 -64.980816)
			(xy 3.877292 -64.980816) (xy 3.877292 -64.92088) (xy 3.885115 -64.861458) (xy 3.900628 -64.803565)
			(xy 3.923564 -64.748192) (xy 3.953531 -64.696286) (xy 3.990018 -64.648736) (xy 4.032398 -64.606356)
			(xy 4.079948 -64.569869) (xy 4.131854 -64.539902) (xy 4.187227 -64.516966) (xy 4.24512 -64.501453)
			(xy 4.304542 -64.49363) (xy 4.364478 -64.49363) (xy 4.4239 -64.501453) (xy 4.481793 -64.516966) (xy 4.537166 -64.539902)
			(xy 4.589072 -64.569869) (xy 4.636622 -64.606356) (xy 4.679002 -64.648736) (xy 4.715489 -64.696286)
			(xy 4.745456 -64.748192) (xy 4.768392 -64.803565) (xy 4.783905 -64.861458) (xy 4.791728 -64.92088)
			(xy 4.792218 -64.950848) (xy 4.791728 -64.980816) (xy 4.783905 -65.040238) (xy 4.768392 -65.098131)
			(xy 4.745456 -65.153504) (xy 4.715489 -65.20541) (xy 4.679002 -65.25296) (xy 4.636622 -65.29534)
			(xy 4.589072 -65.331827) (xy 4.537166 -65.361794) (xy 4.481793 -65.38473) (xy 4.4239 -65.400243)
			(xy 4.364478 -65.408066) (xy 4.304542 -65.408066) (xy 4.24512 -65.400243) (xy 4.187227 -65.38473)
			(xy 4.131854 -65.361794) (xy 4.079948 -65.331827) (xy 4.032398 -65.29534) (xy 3.990018 -65.25296)
			(xy 3.953531 -65.20541) (xy 3.923564 -65.153504) (xy 3.900628 -65.098131) (xy 3.885115 -65.040238)
			(xy 3.877292 -64.980816) (xy 1.288542 -64.980816) (xy 1.288542 -65.756786) (xy 5.817852 -65.756786)
			(xy 5.817852 -65.69685) (xy 5.825675 -65.637428) (xy 5.841188 -65.579535) (xy 5.864124 -65.524162)
			(xy 5.894091 -65.472256) (xy 5.930578 -65.424706) (xy 5.972958 -65.382326) (xy 6.020508 -65.345839)
			(xy 6.072414 -65.315872) (xy 6.127787 -65.292936) (xy 6.18568 -65.277423) (xy 6.245102 -65.2696)
			(xy 6.305038 -65.2696) (xy 6.36446 -65.277423) (xy 6.422353 -65.292936) (xy 6.477726 -65.315872)
			(xy 6.529632 -65.345839) (xy 6.577182 -65.382326) (xy 6.619562 -65.424706) (xy 6.656049 -65.472256)
			(xy 6.686016 -65.524162) (xy 6.708952 -65.579535) (xy 6.724465 -65.637428) (xy 6.732288 -65.69685)
			(xy 6.732778 -65.726818) (xy 6.732288 -65.756786) (xy 6.73095 -65.766946) (xy 9.063972 -65.766946)
			(xy 9.063972 -65.70701) (xy 9.071795 -65.647588) (xy 9.087308 -65.589695) (xy 9.110244 -65.534322)
			(xy 9.140211 -65.482416) (xy 9.176698 -65.434866) (xy 9.219078 -65.392486) (xy 9.266628 -65.355999)
			(xy 9.318534 -65.326032) (xy 9.373907 -65.303096) (xy 9.4318 -65.287583) (xy 9.491222 -65.27976)
			(xy 9.551158 -65.27976) (xy 9.61058 -65.287583) (xy 9.668473 -65.303096) (xy 9.723846 -65.326032)
			(xy 9.775752 -65.355999) (xy 9.823302 -65.392486) (xy 9.865682 -65.434866) (xy 9.902169 -65.482416)
			(xy 9.932136 -65.534322) (xy 9.955072 -65.589695) (xy 9.970585 -65.647588) (xy 9.978408 -65.70701)
			(xy 9.978898 -65.736978) (xy 9.978408 -65.766946) (xy 9.970585 -65.826368) (xy 9.955072 -65.884261)
			(xy 9.932136 -65.939634) (xy 9.902169 -65.99154) (xy 9.865682 -66.03909) (xy 9.823302 -66.08147)
			(xy 9.775752 -66.117957) (xy 9.723846 -66.147924) (xy 9.668473 -66.17086) (xy 9.61058 -66.186373)
			(xy 9.551158 -66.194196) (xy 9.491222 -66.194196) (xy 9.4318 -66.186373) (xy 9.373907 -66.17086)
			(xy 9.318534 -66.147924) (xy 9.266628 -66.117957) (xy 9.219078 -66.08147) (xy 9.176698 -66.03909)
			(xy 9.140211 -65.99154) (xy 9.110244 -65.939634) (xy 9.087308 -65.884261) (xy 9.071795 -65.826368)
			(xy 9.063972 -65.766946) (xy 6.73095 -65.766946) (xy 6.724465 -65.816208) (xy 6.708952 -65.874101)
			(xy 6.686016 -65.929474) (xy 6.656049 -65.98138) (xy 6.619562 -66.02893) (xy 6.577182 -66.07131)
			(xy 6.529632 -66.107797) (xy 6.477726 -66.137764) (xy 6.422353 -66.1607) (xy 6.36446 -66.176213)
			(xy 6.305038 -66.184036) (xy 6.245102 -66.184036) (xy 6.18568 -66.176213) (xy 6.127787 -66.1607)
			(xy 6.072414 -66.137764) (xy 6.020508 -66.107797) (xy 5.972958 -66.07131) (xy 5.930578 -66.02893)
			(xy 5.894091 -65.98138) (xy 5.864124 -65.929474) (xy 5.841188 -65.874101) (xy 5.825675 -65.816208)
			(xy 5.817852 -65.756786) (xy 1.288542 -65.756786) (xy 1.288542 -70.40118) (xy 11.357862 -70.40118)
			(xy 11.361933 -70.345558) (xy 11.374059 -70.291121) (xy 11.393982 -70.23903) (xy 11.421278 -70.190395)
			(xy 11.455364 -70.146252) (xy 11.495513 -70.107543) (xy 11.540871 -70.075092) (xy 11.590471 -70.049591)
			(xy 11.643255 -70.031584) (xy 11.698098 -70.021454) (xy 11.753832 -70.019417) (xy 11.809269 -70.025517)
			(xy 11.863226 -70.039623) (xy 11.914555 -70.061435) (xy 11.962161 -70.090489) (xy 12.005029 -70.126164)
			(xy 12.042246 -70.167701) (xy 12.073019 -70.214214) (xy 12.096691 -70.264711) (xy 12.112759 -70.318118)
			(xy 12.120879 -70.373294) (xy 12.121388 -70.40118) (xy 12.120879 -70.429066) (xy 12.112759 -70.484242)
			(xy 12.096691 -70.537649) (xy 12.073019 -70.588146) (xy 12.042246 -70.634659) (xy 12.005029 -70.676196)
			(xy 11.962161 -70.711871) (xy 11.914555 -70.740925) (xy 11.863226 -70.762737) (xy 11.809269 -70.776843)
			(xy 11.753832 -70.782943) (xy 11.698098 -70.780906) (xy 11.643255 -70.770776) (xy 11.590471 -70.752769)
			(xy 11.540871 -70.727268) (xy 11.495513 -70.694817) (xy 11.455364 -70.656108) (xy 11.421278 -70.611965)
			(xy 11.393982 -70.56333) (xy 11.374059 -70.511239) (xy 11.361933 -70.456802) (xy 11.357862 -70.40118)
			(xy 1.288542 -70.40118) (xy 1.288542 -79.985362) (xy 1.501648 -80.198468) (xy 2.286 -80.198468)
		)
		(stroke
			(width 0)
			(type solid)
		)
		(fill yes)
		(layer "B.Cu")
		(net "GND")
	)
	(gr_poly
		(pts
			(xy 22.0218 -89.3572) (xy 22.040499 -89.339328) (xy 22.082423 -89.309036) (xy 22.128554 -89.285645)
			(xy 22.177766 -89.269726) (xy 22.228857 -89.261668) (xy 22.280579 -89.261668) (xy 22.33167 -89.269726)
			(xy 22.380882 -89.285645) (xy 22.427013 -89.309036) (xy 22.468937 -89.339328) (xy 22.487636 -89.3572)
			(xy 22.821646 -89.3572) (xy 22.840343 -89.339326) (xy 22.882265 -89.309029) (xy 22.928396 -89.285636)
			(xy 22.977609 -89.269719) (xy 23.028702 -89.261668) (xy 23.054564 -89.261188) (xy 23.078573 -89.261614)
			(xy 23.126087 -89.268553) (xy 23.172097 -89.282291) (xy 23.215637 -89.302538) (xy 23.255792 -89.328869)
			(xy 23.27402 -89.3445) (xy 23.288244 -89.3572) (xy 23.368 -89.3572) (xy 23.622 -89.1032) (xy 23.622 -89.027508)
			(xy 23.609046 -89.01303) (xy 23.593115 -88.994734) (xy 23.566233 -88.95435) (xy 23.545542 -88.910471)
			(xy 23.531486 -88.86404) (xy 23.524367 -88.816052) (xy 23.523956 -88.791796) (xy 23.524497 -88.764259)
			(xy 23.533609 -88.709946) (xy 23.551597 -88.657893) (xy 23.577962 -88.609542) (xy 23.611977 -88.566229)
			(xy 23.652699 -88.529152) (xy 23.699004 -88.499338) (xy 23.724108 -88.488012) (xy 23.732998 -88.484202)
			(xy 24.003 -88.2142) (xy 24.003 -87.0712) (xy 24.882094 -86.192106) (xy 24.856948 -86.157054) (xy 24.840926 -86.13378)
			(xy 24.815507 -86.083319) (xy 24.798195 -86.029535) (xy 24.789404 -85.973722) (xy 24.788876 -85.945472)
			(xy 24.788876 -85.564472) (xy 24.789425 -85.535896) (xy 24.798404 -85.479454) (xy 24.816103 -85.425112)
			(xy 24.842088 -85.374209) (xy 24.875718 -85.327999) (xy 24.895556 -85.307424) (xy 25.4254 -84.77758)
			(xy 25.4254 -83.89874) (xy 25.38984 -83.887564) (xy 25.360878 -83.877936) (xy 25.305598 -83.852068)
			(xy 25.254248 -83.819082) (xy 25.207737 -83.779563) (xy 25.166891 -83.734213) (xy 25.132435 -83.683837)
			(xy 25.104981 -83.629328) (xy 25.085015 -83.571653) (xy 25.072892 -83.511837) (xy 25.068827 -83.450939)
			(xy 25.072892 -83.390042) (xy 25.085015 -83.330226) (xy 25.104981 -83.272551) (xy 25.132436 -83.218042)
			(xy 25.166892 -83.167666) (xy 25.207738 -83.122316) (xy 25.254249 -83.082797) (xy 25.305599 -83.049812)
			(xy 25.360879 -83.023943) (xy 25.38984 -83.014312) (xy 25.4254 -83.003136) (xy 25.4254 -81.187544)
			(xy 24.197056 -79.9592) (xy 24.197056 -79.6798) (xy 23.91283 -79.395574) (xy 23.898352 -79.392526)
			(xy 23.870227 -79.386004) (xy 23.816208 -79.365628) (xy 23.765876 -79.337346) (xy 23.72038 -79.301804)
			(xy 23.680756 -79.259814) (xy 23.647912 -79.212334) (xy 23.622594 -79.160447) (xy 23.605383 -79.105339)
			(xy 23.59667 -79.048267) (xy 23.596092 -79.0194) (xy 23.596518 -78.993213) (xy 23.603669 -78.941328)
			(xy 23.61785 -78.89091) (xy 23.638794 -78.842906) (xy 23.666109 -78.798218) (xy 23.69928 -78.757686)
			(xy 23.737683 -78.722073) (xy 23.758906 -78.706726) (xy 23.758906 -78.341474) (xy 23.7361 -78.324883)
			(xy 23.69517 -78.286085) (xy 23.660393 -78.241688) (xy 23.632527 -78.192658) (xy 23.612177 -78.140061)
			(xy 23.599788 -78.085042) (xy 23.595628 -78.0288) (xy 23.599788 -77.972558) (xy 23.612177 -77.917539)
			(xy 23.632527 -77.864942) (xy 23.660393 -77.815912) (xy 23.69517 -77.771515) (xy 23.7361 -77.732717)
			(xy 23.758906 -77.716126) (xy 23.758906 -77.022706) (xy 21.420074 -74.684128) (xy 18.000726 -74.684128)
			(xy 17.60347 -75.08113) (xy 17.623536 -75.115166) (xy 17.646632 -75.154982) (xy 17.686365 -75.238021)
			(xy 17.718429 -75.324312) (xy 17.742561 -75.413147) (xy 17.758564 -75.5038) (xy 17.766307 -75.595529)
			(xy 17.765726 -75.687582) (xy 17.756825 -75.779206) (xy 17.739679 -75.86965) (xy 17.714427 -75.958174)
			(xy 17.681277 -76.044053) (xy 17.640498 -76.126583) (xy 17.592427 -76.205089) (xy 17.537455 -76.278928)
			(xy 17.476034 -76.347496) (xy 17.408665 -76.410231) (xy 17.335902 -76.466619) (xy 17.2974 -76.491846)
			(xy 17.2974 -77.95895) (xy 17.817592 -77.95895) (xy 17.817592 -76.708) (xy 17.818117 -76.678876)
			(xy 17.825769 -76.621131) (xy 17.840891 -76.564878) (xy 17.863224 -76.511079) (xy 17.892385 -76.460654)
			(xy 17.927877 -76.414466) (xy 17.948148 -76.393548) (xy 18.020792 -76.32065) (xy 18.020792 -75.844654)
			(xy 18.021287 -75.815529) (xy 18.028946 -75.757782) (xy 18.044073 -75.701529) (xy 18.066411 -75.647731)
			(xy 18.095578 -75.597306) (xy 18.131074 -75.551119) (xy 18.151348 -75.530202) (xy 18.634202 -75.047348)
			(xy 18.65508 -75.02703) (xy 18.701264 -74.991515) (xy 18.751692 -74.96234) (xy 18.805501 -74.940004)
			(xy 18.861766 -74.92489) (xy 18.919524 -74.917259) (xy 18.948654 -74.916792) (xy 19.23415 -74.916792)
			(xy 19.262939 -74.917271) (xy 19.320036 -74.924698) (xy 19.375697 -74.939434) (xy 19.428989 -74.961233)
			(xy 19.479021 -74.989729) (xy 19.524955 -75.024446) (xy 19.545808 -75.0443) (xy 19.63674 -75.0443)
			(xy 19.63674 -75.171808) (xy 19.641058 -75.181714) (xy 19.653057 -75.210201) (xy 19.669927 -75.269666)
			(xy 19.678409 -75.330893) (xy 19.678904 -75.3618) (xy 19.678904 -75.980544) (xy 19.821144 -76.122784)
			(xy 20.335494 -76.122784) (xy 20.352185 -76.123247) (xy 20.384429 -76.131888) (xy 20.413338 -76.14858)
			(xy 20.436939 -76.172188) (xy 20.453625 -76.201101) (xy 20.462257 -76.233347) (xy 20.462748 -76.250038)
			(xy 20.462748 -77.113638) (xy 21.139912 -77.113638) (xy 21.139912 -76.250038) (xy 21.140475 -76.233354)
			(xy 21.149101 -76.201122) (xy 21.165776 -76.172221) (xy 21.189363 -76.14862) (xy 21.218255 -76.131929)
			(xy 21.250483 -76.123284) (xy 21.267166 -76.122784) (xy 22.435566 -76.122784) (xy 22.452256 -76.123272)
			(xy 22.484499 -76.131905) (xy 22.513407 -76.148593) (xy 22.53701 -76.172196) (xy 22.553696 -76.201105)
			(xy 22.562329 -76.233348) (xy 22.56282 -76.250038) (xy 22.56282 -76.879196) (xy 23.040848 -77.357224)
			(xy 23.060687 -77.377799) (xy 23.094316 -77.424009) (xy 23.120301 -77.474912) (xy 23.138 -77.529254)
			(xy 23.146979 -77.585696) (xy 23.147528 -77.614272) (xy 23.147528 -78.867) (xy 23.146954 -78.895573)
			(xy 23.137961 -78.952007) (xy 23.120257 -79.006341) (xy 23.094279 -79.057242) (xy 23.060665 -79.103456)
			(xy 23.040848 -79.124048) (xy 22.893528 -79.271622) (xy 22.893528 -80.57007) (xy 22.91128 -80.59413)
			(xy 22.941077 -80.645968) (xy 22.963873 -80.701244) (xy 22.97928 -80.759017) (xy 22.987037 -80.818304)
			(xy 22.987508 -80.8482) (xy 22.987073 -80.878099) (xy 22.979322 -80.93739) (xy 22.963913 -80.995167)
			(xy 22.941108 -81.050445) (xy 22.911297 -81.10228) (xy 22.893528 -81.12633) (xy 22.893528 -82.128864)
			(xy 23.088074 -82.128864) (xy 23.088074 -82.068928) (xy 23.095897 -82.009506) (xy 23.11141 -81.951613)
			(xy 23.134346 -81.89624) (xy 23.164313 -81.844334) (xy 23.2008 -81.796784) (xy 23.24318 -81.754404)
			(xy 23.29073 -81.717917) (xy 23.342636 -81.68795) (xy 23.398009 -81.665014) (xy 23.455902 -81.649501)
			(xy 23.515324 -81.641678) (xy 23.57526 -81.641678) (xy 23.634682 -81.649501) (xy 23.692575 -81.665014)
			(xy 23.747948 -81.68795) (xy 23.799854 -81.717917) (xy 23.847404 -81.754404) (xy 23.889784 -81.796784)
			(xy 23.926271 -81.844334) (xy 23.956238 -81.89624) (xy 23.979174 -81.951613) (xy 23.994687 -82.009506)
			(xy 24.00251 -82.068928) (xy 24.003 -82.098896) (xy 24.00251 -82.128864) (xy 23.994687 -82.188286)
			(xy 23.979174 -82.246179) (xy 23.956238 -82.301552) (xy 23.926271 -82.353458) (xy 23.889784 -82.401008)
			(xy 23.847404 -82.443388) (xy 23.799854 -82.479875) (xy 23.747948 -82.509842) (xy 23.692575 -82.532778)
			(xy 23.634682 -82.548291) (xy 23.57526 -82.556114) (xy 23.515324 -82.556114) (xy 23.455902 -82.548291)
			(xy 23.398009 -82.532778) (xy 23.342636 -82.509842) (xy 23.29073 -82.479875) (xy 23.24318 -82.443388)
			(xy 23.2008 -82.401008) (xy 23.164313 -82.353458) (xy 23.134346 -82.301552) (xy 23.11141 -82.246179)
			(xy 23.095897 -82.188286) (xy 23.088074 -82.128864) (xy 22.893528 -82.128864) (xy 22.893528 -83.085178)
			(xy 22.895814 -83.092798) (xy 22.901118 -83.109838) (xy 22.906853 -83.14506) (xy 22.907244 -83.162902)
			(xy 22.907244 -83.430364) (xy 22.867874 -83.430364) (xy 22.85365 -83.458304) (xy 22.852888 -83.459828)
			(xy 22.8473 -83.47075) (xy 22.8473 -83.86618) (xy 23.314182 -83.86618) (xy 23.321933 -83.812234)
			(xy 23.337283 -83.75994) (xy 23.359919 -83.710363) (xy 23.389379 -83.664512) (xy 23.425065 -83.62332)
			(xy 23.46625 -83.587626) (xy 23.512095 -83.558156) (xy 23.561667 -83.53551) (xy 23.613958 -83.52015)
			(xy 23.667902 -83.512387) (xy 23.695152 -83.511898) (xy 23.700994 -83.511898) (xy 23.715528 -83.511618)
			(xy 23.743534 -83.503879) (xy 23.768227 -83.488566) (xy 23.78761 -83.46692) (xy 23.800113 -83.440692)
			(xy 23.804726 -83.412005) (xy 23.801074 -83.38318) (xy 23.795736 -83.369658) (xy 23.785632 -83.345444)
			(xy 23.771373 -83.294953) (xy 23.764172 -83.242983) (xy 23.763732 -83.21675) (xy 23.764202 -83.189497)
			(xy 23.771953 -83.135544) (xy 23.787305 -83.083244) (xy 23.809944 -83.033661) (xy 23.839411 -82.987806)
			(xy 23.875104 -82.946611) (xy 23.916298 -82.910917) (xy 23.962152 -82.881449) (xy 24.011734 -82.858808)
			(xy 24.064034 -82.843455) (xy 24.117987 -82.835703) (xy 24.14524 -82.835242) (xy 24.174755 -82.835795)
			(xy 24.233077 -82.844898) (xy 24.289296 -82.862895) (xy 24.315928 -82.875628) (xy 24.328405 -82.881258)
			(xy 24.355251 -82.886522) (xy 24.382531 -82.88447) (xy 24.408287 -82.875248) (xy 24.43067 -82.859517)
			(xy 24.448072 -82.838409) (xy 24.459245 -82.813437) (xy 24.463386 -82.786395) (xy 24.462232 -82.772758)
			(xy 24.461018 -82.761558) (xy 24.459746 -82.739065) (xy 24.459692 -82.7278) (xy 24.460178 -82.700549)
			(xy 24.467934 -82.646601) (xy 24.483289 -82.594306) (xy 24.505931 -82.544729) (xy 24.535397 -82.498879)
			(xy 24.571088 -82.457688) (xy 24.612279 -82.421997) (xy 24.658129 -82.392531) (xy 24.707706 -82.369889)
			(xy 24.760001 -82.354534) (xy 24.813949 -82.346778) (xy 24.868451 -82.346778) (xy 24.922399 -82.354534)
			(xy 24.974694 -82.369889) (xy 25.024271 -82.392531) (xy 25.070121 -82.421997) (xy 25.111312 -82.457688)
			(xy 25.147003 -82.498879) (xy 25.176469 -82.544729) (xy 25.199111 -82.594306) (xy 25.214466 -82.646601)
			(xy 25.222222 -82.700549) (xy 25.222222 -82.755051) (xy 25.214466 -82.808999) (xy 25.199111 -82.861294)
			(xy 25.176469 -82.910871) (xy 25.147003 -82.956721) (xy 25.111312 -82.997912) (xy 25.070121 -83.033603)
			(xy 25.024271 -83.063069) (xy 24.974694 -83.085711) (xy 24.922399 -83.101066) (xy 24.868451 -83.108822)
			(xy 24.8412 -83.109308) (xy 24.811686 -83.108745) (xy 24.753363 -83.099647) (xy 24.697144 -83.081654)
			(xy 24.670512 -83.068922) (xy 24.658085 -83.063169) (xy 24.631219 -83.05791) (xy 24.603921 -83.059973)
			(xy 24.57815 -83.069211) (xy 24.555758 -83.08496) (xy 24.538351 -83.10609) (xy 24.52718 -83.131083)
			(xy 24.523047 -83.158146) (xy 24.524208 -83.171792) (xy 24.525426 -83.182991) (xy 24.526696 -83.205485)
			(xy 24.526748 -83.21675) (xy 24.526198 -83.244) (xy 24.518449 -83.297946) (xy 24.503102 -83.350239)
			(xy 24.480468 -83.399817) (xy 24.451009 -83.445668) (xy 24.415324 -83.48686) (xy 24.37414 -83.522555)
			(xy 24.328296 -83.552025) (xy 24.278724 -83.57467) (xy 24.226434 -83.59003) (xy 24.17249 -83.597792)
			(xy 24.14524 -83.598258) (xy 24.139398 -83.598258) (xy 24.124868 -83.598592) (xy 24.096872 -83.60633)
			(xy 24.072187 -83.621635) (xy 24.052808 -83.643271) (xy 24.040304 -83.669487) (xy 24.035685 -83.698163)
			(xy 24.039326 -83.726979) (xy 24.044656 -83.740498) (xy 24.054777 -83.764705) (xy 24.06903 -83.8152)
			(xy 24.076223 -83.867172) (xy 24.07666 -83.893406) (xy 24.076216 -83.920656) (xy 24.068459 -83.974601)
			(xy 24.053104 -84.026893) (xy 24.030464 -84.076468) (xy 24.000999 -84.122317) (xy 23.965309 -84.163505)
			(xy 23.924121 -84.199196) (xy 23.878274 -84.228661) (xy 23.828699 -84.251302) (xy 23.776407 -84.266658)
			(xy 23.722462 -84.274415) (xy 23.667962 -84.274417) (xy 23.614016 -84.266663) (xy 23.561723 -84.251311)
			(xy 23.512147 -84.228673) (xy 23.466298 -84.19921) (xy 23.425108 -84.163522) (xy 23.389415 -84.122336)
			(xy 23.359947 -84.076489) (xy 23.337304 -84.026916) (xy 23.321946 -83.974625) (xy 23.314186 -83.92068)
			(xy 23.314182 -83.86618) (xy 22.8473 -83.86618) (xy 22.8473 -83.91525) (xy 22.852888 -83.926172)
			(xy 22.85365 -83.927696) (xy 22.867874 -83.955636) (xy 22.907244 -83.955636) (xy 22.907244 -84.223098)
			(xy 22.906809 -84.240936) (xy 22.901068 -84.27615) (xy 22.895814 -84.293202) (xy 22.893528 -84.300822)
			(xy 22.893528 -85.395308) (xy 22.909793 -85.421593) (xy 22.935447 -85.477831) (xy 22.952834 -85.537148)
			(xy 22.9616 -85.598335) (xy 22.962108 -85.629242) (xy 22.961579 -85.659478) (xy 22.953171 -85.719361)
			(xy 22.936498 -85.777487) (xy 22.911884 -85.832722) (xy 22.879811 -85.883986) (xy 22.840905 -85.930279)
			(xy 22.795925 -85.970695) (xy 22.74575 -86.004447) (xy 22.718776 -86.018116) (xy 22.690328 -86.031832)
			(xy 22.690328 -86.703408) (xy 22.689904 -86.719178) (xy 22.683748 -86.750113) (xy 22.671693 -86.77926)
			(xy 22.654199 -86.805505) (xy 22.643338 -86.816946) (xy 22.414992 -87.045038) (xy 22.414992 -88.50249)
			(xy 22.436791 -88.515079) (xy 22.47661 -88.545874) (xy 22.511305 -88.582346) (xy 22.540073 -88.623654)
			(xy 22.562252 -88.668843) (xy 22.577329 -88.71687) (xy 22.584955 -88.766627) (xy 22.585426 -88.791796)
			(xy 22.584916 -88.817783) (xy 22.724366 -88.817783) (xy 22.724366 -88.765809) (xy 22.732496 -88.714474)
			(xy 22.748557 -88.665044) (xy 22.772153 -88.618734) (xy 22.802703 -88.576686) (xy 22.839454 -88.539935)
			(xy 22.881502 -88.509385) (xy 22.927812 -88.485789) (xy 22.977242 -88.469728) (xy 23.028577 -88.461598)
			(xy 23.080551 -88.461598) (xy 23.131886 -88.469728) (xy 23.181316 -88.485789) (xy 23.227626 -88.509385)
			(xy 23.269674 -88.539935) (xy 23.306425 -88.576686) (xy 23.336975 -88.618734) (xy 23.360571 -88.665044)
			(xy 23.376632 -88.714474) (xy 23.384762 -88.765809) (xy 23.385272 -88.791796) (xy 23.384762 -88.817783)
			(xy 23.376632 -88.869118) (xy 23.360571 -88.918548) (xy 23.336975 -88.964858) (xy 23.306425 -89.006906)
			(xy 23.269674 -89.043657) (xy 23.227626 -89.074207) (xy 23.181316 -89.097803) (xy 23.131886 -89.113864)
			(xy 23.080551 -89.121994) (xy 23.028577 -89.121994) (xy 22.977242 -89.113864) (xy 22.927812 -89.097803)
			(xy 22.881502 -89.074207) (xy 22.839454 -89.043657) (xy 22.802703 -89.006906) (xy 22.772153 -88.964858)
			(xy 22.748557 -88.918548) (xy 22.732496 -88.869118) (xy 22.724366 -88.817783) (xy 22.584916 -88.817783)
			(xy 22.576786 -88.869118) (xy 22.560725 -88.918548) (xy 22.537129 -88.964858) (xy 22.506579 -89.006906)
			(xy 22.469828 -89.043657) (xy 22.42778 -89.074207) (xy 22.38147 -89.097803) (xy 22.33204 -89.113864)
			(xy 22.280705 -89.121994) (xy 22.228731 -89.121994) (xy 22.177396 -89.113864) (xy 22.127966 -89.097803)
			(xy 22.081656 -89.074207) (xy 22.039608 -89.043657) (xy 22.002857 -89.006906) (xy 21.972307 -88.964858)
			(xy 21.948711 -88.918548) (xy 21.93265 -88.869118) (xy 21.92452 -88.817783) (xy 21.92401 -88.791796)
			(xy 21.92447 -88.766626) (xy 21.932088 -88.716866) (xy 21.947161 -88.668836) (xy 21.969342 -88.623647)
			(xy 21.998117 -88.582342) (xy 22.032822 -88.545878) (xy 22.072653 -88.515096) (xy 22.094444 -88.50249)
			(xy 22.094444 -86.97849) (xy 22.094774 -86.962725) (xy 22.100852 -86.931787) (xy 22.112852 -86.902631)
			(xy 22.130312 -86.876377) (xy 22.14118 -86.864952) (xy 22.369272 -86.63686) (xy 22.369272 -86.031832)
			(xy 22.340824 -86.018116) (xy 22.313846 -86.004458) (xy 22.263682 -85.970691) (xy 22.218711 -85.930266)
			(xy 22.17981 -85.883971) (xy 22.147736 -85.832708) (xy 22.123115 -85.777478) (xy 22.106428 -85.719356)
			(xy 22.097999 -85.659477) (xy 22.097492 -85.629242) (xy 22.097994 -85.598335) (xy 22.106754 -85.537145)
			(xy 22.124143 -85.477828) (xy 22.149808 -85.421594) (xy 22.166072 -85.395308) (xy 22.166072 -84.300822)
			(xy 22.163786 -84.293202) (xy 22.158482 -84.276162) (xy 22.152747 -84.24094) (xy 22.152356 -84.223098)
			(xy 22.152356 -83.955636) (xy 22.191726 -83.955636) (xy 22.20595 -83.927696) (xy 22.206712 -83.926172)
			(xy 22.2123 -83.91525) (xy 22.2123 -83.47075) (xy 22.206712 -83.459828) (xy 22.20595 -83.458304)
			(xy 22.191726 -83.430364) (xy 22.152356 -83.430364) (xy 22.152356 -83.33105) (xy 22.151853 -83.316211)
			(xy 22.143307 -83.28779) (xy 22.126952 -83.263025) (xy 22.104168 -83.244007) (xy 22.076879 -83.232342)
			(xy 22.047388 -83.229013) (xy 22.018185 -83.234303) (xy 21.991736 -83.247765) (xy 21.980652 -83.257644)
			(xy 21.959221 -83.277364) (xy 21.911481 -83.310717) (xy 21.85923 -83.336433) (xy 21.80368 -83.353916)
			(xy 21.746118 -83.36276) (xy 21.717 -83.363308) (xy 21.689749 -83.362822) (xy 21.635801 -83.355066)
			(xy 21.583506 -83.339711) (xy 21.533929 -83.317069) (xy 21.488079 -83.287603) (xy 21.446888 -83.251912)
			(xy 21.411197 -83.210721) (xy 21.381731 -83.164871) (xy 21.359089 -83.115294) (xy 21.343734 -83.062999)
			(xy 21.335978 -83.009051) (xy 21.335978 -82.954549) (xy 21.343734 -82.900601) (xy 21.359089 -82.848306)
			(xy 21.381731 -82.798729) (xy 21.411197 -82.752879) (xy 21.446888 -82.711688) (xy 21.488079 -82.675997)
			(xy 21.533929 -82.646531) (xy 21.583506 -82.623889) (xy 21.635801 -82.608534) (xy 21.689749 -82.600778)
			(xy 21.717 -82.600292) (xy 21.742552 -82.600672) (xy 21.7932 -82.607484) (xy 21.842484 -82.621) (xy 21.889521 -82.640976)
			(xy 21.933469 -82.667056) (xy 21.97354 -82.698771) (xy 21.991574 -82.716878) (xy 22.002512 -82.727283)
			(xy 22.028901 -82.741897) (xy 22.05841 -82.748157) (xy 22.088459 -82.745517) (xy 22.116424 -82.734206)
			(xy 22.13986 -82.715214) (xy 22.15672 -82.690199) (xy 22.165529 -82.661349) (xy 22.166072 -82.646266)
			(xy 22.166072 -81.12633) (xy 22.14832 -81.10227) (xy 22.118523 -81.050432) (xy 22.095727 -80.995156)
			(xy 22.08032 -80.937383) (xy 22.072563 -80.878096) (xy 22.072092 -80.8482) (xy 22.072527 -80.818301)
			(xy 22.080278 -80.75901) (xy 22.095687 -80.701233) (xy 22.118492 -80.645955) (xy 22.148303 -80.59412)
			(xy 22.166072 -80.57007) (xy 22.166072 -79.121) (xy 22.166646 -79.092427) (xy 22.175639 -79.035993)
			(xy 22.193343 -78.981659) (xy 22.219321 -78.930758) (xy 22.252935 -78.884544) (xy 22.272752 -78.863952)
			(xy 22.420072 -78.716378) (xy 22.420072 -77.764894) (xy 21.896324 -77.240892) (xy 21.267166 -77.240892)
			(xy 21.250486 -77.24034) (xy 21.218264 -77.2317) (xy 21.189375 -77.215017) (xy 21.165785 -77.191429)
			(xy 21.149102 -77.16254) (xy 21.140461 -77.130318) (xy 21.139912 -77.113638) (xy 20.462748 -77.113638)
			(xy 20.462243 -77.130322) (xy 20.453598 -77.16255) (xy 20.436908 -77.191444) (xy 20.413309 -77.215035)
			(xy 20.38441 -77.231715) (xy 20.352178 -77.240348) (xy 20.335494 -77.240892) (xy 19.167094 -77.240892)
			(xy 19.150415 -77.240315) (xy 19.118194 -77.231682) (xy 19.089305 -77.215005) (xy 19.065714 -77.191421)
			(xy 19.04903 -77.162535) (xy 19.040389 -77.130317) (xy 19.03984 -77.113638) (xy 19.03984 -76.599288)
			(xy 18.95475 -76.514452) (xy 18.907252 -76.56195) (xy 18.904712 -76.577952) (xy 18.899766 -76.605111)
			(xy 18.88399 -76.658014) (xy 18.861777 -76.708553) (xy 18.83347 -76.755948) (xy 18.799505 -76.799468)
			(xy 18.780252 -76.819252) (xy 18.707608 -76.89215) (xy 18.707608 -77.95895) (xy 18.707043 -77.991615)
			(xy 18.69748 -78.056242) (xy 18.678566 -78.118776) (xy 18.65071 -78.17787) (xy 18.614509 -78.232254)
			(xy 18.593054 -78.256892) (xy 18.5801 -78.27137) (xy 18.5801 -78.446376) (xy 19.03984 -78.446376)
			(xy 19.03984 -77.900022) (xy 19.040361 -77.883335) (xy 19.048994 -77.851098) (xy 19.065676 -77.822194)
			(xy 19.089272 -77.798593) (xy 19.118172 -77.781904) (xy 19.150408 -77.773265) (xy 19.167094 -77.772768)
			(xy 20.335494 -77.772768) (xy 20.352184 -77.773247) (xy 20.384425 -77.781886) (xy 20.413332 -77.798576)
			(xy 20.436933 -77.822181) (xy 20.45362 -77.851089) (xy 20.462255 -77.883332) (xy 20.462748 -77.900022)
			(xy 20.462748 -78.763622) (xy 20.462229 -78.780305) (xy 20.453588 -78.812533) (xy 20.436901 -78.841427)
			(xy 20.413305 -78.865018) (xy 20.384407 -78.881699) (xy 20.352177 -78.890332) (xy 20.335494 -78.890876)
			(xy 19.634454 -78.890876) (xy 19.5453 -78.980284) (xy 19.527573 -78.997315) (xy 19.48778 -79.026175)
			(xy 19.443964 -79.048455) (xy 19.397201 -79.063608) (xy 19.348644 -79.07126) (xy 19.324066 -79.071724)
			(xy 18.547588 -79.071724) (xy 18.535142 -79.079852) (xy 18.516611 -79.091018) (xy 18.476362 -79.106871)
			(xy 18.433838 -79.114808) (xy 18.412206 -79.115158) (xy 18.412206 -79.114904) (xy 18.112994 -79.114904)
			(xy 18.112994 -79.115158) (xy 18.090665 -79.114795) (xy 18.046813 -79.106388) (xy 18.00546 -79.089547)
			(xy 17.968212 -79.064925) (xy 17.936514 -79.033477) (xy 17.911598 -78.996425) (xy 17.894429 -78.955207)
			(xy 17.885675 -78.911423) (xy 17.885156 -78.889098) (xy 17.885156 -78.621636) (xy 17.9451 -78.621636)
			(xy 17.9451 -78.270608) (xy 17.925258 -78.249747) (xy 17.890566 -78.203798) (xy 17.862083 -78.153764)
			(xy 17.840282 -78.100477) (xy 17.825528 -78.044825) (xy 17.818067 -77.987737) (xy 17.817592 -77.95895)
			(xy 17.2974 -77.95895) (xy 17.2974 -79.2226) (xy 17.526 -79.4512) (xy 18.338292 -79.4512) (xy 18.354983 -79.429658)
			(xy 18.393502 -79.391111) (xy 18.437118 -79.35844) (xy 18.484941 -79.332313) (xy 18.535996 -79.31326)
			(xy 18.589244 -79.301671) (xy 18.6436 -79.297782) (xy 18.697956 -79.301671) (xy 18.751204 -79.31326)
			(xy 18.802259 -79.332313) (xy 18.850082 -79.35844) (xy 18.893698 -79.391111) (xy 18.932217 -79.429658)
			(xy 18.948908 -79.4512) (xy 19.558 -79.4512) (xy 21.032978 -80.926178) (xy 21.032978 -85.351874)
			(xy 21.052718 -85.369232) (xy 21.087371 -85.408758) (xy 21.115829 -85.452953) (xy 21.137475 -85.500854)
			(xy 21.151836 -85.551419) (xy 21.15566 -85.577426) (xy 21.157946 -85.594444) (xy 21.186902 -85.6234)
			(xy 21.186902 -89.012014) (xy 21.532088 -89.3572)
		)
		(stroke
			(width 0)
			(type solid)
		)
		(fill yes)
		(layer "B.Cu")
		(net "GND")
	)
	(gr_poly
		(pts
			(xy 62.693042 -49.698148) (xy 62.969902 -49.698148) (xy 63.001144 -49.666906) (xy 63.001144 -49.576482)
			(xy 63.001652 -49.575974) (xy 63.001652 -49.214278) (xy 63.003938 -49.212246) (xy 63.003938 -49.20742)
			(xy 63.191644 -49.019714) (xy 63.498222 -49.019714) (xy 63.51524 -49.002696) (xy 63.525372 -48.991854)
			(xy 63.539451 -48.965747) (xy 63.54544 -48.936697) (xy 63.542837 -48.90715) (xy 63.53186 -48.879595)
			(xy 63.513433 -48.856352) (xy 63.501524 -48.847502) (xy 63.480019 -48.831904) (xy 63.441813 -48.794995)
			(xy 63.409997 -48.752456) (xy 63.385386 -48.705379) (xy 63.368615 -48.654974) (xy 63.360114 -48.602537)
			(xy 63.359538 -48.575976) (xy 63.360001 -48.550923) (xy 63.36756 -48.50139) (xy 63.382502 -48.453563)
			(xy 63.404484 -48.408536) (xy 63.433005 -48.367338) (xy 63.467411 -48.330912) (xy 63.506917 -48.30009)
			(xy 63.550618 -48.275578) (xy 63.573914 -48.26635) (xy 63.606934 -48.253904) (xy 63.606934 -48.135286)
			(xy 63.545212 -48.07331) (xy 63.5381 -48.069754) (xy 63.5154 -48.057429) (xy 63.473796 -48.026823)
			(xy 63.437454 -47.990121) (xy 63.40726 -47.948217) (xy 63.383946 -47.902128) (xy 63.368079 -47.852976)
			(xy 63.360046 -47.801955) (xy 63.359538 -47.77613) (xy 63.360005 -47.751079) (xy 63.367569 -47.70155)
			(xy 63.382515 -47.653729) (xy 63.404501 -47.608707) (xy 63.433023 -47.567515) (xy 63.46743 -47.531095)
			(xy 63.506935 -47.500278) (xy 63.550635 -47.475771) (xy 63.573914 -47.466504) (xy 63.606934 -47.454058)
			(xy 63.606934 -47.298102) (xy 63.573914 -47.285656) (xy 63.550617 -47.276413) (xy 63.506894 -47.251917)
			(xy 63.467366 -47.221105) (xy 63.432939 -47.184682) (xy 63.404401 -47.143483) (xy 63.382406 -47.09845)
			(xy 63.367455 -47.050614) (xy 63.359893 -47.00107) (xy 63.359891 -46.950952) (xy 63.367451 -46.901407)
			(xy 63.382398 -46.85357) (xy 63.404391 -46.808535) (xy 63.432926 -46.767334) (xy 63.467351 -46.730909)
			(xy 63.506876 -46.700095) (xy 63.550598 -46.675596) (xy 63.573914 -46.666404) (xy 63.606934 -46.653958)
			(xy 63.606934 -46.498002) (xy 63.573914 -46.485556) (xy 63.550622 -46.476312) (xy 63.506909 -46.451815)
			(xy 63.467393 -46.421002) (xy 63.432977 -46.384581) (xy 63.404451 -46.343383) (xy 63.382468 -46.298353)
			(xy 63.36753 -46.250522) (xy 63.35998 -46.200985) (xy 63.359538 -46.17593) (xy 63.360019 -46.149941)
			(xy 63.368147 -46.098601) (xy 63.384207 -46.049165) (xy 63.407804 -46.002851) (xy 63.438356 -45.9608)
			(xy 63.475112 -45.924046) (xy 63.517165 -45.893495) (xy 63.56348 -45.869901) (xy 63.612917 -45.853843)
			(xy 63.664256 -45.845718) (xy 63.690246 -45.845222) (xy 63.715678 -45.845684) (xy 63.765943 -45.853459)
			(xy 63.790322 -45.860716) (xy 63.797942 -45.863256) (xy 64.355472 -45.863256) (xy 64.372951 -45.863288)
			(xy 64.407886 -45.864559) (xy 64.425322 -45.865796) (xy 64.427354 -45.86605) (xy 65.036954 -45.86605)
			(xy 65.216532 -45.686472) (xy 65.216532 -44.510706) (xy 65.47866 -44.248578) (xy 68.552822 -44.248578)
			(xy 69.170804 -43.630596) (xy 69.170804 -41.240202) (xy 68.9356 -41.004998) (xy 63.583058 -41.004998)
			(xy 63.23076 -41.357296) (xy 63.230506 -41.378378) (xy 63.229837 -41.404134) (xy 63.221497 -41.454974)
			(xy 63.205375 -41.503906) (xy 63.181859 -41.549746) (xy 63.151519 -41.591385) (xy 63.11509 -41.627815)
			(xy 63.073451 -41.658156) (xy 63.027612 -41.681672) (xy 62.97868 -41.697796) (xy 62.92784 -41.706136)
			(xy 62.902084 -41.7068) (xy 62.881002 -41.707054) (xy 62.792864 -41.795192) (xy 62.844934 -41.847516)
			(xy 62.868048 -41.845992) (xy 62.890146 -41.84523) (xy 62.916128 -41.845743) (xy 62.967451 -41.853879)
			(xy 63.016869 -41.869942) (xy 63.063167 -41.893537) (xy 63.105204 -41.924084) (xy 63.141945 -41.960831)
			(xy 63.172487 -42.002872) (xy 63.196076 -42.049173) (xy 63.212132 -42.098594) (xy 63.22026 -42.149918)
			(xy 63.22026 -42.201882) (xy 63.212132 -42.253206) (xy 63.196076 -42.302627) (xy 63.172487 -42.348928)
			(xy 63.141945 -42.390969) (xy 63.105204 -42.427716) (xy 63.063167 -42.458263) (xy 63.016869 -42.481858)
			(xy 62.967451 -42.497921) (xy 62.916128 -42.506057) (xy 62.890146 -42.506646) (xy 62.86507 -42.506185)
			(xy 62.815494 -42.498616) (xy 62.767629 -42.483644) (xy 62.722576 -42.461614) (xy 62.681368 -42.433031)
			(xy 62.64495 -42.39855) (xy 62.614159 -42.358964) (xy 62.589702 -42.315181) (xy 62.572139 -42.268205)
			(xy 62.56655 -42.243756) (xy 62.563326 -42.230438) (xy 62.550815 -42.206072) (xy 62.532268 -42.185915)
			(xy 62.509024 -42.171425) (xy 62.482761 -42.163645) (xy 62.455375 -42.163139) (xy 62.428842 -42.169942)
			(xy 62.405079 -42.183563) (xy 62.3951 -42.192956) (xy 62.241938 -42.346118) (xy 62.241938 -42.68216)
			(xy 62.264691 -42.694465) (xy 62.306403 -42.725054) (xy 62.342842 -42.761765) (xy 62.373121 -42.803702)
			(xy 62.3965 -42.849842) (xy 62.412409 -42.89906) (xy 62.420461 -42.950155) (xy 62.420458 -43.00188)
			(xy 62.420435 -43.002025) (xy 63.360048 -43.002025) (xy 63.360048 -42.950051) (xy 63.368178 -42.898716)
			(xy 63.384239 -42.849286) (xy 63.407835 -42.802976) (xy 63.438385 -42.760928) (xy 63.475136 -42.724177)
			(xy 63.517184 -42.693627) (xy 63.563494 -42.670031) (xy 63.612924 -42.65397) (xy 63.664259 -42.64584)
			(xy 63.716233 -42.64584) (xy 63.767568 -42.65397) (xy 63.816998 -42.670031) (xy 63.863308 -42.693627)
			(xy 63.905356 -42.724177) (xy 63.942107 -42.760928) (xy 63.972657 -42.802976) (xy 63.996253 -42.849286)
			(xy 64.012314 -42.898716) (xy 64.020444 -42.950051) (xy 64.020954 -42.976038) (xy 64.020444 -43.002025)
			(xy 64.159894 -43.002025) (xy 64.159894 -42.950051) (xy 64.168024 -42.898716) (xy 64.184085 -42.849286)
			(xy 64.207681 -42.802976) (xy 64.238231 -42.760928) (xy 64.274982 -42.724177) (xy 64.31703 -42.693627)
			(xy 64.36334 -42.670031) (xy 64.41277 -42.65397) (xy 64.464105 -42.64584) (xy 64.516079 -42.64584)
			(xy 64.567414 -42.65397) (xy 64.616844 -42.670031) (xy 64.663154 -42.693627) (xy 64.705202 -42.724177)
			(xy 64.741953 -42.760928) (xy 64.772503 -42.802976) (xy 64.796099 -42.849286) (xy 64.81216 -42.898716)
			(xy 64.82029 -42.950051) (xy 64.8208 -42.976038) (xy 64.82029 -43.002025) (xy 64.81216 -43.05336)
			(xy 64.796099 -43.10279) (xy 64.772503 -43.1491) (xy 64.741953 -43.191148) (xy 64.705202 -43.227899)
			(xy 64.663154 -43.258449) (xy 64.616844 -43.282045) (xy 64.567414 -43.298106) (xy 64.516079 -43.306236)
			(xy 64.464105 -43.306236) (xy 64.41277 -43.298106) (xy 64.36334 -43.282045) (xy 64.31703 -43.258449)
			(xy 64.274982 -43.227899) (xy 64.238231 -43.191148) (xy 64.207681 -43.1491) (xy 64.184085 -43.10279)
			(xy 64.168024 -43.05336) (xy 64.159894 -43.002025) (xy 64.020444 -43.002025) (xy 64.012314 -43.05336)
			(xy 63.996253 -43.10279) (xy 63.972657 -43.1491) (xy 63.942107 -43.191148) (xy 63.905356 -43.227899)
			(xy 63.863308 -43.258449) (xy 63.816998 -43.282045) (xy 63.767568 -43.298106) (xy 63.716233 -43.306236)
			(xy 63.664259 -43.306236) (xy 63.612924 -43.298106) (xy 63.563494 -43.282045) (xy 63.517184 -43.258449)
			(xy 63.475136 -43.227899) (xy 63.438385 -43.191148) (xy 63.407835 -43.1491) (xy 63.384239 -43.10279)
			(xy 63.368178 -43.05336) (xy 63.360048 -43.002025) (xy 62.420435 -43.002025) (xy 62.412401 -43.052974)
			(xy 62.396487 -43.10219) (xy 62.373103 -43.148328) (xy 62.342819 -43.190262) (xy 62.306376 -43.226969)
			(xy 62.264662 -43.257553) (xy 62.241938 -43.269916) (xy 62.241938 -43.361102) (xy 62.174882 -43.428158)
			(xy 62.2173 -43.470576) (xy 62.225936 -43.474386) (xy 62.250463 -43.486032) (xy 62.295663 -43.516106)
			(xy 62.335349 -43.553154) (xy 62.368458 -43.596181) (xy 62.394102 -43.644034) (xy 62.411593 -43.695431)
			(xy 62.420463 -43.748992) (xy 62.421008 -43.776138) (xy 62.420496 -43.802123) (xy 62.420496 -43.802125)
			(xy 62.559948 -43.802125) (xy 62.559948 -43.750151) (xy 62.568078 -43.698816) (xy 62.584139 -43.649386)
			(xy 62.607735 -43.603076) (xy 62.638285 -43.561028) (xy 62.675036 -43.524277) (xy 62.717084 -43.493727)
			(xy 62.763394 -43.470131) (xy 62.812824 -43.45407) (xy 62.864159 -43.44594) (xy 62.916133 -43.44594)
			(xy 62.967468 -43.45407) (xy 63.016898 -43.470131) (xy 63.063208 -43.493727) (xy 63.105256 -43.524277)
			(xy 63.142007 -43.561028) (xy 63.172557 -43.603076) (xy 63.196153 -43.649386) (xy 63.212214 -43.698816)
			(xy 63.220344 -43.750151) (xy 63.220854 -43.776138) (xy 63.220344 -43.802125) (xy 63.360048 -43.802125)
			(xy 63.360048 -43.750151) (xy 63.368178 -43.698816) (xy 63.384239 -43.649386) (xy 63.407835 -43.603076)
			(xy 63.438385 -43.561028) (xy 63.475136 -43.524277) (xy 63.517184 -43.493727) (xy 63.563494 -43.470131)
			(xy 63.612924 -43.45407) (xy 63.664259 -43.44594) (xy 63.716233 -43.44594) (xy 63.767568 -43.45407)
			(xy 63.816998 -43.470131) (xy 63.863308 -43.493727) (xy 63.905356 -43.524277) (xy 63.942107 -43.561028)
			(xy 63.972657 -43.603076) (xy 63.996253 -43.649386) (xy 64.012314 -43.698816) (xy 64.020444 -43.750151)
			(xy 64.020954 -43.776138) (xy 64.020444 -43.802125) (xy 64.159894 -43.802125) (xy 64.159894 -43.750151)
			(xy 64.168024 -43.698816) (xy 64.184085 -43.649386) (xy 64.207681 -43.603076) (xy 64.238231 -43.561028)
			(xy 64.274982 -43.524277) (xy 64.31703 -43.493727) (xy 64.36334 -43.470131) (xy 64.41277 -43.45407)
			(xy 64.464105 -43.44594) (xy 64.516079 -43.44594) (xy 64.567414 -43.45407) (xy 64.616844 -43.470131)
			(xy 64.663154 -43.493727) (xy 64.705202 -43.524277) (xy 64.741953 -43.561028) (xy 64.772503 -43.603076)
			(xy 64.796099 -43.649386) (xy 64.81216 -43.698816) (xy 64.82029 -43.750151) (xy 64.8208 -43.776138)
			(xy 64.82029 -43.802125) (xy 64.959994 -43.802125) (xy 64.959994 -43.750151) (xy 64.968124 -43.698816)
			(xy 64.984185 -43.649386) (xy 65.007781 -43.603076) (xy 65.038331 -43.561028) (xy 65.075082 -43.524277)
			(xy 65.11713 -43.493727) (xy 65.16344 -43.470131) (xy 65.21287 -43.45407) (xy 65.264205 -43.44594)
			(xy 65.316179 -43.44594) (xy 65.367514 -43.45407) (xy 65.416944 -43.470131) (xy 65.463254 -43.493727)
			(xy 65.505302 -43.524277) (xy 65.542053 -43.561028) (xy 65.572603 -43.603076) (xy 65.596199 -43.649386)
			(xy 65.61226 -43.698816) (xy 65.62039 -43.750151) (xy 65.6209 -43.776138) (xy 65.62039 -43.802125)
			(xy 65.61226 -43.85346) (xy 65.596199 -43.90289) (xy 65.572603 -43.9492) (xy 65.542053 -43.991248)
			(xy 65.505302 -44.027999) (xy 65.463254 -44.058549) (xy 65.416944 -44.082145) (xy 65.367514 -44.098206)
			(xy 65.316179 -44.106336) (xy 65.264205 -44.106336) (xy 65.21287 -44.098206) (xy 65.16344 -44.082145)
			(xy 65.11713 -44.058549) (xy 65.075082 -44.027999) (xy 65.038331 -43.991248) (xy 65.007781 -43.9492)
			(xy 64.984185 -43.90289) (xy 64.968124 -43.85346) (xy 64.959994 -43.802125) (xy 64.82029 -43.802125)
			(xy 64.81216 -43.85346) (xy 64.796099 -43.90289) (xy 64.772503 -43.9492) (xy 64.741953 -43.991248)
			(xy 64.705202 -44.027999) (xy 64.663154 -44.058549) (xy 64.616844 -44.082145) (xy 64.567414 -44.098206)
			(xy 64.516079 -44.106336) (xy 64.464105 -44.106336) (xy 64.41277 -44.098206) (xy 64.36334 -44.082145)
			(xy 64.31703 -44.058549) (xy 64.274982 -44.027999) (xy 64.238231 -43.991248) (xy 64.207681 -43.9492)
			(xy 64.184085 -43.90289) (xy 64.168024 -43.85346) (xy 64.159894 -43.802125) (xy 64.020444 -43.802125)
			(xy 64.012314 -43.85346) (xy 63.996253 -43.90289) (xy 63.972657 -43.9492) (xy 63.942107 -43.991248)
			(xy 63.905356 -44.027999) (xy 63.863308 -44.058549) (xy 63.816998 -44.082145) (xy 63.767568 -44.098206)
			(xy 63.716233 -44.106336) (xy 63.664259 -44.106336) (xy 63.612924 -44.098206) (xy 63.563494 -44.082145)
			(xy 63.517184 -44.058549) (xy 63.475136 -44.027999) (xy 63.438385 -43.991248) (xy 63.407835 -43.9492)
			(xy 63.384239 -43.90289) (xy 63.368178 -43.85346) (xy 63.360048 -43.802125) (xy 63.220344 -43.802125)
			(xy 63.212214 -43.85346) (xy 63.196153 -43.90289) (xy 63.172557 -43.9492) (xy 63.142007 -43.991248)
			(xy 63.105256 -44.027999) (xy 63.063208 -44.058549) (xy 63.016898 -44.082145) (xy 62.967468 -44.098206)
			(xy 62.916133 -44.106336) (xy 62.864159 -44.106336) (xy 62.812824 -44.098206) (xy 62.763394 -44.082145)
			(xy 62.717084 -44.058549) (xy 62.675036 -44.027999) (xy 62.638285 -43.991248) (xy 62.607735 -43.9492)
			(xy 62.584139 -43.90289) (xy 62.568078 -43.85346) (xy 62.559948 -43.802125) (xy 62.420496 -43.802125)
			(xy 62.41236 -43.853453) (xy 62.396296 -43.902879) (xy 62.372698 -43.949183) (xy 62.342148 -43.991226)
			(xy 62.305397 -44.027972) (xy 62.26335 -44.058518) (xy 62.217043 -44.082111) (xy 62.167616 -44.098169)
			(xy 62.116285 -44.106299) (xy 62.0903 -44.106846) (xy 62.06996 -44.106563) (xy 62.029585 -44.101593)
			(xy 62.009782 -44.09694) (xy 61.9947 -44.093715) (xy 61.963923 -44.095481) (xy 61.935072 -44.10634)
			(xy 61.910769 -44.125306) (xy 61.893225 -44.150653) (xy 61.884033 -44.180078) (xy 61.883544 -44.195492)
			(xy 61.883544 -44.27855) (xy 61.945266 -44.27855) (xy 61.955172 -44.274232) (xy 61.976512 -44.265085)
			(xy 62.021116 -44.252193) (xy 62.067085 -44.245675) (xy 62.0903 -44.245276) (xy 62.116288 -44.245786)
			(xy 62.167625 -44.253917) (xy 62.217058 -44.269978) (xy 62.26337 -44.293575) (xy 62.30542 -44.324127)
			(xy 62.342173 -44.36088) (xy 62.372725 -44.40293) (xy 62.396322 -44.449242) (xy 62.412383 -44.498675)
			(xy 62.420514 -44.550012) (xy 62.420514 -44.601971) (xy 62.559948 -44.601971) (xy 62.559948 -44.549997)
			(xy 62.568078 -44.498662) (xy 62.584139 -44.449232) (xy 62.607735 -44.402922) (xy 62.638285 -44.360874)
			(xy 62.675036 -44.324123) (xy 62.717084 -44.293573) (xy 62.763394 -44.269977) (xy 62.812824 -44.253916)
			(xy 62.864159 -44.245786) (xy 62.916133 -44.245786) (xy 62.967468 -44.253916) (xy 63.016898 -44.269977)
			(xy 63.063208 -44.293573) (xy 63.105256 -44.324123) (xy 63.142007 -44.360874) (xy 63.172557 -44.402922)
			(xy 63.196153 -44.449232) (xy 63.212214 -44.498662) (xy 63.220344 -44.549997) (xy 63.220854 -44.575984)
			(xy 63.220344 -44.601971) (xy 63.360048 -44.601971) (xy 63.360048 -44.549997) (xy 63.368178 -44.498662)
			(xy 63.384239 -44.449232) (xy 63.407835 -44.402922) (xy 63.438385 -44.360874) (xy 63.475136 -44.324123)
			(xy 63.517184 -44.293573) (xy 63.563494 -44.269977) (xy 63.612924 -44.253916) (xy 63.664259 -44.245786)
			(xy 63.716233 -44.245786) (xy 63.767568 -44.253916) (xy 63.816998 -44.269977) (xy 63.863308 -44.293573)
			(xy 63.905356 -44.324123) (xy 63.942107 -44.360874) (xy 63.972657 -44.402922) (xy 63.996253 -44.449232)
			(xy 64.012314 -44.498662) (xy 64.020444 -44.549997) (xy 64.020954 -44.575984) (xy 64.020444 -44.601971)
			(xy 64.159894 -44.601971) (xy 64.159894 -44.549997) (xy 64.168024 -44.498662) (xy 64.184085 -44.449232)
			(xy 64.207681 -44.402922) (xy 64.238231 -44.360874) (xy 64.274982 -44.324123) (xy 64.31703 -44.293573)
			(xy 64.36334 -44.269977) (xy 64.41277 -44.253916) (xy 64.464105 -44.245786) (xy 64.516079 -44.245786)
			(xy 64.567414 -44.253916) (xy 64.616844 -44.269977) (xy 64.663154 -44.293573) (xy 64.705202 -44.324123)
			(xy 64.741953 -44.360874) (xy 64.772503 -44.402922) (xy 64.796099 -44.449232) (xy 64.81216 -44.498662)
			(xy 64.82029 -44.549997) (xy 64.8208 -44.575984) (xy 64.82029 -44.601971) (xy 64.81216 -44.653306)
			(xy 64.796099 -44.702736) (xy 64.772503 -44.749046) (xy 64.741953 -44.791094) (xy 64.705202 -44.827845)
			(xy 64.663154 -44.858395) (xy 64.616844 -44.881991) (xy 64.567414 -44.898052) (xy 64.516079 -44.906182)
			(xy 64.464105 -44.906182) (xy 64.41277 -44.898052) (xy 64.36334 -44.881991) (xy 64.31703 -44.858395)
			(xy 64.274982 -44.827845) (xy 64.238231 -44.791094) (xy 64.207681 -44.749046) (xy 64.184085 -44.702736)
			(xy 64.168024 -44.653306) (xy 64.159894 -44.601971) (xy 64.020444 -44.601971) (xy 64.012314 -44.653306)
			(xy 63.996253 -44.702736) (xy 63.972657 -44.749046) (xy 63.942107 -44.791094) (xy 63.905356 -44.827845)
			(xy 63.863308 -44.858395) (xy 63.816998 -44.881991) (xy 63.767568 -44.898052) (xy 63.716233 -44.906182)
			(xy 63.664259 -44.906182) (xy 63.612924 -44.898052) (xy 63.563494 -44.881991) (xy 63.517184 -44.858395)
			(xy 63.475136 -44.827845) (xy 63.438385 -44.791094) (xy 63.407835 -44.749046) (xy 63.384239 -44.702736)
			(xy 63.368178 -44.653306) (xy 63.360048 -44.601971) (xy 63.220344 -44.601971) (xy 63.212214 -44.653306)
			(xy 63.196153 -44.702736) (xy 63.172557 -44.749046) (xy 63.142007 -44.791094) (xy 63.105256 -44.827845)
			(xy 63.063208 -44.858395) (xy 63.016898 -44.881991) (xy 62.967468 -44.898052) (xy 62.916133 -44.906182)
			(xy 62.864159 -44.906182) (xy 62.812824 -44.898052) (xy 62.763394 -44.881991) (xy 62.717084 -44.858395)
			(xy 62.675036 -44.827845) (xy 62.638285 -44.791094) (xy 62.607735 -44.749046) (xy 62.584139 -44.702736)
			(xy 62.568078 -44.653306) (xy 62.559948 -44.601971) (xy 62.420514 -44.601971) (xy 62.420514 -44.601988)
			(xy 62.412383 -44.653325) (xy 62.396322 -44.702758) (xy 62.372725 -44.74907) (xy 62.342173 -44.79112)
			(xy 62.30542 -44.827873) (xy 62.26337 -44.858425) (xy 62.217058 -44.882022) (xy 62.167625 -44.898083)
			(xy 62.116288 -44.906214) (xy 62.0903 -44.906692) (xy 62.06996 -44.906409) (xy 62.029585 -44.901439)
			(xy 62.009782 -44.896786) (xy 61.994697 -44.893562) (xy 61.963916 -44.895328) (xy 61.935059 -44.906187)
			(xy 61.910749 -44.92515) (xy 61.893194 -44.950496) (xy 61.883988 -44.979922) (xy 61.883544 -44.995338)
			(xy 61.883544 -45.07865) (xy 61.945266 -45.07865) (xy 61.955172 -45.074332) (xy 61.976512 -45.065185)
			(xy 62.021116 -45.052293) (xy 62.067085 -45.045775) (xy 62.0903 -45.045376) (xy 62.116288 -45.045886)
			(xy 62.167625 -45.054017) (xy 62.217058 -45.070078) (xy 62.26337 -45.093675) (xy 62.30542 -45.124227)
			(xy 62.342173 -45.16098) (xy 62.372725 -45.20303) (xy 62.396322 -45.249342) (xy 62.412383 -45.298775)
			(xy 62.420514 -45.350112) (xy 62.420514 -45.402071) (xy 62.559948 -45.402071) (xy 62.559948 -45.350097)
			(xy 62.568078 -45.298762) (xy 62.584139 -45.249332) (xy 62.607735 -45.203022) (xy 62.638285 -45.160974)
			(xy 62.675036 -45.124223) (xy 62.717084 -45.093673) (xy 62.763394 -45.070077) (xy 62.812824 -45.054016)
			(xy 62.864159 -45.045886) (xy 62.916133 -45.045886) (xy 62.967468 -45.054016) (xy 63.016898 -45.070077)
			(xy 63.063208 -45.093673) (xy 63.105256 -45.124223) (xy 63.142007 -45.160974) (xy 63.172557 -45.203022)
			(xy 63.196153 -45.249332) (xy 63.212214 -45.298762) (xy 63.220344 -45.350097) (xy 63.220854 -45.376084)
			(xy 63.220344 -45.402071) (xy 63.360048 -45.402071) (xy 63.360048 -45.350097) (xy 63.368178 -45.298762)
			(xy 63.384239 -45.249332) (xy 63.407835 -45.203022) (xy 63.438385 -45.160974) (xy 63.475136 -45.124223)
			(xy 63.517184 -45.093673) (xy 63.563494 -45.070077) (xy 63.612924 -45.054016) (xy 63.664259 -45.045886)
			(xy 63.716233 -45.045886) (xy 63.767568 -45.054016) (xy 63.816998 -45.070077) (xy 63.863308 -45.093673)
			(xy 63.905356 -45.124223) (xy 63.942107 -45.160974) (xy 63.972657 -45.203022) (xy 63.996253 -45.249332)
			(xy 64.012314 -45.298762) (xy 64.020444 -45.350097) (xy 64.020954 -45.376084) (xy 64.020444 -45.402071)
			(xy 64.159894 -45.402071) (xy 64.159894 -45.350097) (xy 64.168024 -45.298762) (xy 64.184085 -45.249332)
			(xy 64.207681 -45.203022) (xy 64.238231 -45.160974) (xy 64.274982 -45.124223) (xy 64.31703 -45.093673)
			(xy 64.36334 -45.070077) (xy 64.41277 -45.054016) (xy 64.464105 -45.045886) (xy 64.516079 -45.045886)
			(xy 64.567414 -45.054016) (xy 64.616844 -45.070077) (xy 64.663154 -45.093673) (xy 64.705202 -45.124223)
			(xy 64.741953 -45.160974) (xy 64.772503 -45.203022) (xy 64.796099 -45.249332) (xy 64.81216 -45.298762)
			(xy 64.82029 -45.350097) (xy 64.8208 -45.376084) (xy 64.82029 -45.402071) (xy 64.81216 -45.453406)
			(xy 64.796099 -45.502836) (xy 64.772503 -45.549146) (xy 64.741953 -45.591194) (xy 64.705202 -45.627945)
			(xy 64.663154 -45.658495) (xy 64.616844 -45.682091) (xy 64.567414 -45.698152) (xy 64.516079 -45.706282)
			(xy 64.464105 -45.706282) (xy 64.41277 -45.698152) (xy 64.36334 -45.682091) (xy 64.31703 -45.658495)
			(xy 64.274982 -45.627945) (xy 64.238231 -45.591194) (xy 64.207681 -45.549146) (xy 64.184085 -45.502836)
			(xy 64.168024 -45.453406) (xy 64.159894 -45.402071) (xy 64.020444 -45.402071) (xy 64.012314 -45.453406)
			(xy 63.996253 -45.502836) (xy 63.972657 -45.549146) (xy 63.942107 -45.591194) (xy 63.905356 -45.627945)
			(xy 63.863308 -45.658495) (xy 63.816998 -45.682091) (xy 63.767568 -45.698152) (xy 63.716233 -45.706282)
			(xy 63.664259 -45.706282) (xy 63.612924 -45.698152) (xy 63.563494 -45.682091) (xy 63.517184 -45.658495)
			(xy 63.475136 -45.627945) (xy 63.438385 -45.591194) (xy 63.407835 -45.549146) (xy 63.384239 -45.502836)
			(xy 63.368178 -45.453406) (xy 63.360048 -45.402071) (xy 63.220344 -45.402071) (xy 63.212214 -45.453406)
			(xy 63.196153 -45.502836) (xy 63.172557 -45.549146) (xy 63.142007 -45.591194) (xy 63.105256 -45.627945)
			(xy 63.063208 -45.658495) (xy 63.016898 -45.682091) (xy 62.967468 -45.698152) (xy 62.916133 -45.706282)
			(xy 62.864159 -45.706282) (xy 62.812824 -45.698152) (xy 62.763394 -45.682091) (xy 62.717084 -45.658495)
			(xy 62.675036 -45.627945) (xy 62.638285 -45.591194) (xy 62.607735 -45.549146) (xy 62.584139 -45.502836)
			(xy 62.568078 -45.453406) (xy 62.559948 -45.402071) (xy 62.420514 -45.402071) (xy 62.420514 -45.402088)
			(xy 62.412383 -45.453425) (xy 62.396322 -45.502858) (xy 62.372725 -45.54917) (xy 62.342173 -45.59122)
			(xy 62.30542 -45.627973) (xy 62.26337 -45.658525) (xy 62.217058 -45.682122) (xy 62.167625 -45.698183)
			(xy 62.116288 -45.706314) (xy 62.0903 -45.706792) (xy 62.069039 -45.706446) (xy 62.02687 -45.700969)
			(xy 62.006226 -45.69587) (xy 61.977778 -45.688504) (xy 61.92139 -45.745146) (xy 61.95568 -45.779182)
			(xy 61.95568 -45.85462) (xy 62.012068 -45.85462) (xy 62.017402 -45.85335) (xy 62.035386 -45.849544)
			(xy 62.07192 -45.84547) (xy 62.0903 -45.845222) (xy 62.116285 -45.845731) (xy 62.167615 -45.853861)
			(xy 62.217041 -45.869921) (xy 62.263346 -45.893515) (xy 62.30539 -45.924062) (xy 62.342138 -45.96081)
			(xy 62.372685 -46.002854) (xy 62.396279 -46.049159) (xy 62.412339 -46.098585) (xy 62.420469 -46.149915)
			(xy 62.420469 -46.201885) (xy 62.420464 -46.201917) (xy 62.559948 -46.201917) (xy 62.559948 -46.149943)
			(xy 62.568078 -46.098608) (xy 62.584139 -46.049178) (xy 62.607735 -46.002868) (xy 62.638285 -45.96082)
			(xy 62.675036 -45.924069) (xy 62.717084 -45.893519) (xy 62.763394 -45.869923) (xy 62.812824 -45.853862)
			(xy 62.864159 -45.845732) (xy 62.916133 -45.845732) (xy 62.967468 -45.853862) (xy 63.016898 -45.869923)
			(xy 63.063208 -45.893519) (xy 63.105256 -45.924069) (xy 63.142007 -45.96082) (xy 63.172557 -46.002868)
			(xy 63.196153 -46.049178) (xy 63.212214 -46.098608) (xy 63.220344 -46.149943) (xy 63.220854 -46.17593)
			(xy 63.220344 -46.201917) (xy 63.212214 -46.253252) (xy 63.196153 -46.302682) (xy 63.172557 -46.348992)
			(xy 63.142007 -46.39104) (xy 63.105256 -46.427791) (xy 63.063208 -46.458341) (xy 63.016898 -46.481937)
			(xy 62.967468 -46.497998) (xy 62.916133 -46.506128) (xy 62.864159 -46.506128) (xy 62.812824 -46.497998)
			(xy 62.763394 -46.481937) (xy 62.717084 -46.458341) (xy 62.675036 -46.427791) (xy 62.638285 -46.39104)
			(xy 62.607735 -46.348992) (xy 62.584139 -46.302682) (xy 62.568078 -46.253252) (xy 62.559948 -46.201917)
			(xy 62.420464 -46.201917) (xy 62.412339 -46.253215) (xy 62.396279 -46.302641) (xy 62.372685 -46.348946)
			(xy 62.342138 -46.39099) (xy 62.30539 -46.427738) (xy 62.263346 -46.458285) (xy 62.217041 -46.481879)
			(xy 62.167615 -46.497939) (xy 62.116285 -46.506069) (xy 62.0903 -46.506638) (xy 62.07192 -46.506388)
			(xy 62.035386 -46.502314) (xy 62.017402 -46.49851) (xy 62.012068 -46.49724) (xy 61.95568 -46.49724)
			(xy 61.95568 -46.65472) (xy 62.012068 -46.65472) (xy 62.017402 -46.65345) (xy 62.035386 -46.649644)
			(xy 62.07192 -46.64557) (xy 62.0903 -46.645322) (xy 62.116285 -46.645831) (xy 62.167615 -46.653961)
			(xy 62.217041 -46.670021) (xy 62.263346 -46.693615) (xy 62.30539 -46.724162) (xy 62.342138 -46.76091)
			(xy 62.372685 -46.802954) (xy 62.396279 -46.849259) (xy 62.412339 -46.898685) (xy 62.420469 -46.950015)
			(xy 62.420469 -47.001985) (xy 62.420464 -47.002017) (xy 62.559948 -47.002017) (xy 62.559948 -46.950043)
			(xy 62.568078 -46.898708) (xy 62.584139 -46.849278) (xy 62.607735 -46.802968) (xy 62.638285 -46.76092)
			(xy 62.675036 -46.724169) (xy 62.717084 -46.693619) (xy 62.763394 -46.670023) (xy 62.812824 -46.653962)
			(xy 62.864159 -46.645832) (xy 62.916133 -46.645832) (xy 62.967468 -46.653962) (xy 63.016898 -46.670023)
			(xy 63.063208 -46.693619) (xy 63.105256 -46.724169) (xy 63.142007 -46.76092) (xy 63.172557 -46.802968)
			(xy 63.196153 -46.849278) (xy 63.212214 -46.898708) (xy 63.220344 -46.950043) (xy 63.220854 -46.97603)
			(xy 63.220344 -47.002017) (xy 63.212214 -47.053352) (xy 63.196153 -47.102782) (xy 63.172557 -47.149092)
			(xy 63.142007 -47.19114) (xy 63.105256 -47.227891) (xy 63.063208 -47.258441) (xy 63.016898 -47.282037)
			(xy 62.967468 -47.298098) (xy 62.916133 -47.306228) (xy 62.864159 -47.306228) (xy 62.812824 -47.298098)
			(xy 62.763394 -47.282037) (xy 62.717084 -47.258441) (xy 62.675036 -47.227891) (xy 62.638285 -47.19114)
			(xy 62.607735 -47.149092) (xy 62.584139 -47.102782) (xy 62.568078 -47.053352) (xy 62.559948 -47.002017)
			(xy 62.420464 -47.002017) (xy 62.412339 -47.053315) (xy 62.396279 -47.102741) (xy 62.372685 -47.149046)
			(xy 62.342138 -47.19109) (xy 62.30539 -47.227838) (xy 62.263346 -47.258385) (xy 62.217041 -47.281979)
			(xy 62.167615 -47.298039) (xy 62.116285 -47.306169) (xy 62.0903 -47.306738) (xy 62.065844 -47.306296)
			(xy 62.017465 -47.299086) (xy 61.970678 -47.284823) (xy 61.926504 -47.263818) (xy 61.88591 -47.236532)
			(xy 61.867542 -47.220378) (xy 61.855689 -47.210363) (xy 61.827531 -47.19736) (xy 61.796771 -47.193389)
			(xy 61.766234 -47.198815) (xy 61.738725 -47.21314) (xy 61.727334 -47.22368) (xy 61.486034 -47.46498)
			(xy 61.273944 -47.46498) (xy 61.267594 -47.47133) (xy 61.135768 -47.47133) (xy 61.045852 -47.561246)
			(xy 61.045852 -47.802117) (xy 61.760102 -47.802117) (xy 61.760102 -47.750143) (xy 61.768232 -47.698808)
			(xy 61.784293 -47.649378) (xy 61.807889 -47.603068) (xy 61.838439 -47.56102) (xy 61.87519 -47.524269)
			(xy 61.917238 -47.493719) (xy 61.963548 -47.470123) (xy 62.012978 -47.454062) (xy 62.064313 -47.445932)
			(xy 62.116287 -47.445932) (xy 62.167622 -47.454062) (xy 62.217052 -47.470123) (xy 62.263362 -47.493719)
			(xy 62.30541 -47.524269) (xy 62.342161 -47.56102) (xy 62.372711 -47.603068) (xy 62.396307 -47.649378)
			(xy 62.412368 -47.698808) (xy 62.420498 -47.750143) (xy 62.421008 -47.77613) (xy 62.420498 -47.802117)
			(xy 62.559948 -47.802117) (xy 62.559948 -47.750143) (xy 62.568078 -47.698808) (xy 62.584139 -47.649378)
			(xy 62.607735 -47.603068) (xy 62.638285 -47.56102) (xy 62.675036 -47.524269) (xy 62.717084 -47.493719)
			(xy 62.763394 -47.470123) (xy 62.812824 -47.454062) (xy 62.864159 -47.445932) (xy 62.916133 -47.445932)
			(xy 62.967468 -47.454062) (xy 63.016898 -47.470123) (xy 63.063208 -47.493719) (xy 63.105256 -47.524269)
			(xy 63.142007 -47.56102) (xy 63.172557 -47.603068) (xy 63.196153 -47.649378) (xy 63.212214 -47.698808)
			(xy 63.220344 -47.750143) (xy 63.220854 -47.77613) (xy 63.220344 -47.802117) (xy 63.212214 -47.853452)
			(xy 63.196153 -47.902882) (xy 63.172557 -47.949192) (xy 63.142007 -47.99124) (xy 63.105256 -48.027991)
			(xy 63.063208 -48.058541) (xy 63.016898 -48.082137) (xy 62.967468 -48.098198) (xy 62.916133 -48.106328)
			(xy 62.864159 -48.106328) (xy 62.812824 -48.098198) (xy 62.763394 -48.082137) (xy 62.717084 -48.058541)
			(xy 62.675036 -48.027991) (xy 62.638285 -47.99124) (xy 62.607735 -47.949192) (xy 62.584139 -47.902882)
			(xy 62.568078 -47.853452) (xy 62.559948 -47.802117) (xy 62.420498 -47.802117) (xy 62.412368 -47.853452)
			(xy 62.396307 -47.902882) (xy 62.372711 -47.949192) (xy 62.342161 -47.99124) (xy 62.30541 -48.027991)
			(xy 62.263362 -48.058541) (xy 62.217052 -48.082137) (xy 62.167622 -48.098198) (xy 62.116287 -48.106328)
			(xy 62.064313 -48.106328) (xy 62.012978 -48.098198) (xy 61.963548 -48.082137) (xy 61.917238 -48.058541)
			(xy 61.87519 -48.027991) (xy 61.838439 -47.99124) (xy 61.807889 -47.949192) (xy 61.784293 -47.902882)
			(xy 61.768232 -47.853452) (xy 61.760102 -47.802117) (xy 61.045852 -47.802117) (xy 61.045852 -47.844456)
			(xy 60.919106 -47.971202) (xy 60.856368 -47.971202) (xy 60.856368 -47.974504) (xy 60.240418 -47.974504)
			(xy 60.209684 -48.005238) (xy 60.209684 -48.487838) (xy 60.330588 -48.608996) (xy 60.957714 -48.608996)
			(xy 60.959746 -48.560482) (xy 60.961397 -48.535314) (xy 60.971374 -48.485875) (xy 60.988744 -48.438525)
			(xy 61.013104 -48.394362) (xy 61.043889 -48.354412) (xy 61.080385 -48.319601) (xy 61.121745 -48.290738)
			(xy 61.167009 -48.268491) (xy 61.215127 -48.253377) (xy 61.264982 -48.245746) (xy 61.2902 -48.245268)
			(xy 61.316846 -48.245812) (xy 61.369444 -48.254375) (xy 61.419989 -48.271265) (xy 61.467169 -48.296043)
			(xy 61.509765 -48.328068) (xy 61.546672 -48.36651) (xy 61.576936 -48.410375) (xy 61.599772 -48.458525)
			(xy 61.614589 -48.509715) (xy 61.618368 -48.536098) (xy 61.620654 -48.55337) (xy 61.668914 -48.60163)
			(xy 61.767466 -48.503078) (xy 61.771022 -48.490124) (xy 61.778571 -48.464145) (xy 61.80094 -48.41489)
			(xy 61.831025 -48.36993) (xy 61.868023 -48.330463) (xy 61.910949 -48.297541) (xy 61.958658 -48.272042)
			(xy 62.009881 -48.254644) (xy 62.063252 -48.245811) (xy 62.0903 -48.245268) (xy 62.116288 -48.245778)
			(xy 62.167624 -48.253908) (xy 62.217056 -48.269969) (xy 62.263367 -48.293564) (xy 62.305417 -48.324113)
			(xy 62.342171 -48.360865) (xy 62.372723 -48.402912) (xy 62.396322 -48.449222) (xy 62.412386 -48.498653)
			(xy 62.420521 -48.549988) (xy 62.421008 -48.575976) (xy 62.420524 -48.60166) (xy 62.420477 -48.601963)
			(xy 62.559948 -48.601963) (xy 62.559948 -48.549989) (xy 62.568078 -48.498654) (xy 62.584139 -48.449224)
			(xy 62.607735 -48.402914) (xy 62.638285 -48.360866) (xy 62.675036 -48.324115) (xy 62.717084 -48.293565)
			(xy 62.763394 -48.269969) (xy 62.812824 -48.253908) (xy 62.864159 -48.245778) (xy 62.916133 -48.245778)
			(xy 62.967468 -48.253908) (xy 63.016898 -48.269969) (xy 63.063208 -48.293565) (xy 63.105256 -48.324115)
			(xy 63.142007 -48.360866) (xy 63.172557 -48.402914) (xy 63.196153 -48.449224) (xy 63.212214 -48.498654)
			(xy 63.220344 -48.549989) (xy 63.220854 -48.575976) (xy 63.220344 -48.601963) (xy 63.212214 -48.653298)
			(xy 63.196153 -48.702728) (xy 63.172557 -48.749038) (xy 63.142007 -48.791086) (xy 63.105256 -48.827837)
			(xy 63.063208 -48.858387) (xy 63.016898 -48.881983) (xy 62.967468 -48.898044) (xy 62.916133 -48.906174)
			(xy 62.864159 -48.906174) (xy 62.812824 -48.898044) (xy 62.763394 -48.881983) (xy 62.717084 -48.858387)
			(xy 62.675036 -48.827837) (xy 62.638285 -48.791086) (xy 62.607735 -48.749038) (xy 62.584139 -48.702728)
			(xy 62.568078 -48.653298) (xy 62.559948 -48.601963) (xy 62.420477 -48.601963) (xy 62.412585 -48.652412)
			(xy 62.396894 -48.701325) (xy 62.373829 -48.747224) (xy 62.343944 -48.789005) (xy 62.307958 -48.825662)
			(xy 62.287658 -48.841406) (xy 62.287658 -49.680114) (xy 62.334648 -49.727104) (xy 62.66434 -49.727104)
		)
		(stroke
			(width 0)
			(type solid)
		)
		(fill yes)
		(layer "B.Cu")
		(net "P1V2_STBY_MVDD_CK")
	)
	(gr_poly
		(pts
			(xy -3.999992 -119.892064) (xy -3.944185 -119.891542) (xy -3.832883 -119.883201) (xy -3.722516 -119.866566)
			(xy -3.6137 -119.841729) (xy -3.507045 -119.80883) (xy -3.403146 -119.768053) (xy -3.302586 -119.719626)
			(xy -3.205925 -119.663818) (xy -3.113705 -119.600944) (xy -3.026442 -119.531354) (xy -2.944623 -119.455437)
			(xy -2.868706 -119.373618) (xy -2.799116 -119.286355) (xy -2.736242 -119.194135) (xy -2.680434 -119.097474)
			(xy -2.632007 -118.996914) (xy -2.59123 -118.893015) (xy -2.558331 -118.78636) (xy -2.533494 -118.677544)
			(xy -2.516859 -118.567177) (xy -2.508518 -118.455875) (xy -2.507996 -118.400068) (xy -2.507996 -6.59003)
			(xy -2.508518 -6.534223) (xy -2.516859 -6.422921) (xy -2.533494 -6.312554) (xy -2.558331 -6.203738)
			(xy -2.59123 -6.097083) (xy -2.632007 -5.993184) (xy -2.680434 -5.892624) (xy -2.736242 -5.795963)
			(xy -2.799116 -5.703743) (xy -2.868706 -5.61648) (xy -2.944623 -5.534661) (xy -3.026442 -5.458744)
			(xy -3.113705 -5.389154) (xy -3.205925 -5.32628) (xy -3.302586 -5.270472) (xy -3.403146 -5.222045)
			(xy -3.507045 -5.181268) (xy -3.6137 -5.148369) (xy -3.722516 -5.123532) (xy -3.832883 -5.106897)
			(xy -3.944185 -5.098556) (xy -3.999992 -5.098034) (xy -17.78 -5.098034) (xy -17.835807 -5.098556)
			(xy -17.947109 -5.106897) (xy -18.057476 -5.123532) (xy -18.166292 -5.148369) (xy -18.272947 -5.181268)
			(xy -18.376846 -5.222045) (xy -18.477406 -5.270472) (xy -18.574067 -5.32628) (xy -18.666287 -5.389154)
			(xy -18.75355 -5.458744) (xy -18.835369 -5.534661) (xy -18.911286 -5.61648) (xy -18.980876 -5.703743)
			(xy -19.04375 -5.795963) (xy -19.099558 -5.892624) (xy -19.147985 -5.993184) (xy -19.188762 -6.097083)
			(xy -19.221661 -6.203738) (xy -19.246498 -6.312554) (xy -19.263133 -6.422921) (xy -19.271474 -6.534223)
			(xy -19.271996 -6.59003) (xy -19.271996 -115.464644) (xy -16.875771 -115.464644) (xy -16.875771 -115.335504)
			(xy -16.867821 -115.206609) (xy -16.851951 -115.078449) (xy -16.828222 -114.951508) (xy -16.796723 -114.826269)
			(xy -16.757574 -114.703206) (xy -16.710923 -114.582787) (xy -16.656948 -114.465468) (xy -16.595853 -114.351694)
			(xy -16.52787 -114.241897) (xy -16.453256 -114.136494) (xy -16.372295 -114.035884) (xy -16.285295 -113.940449)
			(xy -16.192584 -113.85055) (xy -16.094514 -113.766529) (xy -15.991459 -113.688705) (xy -15.883808 -113.617373)
			(xy -15.771969 -113.552803) (xy -15.656368 -113.495241) (xy -15.537443 -113.444904) (xy -15.415644 -113.401984)
			(xy -15.291434 -113.366643) (xy -15.165285 -113.339016) (xy -15.037673 -113.319207) (xy -14.909084 -113.307291)
			(xy -14.780006 -113.303315) (xy -14.650928 -113.307291) (xy -14.522339 -113.319207) (xy -14.394727 -113.339016)
			(xy -14.268578 -113.366643) (xy -14.144368 -113.401984) (xy -14.022569 -113.444904) (xy -13.903644 -113.495241)
			(xy -13.788043 -113.552803) (xy -13.676204 -113.617373) (xy -13.568553 -113.688705) (xy -13.465498 -113.766529)
			(xy -13.367428 -113.85055) (xy -13.274717 -113.940449) (xy -13.187717 -114.035884) (xy -13.106756 -114.136494)
			(xy -13.032142 -114.241897) (xy -12.964159 -114.351694) (xy -12.903064 -114.465468) (xy -12.849089 -114.582787)
			(xy -12.802438 -114.703206) (xy -12.763289 -114.826269) (xy -12.73179 -114.951508) (xy -12.708061 -115.078449)
			(xy -12.692191 -115.206609) (xy -12.684241 -115.335504) (xy -12.683744 -115.400074) (xy -12.684241 -115.464644)
			(xy -12.692191 -115.593539) (xy -12.708061 -115.721699) (xy -12.73179 -115.84864) (xy -12.763289 -115.973879)
			(xy -12.802438 -116.096942) (xy -12.849089 -116.217361) (xy -12.903064 -116.33468) (xy -12.964159 -116.448454)
			(xy -13.032142 -116.558251) (xy -13.106756 -116.663654) (xy -13.187717 -116.764264) (xy -13.274717 -116.859699)
			(xy -13.367428 -116.949598) (xy -13.465498 -117.033619) (xy -13.568553 -117.111443) (xy -13.676204 -117.182775)
			(xy -13.788043 -117.247345) (xy -13.903644 -117.304907) (xy -14.022569 -117.355244) (xy -14.144368 -117.398164)
			(xy -14.268578 -117.433505) (xy -14.394727 -117.461132) (xy -14.522339 -117.480941) (xy -14.650928 -117.492857)
			(xy -14.780006 -117.496834) (xy -14.909084 -117.492857) (xy -15.037673 -117.480941) (xy -15.165285 -117.461132)
			(xy -15.291434 -117.433505) (xy -15.415644 -117.398164) (xy -15.537443 -117.355244) (xy -15.656368 -117.304907)
			(xy -15.771969 -117.247345) (xy -15.883808 -117.182775) (xy -15.991459 -117.111443) (xy -16.094514 -117.033619)
			(xy -16.192584 -116.949598) (xy -16.285295 -116.859699) (xy -16.372295 -116.764264) (xy -16.453256 -116.663654)
			(xy -16.52787 -116.558251) (xy -16.595853 -116.448454) (xy -16.656948 -116.33468) (xy -16.710923 -116.217361)
			(xy -16.757574 -116.096942) (xy -16.796723 -115.973879) (xy -16.828222 -115.84864) (xy -16.851951 -115.721699)
			(xy -16.867821 -115.593539) (xy -16.875771 -115.464644) (xy -19.271996 -115.464644) (xy -19.271996 -118.400068)
			(xy -19.271474 -118.455875) (xy -19.263133 -118.567177) (xy -19.246498 -118.677544) (xy -19.221661 -118.78636)
			(xy -19.188762 -118.893015) (xy -19.147985 -118.996914) (xy -19.099558 -119.097474) (xy -19.04375 -119.194135)
			(xy -18.980876 -119.286355) (xy -18.911286 -119.373618) (xy -18.835369 -119.455437) (xy -18.75355 -119.531354)
			(xy -18.666287 -119.600944) (xy -18.574067 -119.663818) (xy -18.477406 -119.719626) (xy -18.376846 -119.768053)
			(xy -18.272947 -119.80883) (xy -18.166292 -119.841729) (xy -18.057476 -119.866566) (xy -17.947109 -119.883201)
			(xy -17.835807 -119.891542) (xy -17.78 -119.892064)
		)
		(stroke
			(width 0)
			(type solid)
		)
		(fill yes)
		(layer "In1.Cu")
		(net "T_GND")
	)
	(gr_poly
		(pts
			(xy 10.256012 -118.78437) (xy 10.256012 -114.799872) (xy 10.256503 -114.755847) (xy 10.264197 -114.668134)
			(xy 10.279504 -114.581425) (xy 10.302308 -114.49638) (xy 10.332434 -114.413645) (xy 10.369655 -114.333849)
			(xy 10.413686 -114.257599) (xy 10.464194 -114.185476) (xy 10.520793 -114.118028) (xy 10.583054 -114.055768)
			(xy 10.650503 -113.999169) (xy 10.722626 -113.948662) (xy 10.798876 -113.904631) (xy 10.878672 -113.867411)
			(xy 10.961408 -113.837285) (xy 11.046453 -113.814482) (xy 11.133162 -113.799176) (xy 11.220875 -113.791483)
			(xy 11.2649 -113.790984) (xy 12.765024 -113.790984) (xy 12.809049 -113.791474) (xy 12.896764 -113.799165)
			(xy 12.983474 -113.81447) (xy 13.068521 -113.837272) (xy 13.078373 -113.840859) (xy 20.444184 -113.840859)
			(xy 20.444184 -113.786321) (xy 20.451946 -113.732337) (xy 20.467311 -113.680007) (xy 20.489968 -113.630397)
			(xy 20.519454 -113.584516) (xy 20.555169 -113.543299) (xy 20.596386 -113.507584) (xy 20.642267 -113.478098)
			(xy 20.691877 -113.455441) (xy 20.744207 -113.440076) (xy 20.798191 -113.432314) (xy 20.82546 -113.431828)
			(xy 21.71446 -113.431828) (xy 21.741732 -113.432309) (xy 21.795722 -113.440066) (xy 21.848058 -113.455428)
			(xy 21.897675 -113.478083) (xy 21.943562 -113.507569) (xy 21.984786 -113.543285) (xy 22.020507 -113.584506)
			(xy 22.049998 -113.63039) (xy 22.072658 -113.680004) (xy 22.088025 -113.732339) (xy 22.095788 -113.786328)
			(xy 22.095788 -113.840872) (xy 22.088025 -113.894861) (xy 22.072658 -113.947196) (xy 22.049998 -113.99681)
			(xy 22.020507 -114.042694) (xy 21.984786 -114.083915) (xy 21.943562 -114.119631) (xy 21.897675 -114.149117)
			(xy 21.848058 -114.171772) (xy 21.795722 -114.187134) (xy 21.741732 -114.194891) (xy 21.71446 -114.195352)
			(xy 20.82546 -114.195352) (xy 20.798191 -114.194866) (xy 20.744207 -114.187104) (xy 20.691877 -114.171739)
			(xy 20.642267 -114.149082) (xy 20.596386 -114.119596) (xy 20.555169 -114.083881) (xy 20.519454 -114.042664)
			(xy 20.489968 -113.996783) (xy 20.467311 -113.947173) (xy 20.451946 -113.894843) (xy 20.444184 -113.840859)
			(xy 13.078373 -113.840859) (xy 13.151258 -113.867397) (xy 13.231056 -113.904617) (xy 13.307307 -113.948648)
			(xy 13.379432 -113.999155) (xy 13.446881 -114.055754) (xy 13.509143 -114.118016) (xy 13.565743 -114.185465)
			(xy 13.61625 -114.25759) (xy 13.660282 -114.33384) (xy 13.697502 -114.413638) (xy 13.727627 -114.496375)
			(xy 13.750429 -114.581422) (xy 13.765734 -114.668132) (xy 13.773426 -114.755847) (xy 13.773912 -114.799872)
			(xy 13.773912 -116.038376) (xy 13.96492 -116.038376) (xy 13.96492 -115.149376) (xy 13.965406 -115.122125)
			(xy 13.973162 -115.068177) (xy 13.988517 -115.015882) (xy 14.011159 -114.966305) (xy 14.040625 -114.920455)
			(xy 14.076316 -114.879264) (xy 14.117507 -114.843573) (xy 14.163357 -114.814107) (xy 14.212934 -114.791465)
			(xy 14.265229 -114.77611) (xy 14.319177 -114.768354) (xy 14.373679 -114.768354) (xy 14.427627 -114.77611)
			(xy 14.479922 -114.791465) (xy 14.529499 -114.814107) (xy 14.575349 -114.843573) (xy 14.61654 -114.879264)
			(xy 14.652231 -114.920455) (xy 14.681697 -114.966305) (xy 14.704339 -115.015882) (xy 14.719694 -115.068177)
			(xy 14.72745 -115.122125) (xy 14.727936 -115.149376) (xy 14.727936 -116.038376) (xy 15.764764 -116.038376)
			(xy 15.764764 -115.149376) (xy 15.76525 -115.122107) (xy 15.773012 -115.068123) (xy 15.788377 -115.015793)
			(xy 15.811034 -114.966183) (xy 15.84052 -114.920302) (xy 15.876235 -114.879085) (xy 15.917452 -114.84337)
			(xy 15.963333 -114.813884) (xy 16.012943 -114.791227) (xy 16.065273 -114.775862) (xy 16.119257 -114.7681)
			(xy 16.173795 -114.7681) (xy 16.227779 -114.775862) (xy 16.280109 -114.791227) (xy 16.329719 -114.813884)
			(xy 16.3756 -114.84337) (xy 16.416817 -114.879085) (xy 16.452532 -114.920302) (xy 16.482018 -114.966183)
			(xy 16.504675 -115.015793) (xy 16.510811 -115.036691) (xy 23.190153 -115.036691) (xy 23.190153 -114.982149)
			(xy 23.197916 -114.928162) (xy 23.213282 -114.875829) (xy 23.23594 -114.826216) (xy 23.265428 -114.780333)
			(xy 23.301145 -114.739113) (xy 23.342366 -114.703395) (xy 23.38825 -114.673908) (xy 23.437863 -114.651251)
			(xy 23.490196 -114.635885) (xy 23.544183 -114.628123) (xy 23.571454 -114.62766) (xy 24.460454 -114.62766)
			(xy 24.487723 -114.628143) (xy 24.541707 -114.635905) (xy 24.594036 -114.651271) (xy 24.643646 -114.673927)
			(xy 24.689527 -114.703413) (xy 24.730744 -114.739129) (xy 24.766459 -114.780347) (xy 24.795945 -114.826227)
			(xy 24.818601 -114.875838) (xy 24.833966 -114.928167) (xy 24.841728 -114.982151) (xy 24.841728 -115.036689)
			(xy 24.833966 -115.090673) (xy 24.818601 -115.143002) (xy 24.795945 -115.192613) (xy 24.766459 -115.238493)
			(xy 24.730744 -115.279711) (xy 24.689527 -115.315427) (xy 24.643646 -115.344913) (xy 24.594036 -115.367569)
			(xy 24.541707 -115.382935) (xy 24.487723 -115.390697) (xy 24.460454 -115.391184) (xy 23.571454 -115.391184)
			(xy 23.544183 -115.390717) (xy 23.490196 -115.382955) (xy 23.437863 -115.367589) (xy 23.38825 -115.344932)
			(xy 23.342366 -115.315445) (xy 23.301145 -115.279727) (xy 23.265428 -115.238507) (xy 23.23594 -115.192624)
			(xy 23.213282 -115.143011) (xy 23.197916 -115.090678) (xy 23.190153 -115.036691) (xy 16.510811 -115.036691)
			(xy 16.52004 -115.068123) (xy 16.527802 -115.122107) (xy 16.528288 -115.149376) (xy 16.528288 -116.038376)
			(xy 16.527802 -116.065645) (xy 16.52004 -116.119629) (xy 16.504675 -116.171959) (xy 16.482018 -116.221569)
			(xy 16.452532 -116.26745) (xy 16.416817 -116.308667) (xy 16.3756 -116.344382) (xy 16.329719 -116.373868)
			(xy 16.280109 -116.396525) (xy 16.227779 -116.41189) (xy 16.173795 -116.419652) (xy 16.119257 -116.419652)
			(xy 16.065273 -116.41189) (xy 16.012943 -116.396525) (xy 15.963333 -116.373868) (xy 15.917452 -116.344382)
			(xy 15.876235 -116.308667) (xy 15.84052 -116.26745) (xy 15.811034 -116.221569) (xy 15.788377 -116.171959)
			(xy 15.773012 -116.119629) (xy 15.76525 -116.065645) (xy 15.764764 -116.038376) (xy 14.727936 -116.038376)
			(xy 14.72745 -116.065627) (xy 14.719694 -116.119575) (xy 14.704339 -116.17187) (xy 14.681697 -116.221447)
			(xy 14.652231 -116.267297) (xy 14.61654 -116.308488) (xy 14.575349 -116.344179) (xy 14.529499 -116.373645)
			(xy 14.479922 -116.396287) (xy 14.427627 -116.411642) (xy 14.373679 -116.419398) (xy 14.319177 -116.419398)
			(xy 14.265229 -116.411642) (xy 14.212934 -116.396287) (xy 14.163357 -116.373645) (xy 14.117507 -116.344179)
			(xy 14.076316 -116.308488) (xy 14.040625 -116.267297) (xy 14.011159 -116.221447) (xy 13.988517 -116.17187)
			(xy 13.973162 -116.119575) (xy 13.965406 -116.065627) (xy 13.96492 -116.038376) (xy 13.773912 -116.038376)
			(xy 13.773912 -117.3734) (xy 31.116016 -117.3734) (xy 31.116016 -114.77498) (xy 31.116505 -114.713316)
			(xy 31.124564 -114.590252) (xy 31.140653 -114.467979) (xy 31.164706 -114.34702) (xy 31.196619 -114.227893)
			(xy 31.236255 -114.111108) (xy 31.283445 -113.997166) (xy 31.337986 -113.886554) (xy 31.399645 -113.779747)
			(xy 31.468158 -113.677201) (xy 31.543231 -113.579356) (xy 31.624543 -113.48663) (xy 31.711746 -113.399422)
			(xy 31.804466 -113.318103) (xy 31.902306 -113.243024) (xy 32.004847 -113.174504) (xy 32.11165 -113.112838)
			(xy 32.222258 -113.058289) (xy 32.336197 -113.011092) (xy 32.452979 -112.971448) (xy 32.572104 -112.939527)
			(xy 32.693062 -112.915466) (xy 32.815334 -112.899368) (xy 32.938397 -112.891302) (xy 33.061725 -112.891302)
			(xy 33.184788 -112.899368) (xy 33.30706 -112.915466) (xy 33.428018 -112.939527) (xy 33.547143 -112.971448)
			(xy 33.663925 -113.011092) (xy 33.777864 -113.058289) (xy 33.888472 -113.112838) (xy 33.995275 -113.174504)
			(xy 34.097816 -113.243024) (xy 34.195656 -113.318103) (xy 34.288376 -113.399422) (xy 34.375579 -113.48663)
			(xy 34.456891 -113.579356) (xy 34.531964 -113.677201) (xy 34.600477 -113.779747) (xy 34.662136 -113.886554)
			(xy 34.716677 -113.997166) (xy 34.763867 -114.111108) (xy 34.803503 -114.227893) (xy 34.835416 -114.34702)
			(xy 34.859469 -114.467979) (xy 34.875558 -114.590252) (xy 34.883617 -114.713316) (xy 34.884106 -114.77498)
			(xy 34.884106 -117.3734) (xy 43.825922 -117.3734) (xy 43.825922 -114.324892) (xy 43.826423 -114.271251)
			(xy 43.83444 -114.164269) (xy 43.85043 -114.058186) (xy 43.874302 -113.953594) (xy 43.905924 -113.851078)
			(xy 43.945119 -113.751213) (xy 43.991666 -113.654555) (xy 44.045307 -113.561646) (xy 44.105741 -113.473006)
			(xy 44.17263 -113.38913) (xy 44.245601 -113.310487) (xy 44.324244 -113.237516) (xy 44.40812 -113.170627)
			(xy 44.49676 -113.110193) (xy 44.589669 -113.056552) (xy 44.686327 -113.010005) (xy 44.786192 -112.97081)
			(xy 44.888708 -112.939188) (xy 44.9933 -112.915316) (xy 45.099383 -112.899326) (xy 45.206365 -112.891309)
			(xy 45.313647 -112.891309) (xy 45.420629 -112.899326) (xy 45.526712 -112.915316) (xy 45.631304 -112.939188)
			(xy 45.73382 -112.97081) (xy 45.833685 -113.010005) (xy 45.930343 -113.056552) (xy 46.023252 -113.110193)
			(xy 46.111892 -113.170627) (xy 46.195768 -113.237516) (xy 46.274411 -113.310487) (xy 46.347382 -113.38913)
			(xy 46.414271 -113.473006) (xy 46.474705 -113.561646) (xy 46.528346 -113.654555) (xy 46.574893 -113.751213)
			(xy 46.614088 -113.851078) (xy 46.64571 -113.953594) (xy 46.669582 -114.058186) (xy 46.685572 -114.164269)
			(xy 46.693589 -114.271251) (xy 46.69409 -114.324892) (xy 46.69409 -117.3734) (xy 64.026034 -117.3734)
			(xy 64.026034 -114.525044) (xy 64.026532 -114.468001) (xy 64.03449 -114.354194) (xy 64.050367 -114.24122)
			(xy 64.074087 -114.129628) (xy 64.105533 -114.019962) (xy 64.144553 -113.912757) (xy 64.190955 -113.808535)
			(xy 64.244515 -113.707804) (xy 64.304971 -113.611054) (xy 64.372028 -113.518758) (xy 64.445361 -113.431363)
			(xy 64.524611 -113.349297) (xy 64.609393 -113.27296) (xy 64.699293 -113.202722) (xy 64.793874 -113.138926)
			(xy 64.892674 -113.081884) (xy 64.995213 -113.031872) (xy 65.100991 -112.989135) (xy 65.209492 -112.953881)
			(xy 65.320188 -112.926281) (xy 65.43254 -112.906471) (xy 65.546 -112.894546) (xy 65.660016 -112.890564)
			(xy 65.774032 -112.894546) (xy 65.887492 -112.906471) (xy 65.999844 -112.926281) (xy 66.11054 -112.953881)
			(xy 66.219041 -112.989135) (xy 66.324819 -113.031872) (xy 66.427358 -113.081884) (xy 66.526158 -113.138926)
			(xy 66.620739 -113.202722) (xy 66.710639 -113.27296) (xy 66.795421 -113.349297) (xy 66.874671 -113.431363)
			(xy 66.948004 -113.518758) (xy 67.015061 -113.611054) (xy 67.075517 -113.707804) (xy 67.129077 -113.808535)
			(xy 67.175479 -113.912757) (xy 67.214499 -114.019962) (xy 67.245945 -114.129628) (xy 67.269665 -114.24122)
			(xy 67.285542 -114.354194) (xy 67.2935 -114.468001) (xy 67.293998 -114.525044) (xy 67.293998 -117.3734)
			(xy 76.230988 -117.3734) (xy 76.230988 -114.799872) (xy 76.231478 -114.755847) (xy 76.23917 -114.668133)
			(xy 76.254475 -114.581423) (xy 76.277277 -114.496376) (xy 76.307402 -114.413639) (xy 76.344622 -114.333842)
			(xy 76.388653 -114.257592) (xy 76.439161 -114.185468) (xy 76.49576 -114.118018) (xy 76.558021 -114.055757)
			(xy 76.625471 -113.999158) (xy 76.697595 -113.948651) (xy 76.773846 -113.90462) (xy 76.853643 -113.867401)
			(xy 76.93638 -113.837275) (xy 77.021427 -113.814474) (xy 77.108137 -113.799169) (xy 77.195851 -113.791478)
			(xy 77.239876 -113.790984) (xy 78.74 -113.790984) (xy 78.784039 -113.79145) (xy 78.871783 -113.799127)
			(xy 78.958523 -113.814422) (xy 79.043601 -113.837219) (xy 79.126367 -113.867344) (xy 79.206193 -113.904568)
			(xy 79.282471 -113.948608) (xy 79.354621 -113.999129) (xy 79.422092 -114.055745) (xy 79.484372 -114.118027)
			(xy 79.540987 -114.1855) (xy 79.591506 -114.257651) (xy 79.635544 -114.33393) (xy 79.672766 -114.413757)
			(xy 79.702889 -114.496524) (xy 79.725684 -114.581602) (xy 79.740976 -114.668343) (xy 79.748651 -114.756087)
			(xy 79.749142 -114.800126) (xy 79.749142 -118.7196) (xy 79.85379 -118.824248) (xy 80.16875 -118.824248)
			(xy 80.272636 -118.720616) (xy 83.93684 -118.720616) (xy 84.094574 -118.878096) (xy 84.394548 -118.878096)
			(xy 84.491068 -118.781576) (xy 84.491068 -114.799872) (xy 84.491558 -114.755847) (xy 84.49925 -114.668132)
			(xy 84.514555 -114.581421) (xy 84.537356 -114.496374) (xy 84.567482 -114.413636) (xy 84.604701 -114.333838)
			(xy 84.648732 -114.257587) (xy 84.69924 -114.185462) (xy 84.755839 -114.118012) (xy 84.8181 -114.05575)
			(xy 84.885549 -113.999149) (xy 84.957674 -113.948641) (xy 85.033924 -113.904609) (xy 85.113722 -113.867388)
			(xy 85.196458 -113.837261) (xy 85.281506 -113.814458) (xy 85.368216 -113.799152) (xy 85.455931 -113.791459)
			(xy 85.499956 -113.790984) (xy 88.000078 -113.790984) (xy 88.055848 -113.790476) (xy 88.167076 -113.782142)
			(xy 88.277371 -113.76552) (xy 88.386115 -113.740701) (xy 88.4927 -113.707825) (xy 88.596531 -113.667076)
			(xy 88.697025 -113.618682) (xy 88.793622 -113.562913) (xy 88.885782 -113.500081) (xy 88.972988 -113.430538)
			(xy 89.054754 -113.354672) (xy 89.130621 -113.272908) (xy 89.200166 -113.185703) (xy 89.262999 -113.093545)
			(xy 89.31877 -112.996948) (xy 89.367166 -112.896454) (xy 89.407917 -112.792625) (xy 89.440794 -112.68604)
			(xy 89.465615 -112.577297) (xy 89.48224 -112.467002) (xy 89.490575 -112.355774) (xy 89.491058 -112.300004)
			(xy 89.491058 -85.5091) (xy 87.749888 -85.5091) (xy 87.705865 -85.508603) (xy 87.618157 -85.500897)
			(xy 87.531453 -85.485581) (xy 87.446413 -85.46277) (xy 87.363683 -85.432637) (xy 87.283893 -85.395413)
			(xy 87.207648 -85.351379) (xy 87.13553 -85.300871) (xy 87.068085 -85.244273) (xy 87.005827 -85.182015)
			(xy 86.949229 -85.11457) (xy 86.898721 -85.042452) (xy 86.854687 -84.966207) (xy 86.817463 -84.886417)
			(xy 86.78733 -84.803687) (xy 86.764519 -84.718647) (xy 86.749203 -84.631943) (xy 86.741497 -84.544235)
			(xy 86.741 -84.500212) (xy 86.741 -81.999836) (xy 86.741491 -81.955812) (xy 86.749186 -81.868101)
			(xy 86.764493 -81.781393) (xy 86.787298 -81.69635) (xy 86.817425 -81.613616) (xy 86.854646 -81.533822)
			(xy 86.898678 -81.457575) (xy 86.949186 -81.385454) (xy 87.005786 -81.318008) (xy 87.068047 -81.255751)
			(xy 87.135495 -81.199154) (xy 87.207619 -81.14865) (xy 87.283869 -81.104622) (xy 87.363664 -81.067405)
			(xy 87.446399 -81.037282) (xy 87.531444 -81.014482) (xy 87.618152 -80.999179) (xy 87.705864 -80.991489)
			(xy 87.749888 -80.990948) (xy 89.491058 -80.990948) (xy 89.491058 -69.07022) (xy 89.492074 -69.069204)
			(xy 89.492074 -67.757802) (xy 89.491058 -67.756786) (xy 89.491058 -1.999996) (xy 89.490549 -1.944227)
			(xy 89.482214 -1.833001) (xy 89.465589 -1.722708) (xy 89.440769 -1.613967) (xy 89.407892 -1.507384)
			(xy 89.367142 -1.403556) (xy 89.318747 -1.303064) (xy 89.262977 -1.206469) (xy 89.200145 -1.114313)
			(xy 89.130601 -1.027109) (xy 89.054735 -0.945346) (xy 88.972971 -0.869482) (xy 88.885767 -0.79994)
			(xy 88.793609 -0.737109) (xy 88.697013 -0.681341) (xy 88.59652 -0.632947) (xy 88.492692 -0.592199)
			(xy 88.386108 -0.559324) (xy 88.277366 -0.534506) (xy 88.167074 -0.517883) (xy 88.055847 -0.50955)
			(xy 88.000078 -0.509016) (xy 1.999996 -0.509016) (xy 1.944227 -0.509538) (xy 1.833001 -0.517873)
			(xy 1.722709 -0.534497) (xy 1.613967 -0.559317) (xy 1.507385 -0.592194) (xy 1.403557 -0.632943) (xy 1.303065 -0.681338)
			(xy 1.20647 -0.737107) (xy 1.114313 -0.799938) (xy 1.027109 -0.869481) (xy 0.945346 -0.945346) (xy 0.869481 -1.027109)
			(xy 0.799938 -1.114313) (xy 0.737107 -1.20647) (xy 0.681338 -1.303065) (xy 0.632943 -1.403557) (xy 0.592194 -1.507385)
			(xy 0.559317 -1.613967) (xy 0.534497 -1.722709) (xy 0.517873 -1.833001) (xy 0.509538 -1.944227) (xy 0.509016 -1.999996)
			(xy 0.509016 -4.69011) (xy 3.634743 -4.69011) (xy 3.638781 -4.606614) (xy 3.65086 -4.523897) (xy 3.670865 -4.442732)
			(xy 3.69861 -4.363877) (xy 3.733837 -4.288068) (xy 3.776216 -4.216013) (xy 3.825351 -4.148384) (xy 3.880784 -4.085813)
			(xy 3.941997 -4.028884) (xy 4.008419 -3.978129) (xy 4.079429 -3.934021) (xy 4.154365 -3.896973) (xy 4.232527 -3.867331)
			(xy 4.313184 -3.84537) (xy 4.395585 -3.831296) (xy 4.478959 -3.825241) (xy 4.562529 -3.827261) (xy 4.645513 -3.837337)
			(xy 4.727138 -3.855375) (xy 4.80664 -3.881207) (xy 4.883279 -3.914592) (xy 4.956337 -3.955217) (xy 5.025133 -4.002704)
			(xy 5.089025 -4.056609) (xy 5.147417 -4.116428) (xy 5.199762 -4.181604) (xy 5.245572 -4.251528) (xy 5.284421 -4.325547)
			(xy 5.315943 -4.402969) (xy 5.339847 -4.483073) (xy 5.355907 -4.565109) (xy 5.363975 -4.648313) (xy 5.36448 -4.69011)
			(xy 10.635237 -4.69011) (xy 10.639274 -4.606638) (xy 10.651349 -4.523946) (xy 10.671348 -4.442805)
			(xy 10.699086 -4.363973) (xy 10.734302 -4.288186) (xy 10.776668 -4.216152) (xy 10.825789 -4.148543)
			(xy 10.881206 -4.08599) (xy 10.942401 -4.029078) (xy 11.008803 -3.978338) (xy 11.079793 -3.934243)
			(xy 11.154707 -3.897206) (xy 11.232845 -3.867572) (xy 11.313479 -3.845618) (xy 11.395856 -3.831548)
			(xy 11.479206 -3.825495) (xy 11.562751 -3.827514) (xy 11.645711 -3.837588) (xy 11.727311 -3.85562)
			(xy 11.80679 -3.881445) (xy 11.883406 -3.914819) (xy 11.956443 -3.955433) (xy 12.025219 -4.002906)
			(xy 12.089092 -4.056795) (xy 12.147467 -4.116597) (xy 12.199797 -4.181754) (xy 12.245594 -4.251657)
			(xy 12.28443 -4.325654) (xy 12.315944 -4.403054) (xy 12.33984 -4.483134) (xy 12.355896 -4.565146)
			(xy 12.363962 -4.648325) (xy 12.364466 -4.69011) (xy 12.363962 -4.731895) (xy 12.355896 -4.815074)
			(xy 12.33984 -4.897086) (xy 12.315944 -4.977166) (xy 12.28443 -5.054566) (xy 12.265749 -5.09016)
			(xy 66.234821 -5.09016) (xy 66.238859 -5.006664) (xy 66.250938 -4.923947) (xy 66.270943 -4.842782)
			(xy 66.298688 -4.763927) (xy 66.333915 -4.688118) (xy 66.376294 -4.616063) (xy 66.425429 -4.548434)
			(xy 66.480862 -4.485863) (xy 66.542075 -4.428934) (xy 66.608497 -4.378179) (xy 66.679507 -4.334071)
			(xy 66.754443 -4.297023) (xy 66.832605 -4.267381) (xy 66.913262 -4.24542) (xy 66.995663 -4.231346)
			(xy 67.079037 -4.225291) (xy 67.162607 -4.227311) (xy 67.245591 -4.237387) (xy 67.327216 -4.255425)
			(xy 67.406718 -4.281257) (xy 67.483357 -4.314642) (xy 67.556415 -4.355267) (xy 67.625211 -4.402754)
			(xy 67.689103 -4.456659) (xy 67.747495 -4.516478) (xy 67.79984 -4.581654) (xy 67.84565 -4.651578)
			(xy 67.884499 -4.725597) (xy 67.916021 -4.803019) (xy 67.939925 -4.883123) (xy 67.955985 -4.965159)
			(xy 67.964053 -5.048363) (xy 67.964558 -5.09016) (xy 73.235315 -5.09016) (xy 73.239352 -5.006688)
			(xy 73.251427 -4.923996) (xy 73.271426 -4.842855) (xy 73.299164 -4.764023) (xy 73.33438 -4.688236)
			(xy 73.376746 -4.616202) (xy 73.425867 -4.548593) (xy 73.481284 -4.48604) (xy 73.542479 -4.429128)
			(xy 73.608881 -4.378388) (xy 73.679871 -4.334293) (xy 73.754785 -4.297256) (xy 73.832923 -4.267622)
			(xy 73.913557 -4.245668) (xy 73.995934 -4.231598) (xy 74.079284 -4.225545) (xy 74.162829 -4.227564)
			(xy 74.245789 -4.237638) (xy 74.327389 -4.25567) (xy 74.406868 -4.281495) (xy 74.483484 -4.314869)
			(xy 74.556521 -4.355483) (xy 74.625297 -4.402956) (xy 74.68917 -4.456845) (xy 74.747545 -4.516647)
			(xy 74.799875 -4.581804) (xy 74.845672 -4.651707) (xy 74.865827 -4.69011) (xy 77.634595 -4.69011)
			(xy 77.638634 -4.606589) (xy 77.650716 -4.523848) (xy 77.670728 -4.44266) (xy 77.698481 -4.363781)
			(xy 77.733718 -4.28795) (xy 77.776109 -4.215873) (xy 77.825259 -4.148225) (xy 77.880708 -4.085635)
			(xy 77.941939 -4.02869) (xy 78.008381 -3.97792) (xy 78.079412 -3.933799) (xy 78.15437 -3.89674) (xy 78.232554 -3.867089)
			(xy 78.313236 -3.845122) (xy 78.395661 -3.831044) (xy 78.479059 -3.824987) (xy 78.562653 -3.827008)
			(xy 78.645662 -3.837087) (xy 78.727311 -3.85513) (xy 78.806836 -3.88097) (xy 78.883497 -3.914364)
			(xy 78.956577 -3.955001) (xy 79.025394 -4.002502) (xy 79.089304 -4.056423) (xy 79.147713 -4.11626)
			(xy 79.200073 -4.181455) (xy 79.245897 -4.251399) (xy 79.284757 -4.32544) (xy 79.316289 -4.402885)
			(xy 79.340199 -4.483012) (xy 79.356265 -4.565073) (xy 79.364335 -4.648301) (xy 79.36484 -4.69011)
			(xy 84.635089 -4.69011) (xy 84.639127 -4.606614) (xy 84.651206 -4.523897) (xy 84.671211 -4.442732)
			(xy 84.698956 -4.363877) (xy 84.734183 -4.288068) (xy 84.776562 -4.216013) (xy 84.825697 -4.148384)
			(xy 84.88113 -4.085813) (xy 84.942343 -4.028884) (xy 85.008765 -3.978129) (xy 85.079775 -3.934021)
			(xy 85.154711 -3.896973) (xy 85.232873 -3.867331) (xy 85.31353 -3.84537) (xy 85.395931 -3.831296)
			(xy 85.479305 -3.825241) (xy 85.562875 -3.827261) (xy 85.645859 -3.837337) (xy 85.727484 -3.855375)
			(xy 85.806986 -3.881207) (xy 85.883625 -3.914592) (xy 85.956683 -3.955217) (xy 86.025479 -4.002704)
			(xy 86.089371 -4.056609) (xy 86.147763 -4.116428) (xy 86.200108 -4.181604) (xy 86.245918 -4.251528)
			(xy 86.284767 -4.325547) (xy 86.316289 -4.402969) (xy 86.340193 -4.483073) (xy 86.356253 -4.565109)
			(xy 86.364321 -4.648313) (xy 86.364826 -4.69011) (xy 86.364321 -4.731907) (xy 86.356253 -4.815111)
			(xy 86.340193 -4.897147) (xy 86.316289 -4.977251) (xy 86.284767 -5.054673) (xy 86.245918 -5.128692)
			(xy 86.200108 -5.198616) (xy 86.147763 -5.263792) (xy 86.089371 -5.323611) (xy 86.025479 -5.377516)
			(xy 85.956683 -5.425003) (xy 85.883625 -5.465628) (xy 85.806986 -5.499013) (xy 85.727484 -5.524845)
			(xy 85.645859 -5.542883) (xy 85.562875 -5.552959) (xy 85.479305 -5.554979) (xy 85.395931 -5.548924)
			(xy 85.31353 -5.53485) (xy 85.232873 -5.512889) (xy 85.154711 -5.483247) (xy 85.079775 -5.446199)
			(xy 85.008765 -5.402091) (xy 84.942343 -5.351336) (xy 84.88113 -5.294407) (xy 84.825697 -5.231836)
			(xy 84.776562 -5.164207) (xy 84.734183 -5.092152) (xy 84.698956 -5.016343) (xy 84.671211 -4.937488)
			(xy 84.651206 -4.856323) (xy 84.639127 -4.773606) (xy 84.635089 -4.69011) (xy 79.36484 -4.69011)
			(xy 79.364335 -4.731919) (xy 79.356265 -4.815147) (xy 79.340199 -4.897208) (xy 79.316289 -4.977335)
			(xy 79.284757 -5.05478) (xy 79.245897 -5.128821) (xy 79.200073 -5.198765) (xy 79.147713 -5.26396)
			(xy 79.089304 -5.323797) (xy 79.025394 -5.377718) (xy 78.956577 -5.425219) (xy 78.883497 -5.465856)
			(xy 78.806836 -5.49925) (xy 78.727311 -5.52509) (xy 78.645662 -5.543133) (xy 78.562653 -5.553212)
			(xy 78.479059 -5.555233) (xy 78.395661 -5.549176) (xy 78.313236 -5.535098) (xy 78.232554 -5.513131)
			(xy 78.15437 -5.48348) (xy 78.079412 -5.446421) (xy 78.008381 -5.4023) (xy 77.941939 -5.35153) (xy 77.880708 -5.294585)
			(xy 77.825259 -5.231995) (xy 77.776109 -5.164347) (xy 77.733718 -5.09227) (xy 77.698481 -5.016439)
			(xy 77.670728 -4.93756) (xy 77.650716 -4.856372) (xy 77.638634 -4.773631) (xy 77.634595 -4.69011)
			(xy 74.865827 -4.69011) (xy 74.884508 -4.725704) (xy 74.916022 -4.803104) (xy 74.939918 -4.883184)
			(xy 74.955974 -4.965196) (xy 74.96404 -5.048375) (xy 74.964544 -5.09016) (xy 74.96404 -5.131945)
			(xy 74.955974 -5.215124) (xy 74.939918 -5.297136) (xy 74.916022 -5.377216) (xy 74.884508 -5.454616)
			(xy 74.845672 -5.528613) (xy 74.799875 -5.598516) (xy 74.747545 -5.663673) (xy 74.68917 -5.723475)
			(xy 74.625297 -5.777364) (xy 74.556521 -5.824837) (xy 74.483484 -5.865451) (xy 74.406868 -5.898825)
			(xy 74.327389 -5.92465) (xy 74.245789 -5.942682) (xy 74.162829 -5.952756) (xy 74.079284 -5.954775)
			(xy 73.995934 -5.948722) (xy 73.913557 -5.934652) (xy 73.832923 -5.912698) (xy 73.754785 -5.883064)
			(xy 73.679871 -5.846027) (xy 73.608881 -5.801932) (xy 73.542479 -5.751192) (xy 73.481284 -5.69428)
			(xy 73.425867 -5.631727) (xy 73.376746 -5.564118) (xy 73.33438 -5.492084) (xy 73.299164 -5.416297)
			(xy 73.271426 -5.337465) (xy 73.251427 -5.256324) (xy 73.239352 -5.173632) (xy 73.235315 -5.09016)
			(xy 67.964558 -5.09016) (xy 67.964053 -5.131957) (xy 67.955985 -5.215161) (xy 67.939925 -5.297197)
			(xy 67.916021 -5.377301) (xy 67.884499 -5.454723) (xy 67.84565 -5.528742) (xy 67.79984 -5.598666)
			(xy 67.747495 -5.663842) (xy 67.689103 -5.723661) (xy 67.625211 -5.777566) (xy 67.556415 -5.825053)
			(xy 67.483357 -5.865678) (xy 67.406718 -5.899063) (xy 67.327216 -5.924895) (xy 67.245591 -5.942933)
			(xy 67.162607 -5.953009) (xy 67.079037 -5.955029) (xy 66.995663 -5.948974) (xy 66.913262 -5.9349)
			(xy 66.832605 -5.912939) (xy 66.754443 -5.883297) (xy 66.679507 -5.846249) (xy 66.608497 -5.802141)
			(xy 66.542075 -5.751386) (xy 66.480862 -5.694457) (xy 66.425429 -5.631886) (xy 66.376294 -5.564257)
			(xy 66.333915 -5.492202) (xy 66.298688 -5.416393) (xy 66.270943 -5.337538) (xy 66.250938 -5.256373)
			(xy 66.238859 -5.173656) (xy 66.234821 -5.09016) (xy 12.265749 -5.09016) (xy 12.245594 -5.128563)
			(xy 12.199797 -5.198466) (xy 12.147467 -5.263623) (xy 12.089092 -5.323425) (xy 12.025219 -5.377314)
			(xy 11.956443 -5.424787) (xy 11.883406 -5.465401) (xy 11.80679 -5.498775) (xy 11.727311 -5.5246)
			(xy 11.645711 -5.542632) (xy 11.562751 -5.552706) (xy 11.479206 -5.554725) (xy 11.395856 -5.548672)
			(xy 11.313479 -5.534602) (xy 11.232845 -5.512648) (xy 11.154707 -5.483014) (xy 11.079793 -5.445977)
			(xy 11.008803 -5.401882) (xy 10.942401 -5.351142) (xy 10.881206 -5.29423) (xy 10.825789 -5.231677)
			(xy 10.776668 -5.164068) (xy 10.734302 -5.092034) (xy 10.699086 -5.016247) (xy 10.671348 -4.937415)
			(xy 10.651349 -4.856274) (xy 10.639274 -4.773582) (xy 10.635237 -4.69011) (xy 5.36448 -4.69011) (xy 5.363975 -4.731907)
			(xy 5.355907 -4.815111) (xy 5.339847 -4.897147) (xy 5.315943 -4.977251) (xy 5.284421 -5.054673) (xy 5.245572 -5.128692)
			(xy 5.199762 -5.198616) (xy 5.147417 -5.263792) (xy 5.089025 -5.323611) (xy 5.025133 -5.377516) (xy 4.956337 -5.425003)
			(xy 4.883279 -5.465628) (xy 4.80664 -5.499013) (xy 4.727138 -5.524845) (xy 4.645513 -5.542883) (xy 4.562529 -5.552959)
			(xy 4.478959 -5.554979) (xy 4.395585 -5.548924) (xy 4.313184 -5.53485) (xy 4.232527 -5.512889) (xy 4.154365 -5.483247)
			(xy 4.079429 -5.446199) (xy 4.008419 -5.402091) (xy 3.941997 -5.351336) (xy 3.880784 -5.294407) (xy 3.825351 -5.231836)
			(xy 3.776216 -5.164207) (xy 3.733837 -5.092152) (xy 3.69861 -5.016343) (xy 3.670865 -4.937488) (xy 3.65086 -4.856323)
			(xy 3.638781 -4.773606) (xy 3.634743 -4.69011) (xy 0.509016 -4.69011) (xy 0.509016 -13.417248) (xy 41.210697 -13.417248)
			(xy 41.210697 -13.342672) (xy 41.218492 -13.268505) (xy 41.233997 -13.195559) (xy 41.257043 -13.124633)
			(xy 41.287375 -13.056505) (xy 41.324663 -12.991921) (xy 41.368498 -12.931588) (xy 41.418399 -12.876167)
			(xy 41.473819 -12.826266) (xy 41.534152 -12.782432) (xy 41.598737 -12.745144) (xy 41.666865 -12.714812)
			(xy 41.737791 -12.691767) (xy 41.810737 -12.676262) (xy 41.884904 -12.668467) (xy 41.922192 -12.667996)
			(xy 43.922188 -12.667996) (xy 43.959474 -12.668551) (xy 44.033637 -12.676344) (xy 44.106579 -12.691848)
			(xy 44.177502 -12.714891) (xy 44.245627 -12.745221) (xy 44.310208 -12.782506) (xy 44.370538 -12.826338)
			(xy 44.425956 -12.876235) (xy 44.475855 -12.931652) (xy 44.519687 -12.991982) (xy 44.556974 -13.056563)
			(xy 44.587305 -13.124687) (xy 44.610349 -13.195609) (xy 44.625854 -13.268551) (xy 44.633649 -13.342714)
			(xy 44.633649 -13.417286) (xy 44.625854 -13.491449) (xy 44.610349 -13.564391) (xy 44.587305 -13.635313)
			(xy 44.556974 -13.703437) (xy 44.519687 -13.768018) (xy 44.475855 -13.828348) (xy 44.425956 -13.883765)
			(xy 44.370538 -13.933662) (xy 44.310208 -13.977494) (xy 44.245627 -14.014779) (xy 44.177502 -14.045109)
			(xy 44.106579 -14.068152) (xy 44.033637 -14.083656) (xy 43.959474 -14.091449) (xy 43.922188 -14.09192)
			(xy 41.922192 -14.09192) (xy 41.884904 -14.091453) (xy 41.810737 -14.083658) (xy 41.737791 -14.068153)
			(xy 41.666865 -14.045108) (xy 41.598737 -14.014776) (xy 41.534152 -13.977488) (xy 41.473819 -13.933654)
			(xy 41.418399 -13.883753) (xy 41.368498 -13.828332) (xy 41.324663 -13.767999) (xy 41.287375 -13.703415)
			(xy 41.257043 -13.635287) (xy 41.233997 -13.564361) (xy 41.218492 -13.491415) (xy 41.210697 -13.417248)
			(xy 0.509016 -13.417248) (xy 0.509016 -14.917388) (xy 38.210708 -14.917388) (xy 38.210708 -14.842812)
			(xy 38.218503 -14.768646) (xy 38.234008 -14.6957) (xy 38.257053 -14.624775) (xy 38.287386 -14.556647)
			(xy 38.324673 -14.492062) (xy 38.368507 -14.43173) (xy 38.418408 -14.376309) (xy 38.473828 -14.326409)
			(xy 38.534161 -14.282574) (xy 38.598745 -14.245287) (xy 38.666873 -14.214954) (xy 38.737798 -14.191909)
			(xy 38.810744 -14.176403) (xy 38.88491 -14.168608) (xy 38.922198 -14.16812) (xy 40.922194 -14.16812)
			(xy 40.959481 -14.168627) (xy 41.033646 -14.176422) (xy 41.106591 -14.191926) (xy 41.177515 -14.21497)
			(xy 41.245641 -14.245301) (xy 41.310224 -14.282588) (xy 41.370556 -14.326421) (xy 41.425975 -14.37632)
			(xy 41.475875 -14.431739) (xy 41.519709 -14.492071) (xy 41.556996 -14.556653) (xy 41.587328 -14.62478)
			(xy 41.610373 -14.695704) (xy 41.625877 -14.768648) (xy 41.633673 -14.842813) (xy 41.633673 -14.917387)
			(xy 44.210708 -14.917387) (xy 44.210708 -14.842813) (xy 44.218503 -14.768647) (xy 44.234008 -14.695702)
			(xy 44.257052 -14.624777) (xy 44.287384 -14.55665) (xy 44.324671 -14.492066) (xy 44.368504 -14.431734)
			(xy 44.418404 -14.376314) (xy 44.473823 -14.326413) (xy 44.534154 -14.282578) (xy 44.598737 -14.24529)
			(xy 44.666864 -14.214957) (xy 44.737788 -14.191911) (xy 44.810733 -14.176405) (xy 44.884899 -14.168609)
			(xy 44.922186 -14.16812) (xy 46.922182 -14.16812) (xy 46.959469 -14.168626) (xy 47.033636 -14.17642)
			(xy 47.106581 -14.191923) (xy 47.177506 -14.214967) (xy 47.245634 -14.245298) (xy 47.310218 -14.282584)
			(xy 47.370551 -14.326417) (xy 47.425971 -14.376316) (xy 47.475872 -14.431735) (xy 47.519706 -14.492067)
			(xy 47.556994 -14.55665) (xy 47.587327 -14.624777) (xy 47.610372 -14.695702) (xy 47.625877 -14.768647)
			(xy 47.633673 -14.842813) (xy 47.633673 -14.917387) (xy 47.625877 -14.991553) (xy 47.610372 -15.064498)
			(xy 47.587327 -15.135423) (xy 47.556994 -15.20355) (xy 47.519706 -15.268133) (xy 47.475872 -15.328465)
			(xy 47.425971 -15.383884) (xy 47.370551 -15.433783) (xy 47.310218 -15.477616) (xy 47.245634 -15.514902)
			(xy 47.177506 -15.545233) (xy 47.106581 -15.568277) (xy 47.033636 -15.58378) (xy 46.959469 -15.591574)
			(xy 46.922182 -15.592044) (xy 44.922186 -15.592044) (xy 44.884899 -15.591591) (xy 44.810733 -15.583795)
			(xy 44.737788 -15.568289) (xy 44.666864 -15.545243) (xy 44.598737 -15.51491) (xy 44.534154 -15.477622)
			(xy 44.473823 -15.433787) (xy 44.418404 -15.383886) (xy 44.368504 -15.328466) (xy 44.324671 -15.268134)
			(xy 44.287384 -15.20355) (xy 44.257052 -15.135423) (xy 44.234008 -15.064498) (xy 44.218503 -14.991553)
			(xy 44.210708 -14.917387) (xy 41.633673 -14.917387) (xy 41.625877 -14.991552) (xy 41.610373 -15.064496)
			(xy 41.587328 -15.13542) (xy 41.556996 -15.203547) (xy 41.519709 -15.268129) (xy 41.475875 -15.328461)
			(xy 41.425975 -15.38388) (xy 41.370556 -15.433779) (xy 41.310224 -15.477612) (xy 41.245641 -15.514899)
			(xy 41.177515 -15.54523) (xy 41.106591 -15.568274) (xy 41.033646 -15.583778) (xy 40.959481 -15.591573)
			(xy 40.922194 -15.592044) (xy 38.922198 -15.592044) (xy 38.88491 -15.591592) (xy 38.810744 -15.583797)
			(xy 38.737798 -15.568291) (xy 38.666873 -15.545246) (xy 38.598745 -15.514913) (xy 38.534161 -15.477626)
			(xy 38.473828 -15.433791) (xy 38.418408 -15.383891) (xy 38.368507 -15.32847) (xy 38.324673 -15.268138)
			(xy 38.287386 -15.203553) (xy 38.257053 -15.135425) (xy 38.234008 -15.0645) (xy 38.218503 -14.991554)
			(xy 38.210708 -14.917388) (xy 0.509016 -14.917388) (xy 0.509016 -15.147544) (xy 32.352996 -15.147544)
			(xy 32.963104 -15.147544) (xy 32.963104 -15.859252) (xy 32.352996 -15.859252) (xy 32.352996 -15.147544)
			(xy 0.509016 -15.147544) (xy 0.509016 -17.38737) (xy 4.838435 -17.38737) (xy 4.838435 -17.25823)
			(xy 4.846385 -17.129335) (xy 4.862255 -17.001175) (xy 4.885984 -16.874234) (xy 4.917483 -16.748995)
			(xy 4.956632 -16.625932) (xy 5.003283 -16.505513) (xy 5.057258 -16.388194) (xy 5.118353 -16.27442)
			(xy 5.186336 -16.164623) (xy 5.26095 -16.05922) (xy 5.341911 -15.95861) (xy 5.428911 -15.863175)
			(xy 5.521622 -15.773276) (xy 5.619692 -15.689255) (xy 5.722747 -15.611431) (xy 5.830398 -15.540099)
			(xy 5.942237 -15.475529) (xy 6.057838 -15.417967) (xy 6.176763 -15.36763) (xy 6.298562 -15.32471)
			(xy 6.422772 -15.289369) (xy 6.548921 -15.261742) (xy 6.676533 -15.241933) (xy 6.805122 -15.230017)
			(xy 6.9342 -15.226041) (xy 7.063278 -15.230017) (xy 7.191867 -15.241933) (xy 7.319479 -15.261742)
			(xy 7.445628 -15.289369) (xy 7.569838 -15.32471) (xy 7.691637 -15.36763) (xy 7.810562 -15.417967)
			(xy 7.926163 -15.475529) (xy 8.038002 -15.540099) (xy 8.145653 -15.611431) (xy 8.248708 -15.689255)
			(xy 8.346778 -15.773276) (xy 8.439489 -15.863175) (xy 8.526489 -15.95861) (xy 8.60745 -16.05922)
			(xy 8.682064 -16.164623) (xy 8.750047 -16.27442) (xy 8.811142 -16.388194) (xy 8.865117 -16.505513)
			(xy 8.911768 -16.625932) (xy 8.950917 -16.748995) (xy 8.982416 -16.874234) (xy 8.996233 -16.94815)
			(xy 25.574752 -16.94815) (xy 25.574752 -16.05915) (xy 25.575238 -16.031899) (xy 25.582994 -15.977951)
			(xy 25.598349 -15.925656) (xy 25.620991 -15.876079) (xy 25.650457 -15.830229) (xy 25.686148 -15.789038)
			(xy 25.727339 -15.753347) (xy 25.773189 -15.723881) (xy 25.822766 -15.701239) (xy 25.875061 -15.685884)
			(xy 25.929009 -15.678128) (xy 25.983511 -15.678128) (xy 26.037459 -15.685884) (xy 26.089754 -15.701239)
			(xy 26.139331 -15.723881) (xy 26.185181 -15.753347) (xy 26.226372 -15.789038) (xy 26.262063 -15.830229)
			(xy 26.291529 -15.876079) (xy 26.302636 -15.9004) (xy 26.966672 -15.9004) (xy 27.544014 -15.9004)
			(xy 27.557821 -15.8999) (xy 27.584429 -15.892518) (xy 27.608084 -15.878271) (xy 27.627051 -15.858203)
			(xy 27.639942 -15.833783) (xy 27.643328 -15.82039) (xy 27.646599 -15.807276) (xy 27.659197 -15.783373)
			(xy 27.677726 -15.763707) (xy 27.700836 -15.749709) (xy 27.726848 -15.742397) (xy 27.740356 -15.741904)
			(xy 27.881072 -15.741904) (xy 27.881072 -15.801848) (xy 28.146248 -15.801848) (xy 28.146248 -16.183356)
			(xy 28.39466 -16.183356) (xy 28.39466 -15.801848) (xy 28.659836 -15.801848) (xy 28.659836 -15.741904)
			(xy 28.800552 -15.741904) (xy 28.814076 -15.742304) (xy 28.840131 -15.749568) (xy 28.86327 -15.763573)
			(xy 28.881789 -15.783287) (xy 28.894322 -15.807256) (xy 28.89758 -15.82039) (xy 28.900937 -15.833792)
			(xy 28.913842 -15.858213) (xy 28.932816 -15.878284) (xy 28.956473 -15.89254) (xy 28.983084 -15.89994)
			(xy 28.996894 -15.9004) (xy 29.581348 -15.9004) (xy 29.581348 -16.257016) (xy 28.66644 -16.257016)
			(xy 28.66644 -16.250158) (xy 28.665932 -16.249396) (xy 28.659836 -16.2433) (xy 28.659836 -16.183356)
			(xy 28.39466 -16.183356) (xy 28.146248 -16.183356) (xy 27.88158 -16.183356) (xy 27.88158 -16.257016)
			(xy 26.966672 -16.257016) (xy 26.966672 -15.9004) (xy 26.302636 -15.9004) (xy 26.314171 -15.925656)
			(xy 26.329526 -15.977951) (xy 26.337282 -16.031899) (xy 26.337768 -16.05915) (xy 26.337768 -16.94815)
			(xy 26.337282 -16.975401) (xy 26.329526 -17.029349) (xy 26.314171 -17.081644) (xy 26.302636 -17.1069)
			(xy 26.966672 -17.1069) (xy 26.966672 -16.750284) (xy 27.88158 -16.750284) (xy 27.88158 -16.817848)
			(xy 28.146248 -16.817848) (xy 28.146248 -17.199356) (xy 28.39466 -17.199356) (xy 28.39466 -16.817848)
			(xy 28.659836 -16.817848) (xy 28.659836 -16.757904) (xy 28.66644 -16.757904) (xy 28.66644 -16.750284)
			(xy 29.581348 -16.750284) (xy 29.581348 -17.1069) (xy 28.899866 -17.1069) (xy 28.899866 -17.14754)
			(xy 32.352996 -17.14754) (xy 32.963104 -17.14754) (xy 32.963104 -17.480788) (xy 41.21912 -17.480788)
			(xy 41.474136 -17.480788) (xy 41.7195 -17.480788) (xy 41.974008 -17.480788) (xy 42.719244 -17.480788)
			(xy 42.973752 -17.480788) (xy 43.219116 -17.480788) (xy 43.474132 -17.480788) (xy 43.474132 -18.116804)
			(xy 43.219116 -18.116804) (xy 43.219116 -17.480788) (xy 42.973752 -17.480788) (xy 42.973752 -18.116804)
			(xy 42.719244 -18.116804) (xy 42.719244 -17.480788) (xy 41.974008 -17.480788) (xy 41.974008 -18.116804)
			(xy 41.7195 -18.116804) (xy 41.7195 -17.480788) (xy 41.474136 -17.480788) (xy 41.474136 -18.116804)
			(xy 41.21912 -18.116804) (xy 41.21912 -17.480788) (xy 32.963104 -17.480788) (xy 32.963104 -17.859248)
			(xy 32.352996 -17.859248) (xy 32.352996 -17.14754) (xy 28.899866 -17.14754) (xy 28.899866 -17.158462)
			(xy 28.899589 -17.171613) (xy 28.893115 -17.197095) (xy 28.880209 -17.22) (xy 28.861768 -17.238738)
			(xy 28.839072 -17.252009) (xy 28.813697 -17.25889) (xy 28.800552 -17.2593) (xy 28.659836 -17.2593)
			(xy 28.659836 -17.199356) (xy 28.39466 -17.199356) (xy 28.146248 -17.199356) (xy 27.881072 -17.199356)
			(xy 27.881072 -17.2593) (xy 27.740356 -17.2593) (xy 27.727205 -17.258873) (xy 27.701815 -17.252012)
			(xy 27.679101 -17.238753) (xy 27.660642 -17.220017) (xy 27.647724 -17.197107) (xy 27.641242 -17.171617)
			(xy 27.641042 -17.158462) (xy 27.641042 -17.1069) (xy 26.966672 -17.1069) (xy 26.302636 -17.1069)
			(xy 26.291529 -17.131221) (xy 26.262063 -17.177071) (xy 26.226372 -17.218262) (xy 26.185181 -17.253953)
			(xy 26.139331 -17.283419) (xy 26.089754 -17.306061) (xy 26.037459 -17.321416) (xy 25.983511 -17.329172)
			(xy 25.929009 -17.329172) (xy 25.875061 -17.321416) (xy 25.822766 -17.306061) (xy 25.773189 -17.283419)
			(xy 25.727339 -17.253953) (xy 25.686148 -17.218262) (xy 25.650457 -17.177071) (xy 25.620991 -17.131221)
			(xy 25.598349 -17.081644) (xy 25.582994 -17.029349) (xy 25.575238 -16.975401) (xy 25.574752 -16.94815)
			(xy 8.996233 -16.94815) (xy 9.006145 -17.001175) (xy 9.022015 -17.129335) (xy 9.029965 -17.25823)
			(xy 9.030462 -17.3228) (xy 9.029965 -17.38737) (xy 9.022015 -17.516265) (xy 9.006145 -17.644425)
			(xy 8.982416 -17.771366) (xy 8.950917 -17.896605) (xy 8.911768 -18.019668) (xy 8.865117 -18.140087)
			(xy 8.811791 -18.255996) (xy 41.21912 -18.255996) (xy 41.474136 -18.255996) (xy 41.7195 -18.255996)
			(xy 41.974008 -18.255996) (xy 42.719244 -18.255996) (xy 42.973752 -18.255996) (xy 43.219116 -18.255996)
			(xy 43.474132 -18.255996) (xy 43.474132 -18.892012) (xy 43.219116 -18.892012) (xy 43.219116 -18.255996)
			(xy 42.973752 -18.255996) (xy 42.973752 -18.892012) (xy 42.719244 -18.892012) (xy 42.719244 -18.255996)
			(xy 41.974008 -18.255996) (xy 41.974008 -18.892012) (xy 41.7195 -18.892012) (xy 41.7195 -18.255996)
			(xy 41.474136 -18.255996) (xy 41.474136 -18.892012) (xy 41.21912 -18.892012) (xy 41.21912 -18.255996)
			(xy 8.811791 -18.255996) (xy 8.811142 -18.257406) (xy 8.750047 -18.37118) (xy 8.682064 -18.480977)
			(xy 8.60745 -18.58638) (xy 8.526489 -18.68699) (xy 8.439489 -18.782425) (xy 8.346778 -18.872324)
			(xy 8.248708 -18.956345) (xy 8.145653 -19.034169) (xy 8.038002 -19.105501) (xy 7.926163 -19.170071)
			(xy 7.810562 -19.227633) (xy 7.691637 -19.27797) (xy 7.569838 -19.32089) (xy 7.445628 -19.356231)
			(xy 7.319479 -19.383858) (xy 7.191867 -19.403667) (xy 7.063278 -19.415583) (xy 6.9342 -19.41956)
			(xy 6.805122 -19.415583) (xy 6.676533 -19.403667) (xy 6.548921 -19.383858) (xy 6.422772 -19.356231)
			(xy 6.298562 -19.32089) (xy 6.176763 -19.27797) (xy 6.057838 -19.227633) (xy 5.942237 -19.170071)
			(xy 5.830398 -19.105501) (xy 5.722747 -19.034169) (xy 5.619692 -18.956345) (xy 5.521622 -18.872324)
			(xy 5.428911 -18.782425) (xy 5.341911 -18.68699) (xy 5.26095 -18.58638) (xy 5.186336 -18.480977)
			(xy 5.118353 -18.37118) (xy 5.057258 -18.257406) (xy 5.003283 -18.140087) (xy 4.956632 -18.019668)
			(xy 4.917483 -17.896605) (xy 4.885984 -17.771366) (xy 4.862255 -17.644425) (xy 4.846385 -17.516265)
			(xy 4.838435 -17.38737) (xy 0.509016 -17.38737) (xy 0.509016 -21.767292) (xy 40.306244 -21.767292)
			(xy 40.306244 -21.626322) (xy 40.306698 -21.613217) (xy 40.313518 -21.587911) (xy 40.326693 -21.565255)
			(xy 40.345314 -21.546811) (xy 40.368096 -21.533854) (xy 40.393466 -21.527277) (xy 40.406574 -21.527008)
			(xy 40.458644 -21.527008) (xy 40.458644 -20.852384) (xy 40.81526 -20.852384) (xy 40.81526 -21.7678)
			(xy 41.308528 -21.7678) (xy 41.308528 -20.852384) (xy 41.665144 -20.852384) (xy 41.665144 -21.527008)
			(xy 41.72331 -21.527008) (xy 41.736424 -21.527232) (xy 41.761809 -21.533809) (xy 41.784604 -21.546771)
			(xy 41.803237 -21.565223) (xy 41.816421 -21.587891) (xy 41.823245 -21.61321) (xy 41.82364 -21.626322)
			(xy 41.82364 -21.767292) (xy 42.69994 -21.767292) (xy 42.69994 -21.626322) (xy 42.700298 -21.613209)
			(xy 42.707126 -21.587889) (xy 42.720317 -21.565222) (xy 42.738958 -21.546777) (xy 42.761763 -21.533826)
			(xy 42.787154 -21.527265) (xy 42.80027 -21.527008) (xy 42.85234 -21.527008) (xy 42.85234 -20.852384)
			(xy 43.208956 -20.852384) (xy 43.208956 -21.7678) (xy 43.702224 -21.7678) (xy 43.702224 -20.852384)
			(xy 44.05884 -20.852384) (xy 44.05884 -21.527008) (xy 44.117006 -21.527008) (xy 44.13012 -21.527236)
			(xy 44.155505 -21.533812) (xy 44.1783 -21.546773) (xy 44.196933 -21.565224) (xy 44.210116 -21.587892)
			(xy 44.216941 -21.613211) (xy 44.217336 -21.626322) (xy 44.217336 -21.767292) (xy 44.157392 -21.767292)
			(xy 44.157392 -22.03196) (xy 43.775884 -22.03196) (xy 43.775884 -21.7678) (xy 43.702224 -21.7678)
			(xy 43.208956 -21.7678) (xy 43.141392 -21.7678) (xy 43.141392 -22.03196) (xy 42.759884 -22.03196)
			(xy 42.759884 -21.767292) (xy 42.69994 -21.767292) (xy 41.82364 -21.767292) (xy 41.763696 -21.767292)
			(xy 41.763696 -22.03196) (xy 41.382188 -22.03196) (xy 41.382188 -21.7678) (xy 41.308528 -21.7678)
			(xy 40.81526 -21.7678) (xy 40.747696 -21.7678) (xy 40.747696 -22.03196) (xy 40.366188 -22.03196)
			(xy 40.366188 -21.767292) (xy 40.306244 -21.767292) (xy 0.509016 -21.767292) (xy 0.509016 -22.686518)
			(xy 40.306244 -22.686518) (xy 40.306244 -22.545548) (xy 40.366188 -22.545548) (xy 40.366188 -22.28088)
			(xy 40.747696 -22.28088) (xy 40.747696 -22.545548) (xy 40.80764 -22.545548) (xy 40.80764 -22.552152)
			(xy 40.81526 -22.552152) (xy 41.308528 -22.552152) (xy 41.322244 -22.552152) (xy 41.322244 -22.545548)
			(xy 41.382188 -22.545548) (xy 41.382188 -22.28088) (xy 41.763696 -22.28088) (xy 41.763696 -22.545548)
			(xy 41.82364 -22.545548) (xy 41.82364 -22.686518) (xy 42.69994 -22.686518) (xy 42.69994 -22.545548)
			(xy 42.759884 -22.545548) (xy 42.759884 -22.28088) (xy 43.141392 -22.28088) (xy 43.141392 -22.545548)
			(xy 43.201336 -22.545548) (xy 43.201336 -22.552152) (xy 43.208956 -22.552152) (xy 43.702224 -22.552152)
			(xy 43.71594 -22.552152) (xy 43.71594 -22.545548) (xy 43.775884 -22.545548) (xy 43.775884 -22.28088)
			(xy 44.157392 -22.28088) (xy 44.157392 -22.545548) (xy 44.217336 -22.545548) (xy 44.217336 -22.686518)
			(xy 44.216937 -22.699626) (xy 44.210106 -22.724936) (xy 44.196919 -22.747595) (xy 44.178288 -22.766038)
			(xy 44.155496 -22.778993) (xy 44.130117 -22.785566) (xy 44.117006 -22.785832) (xy 44.05884 -22.785832)
			(xy 44.05884 -23.467568) (xy 43.702224 -23.467568) (xy 43.702224 -22.552152) (xy 43.208956 -22.552152)
			(xy 43.208956 -23.467568) (xy 42.85234 -23.467568) (xy 42.85234 -22.785832) (xy 42.80027 -22.785832)
			(xy 42.787158 -22.785586) (xy 42.761779 -22.779007) (xy 42.738987 -22.766048) (xy 42.720356 -22.747601)
			(xy 42.707171 -22.72494) (xy 42.70034 -22.699627) (xy 42.69994 -22.686518) (xy 41.82364 -22.686518)
			(xy 41.823237 -22.699626) (xy 41.816406 -22.724935) (xy 41.80322 -22.747593) (xy 41.784589 -22.766036)
			(xy 41.761799 -22.778991) (xy 41.736421 -22.785565) (xy 41.72331 -22.785832) (xy 41.665144 -22.785832)
			(xy 41.665144 -23.467568) (xy 41.308528 -23.467568) (xy 41.308528 -22.552152) (xy 40.81526 -22.552152)
			(xy 40.81526 -23.467568) (xy 40.458644 -23.467568) (xy 40.458644 -22.785832) (xy 40.406574 -22.785832)
			(xy 40.393462 -22.785582) (xy 40.368083 -22.779005) (xy 40.345292 -22.766046) (xy 40.32666 -22.7476)
			(xy 40.313475 -22.724939) (xy 40.306644 -22.699627) (xy 40.306244 -22.686518) (xy 0.509016 -22.686518)
			(xy 0.509016 -24.482675) (xy 40.239076 -24.482675) (xy 40.239076 -24.428125) (xy 40.246839 -24.374131)
			(xy 40.262209 -24.321791) (xy 40.284871 -24.272172) (xy 40.314365 -24.226283) (xy 40.350089 -24.185059)
			(xy 40.391317 -24.149339) (xy 40.437209 -24.119851) (xy 40.486831 -24.097194) (xy 40.539172 -24.08183)
			(xy 40.593167 -24.074073) (xy 40.620442 -24.073612) (xy 41.509442 -24.073612) (xy 41.536708 -24.074153)
			(xy 41.590683 -24.081919) (xy 41.643004 -24.097287) (xy 41.692605 -24.119944) (xy 41.738478 -24.149429)
			(xy 41.779688 -24.185142) (xy 41.815396 -24.226356) (xy 41.844876 -24.272232) (xy 41.867528 -24.321836)
			(xy 41.88289 -24.374158) (xy 41.89065 -24.428134) (xy 41.89065 -24.482666) (xy 41.890649 -24.482675)
			(xy 42.632776 -24.482675) (xy 42.632776 -24.428125) (xy 42.640539 -24.374132) (xy 42.655909 -24.321792)
			(xy 42.67857 -24.272173) (xy 42.708064 -24.226285) (xy 42.743788 -24.185061) (xy 42.785015 -24.149341)
			(xy 42.830907 -24.119852) (xy 42.880528 -24.097195) (xy 42.932869 -24.081831) (xy 42.986863 -24.074073)
			(xy 43.014138 -24.073612) (xy 43.903138 -24.073612) (xy 43.930404 -24.074153) (xy 43.98438 -24.081918)
			(xy 44.036701 -24.097286) (xy 44.086303 -24.119943) (xy 44.132176 -24.149428) (xy 44.173386 -24.185141)
			(xy 44.209095 -24.226354) (xy 44.238575 -24.27223) (xy 44.261227 -24.321835) (xy 44.27659 -24.374158)
			(xy 44.28435 -24.428134) (xy 44.28435 -24.482666) (xy 44.27659 -24.536642) (xy 44.261227 -24.588965)
			(xy 44.238575 -24.63857) (xy 44.209095 -24.684446) (xy 44.173386 -24.725659) (xy 44.132176 -24.761372)
			(xy 44.086303 -24.790857) (xy 44.036701 -24.813514) (xy 43.98438 -24.828882) (xy 43.930404 -24.836647)
			(xy 43.903138 -24.837136) (xy 43.014138 -24.837136) (xy 42.986863 -24.836727) (xy 42.932869 -24.828969)
			(xy 42.880528 -24.813605) (xy 42.830907 -24.790948) (xy 42.785015 -24.761459) (xy 42.743788 -24.725739)
			(xy 42.708064 -24.684515) (xy 42.67857 -24.638627) (xy 42.655909 -24.589008) (xy 42.640539 -24.536668)
			(xy 42.632776 -24.482675) (xy 41.890649 -24.482675) (xy 41.88289 -24.536642) (xy 41.867528 -24.588964)
			(xy 41.844876 -24.638568) (xy 41.815396 -24.684444) (xy 41.779688 -24.725658) (xy 41.738478 -24.761371)
			(xy 41.692605 -24.790856) (xy 41.643004 -24.813513) (xy 41.590683 -24.828881) (xy 41.536708 -24.836647)
			(xy 41.509442 -24.837136) (xy 40.620442 -24.837136) (xy 40.593167 -24.836727) (xy 40.539172 -24.82897)
			(xy 40.486831 -24.813606) (xy 40.437209 -24.790949) (xy 40.391317 -24.761461) (xy 40.350089 -24.725741)
			(xy 40.314365 -24.684517) (xy 40.284871 -24.638628) (xy 40.262209 -24.589009) (xy 40.246839 -24.536669)
			(xy 40.239076 -24.482675) (xy 0.509016 -24.482675) (xy 0.509016 -26.898451) (xy 62.226946 -26.898451)
			(xy 62.226946 -26.843949) (xy 62.234702 -26.790001) (xy 62.250056 -26.737705) (xy 62.272695 -26.688127)
			(xy 62.302159 -26.642275) (xy 62.337849 -26.601083) (xy 62.379037 -26.565388) (xy 62.424885 -26.535918)
			(xy 62.47446 -26.513272) (xy 62.526754 -26.497912) (xy 62.580701 -26.490149) (xy 62.607952 -26.48966)
			(xy 63.496952 -26.48966) (xy 63.524205 -26.490184) (xy 63.578156 -26.497935) (xy 63.630456 -26.513285)
			(xy 63.680038 -26.535923) (xy 63.725893 -26.565387) (xy 63.767088 -26.601078) (xy 63.802784 -26.642269)
			(xy 63.832254 -26.68812) (xy 63.854898 -26.737699) (xy 63.870255 -26.789997) (xy 63.878013 -26.843947)
			(xy 63.878013 -26.898453) (xy 63.870255 -26.952403) (xy 63.863218 -26.976368) (xy 64.442847 -26.976368)
			(xy 64.442847 -26.921832) (xy 64.450609 -26.867852) (xy 64.465973 -26.815525) (xy 64.488628 -26.765918)
			(xy 64.518112 -26.72004) (xy 64.553826 -26.678824) (xy 64.595041 -26.643111) (xy 64.64092 -26.613627)
			(xy 64.690527 -26.590972) (xy 64.742854 -26.575608) (xy 64.796834 -26.567847) (xy 64.824102 -26.567384)
			(xy 65.713102 -26.567384) (xy 65.740375 -26.567779) (xy 65.794364 -26.575542) (xy 65.8467 -26.590909)
			(xy 65.896316 -26.613568) (xy 65.942202 -26.643057) (xy 65.983424 -26.678777) (xy 66.019144 -26.72)
			(xy 66.048633 -26.765886) (xy 66.071292 -26.815502) (xy 66.086659 -26.867838) (xy 66.094421 -26.921827)
			(xy 66.094421 -26.976373) (xy 66.086659 -27.030362) (xy 66.071292 -27.082698) (xy 66.048633 -27.132314)
			(xy 66.019144 -27.1782) (xy 65.983424 -27.219423) (xy 65.942202 -27.255143) (xy 65.896316 -27.284632)
			(xy 65.8467 -27.307291) (xy 65.794364 -27.322658) (xy 65.740375 -27.330421) (xy 65.713102 -27.330908)
			(xy 64.824102 -27.330908) (xy 64.796834 -27.330353) (xy 64.742854 -27.322592) (xy 64.690527 -27.307228)
			(xy 64.64092 -27.284573) (xy 64.595041 -27.255089) (xy 64.553826 -27.219376) (xy 64.518112 -27.17816)
			(xy 64.488628 -27.132282) (xy 64.465973 -27.082675) (xy 64.450609 -27.030348) (xy 64.442847 -26.976368)
			(xy 63.863218 -26.976368) (xy 63.854898 -27.004701) (xy 63.832254 -27.05428) (xy 63.802784 -27.100131)
			(xy 63.767088 -27.141322) (xy 63.725893 -27.177013) (xy 63.680038 -27.206477) (xy 63.630456 -27.229115)
			(xy 63.578156 -27.244465) (xy 63.524205 -27.252216) (xy 63.496952 -27.252676) (xy 62.607952 -27.252676)
			(xy 62.580701 -27.252251) (xy 62.526754 -27.244488) (xy 62.47446 -27.229128) (xy 62.424885 -27.206482)
			(xy 62.379037 -27.177012) (xy 62.337849 -27.141317) (xy 62.302159 -27.100125) (xy 62.272695 -27.054273)
			(xy 62.250056 -27.004695) (xy 62.234702 -26.952399) (xy 62.226946 -26.898451) (xy 0.509016 -26.898451)
			(xy 0.509016 -28.166568) (xy 63.784988 -28.166568) (xy 63.784988 -27.865832) (xy 63.785257 -27.852741)
			(xy 63.791877 -27.827414) (xy 63.804855 -27.804679) (xy 63.823297 -27.786101) (xy 63.845936 -27.772957)
			(xy 63.871213 -27.766151) (xy 63.884302 -27.765756) (xy 64.025272 -27.765756) (xy 64.025272 -27.8257)
			(xy 64.28994 -27.8257) (xy 64.28994 -28.2067) (xy 64.53886 -28.2067) (xy 64.53886 -27.8257) (xy 64.803528 -27.8257)
			(xy 64.803528 -27.765756) (xy 64.944498 -27.765756) (xy 64.957583 -27.76618) (xy 64.982853 -27.772984)
			(xy 65.005485 -27.786124) (xy 65.023922 -27.804697) (xy 65.036896 -27.827425) (xy 65.043514 -27.852744)
			(xy 65.043812 -27.865832) (xy 65.043812 -28.166568) (xy 65.537588 -28.166568) (xy 65.537588 -27.865832)
			(xy 65.537857 -27.852741) (xy 65.544477 -27.827414) (xy 65.557455 -27.804679) (xy 65.575897 -27.786101)
			(xy 65.598536 -27.772957) (xy 65.623813 -27.766151) (xy 65.636902 -27.765756) (xy 65.777872 -27.765756)
			(xy 65.777872 -27.8257) (xy 66.04254 -27.8257) (xy 66.04254 -28.2067) (xy 66.29146 -28.2067) (xy 66.29146 -27.8257)
			(xy 66.556128 -27.8257) (xy 66.556128 -27.765756) (xy 66.697098 -27.765756) (xy 66.710183 -27.76618)
			(xy 66.735453 -27.772984) (xy 66.758085 -27.786124) (xy 66.776522 -27.804697) (xy 66.789496 -27.827425)
			(xy 66.796114 -27.852744) (xy 66.796412 -27.865832) (xy 66.796412 -28.166568) (xy 66.796143 -28.179659)
			(xy 66.789523 -28.204986) (xy 66.776545 -28.227721) (xy 66.758103 -28.246299) (xy 66.735464 -28.259443)
			(xy 66.710187 -28.266249) (xy 66.697098 -28.266644) (xy 66.556128 -28.266644) (xy 66.556128 -28.2067)
			(xy 66.29146 -28.2067) (xy 66.04254 -28.2067) (xy 65.777872 -28.2067) (xy 65.777872 -28.266644) (xy 65.636902 -28.266644)
			(xy 65.623817 -28.26622) (xy 65.598547 -28.259416) (xy 65.575915 -28.246276) (xy 65.557478 -28.227703)
			(xy 65.544504 -28.204975) (xy 65.537886 -28.179656) (xy 65.537588 -28.166568) (xy 65.043812 -28.166568)
			(xy 65.043543 -28.179659) (xy 65.036923 -28.204986) (xy 65.023945 -28.227721) (xy 65.005503 -28.246299)
			(xy 64.982864 -28.259443) (xy 64.957587 -28.266249) (xy 64.944498 -28.266644) (xy 64.803528 -28.266644)
			(xy 64.803528 -28.2067) (xy 64.53886 -28.2067) (xy 64.28994 -28.2067) (xy 64.025272 -28.2067) (xy 64.025272 -28.266644)
			(xy 63.884302 -28.266644) (xy 63.871217 -28.26622) (xy 63.845947 -28.259416) (xy 63.823315 -28.246276)
			(xy 63.804878 -28.227703) (xy 63.791904 -28.204975) (xy 63.785286 -28.179656) (xy 63.784988 -28.166568)
			(xy 0.509016 -28.166568) (xy 0.509016 -28.988004) (xy 64.349884 -28.988004) (xy 64.349884 -28.847034)
			(xy 64.350308 -28.833948) (xy 64.357107 -28.808675) (xy 64.370245 -28.78604) (xy 64.388819 -28.767602)
			(xy 64.411549 -28.754629) (xy 64.436872 -28.748015) (xy 64.44996 -28.74772) (xy 64.750696 -28.74772)
			(xy 64.763787 -28.748021) (xy 64.789116 -28.754627) (xy 64.811854 -28.767595) (xy 64.830435 -28.786032)
			(xy 64.843579 -28.808669) (xy 64.850381 -28.833946) (xy 64.850772 -28.847034) (xy 64.850772 -28.988004)
			(xy 65.367408 -28.988004) (xy 65.367408 -28.847034) (xy 65.367809 -28.833925) (xy 65.374631 -28.808609)
			(xy 65.387815 -28.785946) (xy 65.406447 -28.767501) (xy 65.429242 -28.754548) (xy 65.454625 -28.747982)
			(xy 65.467738 -28.74772) (xy 65.768474 -28.74772) (xy 65.781588 -28.747964) (xy 65.806973 -28.754534)
			(xy 65.82977 -28.76749) (xy 65.848404 -28.785939) (xy 65.861587 -28.808605) (xy 65.86841 -28.833923)
			(xy 65.868804 -28.847034) (xy 65.868804 -28.988004) (xy 65.80886 -28.988004) (xy 65.80886 -29.252672)
			(xy 65.427352 -29.252672) (xy 65.427352 -28.988004) (xy 65.367408 -28.988004) (xy 64.850772 -28.988004)
			(xy 64.790828 -28.988004) (xy 64.790828 -29.252672) (xy 64.409828 -29.252672) (xy 64.409828 -28.988004)
			(xy 64.349884 -28.988004) (xy 0.509016 -28.988004) (xy 0.509016 -29.90723) (xy 64.349884 -29.90723)
			(xy 64.349884 -29.76626) (xy 64.409828 -29.76626) (xy 64.409828 -29.501592) (xy 64.790828 -29.501592)
			(xy 64.790828 -29.76626) (xy 64.850772 -29.76626) (xy 64.850772 -29.90723) (xy 65.367408 -29.90723)
			(xy 65.367408 -29.76626) (xy 65.427352 -29.76626) (xy 65.427352 -29.501592) (xy 65.80886 -29.501592)
			(xy 65.80886 -29.76626) (xy 65.868804 -29.76626) (xy 65.868804 -29.90723) (xy 65.868447 -29.920341)
			(xy 65.861611 -29.945657) (xy 65.848417 -29.968318) (xy 65.829776 -29.986762) (xy 65.806976 -29.999714)
			(xy 65.781589 -30.006282) (xy 65.768474 -30.006544) (xy 65.467738 -30.006544) (xy 65.454629 -30.006226)
			(xy 65.429254 -29.999664) (xy 65.406464 -29.98672) (xy 65.387832 -29.968287) (xy 65.374643 -29.945638)
			(xy 65.367809 -29.920335) (xy 65.367408 -29.90723) (xy 64.850772 -29.90723) (xy 64.850448 -29.920323)
			(xy 64.84363 -29.945605) (xy 64.830472 -29.968244) (xy 64.811879 -29.986682) (xy 64.78913 -29.999649)
			(xy 64.763791 -30.006255) (xy 64.750696 -30.006544) (xy 64.44996 -30.006544) (xy 64.436872 -30.006219)
			(xy 64.411551 -29.999608) (xy 64.38882 -29.986641) (xy 64.370242 -29.96821) (xy 64.357094 -29.945582)
			(xy 64.350283 -29.920315) (xy 64.349884 -29.90723) (xy 0.509016 -29.90723) (xy 0.509016 -34.481516)
			(xy 62.285372 -34.481516) (xy 62.285372 -34.3408) (xy 62.285779 -34.327692) (xy 62.292606 -34.302381)
			(xy 62.30579 -34.279722) (xy 62.324421 -34.261278) (xy 62.347212 -34.248323) (xy 62.372591 -34.241751)
			(xy 62.385702 -34.241486) (xy 62.385956 -34.24174) (xy 62.686184 -34.24174) (xy 62.686438 -34.241486)
			(xy 62.699552 -34.241707) (xy 62.724934 -34.248289) (xy 62.747727 -34.261253) (xy 62.766359 -34.279705)
			(xy 62.779543 -34.302372) (xy 62.78637 -34.327689) (xy 62.786768 -34.3408) (xy 62.786768 -34.481516)
			(xy 63.303404 -34.481516) (xy 63.303404 -34.3408) (xy 63.303778 -34.327711) (xy 63.310587 -34.302433)
			(xy 63.323735 -34.279797) (xy 63.342319 -34.261359) (xy 63.365058 -34.248388) (xy 63.390388 -34.241778)
			(xy 63.40348 -34.241486) (xy 63.403734 -34.24174) (xy 63.703962 -34.24174) (xy 63.704216 -34.241486)
			(xy 63.717305 -34.241803) (xy 63.74263 -34.24841) (xy 63.765364 -34.261377) (xy 63.783944 -34.279811)
			(xy 63.79709 -34.302442) (xy 63.803897 -34.327714) (xy 63.804292 -34.3408) (xy 63.804292 -34.481516)
			(xy 63.744348 -34.481516) (xy 63.744348 -34.746692) (xy 63.363348 -34.746692) (xy 63.363348 -34.481516)
			(xy 63.303404 -34.481516) (xy 62.786768 -34.481516) (xy 62.726824 -34.481516) (xy 62.726824 -34.746692)
			(xy 62.345316 -34.746692) (xy 62.345316 -34.481516) (xy 62.285372 -34.481516) (xy 0.509016 -34.481516)
			(xy 0.509016 -35.400996) (xy 62.285372 -35.400996) (xy 62.285372 -35.26028) (xy 62.345316 -35.26028)
			(xy 62.345316 -34.995104) (xy 62.726824 -34.995104) (xy 62.726824 -35.26028) (xy 62.786768 -35.26028)
			(xy 62.786768 -35.400996) (xy 63.303404 -35.400996) (xy 63.303404 -35.26028) (xy 63.363348 -35.26028)
			(xy 63.363348 -34.995104) (xy 63.744348 -34.995104) (xy 63.744348 -35.26028) (xy 63.804292 -35.26028)
			(xy 63.804292 -35.400996) (xy 63.803918 -35.414085) (xy 63.79711 -35.439363) (xy 63.783962 -35.462)
			(xy 63.765378 -35.480439) (xy 63.742639 -35.493409) (xy 63.717308 -35.500018) (xy 63.704216 -35.50031)
			(xy 63.703962 -35.500056) (xy 63.403734 -35.500056) (xy 63.40348 -35.50031) (xy 63.39039 -35.500001)
			(xy 63.365065 -35.493392) (xy 63.34233 -35.480424) (xy 63.32375 -35.461989) (xy 63.310605 -35.439356)
			(xy 63.303799 -35.414083) (xy 63.303404 -35.400996) (xy 62.786768 -35.400996) (xy 62.786418 -35.414109)
			(xy 62.779586 -35.439429) (xy 62.766393 -35.462094) (xy 62.74775 -35.480539) (xy 62.724946 -35.49349)
			(xy 62.699554 -35.500052) (xy 62.686438 -35.50031) (xy 62.686184 -35.500056) (xy 62.385956 -35.500056)
			(xy 62.385702 -35.50031) (xy 62.372589 -35.500057) (xy 62.347208 -35.493485) (xy 62.324414 -35.480528)
			(xy 62.305782 -35.462082) (xy 62.292597 -35.43942) (xy 62.285769 -35.414105) (xy 62.285372 -35.400996)
			(xy 0.509016 -35.400996) (xy 0.509016 -48.189134) (xy 23.749 -48.189134) (xy 23.749 -46.588934) (xy 23.749498 -46.511651)
			(xy 23.757454 -46.357291) (xy 23.773347 -46.203545) (xy 23.797133 -46.050821) (xy 23.82875 -45.899525)
			(xy 23.868113 -45.750056) (xy 23.915118 -45.602812) (xy 23.969642 -45.458182) (xy 24.031538 -45.316552)
			(xy 24.100643 -45.178295) (xy 24.176774 -45.04378) (xy 24.259728 -44.913361) (xy 24.349287 -44.787386)
			(xy 24.445211 -44.666189) (xy 24.547248 -44.55009) (xy 24.655125 -44.439398) (xy 24.768558 -44.334406)
			(xy 24.887246 -44.235393) (xy 25.010873 -44.14262) (xy 25.139112 -44.056335) (xy 25.271623 -43.976766)
			(xy 25.408055 -43.904124) (xy 25.548045 -43.838602) (xy 25.691222 -43.780373) (xy 25.837207 -43.729592)
			(xy 25.985613 -43.686393) (xy 26.136045 -43.650891) (xy 26.288106 -43.623181) (xy 26.441392 -43.603335)
			(xy 26.595496 -43.591406) (xy 26.75001 -43.587427) (xy 26.904524 -43.591406) (xy 27.058628 -43.603335)
			(xy 27.211914 -43.623181) (xy 27.363975 -43.650891) (xy 27.514407 -43.686393) (xy 27.662813 -43.729592)
			(xy 27.808798 -43.780373) (xy 27.951975 -43.838602) (xy 28.091965 -43.904124) (xy 28.228397 -43.976766)
			(xy 28.360908 -44.056335) (xy 28.489147 -44.14262) (xy 28.612774 -44.235393) (xy 28.731462 -44.334406)
			(xy 28.844895 -44.439398) (xy 28.952772 -44.55009) (xy 29.054809 -44.666189) (xy 29.150733 -44.787386)
			(xy 29.240292 -44.913361) (xy 29.252254 -44.932168) (xy 66.731138 -44.932168) (xy 66.731138 -44.877632)
			(xy 66.738899 -44.823652) (xy 66.754264 -44.771325) (xy 66.776918 -44.721717) (xy 66.806402 -44.675839)
			(xy 66.842114 -44.634623) (xy 66.883329 -44.598909) (xy 66.929207 -44.569424) (xy 66.978814 -44.546768)
			(xy 67.03114 -44.531402) (xy 67.08512 -44.523639) (xy 67.112388 -44.523152) (xy 68.001388 -44.523152)
			(xy 68.028661 -44.523587) (xy 68.082651 -44.531348) (xy 68.134987 -44.546714) (xy 68.184603 -44.569371)
			(xy 68.23049 -44.59886) (xy 68.271713 -44.634578) (xy 68.307433 -44.6758) (xy 68.336923 -44.721686)
			(xy 68.359582 -44.771302) (xy 68.37495 -44.823638) (xy 68.382712 -44.877627) (xy 68.382712 -44.932173)
			(xy 68.37495 -44.986162) (xy 68.359582 -45.038498) (xy 68.336923 -45.088114) (xy 68.307433 -45.134)
			(xy 68.271713 -45.175222) (xy 68.23049 -45.21094) (xy 68.184603 -45.240429) (xy 68.134987 -45.263086)
			(xy 68.082651 -45.278452) (xy 68.028661 -45.286213) (xy 68.001388 -45.286676) (xy 67.112388 -45.286676)
			(xy 67.08512 -45.286161) (xy 67.03114 -45.278398) (xy 66.978814 -45.263032) (xy 66.929207 -45.240376)
			(xy 66.883329 -45.210891) (xy 66.842114 -45.175177) (xy 66.806402 -45.133961) (xy 66.776918 -45.088083)
			(xy 66.754264 -45.038475) (xy 66.738899 -44.986148) (xy 66.731138 -44.932168) (xy 29.252254 -44.932168)
			(xy 29.323246 -45.04378) (xy 29.399377 -45.178295) (xy 29.468482 -45.316552) (xy 29.530378 -45.458182)
			(xy 29.584902 -45.602812) (xy 29.631907 -45.750056) (xy 29.67127 -45.899525) (xy 29.702887 -46.050821)
			(xy 29.726673 -46.203545) (xy 29.742566 -46.357291) (xy 29.750522 -46.511651) (xy 29.75102 -46.588934)
			(xy 29.75102 -48.189134) (xy 29.750522 -48.266417) (xy 29.742566 -48.420777) (xy 29.726673 -48.574523)
			(xy 29.702887 -48.727247) (xy 29.67127 -48.878543) (xy 29.631907 -49.028012) (xy 29.584902 -49.175256)
			(xy 29.530378 -49.319886) (xy 29.468482 -49.461516) (xy 29.399377 -49.599773) (xy 29.323246 -49.734288)
			(xy 29.240292 -49.864707) (xy 29.150733 -49.990682) (xy 29.054809 -50.111879) (xy 28.952772 -50.227978)
			(xy 28.844895 -50.33867) (xy 28.731462 -50.443662) (xy 28.612774 -50.542675) (xy 28.489147 -50.635448)
			(xy 28.360908 -50.721733) (xy 28.228397 -50.801302) (xy 28.091965 -50.873944) (xy 27.951975 -50.939466)
			(xy 27.808798 -50.997695) (xy 27.662813 -51.048476) (xy 27.514407 -51.091675) (xy 27.363975 -51.127177)
			(xy 27.211914 -51.154887) (xy 27.058628 -51.174733) (xy 26.904524 -51.186662) (xy 26.75001 -51.190642)
			(xy 26.595496 -51.186662) (xy 26.441392 -51.174733) (xy 26.288106 -51.154887) (xy 26.136045 -51.127177)
			(xy 25.985613 -51.091675) (xy 25.837207 -51.048476) (xy 25.691222 -50.997695) (xy 25.548045 -50.939466)
			(xy 25.408055 -50.873944) (xy 25.271623 -50.801302) (xy 25.139112 -50.721733) (xy 25.010873 -50.635448)
			(xy 24.887246 -50.542675) (xy 24.768558 -50.443662) (xy 24.655125 -50.33867) (xy 24.547248 -50.227978)
			(xy 24.445211 -50.111879) (xy 24.349287 -49.990682) (xy 24.259728 -49.864707) (xy 24.176774 -49.734288)
			(xy 24.100643 -49.599773) (xy 24.031538 -49.461516) (xy 23.969642 -49.319886) (xy 23.915118 -49.175256)
			(xy 23.868113 -49.028012) (xy 23.82875 -48.878543) (xy 23.797133 -48.727247) (xy 23.773347 -48.574523)
			(xy 23.757454 -48.420777) (xy 23.749498 -48.266417) (xy 23.749 -48.189134) (xy 0.509016 -48.189134)
			(xy 0.509016 -52.67175) (xy 66.314303 -52.67175) (xy 66.314303 -52.61725) (xy 66.32206 -52.563304)
			(xy 66.337415 -52.511011) (xy 66.360056 -52.461436) (xy 66.389522 -52.415587) (xy 66.425214 -52.374399)
			(xy 66.466403 -52.33871) (xy 66.512253 -52.309246) (xy 66.56183 -52.286608) (xy 66.614123 -52.271256)
			(xy 66.66807 -52.263502) (xy 66.69532 -52.26304) (xy 67.58432 -52.26304) (xy 67.611574 -52.263431)
			(xy 67.665526 -52.271191) (xy 67.717825 -52.28655) (xy 67.767406 -52.309195) (xy 67.81326 -52.338666)
			(xy 67.854453 -52.374362) (xy 67.890146 -52.415556) (xy 67.919615 -52.461412) (xy 67.942257 -52.510994)
			(xy 67.957613 -52.563293) (xy 67.96537 -52.617246) (xy 67.96537 -52.671754) (xy 67.957613 -52.725707)
			(xy 67.942257 -52.778006) (xy 67.919615 -52.827588) (xy 67.890146 -52.873444) (xy 67.854453 -52.914638)
			(xy 67.81326 -52.950334) (xy 67.767406 -52.979805) (xy 67.717825 -53.00245) (xy 67.665526 -53.017809)
			(xy 67.611574 -53.025569) (xy 67.58432 -53.026056) (xy 66.69532 -53.026056) (xy 66.66807 -53.025498)
			(xy 66.614123 -53.017744) (xy 66.56183 -53.002392) (xy 66.512253 -52.979754) (xy 66.466403 -52.95029)
			(xy 66.425214 -52.914601) (xy 66.389522 -52.873413) (xy 66.360056 -52.827564) (xy 66.337415 -52.777989)
			(xy 66.32206 -52.725696) (xy 66.314303 -52.67175) (xy 0.509016 -52.67175) (xy 0.509016 -54.53387)
			(xy 66.568023 -54.53387) (xy 66.568023 -54.47933) (xy 66.575786 -54.425344) (xy 66.591152 -54.373013)
			(xy 66.61381 -54.323401) (xy 66.643298 -54.277519) (xy 66.679015 -54.236301) (xy 66.720235 -54.200586)
			(xy 66.766119 -54.1711) (xy 66.815732 -54.148445) (xy 66.868064 -54.133081) (xy 66.92205 -54.125322)
			(xy 66.94932 -54.12486) (xy 67.83832 -54.12486) (xy 67.86559 -54.125304) (xy 67.919575 -54.133068)
			(xy 67.971905 -54.148436) (xy 68.021515 -54.171095) (xy 68.067396 -54.200583) (xy 68.108614 -54.2363)
			(xy 68.144329 -54.27752) (xy 68.173815 -54.323402) (xy 68.196471 -54.373014) (xy 68.211836 -54.425345)
			(xy 68.219598 -54.47933) (xy 68.219598 -54.53387) (xy 68.211836 -54.587855) (xy 68.196471 -54.640186)
			(xy 68.173815 -54.689798) (xy 68.144329 -54.73568) (xy 68.108614 -54.7769) (xy 68.067396 -54.812617)
			(xy 68.021515 -54.842105) (xy 67.971905 -54.864764) (xy 67.919575 -54.880132) (xy 67.86559 -54.887896)
			(xy 67.83832 -54.888384) (xy 66.94932 -54.888384) (xy 66.92205 -54.887878) (xy 66.868064 -54.880119)
			(xy 66.815732 -54.864755) (xy 66.766119 -54.8421) (xy 66.720235 -54.812614) (xy 66.679015 -54.776899)
			(xy 66.643298 -54.735681) (xy 66.61381 -54.689799) (xy 66.591152 -54.640187) (xy 66.575786 -54.587856)
			(xy 66.568023 -54.53387) (xy 0.509016 -54.53387) (xy 0.509016 -58.166508) (xy 60.959492 -58.166508)
			(xy 60.959492 -57.366662) (xy 60.959966 -57.340674) (xy 60.968103 -57.289338) (xy 60.984169 -57.239907)
			(xy 61.007769 -57.193597) (xy 61.038323 -57.15155) (xy 61.075078 -57.114799) (xy 61.11713 -57.08425)
			(xy 61.163442 -57.060654) (xy 61.212875 -57.044594) (xy 61.264212 -57.036464) (xy 61.2902 -57.035954)
			(xy 61.317668 -57.036479) (xy 61.371851 -57.04555) (xy 61.423791 -57.063444) (xy 61.472065 -57.089668)
			(xy 61.515345 -57.123503) (xy 61.534294 -57.143396) (xy 61.55212 -57.162087) (xy 61.582322 -57.203984)
			(xy 61.605643 -57.250068) (xy 61.621515 -57.299217) (xy 61.629551 -57.350236) (xy 61.630052 -57.37606)
			(xy 61.629773 -57.39555) (xy 61.625189 -57.43426) (xy 61.620908 -57.453276) (xy 61.620908 -58.166508)
			(xy 61.620398 -58.192491) (xy 63.359983 -58.192491) (xy 63.359983 -58.140509) (xy 63.368116 -58.089167)
			(xy 63.38418 -58.03973) (xy 63.407782 -57.993415) (xy 63.438338 -57.951362) (xy 63.475097 -57.914608)
			(xy 63.517154 -57.884058) (xy 63.563473 -57.860463) (xy 63.612912 -57.844405) (xy 63.664255 -57.83628)
			(xy 63.690246 -57.8358) (xy 64.490092 -57.8358) (xy 64.516082 -57.836267) (xy 64.567423 -57.844397)
			(xy 64.61686 -57.860459) (xy 64.663175 -57.884057) (xy 64.705229 -57.91461) (xy 64.741985 -57.951365)
			(xy 64.772539 -57.993418) (xy 64.796138 -58.039733) (xy 64.812201 -58.089169) (xy 64.820333 -58.14051)
			(xy 64.820333 -58.19249) (xy 64.812201 -58.243831) (xy 64.796138 -58.293267) (xy 64.772539 -58.339582)
			(xy 64.741985 -58.381635) (xy 64.705229 -58.41839) (xy 64.663175 -58.448943) (xy 64.61686 -58.472541)
			(xy 64.567423 -58.488603) (xy 64.516082 -58.496733) (xy 64.490092 -58.497216) (xy 63.690246 -58.497216)
			(xy 63.664255 -58.49672) (xy 63.612912 -58.488595) (xy 63.563473 -58.472537) (xy 63.517154 -58.448942)
			(xy 63.475097 -58.418392) (xy 63.438338 -58.381638) (xy 63.407782 -58.339585) (xy 63.38418 -58.29327)
			(xy 63.368116 -58.243833) (xy 63.359983 -58.192491) (xy 61.620398 -58.192491) (xy 61.620398 -58.192495)
			(xy 61.612268 -58.24383) (xy 61.596207 -58.29326) (xy 61.572611 -58.33957) (xy 61.542061 -58.381618)
			(xy 61.50531 -58.418369) (xy 61.463262 -58.448919) (xy 61.416952 -58.472515) (xy 61.367522 -58.488576)
			(xy 61.316187 -58.496706) (xy 61.264213 -58.496706) (xy 61.212878 -58.488576) (xy 61.163448 -58.472515)
			(xy 61.117138 -58.448919) (xy 61.07509 -58.418369) (xy 61.038339 -58.381618) (xy 61.007789 -58.33957)
			(xy 60.984193 -58.29326) (xy 60.968132 -58.24383) (xy 60.960002 -58.192495) (xy 60.959492 -58.166508)
			(xy 0.509016 -58.166508) (xy 0.509016 -58.992411) (xy 61.759802 -58.992411) (xy 61.759802 -58.940389)
			(xy 61.76794 -58.889008) (xy 61.784015 -58.839533) (xy 61.807633 -58.793181) (xy 61.83821 -58.751095)
			(xy 61.874995 -58.71431) (xy 61.917081 -58.683733) (xy 61.963433 -58.660115) (xy 62.012908 -58.64404)
			(xy 62.064289 -58.635902) (xy 62.0903 -58.635392) (xy 62.890146 -58.635392) (xy 62.916147 -58.635998)
			(xy 62.967508 -58.644139) (xy 63.016964 -58.660214) (xy 63.063296 -58.683827) (xy 63.105364 -58.714397)
			(xy 63.142133 -58.751171) (xy 63.172697 -58.793243) (xy 63.196303 -58.839579) (xy 63.212372 -58.889036)
			(xy 63.220506 -58.940399) (xy 63.220506 -58.992401) (xy 63.220505 -58.99241) (xy 64.159602 -58.99241)
			(xy 64.159602 -58.94039) (xy 64.16774 -58.889009) (xy 64.183815 -58.839535) (xy 64.207431 -58.793184)
			(xy 64.238008 -58.751098) (xy 64.274792 -58.714313) (xy 64.316877 -58.683735) (xy 64.363227 -58.660118)
			(xy 64.412702 -58.644042) (xy 64.464082 -58.635903) (xy 64.490092 -58.635392) (xy 65.289938 -58.635392)
			(xy 65.31594 -58.635997) (xy 65.367302 -58.644137) (xy 65.416758 -58.660212) (xy 65.463091 -58.683825)
			(xy 65.505161 -58.714394) (xy 65.541931 -58.751168) (xy 65.572495 -58.793241) (xy 65.596103 -58.839577)
			(xy 65.612171 -58.889035) (xy 65.620306 -58.940398) (xy 65.620306 -58.992402) (xy 65.612171 -59.043765)
			(xy 65.596103 -59.093223) (xy 65.572495 -59.139559) (xy 65.541931 -59.181632) (xy 65.505161 -59.218406)
			(xy 65.463091 -59.248975) (xy 65.416758 -59.272588) (xy 65.367302 -59.288663) (xy 65.31594 -59.296803)
			(xy 65.289938 -59.297316) (xy 64.490092 -59.297316) (xy 64.464082 -59.296897) (xy 64.412702 -59.288758)
			(xy 64.363227 -59.272682) (xy 64.316877 -59.249065) (xy 64.274792 -59.218487) (xy 64.238008 -59.181702)
			(xy 64.207431 -59.139616) (xy 64.183815 -59.093265) (xy 64.16774 -59.043791) (xy 64.159602 -58.99241)
			(xy 63.220505 -58.99241) (xy 63.212372 -59.043763) (xy 63.196303 -59.093221) (xy 63.172697 -59.139557)
			(xy 63.142133 -59.181629) (xy 63.105364 -59.218403) (xy 63.063296 -59.248973) (xy 63.016964 -59.272586)
			(xy 62.967508 -59.288661) (xy 62.916147 -59.296802) (xy 62.890146 -59.297316) (xy 62.0903 -59.297316)
			(xy 62.064289 -59.296898) (xy 62.012908 -59.28876) (xy 61.963433 -59.272685) (xy 61.917081 -59.249067)
			(xy 61.874995 -59.21849) (xy 61.83821 -59.181705) (xy 61.807633 -59.139619) (xy 61.784015 -59.093267)
			(xy 61.76794 -59.043792) (xy 61.759802 -58.992411) (xy 0.509016 -58.992411) (xy 0.509016 -59.792515)
			(xy 63.359676 -59.792515) (xy 63.359676 -59.740485) (xy 63.367816 -59.689095) (xy 63.383895 -59.639612)
			(xy 63.407519 -59.593254) (xy 63.438104 -59.551162) (xy 63.474897 -59.514374) (xy 63.516993 -59.483794)
			(xy 63.563355 -59.460178) (xy 63.61284 -59.444105) (xy 63.664231 -59.435972) (xy 63.690246 -59.435492)
			(xy 64.490092 -59.435492) (xy 64.516098 -59.436067) (xy 64.56747 -59.444202) (xy 64.616937 -59.460274)
			(xy 64.66328 -59.483886) (xy 64.705359 -59.514457) (xy 64.742138 -59.551235) (xy 64.77271 -59.593313)
			(xy 64.796323 -59.639656) (xy 64.812396 -59.689122) (xy 64.820533 -59.740494) (xy 64.820533 -59.792506)
			(xy 64.812396 -59.843878) (xy 64.796323 -59.893344) (xy 64.77271 -59.939687) (xy 64.742138 -59.981765)
			(xy 64.705359 -60.018543) (xy 64.66328 -60.049114) (xy 64.616937 -60.072726) (xy 64.56747 -60.088798)
			(xy 64.516098 -60.096933) (xy 64.490092 -60.097416) (xy 63.690246 -60.097416) (xy 63.664231 -60.097028)
			(xy 63.61284 -60.088895) (xy 63.563355 -60.072822) (xy 63.516993 -60.049206) (xy 63.474897 -60.018626)
			(xy 63.438104 -59.981838) (xy 63.407519 -59.939746) (xy 63.383895 -59.893388) (xy 63.367816 -59.843905)
			(xy 63.359676 -59.792515) (xy 0.509016 -59.792515) (xy 0.509016 -60.3494) (xy 60.569868 -60.3494)
			(xy 60.573857 -60.296174) (xy 60.585733 -60.244137) (xy 60.605233 -60.194451) (xy 60.631919 -60.148227)
			(xy 60.665197 -60.106496) (xy 60.704323 -60.07019) (xy 60.748422 -60.040121) (xy 60.796511 -60.016961)
			(xy 60.847514 -60.001226) (xy 60.900292 -59.993268) (xy 60.92698 -59.992768) (xy 60.949767 -59.993141)
			(xy 60.994967 -59.998968) (xy 61.03906 -60.010491) (xy 61.06033 -60.018676) (xy 61.555376 -60.018676)
			(xy 61.564012 -60.015374) (xy 61.594178 -60.00485) (xy 61.657039 -59.993478) (xy 61.68898 -59.992768)
			(xy 61.717333 -59.993267) (xy 61.773326 -60.002234) (xy 61.827196 -60.019945) (xy 61.877586 -60.045954)
			(xy 61.923227 -60.079606) (xy 61.943488 -60.099448) (xy 61.962622 -60.116719) (xy 61.995857 -60.156112)
			(xy 62.022581 -60.200183) (xy 62.042146 -60.247865) (xy 62.054078 -60.298005) (xy 62.058089 -60.34939)
			(xy 62.054081 -60.400774) (xy 62.042152 -60.450915) (xy 62.022591 -60.498599) (xy 61.99587 -60.542671)
			(xy 61.962636 -60.582066) (xy 61.943488 -60.59932) (xy 61.923242 -60.619175) (xy 61.877589 -60.652806)
			(xy 61.827194 -60.678797) (xy 61.773323 -60.696496) (xy 61.717332 -60.705456) (xy 61.68898 -60.706)
			(xy 61.657039 -60.705289) (xy 61.594177 -60.693921) (xy 61.564012 -60.683394) (xy 61.555376 -60.680092)
			(xy 61.06033 -60.680092) (xy 61.039069 -60.688303) (xy 60.994975 -60.699837) (xy 60.949769 -60.705644)
			(xy 60.92698 -60.706) (xy 60.900292 -60.705532) (xy 60.847514 -60.697574) (xy 60.796511 -60.681839)
			(xy 60.748422 -60.658679) (xy 60.704323 -60.62861) (xy 60.665197 -60.592304) (xy 60.631919 -60.550573)
			(xy 60.605233 -60.504349) (xy 60.585733 -60.454663) (xy 60.573857 -60.402626) (xy 60.569868 -60.3494)
			(xy 0.509016 -60.3494) (xy 0.509016 -61.539628) (xy 0.508 -61.540644) (xy 0.508 -62.988444) (xy 0.509016 -62.98946)
			(xy 0.509016 -75.635104) (xy 15.732516 -75.635104) (xy 15.736498 -75.545176) (xy 15.748412 -75.455952)
			(xy 15.768165 -75.36813) (xy 15.795602 -75.282397) (xy 15.830509 -75.199425) (xy 15.872613 -75.119862)
			(xy 15.921583 -75.044332) (xy 15.977038 -74.973426) (xy 16.038542 -74.907698) (xy 16.105614 -74.847663)
			(xy 16.17773 -74.793791) (xy 16.254325 -74.746503) (xy 16.334799 -74.70617) (xy 16.418523 -74.673107)
			(xy 16.504842 -74.647573) (xy 16.59308 -74.629768) (xy 16.682545 -74.61983) (xy 16.77254 -74.617839)
			(xy 16.862357 -74.623809) (xy 16.951296 -74.637694) (xy 17.03866 -74.659385) (xy 17.123765 -74.688712)
			(xy 17.205944 -74.725446) (xy 17.284556 -74.7693) (xy 17.358984 -74.819929) (xy 17.428646 -74.876939)
			(xy 17.492997 -74.939882) (xy 17.551534 -75.008266) (xy 17.603797 -75.081556) (xy 17.649379 -75.159178)
			(xy 17.687922 -75.240525) (xy 17.719125 -75.32496) (xy 17.742743 -75.411822) (xy 17.758592 -75.500432)
			(xy 17.766548 -75.590096) (xy 17.767046 -75.635104) (xy 35.491176 -75.635104) (xy 35.495155 -75.535091)
			(xy 35.507068 -75.43571) (xy 35.526839 -75.33759) (xy 35.554343 -75.241351) (xy 35.589406 -75.147602)
			(xy 35.631807 -75.056934) (xy 35.681278 -74.969922) (xy 35.737505 -74.887115) (xy 35.800133 -74.809038)
			(xy 35.868767 -74.736183) (xy 35.942972 -74.669011) (xy 36.02228 -74.607948) (xy 36.106188 -74.553378)
			(xy 36.194166 -74.505647) (xy 36.285659 -74.465057) (xy 36.380087 -74.431865) (xy 36.476854 -74.40628)
			(xy 36.575348 -74.388463) (xy 36.674946 -74.378529) (xy 36.775018 -74.376539) (xy 36.874932 -74.382506)
			(xy 36.974056 -74.396392) (xy 37.071764 -74.41811) (xy 37.167437 -74.447522) (xy 37.260471 -74.484443)
			(xy 37.350277 -74.528638) (xy 37.436289 -74.579828) (xy 37.517961 -74.637691) (xy 37.594778 -74.701859)
			(xy 37.666254 -74.771928) (xy 37.731937 -74.847454) (xy 37.791412 -74.92796) (xy 37.844303 -75.012936)
			(xy 37.890275 -75.101846) (xy 37.929037 -75.194128) (xy 37.960346 -75.289197) (xy 37.984002 -75.386454)
			(xy 37.999856 -75.485282) (xy 38.007809 -75.585058) (xy 38.008306 -75.635104) (xy 38.007809 -75.68515)
			(xy 37.999856 -75.784926) (xy 37.984002 -75.883754) (xy 37.960346 -75.981011) (xy 37.929037 -76.07608)
			(xy 37.890275 -76.168362) (xy 37.844303 -76.257272) (xy 37.791412 -76.342248) (xy 37.731937 -76.422754)
			(xy 37.666254 -76.49828) (xy 37.594778 -76.568349) (xy 37.517961 -76.632517) (xy 37.436289 -76.69038)
			(xy 37.350277 -76.74157) (xy 37.260471 -76.785765) (xy 37.167437 -76.822686) (xy 37.071764 -76.852098)
			(xy 36.974056 -76.873816) (xy 36.874932 -76.887702) (xy 36.775018 -76.893669) (xy 36.674946 -76.891679)
			(xy 36.575348 -76.881745) (xy 36.476854 -76.863928) (xy 36.380087 -76.838343) (xy 36.285659 -76.805151)
			(xy 36.194166 -76.764561) (xy 36.106188 -76.71683) (xy 36.02228 -76.66226) (xy 35.942972 -76.601197)
			(xy 35.868767 -76.534025) (xy 35.800133 -76.46117) (xy 35.737505 -76.383093) (xy 35.681278 -76.300286)
			(xy 35.631807 -76.213274) (xy 35.589406 -76.122606) (xy 35.554343 -76.028857) (xy 35.526839 -75.932618)
			(xy 35.507068 -75.834498) (xy 35.495155 -75.735117) (xy 35.491176 -75.635104) (xy 17.767046 -75.635104)
			(xy 17.766548 -75.680112) (xy 17.758592 -75.769776) (xy 17.742743 -75.858386) (xy 17.719125 -75.945248)
			(xy 17.687922 -76.029683) (xy 17.649379 -76.11103) (xy 17.603797 -76.188652) (xy 17.551534 -76.261942)
			(xy 17.492997 -76.330326) (xy 17.428646 -76.393269) (xy 17.358984 -76.450279) (xy 17.284556 -76.500908)
			(xy 17.205944 -76.544762) (xy 17.123765 -76.581496) (xy 17.03866 -76.610823) (xy 16.951296 -76.632514)
			(xy 16.862357 -76.646399) (xy 16.77254 -76.652369) (xy 16.682545 -76.650378) (xy 16.59308 -76.64044)
			(xy 16.504842 -76.622635) (xy 16.418523 -76.597101) (xy 16.334799 -76.564038) (xy 16.254325 -76.523705)
			(xy 16.17773 -76.476417) (xy 16.105614 -76.422545) (xy 16.038542 -76.36251) (xy 15.977038 -76.296782)
			(xy 15.921583 -76.225876) (xy 15.872613 -76.150346) (xy 15.830509 -76.070783) (xy 15.795602 -75.987811)
			(xy 15.768165 -75.902078) (xy 15.748412 -75.814256) (xy 15.736498 -75.725032) (xy 15.732516 -75.635104)
			(xy 0.509016 -75.635104) (xy 0.509016 -80.990948) (xy 2.249932 -80.990948) (xy 2.293971 -80.991429)
			(xy 2.381714 -80.999105) (xy 2.468454 -81.0144) (xy 2.553531 -81.037196) (xy 2.636297 -81.067321)
			(xy 2.716123 -81.104545) (xy 2.792401 -81.148584) (xy 2.86455 -81.199103) (xy 2.932022 -81.255719)
			(xy 2.994302 -81.318) (xy 3.050918 -81.385471) (xy 3.101437 -81.457621) (xy 3.145476 -81.533899)
			(xy 3.1827 -81.613725) (xy 3.212824 -81.696491) (xy 3.23562 -81.781568) (xy 3.250915 -81.868308)
			(xy 3.258592 -81.956051) (xy 3.259074 -82.00009) (xy 3.259074 -84.499958) (xy 3.258594 -84.543997)
			(xy 3.250917 -84.63174) (xy 3.235623 -84.718481) (xy 3.212827 -84.803558) (xy 3.182702 -84.886325)
			(xy 3.145479 -84.966151) (xy 3.10144 -85.042429) (xy 3.05092 -85.114579) (xy 2.994305 -85.182051)
			(xy 2.932024 -85.244332) (xy 2.864552 -85.300948) (xy 2.792403 -85.351468) (xy 2.716124 -85.395507)
			(xy 2.636298 -85.432731) (xy 2.553532 -85.462855) (xy 2.468455 -85.485652) (xy 2.381714 -85.500947)
			(xy 2.293971 -85.508623) (xy 2.249932 -85.5091) (xy 0.509016 -85.5091) (xy 0.509016 -97.978249) (xy 45.046914 -97.978249)
			(xy 45.046914 -97.923751) (xy 45.05467 -97.869809) (xy 45.070024 -97.817519) (xy 45.092663 -97.767947)
			(xy 45.122126 -97.722101) (xy 45.157814 -97.680914) (xy 45.199001 -97.645226) (xy 45.244847 -97.615763)
			(xy 45.294419 -97.593124) (xy 45.346709 -97.57777) (xy 45.400651 -97.570014) (xy 45.4279 -97.569528)
			(xy 46.3169 -97.569528) (xy 46.344154 -97.569942) (xy 46.398107 -97.577699) (xy 46.450406 -97.593056)
			(xy 46.499988 -97.615699) (xy 46.545843 -97.645168) (xy 46.587037 -97.680863) (xy 46.622732 -97.722057)
			(xy 46.652201 -97.767912) (xy 46.674844 -97.817494) (xy 46.690201 -97.869793) (xy 46.697958 -97.923746)
			(xy 46.697958 -97.978254) (xy 46.690201 -98.032207) (xy 46.674844 -98.084506) (xy 46.652201 -98.134088)
			(xy 46.622732 -98.179943) (xy 46.587037 -98.221137) (xy 46.545843 -98.256832) (xy 46.499988 -98.286301)
			(xy 46.450406 -98.308944) (xy 46.398107 -98.324301) (xy 46.344154 -98.332058) (xy 46.3169 -98.332544)
			(xy 45.4279 -98.332544) (xy 45.400651 -98.331986) (xy 45.346709 -98.32423) (xy 45.294419 -98.308876)
			(xy 45.244847 -98.286237) (xy 45.199001 -98.256774) (xy 45.157814 -98.221086) (xy 45.122126 -98.179899)
			(xy 45.092663 -98.134053) (xy 45.070024 -98.084481) (xy 45.05467 -98.032191) (xy 45.046914 -97.978249)
			(xy 0.509016 -97.978249) (xy 0.509016 -98.410049) (xy 40.017714 -98.410049) (xy 40.017714 -98.355551)
			(xy 40.02547 -98.301609) (xy 40.040824 -98.249319) (xy 40.063463 -98.199747) (xy 40.092926 -98.153901)
			(xy 40.128614 -98.112714) (xy 40.169801 -98.077026) (xy 40.215647 -98.047563) (xy 40.265219 -98.024924)
			(xy 40.317509 -98.00957) (xy 40.371451 -98.001814) (xy 40.3987 -98.001328) (xy 41.2877 -98.001328)
			(xy 41.314954 -98.001742) (xy 41.368907 -98.009499) (xy 41.421206 -98.024856) (xy 41.470788 -98.047499)
			(xy 41.516643 -98.076968) (xy 41.557837 -98.112663) (xy 41.593532 -98.153857) (xy 41.623001 -98.199712)
			(xy 41.645644 -98.249294) (xy 41.661001 -98.301593) (xy 41.668758 -98.355546) (xy 41.668758 -98.410054)
			(xy 41.661001 -98.464007) (xy 41.645644 -98.516306) (xy 41.623001 -98.565888) (xy 41.593532 -98.611743)
			(xy 41.557837 -98.652937) (xy 41.516643 -98.688632) (xy 41.470788 -98.718101) (xy 41.421206 -98.740744)
			(xy 41.368907 -98.756101) (xy 41.314954 -98.763858) (xy 41.2877 -98.764344) (xy 40.3987 -98.764344)
			(xy 40.371451 -98.763786) (xy 40.317509 -98.75603) (xy 40.265219 -98.740676) (xy 40.215647 -98.718037)
			(xy 40.169801 -98.688574) (xy 40.128614 -98.652886) (xy 40.092926 -98.611699) (xy 40.063463 -98.565853)
			(xy 40.040824 -98.516281) (xy 40.02547 -98.463991) (xy 40.017714 -98.410049) (xy 0.509016 -98.410049)
			(xy 0.509016 -104.205349) (xy 54.921178 -104.205349) (xy 54.921178 -104.150851) (xy 54.928933 -104.096908)
			(xy 54.944285 -104.044617) (xy 54.966923 -103.995043) (xy 54.996385 -103.949195) (xy 55.032071 -103.908006)
			(xy 55.073255 -103.872315) (xy 55.119099 -103.842847) (xy 55.16867 -103.820203) (xy 55.220959 -103.804843)
			(xy 55.274901 -103.797081) (xy 55.30215 -103.796592) (xy 56.19115 -103.796592) (xy 56.218405 -103.797052)
			(xy 56.272362 -103.804803) (xy 56.324665 -103.820155) (xy 56.374252 -103.842794) (xy 56.420111 -103.872261)
			(xy 56.46131 -103.907955) (xy 56.497009 -103.949149) (xy 56.526482 -103.995004) (xy 56.549128 -104.044588)
			(xy 56.564486 -104.09689) (xy 56.572245 -104.150845) (xy 56.572245 -104.205355) (xy 56.564486 -104.25931)
			(xy 56.549128 -104.311612) (xy 56.526482 -104.361196) (xy 56.497009 -104.407051) (xy 56.46131 -104.448245)
			(xy 56.420111 -104.483939) (xy 56.374252 -104.513406) (xy 56.324665 -104.536045) (xy 56.272362 -104.551397)
			(xy 56.218405 -104.559148) (xy 56.19115 -104.559608) (xy 55.30215 -104.559608) (xy 55.274901 -104.559119)
			(xy 55.220959 -104.551357) (xy 55.16867 -104.535997) (xy 55.119099 -104.513353) (xy 55.073255 -104.483885)
			(xy 55.032071 -104.448194) (xy 54.996385 -104.407005) (xy 54.966923 -104.361157) (xy 54.944285 -104.311583)
			(xy 54.928933 -104.259292) (xy 54.921178 -104.205349) (xy 0.509016 -104.205349) (xy 0.509016 -107.774051)
			(xy 13.017478 -107.774051) (xy 13.017478 -107.719549) (xy 13.025234 -107.665601) (xy 13.040589 -107.613306)
			(xy 13.063231 -107.563729) (xy 13.092697 -107.517879) (xy 13.128388 -107.476688) (xy 13.169579 -107.440997)
			(xy 13.215429 -107.411531) (xy 13.265006 -107.388889) (xy 13.317301 -107.373534) (xy 13.371249 -107.365778)
			(xy 13.3985 -107.365292) (xy 14.2875 -107.365292) (xy 14.314751 -107.365778) (xy 14.368699 -107.373534)
			(xy 14.420994 -107.388889) (xy 14.470571 -107.411531) (xy 14.516421 -107.440997) (xy 14.557612 -107.476688)
			(xy 14.593303 -107.517879) (xy 14.622769 -107.563729) (xy 14.645411 -107.613306) (xy 14.660766 -107.665601)
			(xy 14.668522 -107.719549) (xy 14.668522 -107.77382) (xy 17.94482 -107.77382) (xy 17.94482 -107.71928)
			(xy 17.952582 -107.665296) (xy 17.967948 -107.612966) (xy 17.990604 -107.563355) (xy 18.02009 -107.517474)
			(xy 18.055806 -107.476256) (xy 18.097024 -107.44054) (xy 18.142905 -107.411054) (xy 18.192516 -107.388398)
			(xy 18.244846 -107.373032) (xy 18.29883 -107.36527) (xy 18.3261 -107.364784) (xy 19.2151 -107.364784)
			(xy 19.242369 -107.365278) (xy 19.296352 -107.37304) (xy 19.348681 -107.388405) (xy 19.398291 -107.411061)
			(xy 19.444171 -107.440547) (xy 19.485388 -107.476262) (xy 19.521103 -107.517479) (xy 19.550589 -107.563359)
			(xy 19.573245 -107.612969) (xy 19.58861 -107.665298) (xy 19.596372 -107.719281) (xy 19.596372 -107.773819)
			(xy 19.58861 -107.827802) (xy 19.573245 -107.880131) (xy 19.550589 -107.929741) (xy 19.521103 -107.975621)
			(xy 19.485388 -108.016838) (xy 19.444171 -108.052553) (xy 19.398291 -108.082039) (xy 19.348681 -108.104695)
			(xy 19.296352 -108.12006) (xy 19.242369 -108.127822) (xy 19.2151 -108.128308) (xy 18.3261 -108.128308)
			(xy 18.29883 -108.12783) (xy 18.244846 -108.120068) (xy 18.192516 -108.104702) (xy 18.142905 -108.082046)
			(xy 18.097024 -108.05256) (xy 18.055806 -108.016844) (xy 18.02009 -107.975626) (xy 17.990604 -107.929745)
			(xy 17.967948 -107.880134) (xy 17.952582 -107.827804) (xy 17.94482 -107.77382) (xy 14.668522 -107.77382)
			(xy 14.668522 -107.774051) (xy 14.660766 -107.827999) (xy 14.645411 -107.880294) (xy 14.622769 -107.929871)
			(xy 14.593303 -107.975721) (xy 14.557612 -108.016912) (xy 14.516421 -108.052603) (xy 14.470571 -108.082069)
			(xy 14.420994 -108.104711) (xy 14.368699 -108.120066) (xy 14.314751 -108.127822) (xy 14.2875 -108.128308)
			(xy 13.3985 -108.128308) (xy 13.371249 -108.127822) (xy 13.317301 -108.120066) (xy 13.265006 -108.104711)
			(xy 13.215429 -108.082069) (xy 13.169579 -108.052603) (xy 13.128388 -108.016912) (xy 13.092697 -107.975721)
			(xy 13.063231 -107.929871) (xy 13.040589 -107.880294) (xy 13.025234 -107.827999) (xy 13.017478 -107.774051)
			(xy 0.509016 -107.774051) (xy 0.509016 -108.957872) (xy 13.084556 -108.957872) (xy 13.084556 -108.816902)
			(xy 13.08498 -108.803817) (xy 13.091784 -108.778547) (xy 13.104924 -108.755915) (xy 13.123497 -108.737478)
			(xy 13.146225 -108.724504) (xy 13.171544 -108.717886) (xy 13.184632 -108.717588) (xy 13.485368 -108.717588)
			(xy 13.498459 -108.717857) (xy 13.523786 -108.724477) (xy 13.546521 -108.737455) (xy 13.565099 -108.755897)
			(xy 13.578243 -108.778536) (xy 13.585049 -108.803813) (xy 13.585444 -108.816902) (xy 13.585444 -108.957872)
			(xy 14.100556 -108.957872) (xy 14.100556 -108.816902) (xy 14.10098 -108.803817) (xy 14.107784 -108.778547)
			(xy 14.120924 -108.755915) (xy 14.139497 -108.737478) (xy 14.162225 -108.724504) (xy 14.187544 -108.717886)
			(xy 14.200632 -108.717588) (xy 14.501368 -108.717588) (xy 14.514459 -108.717857) (xy 14.539786 -108.724477)
			(xy 14.562521 -108.737455) (xy 14.581099 -108.755897) (xy 14.594243 -108.778536) (xy 14.601049 -108.803813)
			(xy 14.601444 -108.816902) (xy 14.601444 -108.957872) (xy 14.5415 -108.957872) (xy 14.5415 -109.22254)
			(xy 14.1605 -109.22254) (xy 14.1605 -108.957872) (xy 14.100556 -108.957872) (xy 13.585444 -108.957872)
			(xy 13.5255 -108.957872) (xy 13.5255 -109.22254) (xy 13.1445 -109.22254) (xy 13.1445 -108.957872)
			(xy 13.084556 -108.957872) (xy 0.509016 -108.957872) (xy 0.509016 -109.877098) (xy 13.084556 -109.877098)
			(xy 13.084556 -109.736128) (xy 13.1445 -109.736128) (xy 13.1445 -109.47146) (xy 13.5255 -109.47146)
			(xy 13.5255 -109.736128) (xy 13.585444 -109.736128) (xy 13.585444 -109.877098) (xy 14.100556 -109.877098)
			(xy 14.100556 -109.736128) (xy 14.1605 -109.736128) (xy 14.1605 -109.47146) (xy 14.5415 -109.47146)
			(xy 14.5415 -109.570609) (xy 15.016716 -109.570609) (xy 15.016716 -109.516071) (xy 15.024478 -109.462088)
			(xy 15.039843 -109.409759) (xy 15.062499 -109.360149) (xy 15.091985 -109.314268) (xy 15.127699 -109.273051)
			(xy 15.168917 -109.237336) (xy 15.214797 -109.20785) (xy 15.264407 -109.185194) (xy 15.316736 -109.169828)
			(xy 15.370719 -109.162067) (xy 15.397988 -109.16158) (xy 16.286988 -109.16158) (xy 16.314259 -109.162039)
			(xy 16.368247 -109.169801) (xy 16.42058 -109.185167) (xy 16.470193 -109.207825) (xy 16.516078 -109.237313)
			(xy 16.557298 -109.27303) (xy 16.593016 -109.314251) (xy 16.622504 -109.360135) (xy 16.645162 -109.409748)
			(xy 16.660528 -109.462081) (xy 16.668291 -109.516069) (xy 16.668291 -109.570611) (xy 16.660528 -109.624599)
			(xy 16.645162 -109.676932) (xy 16.622504 -109.726545) (xy 16.593016 -109.772429) (xy 16.557298 -109.81365)
			(xy 16.516078 -109.849367) (xy 16.470193 -109.878855) (xy 16.42058 -109.901513) (xy 16.368247 -109.916879)
			(xy 16.314259 -109.924641) (xy 16.286988 -109.925104) (xy 15.397988 -109.925104) (xy 15.370719 -109.924613)
			(xy 15.316736 -109.916852) (xy 15.264407 -109.901486) (xy 15.214797 -109.87883) (xy 15.168917 -109.849344)
			(xy 15.127699 -109.813629) (xy 15.091985 -109.772412) (xy 15.062499 -109.726531) (xy 15.039843 -109.676921)
			(xy 15.024478 -109.624592) (xy 15.016716 -109.570609) (xy 14.5415 -109.570609) (xy 14.5415 -109.736128)
			(xy 14.601444 -109.736128) (xy 14.601444 -109.877098) (xy 14.60102 -109.890183) (xy 14.594216 -109.915453)
			(xy 14.581076 -109.938085) (xy 14.562503 -109.956522) (xy 14.539775 -109.969496) (xy 14.514456 -109.976114)
			(xy 14.501368 -109.976412) (xy 14.200632 -109.976412) (xy 14.187541 -109.976143) (xy 14.162214 -109.969523)
			(xy 14.139479 -109.956545) (xy 14.120901 -109.938103) (xy 14.107757 -109.915464) (xy 14.100951 -109.890187)
			(xy 14.100556 -109.877098) (xy 13.585444 -109.877098) (xy 13.58502 -109.890183) (xy 13.578216 -109.915453)
			(xy 13.565076 -109.938085) (xy 13.546503 -109.956522) (xy 13.523775 -109.969496) (xy 13.498456 -109.976114)
			(xy 13.485368 -109.976412) (xy 13.184632 -109.976412) (xy 13.171541 -109.976143) (xy 13.146214 -109.969523)
			(xy 13.123479 -109.956545) (xy 13.104901 -109.938103) (xy 13.091757 -109.915464) (xy 13.084951 -109.890187)
			(xy 13.084556 -109.877098) (xy 0.509016 -109.877098) (xy 0.509016 -109.998056) (xy 84.426541 -109.998056)
			(xy 84.426541 -109.868916) (xy 84.434491 -109.740021) (xy 84.450361 -109.611861) (xy 84.47409 -109.48492)
			(xy 84.505589 -109.359681) (xy 84.544738 -109.236618) (xy 84.591389 -109.116199) (xy 84.645364 -108.99888)
			(xy 84.706459 -108.885106) (xy 84.774442 -108.775309) (xy 84.849056 -108.669906) (xy 84.930017 -108.569296)
			(xy 85.017017 -108.473861) (xy 85.109728 -108.383962) (xy 85.207798 -108.299941) (xy 85.310853 -108.222117)
			(xy 85.418504 -108.150785) (xy 85.530343 -108.086215) (xy 85.645944 -108.028653) (xy 85.764869 -107.978316)
			(xy 85.886668 -107.935396) (xy 86.010878 -107.900055) (xy 86.137027 -107.872428) (xy 86.264639 -107.852619)
			(xy 86.393228 -107.840703) (xy 86.522306 -107.836727) (xy 86.651384 -107.840703) (xy 86.779973 -107.852619)
			(xy 86.907585 -107.872428) (xy 87.033734 -107.900055) (xy 87.157944 -107.935396) (xy 87.279743 -107.978316)
			(xy 87.398668 -108.028653) (xy 87.514269 -108.086215) (xy 87.626108 -108.150785) (xy 87.733759 -108.222117)
			(xy 87.836814 -108.299941) (xy 87.934884 -108.383962) (xy 88.027595 -108.473861) (xy 88.114595 -108.569296)
			(xy 88.195556 -108.669906) (xy 88.27017 -108.775309) (xy 88.338153 -108.885106) (xy 88.399248 -108.99888)
			(xy 88.453223 -109.116199) (xy 88.499874 -109.236618) (xy 88.539023 -109.359681) (xy 88.570522 -109.48492)
			(xy 88.594251 -109.611861) (xy 88.610121 -109.740021) (xy 88.618071 -109.868916) (xy 88.618568 -109.933486)
			(xy 88.618071 -109.998056) (xy 88.610121 -110.126951) (xy 88.594251 -110.255111) (xy 88.570522 -110.382052)
			(xy 88.539023 -110.507291) (xy 88.499874 -110.630354) (xy 88.453223 -110.750773) (xy 88.399248 -110.868092)
			(xy 88.338153 -110.981866) (xy 88.27017 -111.091663) (xy 88.195556 -111.197066) (xy 88.114595 -111.297676)
			(xy 88.027595 -111.393111) (xy 87.934884 -111.48301) (xy 87.836814 -111.567031) (xy 87.733759 -111.644855)
			(xy 87.626108 -111.716187) (xy 87.514269 -111.780757) (xy 87.398668 -111.838319) (xy 87.279743 -111.888656)
			(xy 87.157944 -111.931576) (xy 87.033734 -111.966917) (xy 86.907585 -111.994544) (xy 86.779973 -112.014353)
			(xy 86.651384 -112.026269) (xy 86.522306 -112.030246) (xy 86.393228 -112.026269) (xy 86.264639 -112.014353)
			(xy 86.137027 -111.994544) (xy 86.010878 -111.966917) (xy 85.886668 -111.931576) (xy 85.764869 -111.888656)
			(xy 85.645944 -111.838319) (xy 85.530343 -111.780757) (xy 85.418504 -111.716187) (xy 85.310853 -111.644855)
			(xy 85.207798 -111.567031) (xy 85.109728 -111.48301) (xy 85.017017 -111.393111) (xy 84.930017 -111.297676)
			(xy 84.849056 -111.197066) (xy 84.774442 -111.091663) (xy 84.706459 -110.981866) (xy 84.645364 -110.868092)
			(xy 84.591389 -110.750773) (xy 84.544738 -110.630354) (xy 84.505589 -110.507291) (xy 84.47409 -110.382052)
			(xy 84.450361 -110.255111) (xy 84.434491 -110.126951) (xy 84.426541 -109.998056) (xy 0.509016 -109.998056)
			(xy 0.509016 -112.300004) (xy 0.509494 -112.35115) (xy 53.778158 -112.35115) (xy 53.778158 -112.29665)
			(xy 53.785913 -112.242703) (xy 53.801267 -112.19041) (xy 53.823905 -112.140833) (xy 53.853369 -112.094983)
			(xy 53.889057 -112.053792) (xy 53.930243 -112.018099) (xy 53.976089 -111.988629) (xy 54.025663 -111.965984)
			(xy 54.077955 -111.950624) (xy 54.1319 -111.942861) (xy 54.15915 -111.942372) (xy 55.04815 -111.942372)
			(xy 55.075404 -111.942872) (xy 55.129357 -111.950623) (xy 55.181658 -111.965974) (xy 55.231242 -111.988612)
			(xy 55.277099 -112.018077) (xy 55.318296 -112.053769) (xy 55.353993 -112.094961) (xy 55.383464 -112.140814)
			(xy 55.406109 -112.190395) (xy 55.421467 -112.242694) (xy 55.429225 -112.296646) (xy 55.429225 -112.351154)
			(xy 55.421467 -112.405106) (xy 55.406109 -112.457405) (xy 55.383464 -112.506986) (xy 55.353993 -112.552839)
			(xy 55.318296 -112.594031) (xy 55.277099 -112.629723) (xy 55.231242 -112.659188) (xy 55.181658 -112.681826)
			(xy 55.129357 -112.697177) (xy 55.075404 -112.704928) (xy 55.04815 -112.705388) (xy 54.15915 -112.705388)
			(xy 54.1319 -112.704939) (xy 54.077955 -112.697176) (xy 54.025663 -112.681816) (xy 53.976089 -112.659171)
			(xy 53.930243 -112.629701) (xy 53.889057 -112.594008) (xy 53.853369 -112.552817) (xy 53.823905 -112.506967)
			(xy 53.801267 -112.45739) (xy 53.785913 -112.405097) (xy 53.778158 -112.35115) (xy 0.509494 -112.35115)
			(xy 0.509537 -112.355773) (xy 0.517873 -112.466999) (xy 0.534497 -112.577291) (xy 0.559316 -112.686033)
			(xy 0.592193 -112.792616) (xy 0.632942 -112.896444) (xy 0.681337 -112.996936) (xy 0.737106 -113.093531)
			(xy 0.796039 -113.17997) (xy 23.969706 -113.17997) (xy 23.969706 -113.12543) (xy 23.977468 -113.071446)
			(xy 23.992833 -113.019115) (xy 24.015489 -112.969504) (xy 24.044974 -112.923622) (xy 24.080689 -112.882403)
			(xy 24.121906 -112.846686) (xy 24.167787 -112.817198) (xy 24.217397 -112.79454) (xy 24.269726 -112.779172)
			(xy 24.32371 -112.771408) (xy 24.35098 -112.77092) (xy 25.23998 -112.77092) (xy 25.267251 -112.771418)
			(xy 25.321237 -112.779178) (xy 25.37357 -112.794541) (xy 25.423183 -112.817197) (xy 25.469067 -112.846682)
			(xy 25.510288 -112.882398) (xy 25.546006 -112.923617) (xy 25.575494 -112.969499) (xy 25.598152 -113.019111)
			(xy 25.613518 -113.071443) (xy 25.62128 -113.125429) (xy 25.62128 -113.179971) (xy 25.613518 -113.233957)
			(xy 25.598152 -113.286289) (xy 25.575494 -113.335901) (xy 25.546006 -113.381783) (xy 25.510288 -113.423002)
			(xy 25.469067 -113.458718) (xy 25.423183 -113.488203) (xy 25.37357 -113.510859) (xy 25.321237 -113.526222)
			(xy 25.267251 -113.533982) (xy 25.23998 -113.534444) (xy 24.35098 -113.534444) (xy 24.32371 -113.533992)
			(xy 24.269726 -113.526228) (xy 24.217397 -113.51086) (xy 24.167787 -113.488202) (xy 24.121906 -113.458714)
			(xy 24.080689 -113.422997) (xy 24.044974 -113.381778) (xy 24.015489 -113.335896) (xy 23.992833 -113.286285)
			(xy 23.977468 -113.233954) (xy 23.969706 -113.17997) (xy 0.796039 -113.17997) (xy 0.799937 -113.185688)
			(xy 0.86948 -113.272892) (xy 0.945345 -113.354655) (xy 1.027108 -113.43052) (xy 1.114312 -113.500063)
			(xy 1.206469 -113.562894) (xy 1.303064 -113.618663) (xy 1.403556 -113.667058) (xy 1.507384 -113.707807)
			(xy 1.613967 -113.740684) (xy 1.722709 -113.765503) (xy 1.833001 -113.782127) (xy 1.944227 -113.790463)
			(xy 1.999996 -113.790984) (xy 4.500118 -113.790984) (xy 4.544143 -113.791475) (xy 4.631856 -113.799169)
			(xy 4.718565 -113.814476) (xy 4.803611 -113.83728) (xy 4.886347 -113.867406) (xy 4.966143 -113.904627)
			(xy 5.042392 -113.948658) (xy 5.114516 -113.999166) (xy 5.181964 -114.055765) (xy 5.244225 -114.118026)
			(xy 5.300824 -114.185474) (xy 5.351332 -114.257598) (xy 5.395363 -114.333847) (xy 5.432584 -114.413643)
			(xy 5.46271 -114.496379) (xy 5.485514 -114.581425) (xy 5.500821 -114.668134) (xy 5.508515 -114.755847)
			(xy 5.509006 -114.799872) (xy 5.509006 -118.711726) (xy 5.621528 -118.824248) (xy 5.936488 -118.824248)
			(xy 6.040374 -118.720616) (xy 9.704578 -118.720616) (xy 9.862312 -118.878096) (xy 10.162286 -118.878096)
		)
		(stroke
			(width 0)
			(type solid)
		)
		(fill yes)
		(layer "In1.Cu")
		(net "GND")
	)
	(gr_poly
		(pts
			(xy 121.000012 -119.892064) (xy 121.055819 -119.891554) (xy 121.16712 -119.883212) (xy 121.277487 -119.866576)
			(xy 121.386302 -119.841739) (xy 121.492956 -119.808839) (xy 121.596854 -119.768061) (xy 121.697414 -119.719632)
			(xy 121.794073 -119.663824) (xy 121.886292 -119.600949) (xy 121.973554 -119.531358) (xy 122.055371 -119.45544)
			(xy 122.131287 -119.373621) (xy 122.200875 -119.286356) (xy 122.263748 -119.194136) (xy 122.319553 -119.097475)
			(xy 122.367978 -118.996914) (xy 122.408754 -118.893015) (xy 122.44165 -118.786359) (xy 122.466484 -118.677544)
			(xy 122.483117 -118.567176) (xy 122.491456 -118.455875) (xy 122.492008 -118.400068) (xy 122.492008 129.499868)
			(xy 122.4915 129.555676) (xy 122.483161 129.666981) (xy 122.466528 129.777352) (xy 122.441693 129.886171)
			(xy 122.408795 129.992829) (xy 122.368019 130.096731) (xy 122.319592 130.197295) (xy 122.263785 130.293959)
			(xy 122.200911 130.386183) (xy 122.13132 130.473449) (xy 122.055402 130.555271) (xy 121.973583 130.631191)
			(xy 121.886318 130.700784) (xy 121.794097 130.763662) (xy 121.697434 130.819471) (xy 121.596872 130.867901)
			(xy 121.492971 130.908681) (xy 121.386313 130.941581) (xy 121.277495 130.96642) (xy 121.167125 130.983056)
			(xy 121.05582 130.991398) (xy 121.000012 130.991864) (xy 94.000066 130.991864) (xy 93.94426 130.991341)
			(xy 93.832961 130.982998) (xy 93.722596 130.96636) (xy 93.613784 130.941522) (xy 93.507131 130.908622)
			(xy 93.403236 130.867843) (xy 93.302679 130.819414) (xy 93.206021 130.763606) (xy 93.113805 130.700731)
			(xy 93.026545 130.631141) (xy 92.94473 130.555224) (xy 92.868816 130.473405) (xy 92.79923 130.386142)
			(xy 92.736359 130.293923) (xy 92.680555 130.197263) (xy 92.632131 130.096703) (xy 92.591357 129.992806)
			(xy 92.558461 129.886153) (xy 92.533627 129.777339) (xy 92.516995 129.666973) (xy 92.508656 129.555674)
			(xy 92.50807 129.499868) (xy 92.50807 126.435304) (xy 115.904253 126.435304) (xy 115.904253 126.564444)
			(xy 115.912203 126.693339) (xy 115.928073 126.821499) (xy 115.951802 126.94844) (xy 115.983301 127.073679)
			(xy 116.02245 127.196742) (xy 116.069101 127.317161) (xy 116.123076 127.43448) (xy 116.184171 127.548254)
			(xy 116.252154 127.658051) (xy 116.326768 127.763454) (xy 116.407729 127.864064) (xy 116.494729 127.959499)
			(xy 116.58744 128.049398) (xy 116.68551 128.133419) (xy 116.788565 128.211243) (xy 116.896216 128.282575)
			(xy 117.008055 128.347145) (xy 117.123656 128.404707) (xy 117.242581 128.455044) (xy 117.36438 128.497964)
			(xy 117.48859 128.533305) (xy 117.614739 128.560932) (xy 117.742351 128.580741) (xy 117.87094 128.592657)
			(xy 118.000018 128.596634) (xy 118.129096 128.592657) (xy 118.257685 128.580741) (xy 118.385297 128.560932)
			(xy 118.511446 128.533305) (xy 118.635656 128.497964) (xy 118.757455 128.455044) (xy 118.87638 128.404707)
			(xy 118.991981 128.347145) (xy 119.10382 128.282575) (xy 119.211471 128.211243) (xy 119.314526 128.133419)
			(xy 119.412596 128.049398) (xy 119.505307 127.959499) (xy 119.592307 127.864064) (xy 119.673268 127.763454)
			(xy 119.747882 127.658051) (xy 119.815865 127.548254) (xy 119.87696 127.43448) (xy 119.930935 127.317161)
			(xy 119.977586 127.196742) (xy 120.016735 127.073679) (xy 120.048234 126.94844) (xy 120.071963 126.821499)
			(xy 120.087833 126.693339) (xy 120.095783 126.564444) (xy 120.09628 126.499874) (xy 120.095783 126.435304)
			(xy 120.087833 126.306409) (xy 120.071963 126.178249) (xy 120.048234 126.051308) (xy 120.016735 125.926069)
			(xy 119.977586 125.803006) (xy 119.930935 125.682587) (xy 119.87696 125.565268) (xy 119.815865 125.451494)
			(xy 119.747882 125.341697) (xy 119.673268 125.236294) (xy 119.592307 125.135684) (xy 119.505307 125.040249)
			(xy 119.412596 124.95035) (xy 119.314526 124.866329) (xy 119.211471 124.788505) (xy 119.10382 124.717173)
			(xy 118.991981 124.652603) (xy 118.87638 124.595041) (xy 118.757455 124.544704) (xy 118.635656 124.501784)
			(xy 118.511446 124.466443) (xy 118.385297 124.438816) (xy 118.257685 124.419007) (xy 118.129096 124.407091)
			(xy 118.000018 124.403115) (xy 117.87094 124.407091) (xy 117.742351 124.419007) (xy 117.614739 124.438816)
			(xy 117.48859 124.466443) (xy 117.36438 124.501784) (xy 117.242581 124.544704) (xy 117.123656 124.595041)
			(xy 117.008055 124.652603) (xy 116.896216 124.717173) (xy 116.788565 124.788505) (xy 116.68551 124.866329)
			(xy 116.58744 124.95035) (xy 116.494729 125.040249) (xy 116.407729 125.135684) (xy 116.326768 125.236294)
			(xy 116.252154 125.341697) (xy 116.184171 125.451494) (xy 116.123076 125.565268) (xy 116.069101 125.682587)
			(xy 116.02245 125.803006) (xy 115.983301 125.926069) (xy 115.951802 126.051308) (xy 115.928073 126.178249)
			(xy 115.912203 126.306409) (xy 115.904253 126.435304) (xy 92.50807 126.435304) (xy 92.50807 122.226375)
			(xy 99.070401 122.226375) (xy 99.070401 122.312125) (xy 99.078313 122.397508) (xy 99.094069 122.481798)
			(xy 99.117536 122.564274) (xy 99.148512 122.644233) (xy 99.186734 122.720993) (xy 99.231875 122.793899)
			(xy 99.283551 122.862328) (xy 99.34132 122.925698) (xy 99.40469 122.983467) (xy 99.473119 123.035143)
			(xy 99.546025 123.080284) (xy 99.622785 123.118506) (xy 99.702744 123.149482) (xy 99.78522 123.172949)
			(xy 99.86951 123.188705) (xy 99.954893 123.196617) (xy 100.040643 123.196617) (xy 100.126026 123.188705)
			(xy 100.210316 123.172949) (xy 100.292792 123.149482) (xy 100.372751 123.118506) (xy 100.449511 123.080284)
			(xy 100.522417 123.035143) (xy 100.590846 122.983467) (xy 100.654216 122.925698) (xy 100.711985 122.862328)
			(xy 100.763661 122.793899) (xy 100.808802 122.720993) (xy 100.847024 122.644233) (xy 100.878 122.564274)
			(xy 100.901467 122.481798) (xy 100.917223 122.397508) (xy 100.925135 122.312125) (xy 100.92563 122.26925)
			(xy 100.925135 122.226375) (xy 101.610401 122.226375) (xy 101.610401 122.312125) (xy 101.618313 122.397508)
			(xy 101.634069 122.481798) (xy 101.657536 122.564274) (xy 101.688512 122.644233) (xy 101.726734 122.720993)
			(xy 101.771875 122.793899) (xy 101.823551 122.862328) (xy 101.88132 122.925698) (xy 101.94469 122.983467)
			(xy 102.013119 123.035143) (xy 102.086025 123.080284) (xy 102.162785 123.118506) (xy 102.242744 123.149482)
			(xy 102.32522 123.172949) (xy 102.40951 123.188705) (xy 102.494893 123.196617) (xy 102.580643 123.196617)
			(xy 102.666026 123.188705) (xy 102.750316 123.172949) (xy 102.832792 123.149482) (xy 102.912751 123.118506)
			(xy 102.989511 123.080284) (xy 103.062417 123.035143) (xy 103.130846 122.983467) (xy 103.194216 122.925698)
			(xy 103.251985 122.862328) (xy 103.303661 122.793899) (xy 103.348802 122.720993) (xy 103.387024 122.644233)
			(xy 103.418 122.564274) (xy 103.441467 122.481798) (xy 103.457223 122.397508) (xy 103.465135 122.312125)
			(xy 103.46563 122.26925) (xy 103.465135 122.226375) (xy 103.457223 122.140992) (xy 103.441467 122.056702)
			(xy 103.418 121.974226) (xy 103.387024 121.894267) (xy 103.348802 121.817507) (xy 103.303661 121.744601)
			(xy 103.251985 121.676172) (xy 103.194216 121.612802) (xy 103.130846 121.555033) (xy 103.062417 121.503357)
			(xy 102.989511 121.458216) (xy 102.912751 121.419994) (xy 102.832792 121.389018) (xy 102.750316 121.365551)
			(xy 102.666026 121.349795) (xy 102.580643 121.341883) (xy 102.494893 121.341883) (xy 102.40951 121.349795)
			(xy 102.32522 121.365551) (xy 102.242744 121.389018) (xy 102.162785 121.419994) (xy 102.086025 121.458216)
			(xy 102.013119 121.503357) (xy 101.94469 121.555033) (xy 101.88132 121.612802) (xy 101.823551 121.676172)
			(xy 101.771875 121.744601) (xy 101.726734 121.817507) (xy 101.688512 121.894267) (xy 101.657536 121.974226)
			(xy 101.634069 122.056702) (xy 101.618313 122.140992) (xy 101.610401 122.226375) (xy 100.925135 122.226375)
			(xy 100.917223 122.140992) (xy 100.901467 122.056702) (xy 100.878 121.974226) (xy 100.847024 121.894267)
			(xy 100.808802 121.817507) (xy 100.763661 121.744601) (xy 100.711985 121.676172) (xy 100.654216 121.612802)
			(xy 100.590846 121.555033) (xy 100.522417 121.503357) (xy 100.449511 121.458216) (xy 100.372751 121.419994)
			(xy 100.292792 121.389018) (xy 100.210316 121.365551) (xy 100.126026 121.349795) (xy 100.040643 121.341883)
			(xy 99.954893 121.341883) (xy 99.86951 121.349795) (xy 99.78522 121.365551) (xy 99.702744 121.389018)
			(xy 99.622785 121.419994) (xy 99.546025 121.458216) (xy 99.473119 121.503357) (xy 99.40469 121.555033)
			(xy 99.34132 121.612802) (xy 99.283551 121.676172) (xy 99.231875 121.744601) (xy 99.186734 121.817507)
			(xy 99.148512 121.894267) (xy 99.117536 121.974226) (xy 99.094069 122.056702) (xy 99.078313 122.140992)
			(xy 99.070401 122.226375) (xy 92.50807 122.226375) (xy 92.50807 117.881334) (xy 100.454746 117.881334)
			(xy 100.454746 117.935866) (xy 100.462507 117.989844) (xy 100.47787 118.042168) (xy 100.500522 118.091773)
			(xy 100.530003 118.13765) (xy 100.565713 118.178864) (xy 100.606924 118.214578) (xy 100.652799 118.244063)
			(xy 100.702402 118.266719) (xy 100.754725 118.282087) (xy 100.808702 118.289851) (xy 100.835968 118.29034)
			(xy 101.699568 118.29034) (xy 101.726842 118.289923) (xy 101.780835 118.282164) (xy 101.833175 118.266799)
			(xy 101.882795 118.244142) (xy 101.928685 118.214654) (xy 101.969912 118.178934) (xy 102.005635 118.137711)
			(xy 102.035127 118.091823) (xy 102.057788 118.042205) (xy 102.073157 117.989867) (xy 102.08092 117.935874)
			(xy 102.08092 117.881326) (xy 102.073157 117.827333) (xy 102.057788 117.774995) (xy 102.035127 117.725377)
			(xy 102.005635 117.679489) (xy 101.969912 117.638266) (xy 101.928685 117.602546) (xy 101.882795 117.573058)
			(xy 101.833175 117.550401) (xy 101.780836 117.535036) (xy 101.726842 117.527277) (xy 101.699568 117.526816)
			(xy 100.835968 117.526816) (xy 100.808702 117.527349) (xy 100.754725 117.535113) (xy 100.702402 117.550481)
			(xy 100.652799 117.573137) (xy 100.606924 117.602622) (xy 100.565713 117.638336) (xy 100.530003 117.67955)
			(xy 100.500522 117.725427) (xy 100.47787 117.775032) (xy 100.462507 117.827356) (xy 100.454746 117.881334)
			(xy 92.50807 117.881334) (xy 92.50807 115.606627) (xy 93.714049 115.606627) (xy 93.714049 115.692377)
			(xy 93.721961 115.77776) (xy 93.737717 115.86205) (xy 93.761184 115.944526) (xy 93.79216 116.024485)
			(xy 93.830382 116.101245) (xy 93.875523 116.174151) (xy 93.927199 116.24258) (xy 93.984968 116.30595)
			(xy 94.048338 116.363719) (xy 94.116767 116.415395) (xy 94.189673 116.460536) (xy 94.266433 116.498758)
			(xy 94.346392 116.529734) (xy 94.428868 116.553201) (xy 94.513158 116.568957) (xy 94.598541 116.576869)
			(xy 94.684291 116.576869) (xy 94.769674 116.568957) (xy 94.853964 116.553201) (xy 94.93644 116.529734)
			(xy 95.016399 116.498758) (xy 95.093159 116.460536) (xy 95.166065 116.415395) (xy 95.234494 116.363719)
			(xy 95.297864 116.30595) (xy 95.355633 116.24258) (xy 95.407309 116.174151) (xy 95.45245 116.101245)
			(xy 95.490672 116.024485) (xy 95.521648 115.944526) (xy 95.545115 115.86205) (xy 95.560871 115.77776)
			(xy 95.568783 115.692377) (xy 95.569278 115.649502) (xy 95.568783 115.606627) (xy 96.254049 115.606627)
			(xy 96.254049 115.692377) (xy 96.261961 115.77776) (xy 96.277717 115.86205) (xy 96.301184 115.944526)
			(xy 96.33216 116.024485) (xy 96.370382 116.101245) (xy 96.415523 116.174151) (xy 96.467199 116.24258)
			(xy 96.524968 116.30595) (xy 96.588338 116.363719) (xy 96.656767 116.415395) (xy 96.729673 116.460536)
			(xy 96.806433 116.498758) (xy 96.886392 116.529734) (xy 96.968868 116.553201) (xy 97.053158 116.568957)
			(xy 97.138541 116.576869) (xy 97.224291 116.576869) (xy 97.309674 116.568957) (xy 97.393964 116.553201)
			(xy 97.47644 116.529734) (xy 97.556399 116.498758) (xy 97.633159 116.460536) (xy 97.706065 116.415395)
			(xy 97.774494 116.363719) (xy 97.837864 116.30595) (xy 97.895633 116.24258) (xy 97.947309 116.174151)
			(xy 97.99245 116.101245) (xy 98.030672 116.024485) (xy 98.061648 115.944526) (xy 98.081039 115.876375)
			(xy 99.070401 115.876375) (xy 99.070401 115.962125) (xy 99.078313 116.047508) (xy 99.094069 116.131798)
			(xy 99.117536 116.214274) (xy 99.148512 116.294233) (xy 99.186734 116.370993) (xy 99.231875 116.443899)
			(xy 99.283551 116.512328) (xy 99.34132 116.575698) (xy 99.40469 116.633467) (xy 99.473119 116.685143)
			(xy 99.546025 116.730284) (xy 99.622785 116.768506) (xy 99.702744 116.799482) (xy 99.78522 116.822949)
			(xy 99.86951 116.838705) (xy 99.954893 116.846617) (xy 100.040643 116.846617) (xy 100.126026 116.838705)
			(xy 100.210316 116.822949) (xy 100.292792 116.799482) (xy 100.372751 116.768506) (xy 100.449511 116.730284)
			(xy 100.522417 116.685143) (xy 100.590846 116.633467) (xy 100.654216 116.575698) (xy 100.711985 116.512328)
			(xy 100.763661 116.443899) (xy 100.808802 116.370993) (xy 100.847024 116.294233) (xy 100.878 116.214274)
			(xy 100.901467 116.131798) (xy 100.917223 116.047508) (xy 100.925135 115.962125) (xy 100.92563 115.91925)
			(xy 100.925135 115.876375) (xy 101.610401 115.876375) (xy 101.610401 115.962125) (xy 101.618313 116.047508)
			(xy 101.634069 116.131798) (xy 101.657536 116.214274) (xy 101.688512 116.294233) (xy 101.726734 116.370993)
			(xy 101.771875 116.443899) (xy 101.823551 116.512328) (xy 101.88132 116.575698) (xy 101.94469 116.633467)
			(xy 102.013119 116.685143) (xy 102.086025 116.730284) (xy 102.162785 116.768506) (xy 102.242744 116.799482)
			(xy 102.32522 116.822949) (xy 102.40951 116.838705) (xy 102.494893 116.846617) (xy 102.580643 116.846617)
			(xy 102.666026 116.838705) (xy 102.750316 116.822949) (xy 102.832792 116.799482) (xy 102.912751 116.768506)
			(xy 102.989511 116.730284) (xy 103.062417 116.685143) (xy 103.130846 116.633467) (xy 103.194216 116.575698)
			(xy 103.251985 116.512328) (xy 103.303661 116.443899) (xy 103.348802 116.370993) (xy 103.387024 116.294233)
			(xy 103.418 116.214274) (xy 103.441467 116.131798) (xy 103.457223 116.047508) (xy 103.465135 115.962125)
			(xy 103.46563 115.91925) (xy 103.465135 115.876375) (xy 103.457223 115.790992) (xy 103.441467 115.706702)
			(xy 103.418 115.624226) (xy 103.387024 115.544267) (xy 103.348802 115.467507) (xy 103.303661 115.394601)
			(xy 103.251985 115.326172) (xy 103.194216 115.262802) (xy 103.130846 115.205033) (xy 103.062417 115.153357)
			(xy 102.989511 115.108216) (xy 102.912751 115.069994) (xy 102.832792 115.039018) (xy 102.750316 115.015551)
			(xy 102.666026 114.999795) (xy 102.580643 114.991883) (xy 102.494893 114.991883) (xy 102.40951 114.999795)
			(xy 102.32522 115.015551) (xy 102.242744 115.039018) (xy 102.162785 115.069994) (xy 102.086025 115.108216)
			(xy 102.013119 115.153357) (xy 101.94469 115.205033) (xy 101.88132 115.262802) (xy 101.823551 115.326172)
			(xy 101.771875 115.394601) (xy 101.726734 115.467507) (xy 101.688512 115.544267) (xy 101.657536 115.624226)
			(xy 101.634069 115.706702) (xy 101.618313 115.790992) (xy 101.610401 115.876375) (xy 100.925135 115.876375)
			(xy 100.917223 115.790992) (xy 100.901467 115.706702) (xy 100.878 115.624226) (xy 100.847024 115.544267)
			(xy 100.808802 115.467507) (xy 100.763661 115.394601) (xy 100.711985 115.326172) (xy 100.654216 115.262802)
			(xy 100.590846 115.205033) (xy 100.522417 115.153357) (xy 100.449511 115.108216) (xy 100.372751 115.069994)
			(xy 100.292792 115.039018) (xy 100.210316 115.015551) (xy 100.126026 114.999795) (xy 100.040643 114.991883)
			(xy 99.954893 114.991883) (xy 99.86951 114.999795) (xy 99.78522 115.015551) (xy 99.702744 115.039018)
			(xy 99.622785 115.069994) (xy 99.546025 115.108216) (xy 99.473119 115.153357) (xy 99.40469 115.205033)
			(xy 99.34132 115.262802) (xy 99.283551 115.326172) (xy 99.231875 115.394601) (xy 99.186734 115.467507)
			(xy 99.148512 115.544267) (xy 99.117536 115.624226) (xy 99.094069 115.706702) (xy 99.078313 115.790992)
			(xy 99.070401 115.876375) (xy 98.081039 115.876375) (xy 98.085115 115.86205) (xy 98.100871 115.77776)
			(xy 98.108783 115.692377) (xy 98.109278 115.649502) (xy 98.108783 115.606627) (xy 98.100871 115.521244)
			(xy 98.085115 115.436954) (xy 98.061648 115.354478) (xy 98.030672 115.274519) (xy 97.99245 115.197759)
			(xy 97.947309 115.124853) (xy 97.895633 115.056424) (xy 97.837864 114.993054) (xy 97.774494 114.935285)
			(xy 97.706065 114.883609) (xy 97.633159 114.838468) (xy 97.556399 114.800246) (xy 97.47644 114.76927)
			(xy 97.393964 114.745803) (xy 97.309674 114.730047) (xy 97.224291 114.722135) (xy 97.138541 114.722135)
			(xy 97.053158 114.730047) (xy 96.968868 114.745803) (xy 96.886392 114.76927) (xy 96.806433 114.800246)
			(xy 96.729673 114.838468) (xy 96.656767 114.883609) (xy 96.588338 114.935285) (xy 96.524968 114.993054)
			(xy 96.467199 115.056424) (xy 96.415523 115.124853) (xy 96.370382 115.197759) (xy 96.33216 115.274519)
			(xy 96.301184 115.354478) (xy 96.277717 115.436954) (xy 96.261961 115.521244) (xy 96.254049 115.606627)
			(xy 95.568783 115.606627) (xy 95.560871 115.521244) (xy 95.545115 115.436954) (xy 95.521648 115.354478)
			(xy 95.490672 115.274519) (xy 95.45245 115.197759) (xy 95.407309 115.124853) (xy 95.355633 115.056424)
			(xy 95.297864 114.993054) (xy 95.234494 114.935285) (xy 95.166065 114.883609) (xy 95.093159 114.838468)
			(xy 95.016399 114.800246) (xy 94.93644 114.76927) (xy 94.853964 114.745803) (xy 94.769674 114.730047)
			(xy 94.684291 114.722135) (xy 94.598541 114.722135) (xy 94.513158 114.730047) (xy 94.428868 114.745803)
			(xy 94.346392 114.76927) (xy 94.266433 114.800246) (xy 94.189673 114.838468) (xy 94.116767 114.883609)
			(xy 94.048338 114.935285) (xy 93.984968 114.993054) (xy 93.927199 115.056424) (xy 93.875523 115.124853)
			(xy 93.830382 115.197759) (xy 93.79216 115.274519) (xy 93.761184 115.354478) (xy 93.737717 115.436954)
			(xy 93.721961 115.521244) (xy 93.714049 115.606627) (xy 92.50807 115.606627) (xy 92.50807 111.261526)
			(xy 95.098272 111.261526) (xy 95.098272 111.316074) (xy 95.106035 111.370066) (xy 95.121403 111.422404)
			(xy 95.144064 111.472023) (xy 95.173555 111.517911) (xy 95.209277 111.559134) (xy 95.250502 111.594855)
			(xy 95.296392 111.624344) (xy 95.346011 111.647003) (xy 95.398349 111.662369) (xy 95.452342 111.67013)
			(xy 95.479616 111.670592) (xy 96.343216 111.670592) (xy 96.370482 111.670045) (xy 96.42446 111.662282)
			(xy 96.476784 111.646916) (xy 96.526388 111.624261) (xy 96.572263 111.594777) (xy 96.613476 111.559064)
			(xy 96.649186 111.51785) (xy 96.678668 111.471974) (xy 96.701322 111.422369) (xy 96.716685 111.370044)
			(xy 96.724446 111.316067) (xy 96.724446 111.261534) (xy 96.716685 111.207556) (xy 96.701322 111.155231)
			(xy 96.678668 111.105626) (xy 96.649186 111.05975) (xy 96.613476 111.018536) (xy 96.572263 110.982823)
			(xy 96.526388 110.953339) (xy 96.476784 110.930684) (xy 96.42446 110.915318) (xy 96.370482 110.907555)
			(xy 96.343216 110.907068) (xy 95.479616 110.907068) (xy 95.452342 110.90747) (xy 95.398349 110.915231)
			(xy 95.346011 110.930597) (xy 95.296392 110.953256) (xy 95.250502 110.982745) (xy 95.209277 111.018466)
			(xy 95.173555 111.059689) (xy 95.144064 111.105577) (xy 95.121403 111.155196) (xy 95.106035 111.207534)
			(xy 95.098272 111.261526) (xy 92.50807 111.261526) (xy 92.50807 109.256627) (xy 93.714049 109.256627)
			(xy 93.714049 109.342377) (xy 93.721961 109.42776) (xy 93.737717 109.51205) (xy 93.761184 109.594526)
			(xy 93.79216 109.674485) (xy 93.830382 109.751245) (xy 93.875523 109.824151) (xy 93.927199 109.89258)
			(xy 93.984968 109.95595) (xy 94.048338 110.013719) (xy 94.116767 110.065395) (xy 94.189673 110.110536)
			(xy 94.266433 110.148758) (xy 94.346392 110.179734) (xy 94.428868 110.203201) (xy 94.513158 110.218957)
			(xy 94.598541 110.226869) (xy 94.684291 110.226869) (xy 94.769674 110.218957) (xy 94.853964 110.203201)
			(xy 94.93644 110.179734) (xy 95.016399 110.148758) (xy 95.093159 110.110536) (xy 95.166065 110.065395)
			(xy 95.234494 110.013719) (xy 95.297864 109.95595) (xy 95.355633 109.89258) (xy 95.407309 109.824151)
			(xy 95.45245 109.751245) (xy 95.490672 109.674485) (xy 95.521648 109.594526) (xy 95.545115 109.51205)
			(xy 95.560871 109.42776) (xy 95.568783 109.342377) (xy 95.569278 109.299502) (xy 95.568783 109.256627)
			(xy 96.254049 109.256627) (xy 96.254049 109.342377) (xy 96.261961 109.42776) (xy 96.277717 109.51205)
			(xy 96.301184 109.594526) (xy 96.33216 109.674485) (xy 96.370382 109.751245) (xy 96.415523 109.824151)
			(xy 96.467199 109.89258) (xy 96.524968 109.95595) (xy 96.588338 110.013719) (xy 96.656767 110.065395)
			(xy 96.729673 110.110536) (xy 96.806433 110.148758) (xy 96.886392 110.179734) (xy 96.968868 110.203201)
			(xy 97.053158 110.218957) (xy 97.138541 110.226869) (xy 97.224291 110.226869) (xy 97.309674 110.218957)
			(xy 97.393964 110.203201) (xy 97.47644 110.179734) (xy 97.556399 110.148758) (xy 97.633159 110.110536)
			(xy 97.706065 110.065395) (xy 97.774494 110.013719) (xy 97.837864 109.95595) (xy 97.895633 109.89258)
			(xy 97.947309 109.824151) (xy 97.99245 109.751245) (xy 98.030672 109.674485) (xy 98.061648 109.594526)
			(xy 98.085115 109.51205) (xy 98.100871 109.42776) (xy 98.108783 109.342377) (xy 98.109278 109.299502)
			(xy 98.108783 109.256627) (xy 98.100871 109.171244) (xy 98.085115 109.086954) (xy 98.061648 109.004478)
			(xy 98.030672 108.924519) (xy 97.99245 108.847759) (xy 97.947309 108.774853) (xy 97.895633 108.706424)
			(xy 97.837864 108.643054) (xy 97.774494 108.585285) (xy 97.706065 108.533609) (xy 97.633159 108.488468)
			(xy 97.556399 108.450246) (xy 97.47644 108.41927) (xy 97.393964 108.395803) (xy 97.309674 108.380047)
			(xy 97.224291 108.372135) (xy 97.138541 108.372135) (xy 97.053158 108.380047) (xy 96.968868 108.395803)
			(xy 96.886392 108.41927) (xy 96.806433 108.450246) (xy 96.729673 108.488468) (xy 96.656767 108.533609)
			(xy 96.588338 108.585285) (xy 96.524968 108.643054) (xy 96.467199 108.706424) (xy 96.415523 108.774853)
			(xy 96.370382 108.847759) (xy 96.33216 108.924519) (xy 96.301184 109.004478) (xy 96.277717 109.086954)
			(xy 96.261961 109.171244) (xy 96.254049 109.256627) (xy 95.568783 109.256627) (xy 95.560871 109.171244)
			(xy 95.545115 109.086954) (xy 95.521648 109.004478) (xy 95.490672 108.924519) (xy 95.45245 108.847759)
			(xy 95.407309 108.774853) (xy 95.355633 108.706424) (xy 95.297864 108.643054) (xy 95.234494 108.585285)
			(xy 95.166065 108.533609) (xy 95.093159 108.488468) (xy 95.016399 108.450246) (xy 94.93644 108.41927)
			(xy 94.853964 108.395803) (xy 94.769674 108.380047) (xy 94.684291 108.372135) (xy 94.598541 108.372135)
			(xy 94.513158 108.380047) (xy 94.428868 108.395803) (xy 94.346392 108.41927) (xy 94.266433 108.450246)
			(xy 94.189673 108.488468) (xy 94.116767 108.533609) (xy 94.048338 108.585285) (xy 93.984968 108.643054)
			(xy 93.927199 108.706424) (xy 93.875523 108.774853) (xy 93.830382 108.847759) (xy 93.79216 108.924519)
			(xy 93.761184 109.004478) (xy 93.737717 109.086954) (xy 93.721961 109.171244) (xy 93.714049 109.256627)
			(xy 92.50807 109.256627) (xy 92.50807 56.800039) (xy 93.729289 56.800039) (xy 93.729289 56.885789)
			(xy 93.737201 56.971172) (xy 93.752957 57.055462) (xy 93.776424 57.137938) (xy 93.8074 57.217897)
			(xy 93.845622 57.294657) (xy 93.890763 57.367563) (xy 93.942439 57.435992) (xy 94.000208 57.499362)
			(xy 94.063578 57.557131) (xy 94.132007 57.608807) (xy 94.204913 57.653948) (xy 94.281673 57.69217)
			(xy 94.361632 57.723146) (xy 94.444108 57.746613) (xy 94.528398 57.762369) (xy 94.613781 57.770281)
			(xy 94.699531 57.770281) (xy 94.784914 57.762369) (xy 94.869204 57.746613) (xy 94.95168 57.723146)
			(xy 95.031639 57.69217) (xy 95.108399 57.653948) (xy 95.181305 57.608807) (xy 95.249734 57.557131)
			(xy 95.313104 57.499362) (xy 95.370873 57.435992) (xy 95.422549 57.367563) (xy 95.46769 57.294657)
			(xy 95.505912 57.217897) (xy 95.536888 57.137938) (xy 95.560355 57.055462) (xy 95.576111 56.971172)
			(xy 95.584023 56.885789) (xy 95.584518 56.842914) (xy 95.584023 56.800039) (xy 96.269289 56.800039)
			(xy 96.269289 56.885789) (xy 96.277201 56.971172) (xy 96.292957 57.055462) (xy 96.316424 57.137938)
			(xy 96.3474 57.217897) (xy 96.385622 57.294657) (xy 96.430763 57.367563) (xy 96.482439 57.435992)
			(xy 96.540208 57.499362) (xy 96.603578 57.557131) (xy 96.672007 57.608807) (xy 96.744913 57.653948)
			(xy 96.821673 57.69217) (xy 96.901632 57.723146) (xy 96.984108 57.746613) (xy 97.068398 57.762369)
			(xy 97.153781 57.770281) (xy 97.239531 57.770281) (xy 97.324914 57.762369) (xy 97.409204 57.746613)
			(xy 97.49168 57.723146) (xy 97.571639 57.69217) (xy 97.648399 57.653948) (xy 97.721305 57.608807)
			(xy 97.789734 57.557131) (xy 97.853104 57.499362) (xy 97.910873 57.435992) (xy 97.962549 57.367563)
			(xy 98.00769 57.294657) (xy 98.045912 57.217897) (xy 98.076888 57.137938) (xy 98.100355 57.055462)
			(xy 98.116111 56.971172) (xy 98.124023 56.885789) (xy 98.124518 56.842914) (xy 98.124023 56.800039)
			(xy 98.116111 56.714656) (xy 98.100355 56.630366) (xy 98.076888 56.54789) (xy 98.045912 56.467931)
			(xy 98.00769 56.391171) (xy 97.962549 56.318265) (xy 97.910873 56.249836) (xy 97.853104 56.186466)
			(xy 97.789734 56.128697) (xy 97.721305 56.077021) (xy 97.648399 56.03188) (xy 97.571639 55.993658)
			(xy 97.49168 55.962682) (xy 97.409204 55.939215) (xy 97.324914 55.923459) (xy 97.239531 55.915547)
			(xy 97.153781 55.915547) (xy 97.068398 55.923459) (xy 96.984108 55.939215) (xy 96.901632 55.962682)
			(xy 96.821673 55.993658) (xy 96.744913 56.03188) (xy 96.672007 56.077021) (xy 96.603578 56.128697)
			(xy 96.540208 56.186466) (xy 96.482439 56.249836) (xy 96.430763 56.318265) (xy 96.385622 56.391171)
			(xy 96.3474 56.467931) (xy 96.316424 56.54789) (xy 96.292957 56.630366) (xy 96.277201 56.714656)
			(xy 96.269289 56.800039) (xy 95.584023 56.800039) (xy 95.576111 56.714656) (xy 95.560355 56.630366)
			(xy 95.536888 56.54789) (xy 95.505912 56.467931) (xy 95.46769 56.391171) (xy 95.422549 56.318265)
			(xy 95.370873 56.249836) (xy 95.313104 56.186466) (xy 95.249734 56.128697) (xy 95.181305 56.077021)
			(xy 95.108399 56.03188) (xy 95.031639 55.993658) (xy 94.95168 55.962682) (xy 94.869204 55.939215)
			(xy 94.784914 55.923459) (xy 94.699531 55.915547) (xy 94.613781 55.915547) (xy 94.528398 55.923459)
			(xy 94.444108 55.939215) (xy 94.361632 55.962682) (xy 94.281673 55.993658) (xy 94.204913 56.03188)
			(xy 94.132007 56.077021) (xy 94.063578 56.128697) (xy 94.000208 56.186466) (xy 93.942439 56.249836)
			(xy 93.890763 56.318265) (xy 93.845622 56.391171) (xy 93.8074 56.467931) (xy 93.776424 56.54789)
			(xy 93.752957 56.630366) (xy 93.737201 56.714656) (xy 93.729289 56.800039) (xy 92.50807 56.800039)
			(xy 92.50807 54.826334) (xy 95.113638 54.826334) (xy 95.113638 54.880866) (xy 95.121398 54.934844)
			(xy 95.136761 54.987168) (xy 95.159413 55.036774) (xy 95.188894 55.082651) (xy 95.224603 55.123866)
			(xy 95.265814 55.15958) (xy 95.311688 55.189066) (xy 95.36129 55.211724) (xy 95.413613 55.227092)
			(xy 95.46759 55.234859) (xy 95.494856 55.235348) (xy 96.358456 55.235348) (xy 96.38573 55.234915)
			(xy 96.439724 55.227158) (xy 96.492064 55.211795) (xy 96.541684 55.189139) (xy 96.587575 55.159652)
			(xy 96.628802 55.123933) (xy 96.664525 55.08271) (xy 96.694018 55.036823) (xy 96.71668 54.987205)
			(xy 96.732049 54.934867) (xy 96.739812 54.880874) (xy 96.739812 54.826326) (xy 96.732049 54.772333)
			(xy 96.71668 54.719995) (xy 96.694018 54.670377) (xy 96.664525 54.62449) (xy 96.628802 54.583267)
			(xy 96.587575 54.547548) (xy 96.541684 54.518061) (xy 96.492064 54.495405) (xy 96.439724 54.480042)
			(xy 96.38573 54.472285) (xy 96.358456 54.471824) (xy 95.494856 54.471824) (xy 95.46759 54.472341)
			(xy 95.413613 54.480108) (xy 95.36129 54.495476) (xy 95.311688 54.518134) (xy 95.265814 54.54762)
			(xy 95.224603 54.583334) (xy 95.188894 54.624549) (xy 95.159413 54.670426) (xy 95.136761 54.720032)
			(xy 95.121399 54.772356) (xy 95.113638 54.826334) (xy 92.50807 54.826334) (xy 92.50807 50.450039)
			(xy 93.729289 50.450039) (xy 93.729289 50.535789) (xy 93.737201 50.621172) (xy 93.752957 50.705462)
			(xy 93.776424 50.787938) (xy 93.8074 50.867897) (xy 93.845622 50.944657) (xy 93.890763 51.017563)
			(xy 93.942439 51.085992) (xy 94.000208 51.149362) (xy 94.063578 51.207131) (xy 94.132007 51.258807)
			(xy 94.204913 51.303948) (xy 94.281673 51.34217) (xy 94.361632 51.373146) (xy 94.444108 51.396613)
			(xy 94.528398 51.412369) (xy 94.613781 51.420281) (xy 94.699531 51.420281) (xy 94.784914 51.412369)
			(xy 94.869204 51.396613) (xy 94.95168 51.373146) (xy 95.031639 51.34217) (xy 95.108399 51.303948)
			(xy 95.181305 51.258807) (xy 95.249734 51.207131) (xy 95.313104 51.149362) (xy 95.370873 51.085992)
			(xy 95.422549 51.017563) (xy 95.46769 50.944657) (xy 95.505912 50.867897) (xy 95.536888 50.787938)
			(xy 95.560355 50.705462) (xy 95.576111 50.621172) (xy 95.584023 50.535789) (xy 95.584518 50.492914)
			(xy 95.584023 50.450039) (xy 96.269289 50.450039) (xy 96.269289 50.535789) (xy 96.277201 50.621172)
			(xy 96.292957 50.705462) (xy 96.316424 50.787938) (xy 96.3474 50.867897) (xy 96.385622 50.944657)
			(xy 96.430763 51.017563) (xy 96.482439 51.085992) (xy 96.540208 51.149362) (xy 96.603578 51.207131)
			(xy 96.672007 51.258807) (xy 96.744913 51.303948) (xy 96.821673 51.34217) (xy 96.901632 51.373146)
			(xy 96.984108 51.396613) (xy 97.068398 51.412369) (xy 97.153781 51.420281) (xy 97.239531 51.420281)
			(xy 97.324914 51.412369) (xy 97.409204 51.396613) (xy 97.49168 51.373146) (xy 97.571639 51.34217)
			(xy 97.648399 51.303948) (xy 97.721305 51.258807) (xy 97.789734 51.207131) (xy 97.853104 51.149362)
			(xy 97.910873 51.085992) (xy 97.962549 51.017563) (xy 98.00769 50.944657) (xy 98.045912 50.867897)
			(xy 98.076888 50.787938) (xy 98.100355 50.705462) (xy 98.116111 50.621172) (xy 98.124023 50.535789)
			(xy 98.124518 50.492914) (xy 98.124023 50.450039) (xy 98.116111 50.364656) (xy 98.100355 50.280366)
			(xy 98.076888 50.19789) (xy 98.045912 50.117931) (xy 98.00769 50.041171) (xy 97.962549 49.968265)
			(xy 97.910873 49.899836) (xy 97.853104 49.836466) (xy 97.789734 49.778697) (xy 97.721305 49.727021)
			(xy 97.648399 49.68188) (xy 97.571639 49.643658) (xy 97.49168 49.612682) (xy 97.409204 49.589215)
			(xy 97.324914 49.573459) (xy 97.239531 49.565547) (xy 97.153781 49.565547) (xy 97.068398 49.573459)
			(xy 96.984108 49.589215) (xy 96.901632 49.612682) (xy 96.821673 49.643658) (xy 96.744913 49.68188)
			(xy 96.672007 49.727021) (xy 96.603578 49.778697) (xy 96.540208 49.836466) (xy 96.482439 49.899836)
			(xy 96.430763 49.968265) (xy 96.385622 50.041171) (xy 96.3474 50.117931) (xy 96.316424 50.19789)
			(xy 96.292957 50.280366) (xy 96.277201 50.364656) (xy 96.269289 50.450039) (xy 95.584023 50.450039)
			(xy 95.576111 50.364656) (xy 95.560355 50.280366) (xy 95.536888 50.19789) (xy 95.505912 50.117931)
			(xy 95.46769 50.041171) (xy 95.422549 49.968265) (xy 95.370873 49.899836) (xy 95.313104 49.836466)
			(xy 95.249734 49.778697) (xy 95.181305 49.727021) (xy 95.108399 49.68188) (xy 95.031639 49.643658)
			(xy 94.95168 49.612682) (xy 94.869204 49.589215) (xy 94.784914 49.573459) (xy 94.699531 49.565547)
			(xy 94.613781 49.565547) (xy 94.528398 49.573459) (xy 94.444108 49.589215) (xy 94.361632 49.612682)
			(xy 94.281673 49.643658) (xy 94.204913 49.68188) (xy 94.132007 49.727021) (xy 94.063578 49.778697)
			(xy 94.000208 49.836466) (xy 93.942439 49.899836) (xy 93.890763 49.968265) (xy 93.845622 50.041171)
			(xy 93.8074 50.117931) (xy 93.776424 50.19789) (xy 93.752957 50.280366) (xy 93.737201 50.364656)
			(xy 93.729289 50.450039) (xy 92.50807 50.450039) (xy 92.50807 44.925539) (xy 93.706937 44.925539)
			(xy 93.706937 45.011289) (xy 93.714849 45.096672) (xy 93.730605 45.180962) (xy 93.754072 45.263438)
			(xy 93.785048 45.343397) (xy 93.82327 45.420157) (xy 93.868411 45.493063) (xy 93.920087 45.561492)
			(xy 93.977856 45.624862) (xy 94.041226 45.682631) (xy 94.109655 45.734307) (xy 94.182561 45.779448)
			(xy 94.259321 45.81767) (xy 94.33928 45.848646) (xy 94.421756 45.872113) (xy 94.506046 45.887869)
			(xy 94.591429 45.895781) (xy 94.677179 45.895781) (xy 94.762562 45.887869) (xy 94.846852 45.872113)
			(xy 94.929328 45.848646) (xy 95.009287 45.81767) (xy 95.086047 45.779448) (xy 95.158953 45.734307)
			(xy 95.227382 45.682631) (xy 95.290752 45.624862) (xy 95.348521 45.561492) (xy 95.400197 45.493063)
			(xy 95.445338 45.420157) (xy 95.48356 45.343397) (xy 95.514536 45.263438) (xy 95.538003 45.180962)
			(xy 95.553759 45.096672) (xy 95.561671 45.011289) (xy 95.562166 44.968414) (xy 95.561671 44.925539)
			(xy 96.246937 44.925539) (xy 96.246937 45.011289) (xy 96.254849 45.096672) (xy 96.270605 45.180962)
			(xy 96.294072 45.263438) (xy 96.325048 45.343397) (xy 96.36327 45.420157) (xy 96.408411 45.493063)
			(xy 96.460087 45.561492) (xy 96.517856 45.624862) (xy 96.581226 45.682631) (xy 96.649655 45.734307)
			(xy 96.722561 45.779448) (xy 96.799321 45.81767) (xy 96.87928 45.848646) (xy 96.961756 45.872113)
			(xy 97.046046 45.887869) (xy 97.131429 45.895781) (xy 97.217179 45.895781) (xy 97.302562 45.887869)
			(xy 97.386852 45.872113) (xy 97.469328 45.848646) (xy 97.549287 45.81767) (xy 97.626047 45.779448)
			(xy 97.698953 45.734307) (xy 97.767382 45.682631) (xy 97.830752 45.624862) (xy 97.888521 45.561492)
			(xy 97.940197 45.493063) (xy 97.985338 45.420157) (xy 98.02356 45.343397) (xy 98.054536 45.263438)
			(xy 98.078003 45.180962) (xy 98.093759 45.096672) (xy 98.101671 45.011289) (xy 98.102166 44.968414)
			(xy 98.101671 44.925539) (xy 98.093759 44.840156) (xy 98.078003 44.755866) (xy 98.054536 44.67339)
			(xy 98.02356 44.593431) (xy 97.985338 44.516671) (xy 97.940197 44.443765) (xy 97.888521 44.375336)
			(xy 97.830752 44.311966) (xy 97.767382 44.254197) (xy 97.698953 44.202521) (xy 97.626047 44.15738)
			(xy 97.549287 44.119158) (xy 97.469328 44.088182) (xy 97.386852 44.064715) (xy 97.302562 44.048959)
			(xy 97.217179 44.041047) (xy 97.131429 44.041047) (xy 97.046046 44.048959) (xy 96.961756 44.064715)
			(xy 96.87928 44.088182) (xy 96.799321 44.119158) (xy 96.722561 44.15738) (xy 96.649655 44.202521)
			(xy 96.581226 44.254197) (xy 96.517856 44.311966) (xy 96.460087 44.375336) (xy 96.408411 44.443765)
			(xy 96.36327 44.516671) (xy 96.325048 44.593431) (xy 96.294072 44.67339) (xy 96.270605 44.755866)
			(xy 96.254849 44.840156) (xy 96.246937 44.925539) (xy 95.561671 44.925539) (xy 95.553759 44.840156)
			(xy 95.538003 44.755866) (xy 95.514536 44.67339) (xy 95.48356 44.593431) (xy 95.445338 44.516671)
			(xy 95.400197 44.443765) (xy 95.348521 44.375336) (xy 95.290752 44.311966) (xy 95.227382 44.254197)
			(xy 95.158953 44.202521) (xy 95.086047 44.15738) (xy 95.009287 44.119158) (xy 94.929328 44.088182)
			(xy 94.846852 44.064715) (xy 94.762562 44.048959) (xy 94.677179 44.041047) (xy 94.591429 44.041047)
			(xy 94.506046 44.048959) (xy 94.421756 44.064715) (xy 94.33928 44.088182) (xy 94.259321 44.119158)
			(xy 94.182561 44.15738) (xy 94.109655 44.202521) (xy 94.041226 44.254197) (xy 93.977856 44.311966)
			(xy 93.920087 44.375336) (xy 93.868411 44.443765) (xy 93.82327 44.516671) (xy 93.785048 44.593431)
			(xy 93.754072 44.67339) (xy 93.730605 44.755866) (xy 93.714849 44.840156) (xy 93.706937 44.925539)
			(xy 92.50807 44.925539) (xy 92.50807 40.607742) (xy 95.090996 40.607742) (xy 95.091524 40.636285)
			(xy 95.100004 40.692737) (xy 95.1168 40.747296) (xy 95.141536 40.798744) (xy 95.17366 40.845933)
			(xy 95.212456 40.88781) (xy 95.257057 40.923441) (xy 95.281496 40.938196) (xy 95.281496 41.736772)
			(xy 96.532192 41.736772) (xy 96.532192 40.935148) (xy 96.556039 40.920245) (xy 96.5995 40.884561)
			(xy 96.637256 40.842889) (xy 96.668492 40.796129) (xy 96.692532 40.745294) (xy 96.708855 40.691482)
			(xy 96.717109 40.635858) (xy 96.717612 40.607742) (xy 96.717038 40.580487) (xy 96.70929 40.526532)
			(xy 96.693945 40.474227) (xy 96.671316 40.424638) (xy 96.641862 40.378771) (xy 96.606184 40.337561)
			(xy 96.565006 40.301845) (xy 96.519166 40.27235) (xy 96.469597 40.249676) (xy 96.417307 40.234284)
			(xy 96.363358 40.226487) (xy 96.336104 40.22598) (xy 95.472504 40.22598) (xy 95.44524 40.22646) (xy 95.391268 40.234222)
			(xy 95.338951 40.24959) (xy 95.289355 40.27225) (xy 95.24349 40.30174) (xy 95.202291 40.33746) (xy 95.166597 40.378681)
			(xy 95.137136 40.424564) (xy 95.114507 40.474174) (xy 95.099172 40.526501) (xy 95.091443 40.580478)
			(xy 95.090996 40.607742) (xy 92.50807 40.607742) (xy 92.50807 38.575539) (xy 93.706937 38.575539)
			(xy 93.706937 38.661289) (xy 93.714849 38.746672) (xy 93.730605 38.830962) (xy 93.754072 38.913438)
			(xy 93.785048 38.993397) (xy 93.82327 39.070157) (xy 93.868411 39.143063) (xy 93.920087 39.211492)
			(xy 93.977856 39.274862) (xy 94.041226 39.332631) (xy 94.109655 39.384307) (xy 94.182561 39.429448)
			(xy 94.259321 39.46767) (xy 94.33928 39.498646) (xy 94.421756 39.522113) (xy 94.506046 39.537869)
			(xy 94.591429 39.545781) (xy 94.677179 39.545781) (xy 94.762562 39.537869) (xy 94.846852 39.522113)
			(xy 94.929328 39.498646) (xy 95.009287 39.46767) (xy 95.086047 39.429448) (xy 95.158953 39.384307)
			(xy 95.227382 39.332631) (xy 95.290752 39.274862) (xy 95.348521 39.211492) (xy 95.400197 39.143063)
			(xy 95.445338 39.070157) (xy 95.48356 38.993397) (xy 95.514536 38.913438) (xy 95.538003 38.830962)
			(xy 95.553759 38.746672) (xy 95.561671 38.661289) (xy 95.562166 38.618414) (xy 95.561671 38.575539)
			(xy 96.246937 38.575539) (xy 96.246937 38.661289) (xy 96.254849 38.746672) (xy 96.270605 38.830962)
			(xy 96.294072 38.913438) (xy 96.325048 38.993397) (xy 96.36327 39.070157) (xy 96.408411 39.143063)
			(xy 96.460087 39.211492) (xy 96.517856 39.274862) (xy 96.581226 39.332631) (xy 96.649655 39.384307)
			(xy 96.722561 39.429448) (xy 96.799321 39.46767) (xy 96.87928 39.498646) (xy 96.961756 39.522113)
			(xy 97.046046 39.537869) (xy 97.131429 39.545781) (xy 97.217179 39.545781) (xy 97.302562 39.537869)
			(xy 97.386852 39.522113) (xy 97.469328 39.498646) (xy 97.549287 39.46767) (xy 97.626047 39.429448)
			(xy 97.698953 39.384307) (xy 97.767382 39.332631) (xy 97.830752 39.274862) (xy 97.888521 39.211492)
			(xy 97.940197 39.143063) (xy 97.985338 39.070157) (xy 98.02356 38.993397) (xy 98.054536 38.913438)
			(xy 98.078003 38.830962) (xy 98.093759 38.746672) (xy 98.101671 38.661289) (xy 98.102166 38.618414)
			(xy 98.101671 38.575539) (xy 98.093759 38.490156) (xy 98.078003 38.405866) (xy 98.054536 38.32339)
			(xy 98.02356 38.243431) (xy 97.985338 38.166671) (xy 97.940197 38.093765) (xy 97.888521 38.025336)
			(xy 97.830752 37.961966) (xy 97.767382 37.904197) (xy 97.698953 37.852521) (xy 97.626047 37.80738)
			(xy 97.549287 37.769158) (xy 97.469328 37.738182) (xy 97.386852 37.714715) (xy 97.302562 37.698959)
			(xy 97.217179 37.691047) (xy 97.131429 37.691047) (xy 97.046046 37.698959) (xy 96.961756 37.714715)
			(xy 96.87928 37.738182) (xy 96.799321 37.769158) (xy 96.722561 37.80738) (xy 96.649655 37.852521)
			(xy 96.581226 37.904197) (xy 96.517856 37.961966) (xy 96.460087 38.025336) (xy 96.408411 38.093765)
			(xy 96.36327 38.166671) (xy 96.325048 38.243431) (xy 96.294072 38.32339) (xy 96.270605 38.405866)
			(xy 96.254849 38.490156) (xy 96.246937 38.575539) (xy 95.561671 38.575539) (xy 95.553759 38.490156)
			(xy 95.538003 38.405866) (xy 95.514536 38.32339) (xy 95.48356 38.243431) (xy 95.445338 38.166671)
			(xy 95.400197 38.093765) (xy 95.348521 38.025336) (xy 95.290752 37.961966) (xy 95.227382 37.904197)
			(xy 95.158953 37.852521) (xy 95.086047 37.80738) (xy 95.009287 37.769158) (xy 94.929328 37.738182)
			(xy 94.846852 37.714715) (xy 94.762562 37.698959) (xy 94.677179 37.691047) (xy 94.591429 37.691047)
			(xy 94.506046 37.698959) (xy 94.421756 37.714715) (xy 94.33928 37.738182) (xy 94.259321 37.769158)
			(xy 94.182561 37.80738) (xy 94.109655 37.852521) (xy 94.041226 37.904197) (xy 93.977856 37.961966)
			(xy 93.920087 38.025336) (xy 93.868411 38.093765) (xy 93.82327 38.166671) (xy 93.785048 38.243431)
			(xy 93.754072 38.32339) (xy 93.730605 38.405866) (xy 93.714849 38.490156) (xy 93.706937 38.575539)
			(xy 92.50807 38.575539) (xy 92.50807 32.685787) (xy 99.092753 32.685787) (xy 99.092753 32.771537)
			(xy 99.100665 32.85692) (xy 99.116421 32.94121) (xy 99.139888 33.023686) (xy 99.170864 33.103645)
			(xy 99.209086 33.180405) (xy 99.254227 33.253311) (xy 99.305903 33.32174) (xy 99.363672 33.38511)
			(xy 99.427042 33.442879) (xy 99.495471 33.494555) (xy 99.568377 33.539696) (xy 99.645137 33.577918)
			(xy 99.725096 33.608894) (xy 99.807572 33.632361) (xy 99.891862 33.648117) (xy 99.977245 33.656029)
			(xy 100.062995 33.656029) (xy 100.148378 33.648117) (xy 100.232668 33.632361) (xy 100.315144 33.608894)
			(xy 100.395103 33.577918) (xy 100.471863 33.539696) (xy 100.544769 33.494555) (xy 100.613198 33.442879)
			(xy 100.676568 33.38511) (xy 100.734337 33.32174) (xy 100.786013 33.253311) (xy 100.831154 33.180405)
			(xy 100.869376 33.103645) (xy 100.900352 33.023686) (xy 100.923819 32.94121) (xy 100.939575 32.85692)
			(xy 100.947487 32.771537) (xy 100.947982 32.728662) (xy 100.947487 32.685787) (xy 101.632753 32.685787)
			(xy 101.632753 32.771537) (xy 101.640665 32.85692) (xy 101.656421 32.94121) (xy 101.679888 33.023686)
			(xy 101.710864 33.103645) (xy 101.749086 33.180405) (xy 101.794227 33.253311) (xy 101.845903 33.32174)
			(xy 101.903672 33.38511) (xy 101.967042 33.442879) (xy 102.035471 33.494555) (xy 102.108377 33.539696)
			(xy 102.185137 33.577918) (xy 102.265096 33.608894) (xy 102.347572 33.632361) (xy 102.431862 33.648117)
			(xy 102.517245 33.656029) (xy 102.602995 33.656029) (xy 102.688378 33.648117) (xy 102.772668 33.632361)
			(xy 102.855144 33.608894) (xy 102.935103 33.577918) (xy 103.011863 33.539696) (xy 103.084769 33.494555)
			(xy 103.153198 33.442879) (xy 103.216568 33.38511) (xy 103.274337 33.32174) (xy 103.326013 33.253311)
			(xy 103.371154 33.180405) (xy 103.409376 33.103645) (xy 103.440352 33.023686) (xy 103.463819 32.94121)
			(xy 103.479575 32.85692) (xy 103.487487 32.771537) (xy 103.487982 32.728662) (xy 103.487487 32.685787)
			(xy 103.479575 32.600404) (xy 103.463819 32.516114) (xy 103.440352 32.433638) (xy 103.409376 32.353679)
			(xy 103.371154 32.276919) (xy 103.326013 32.204013) (xy 103.274337 32.135584) (xy 103.216568 32.072214)
			(xy 103.153198 32.014445) (xy 103.084769 31.962769) (xy 103.011863 31.917628) (xy 102.935103 31.879406)
			(xy 102.855144 31.84843) (xy 102.772668 31.824963) (xy 102.688378 31.809207) (xy 102.602995 31.801295)
			(xy 102.517245 31.801295) (xy 102.431862 31.809207) (xy 102.347572 31.824963) (xy 102.265096 31.84843)
			(xy 102.185137 31.879406) (xy 102.108377 31.917628) (xy 102.035471 31.962769) (xy 101.967042 32.014445)
			(xy 101.903672 32.072214) (xy 101.845903 32.135584) (xy 101.794227 32.204013) (xy 101.749086 32.276919)
			(xy 101.710864 32.353679) (xy 101.679888 32.433638) (xy 101.656421 32.516114) (xy 101.640665 32.600404)
			(xy 101.632753 32.685787) (xy 100.947487 32.685787) (xy 100.939575 32.600404) (xy 100.923819 32.516114)
			(xy 100.900352 32.433638) (xy 100.869376 32.353679) (xy 100.831154 32.276919) (xy 100.786013 32.204013)
			(xy 100.734337 32.135584) (xy 100.676568 32.072214) (xy 100.613198 32.014445) (xy 100.544769 31.962769)
			(xy 100.471863 31.917628) (xy 100.395103 31.879406) (xy 100.315144 31.84843) (xy 100.232668 31.824963)
			(xy 100.148378 31.809207) (xy 100.062995 31.801295) (xy 99.977245 31.801295) (xy 99.891862 31.809207)
			(xy 99.807572 31.824963) (xy 99.725096 31.84843) (xy 99.645137 31.879406) (xy 99.568377 31.917628)
			(xy 99.495471 31.962769) (xy 99.427042 32.014445) (xy 99.363672 32.072214) (xy 99.305903 32.135584)
			(xy 99.254227 32.204013) (xy 99.209086 32.276919) (xy 99.170864 32.353679) (xy 99.139888 32.433638)
			(xy 99.116421 32.516114) (xy 99.100665 32.600404) (xy 99.092753 32.685787) (xy 92.50807 32.685787)
			(xy 92.50807 30.712026) (xy 100.476968 30.712026) (xy 100.476968 30.766574) (xy 100.484731 30.820568)
			(xy 100.5001 30.872907) (xy 100.522761 30.922526) (xy 100.552253 30.968414) (xy 100.587976 31.009639)
			(xy 100.629202 31.045359) (xy 100.675092 31.074849) (xy 100.724712 31.097507) (xy 100.777052 31.112873)
			(xy 100.831046 31.120634) (xy 100.85832 31.121096) (xy 101.72192 31.121096) (xy 101.749186 31.12054)
			(xy 101.803163 31.112777) (xy 101.855485 31.097411) (xy 101.905088 31.074756) (xy 101.950963 31.045272)
			(xy 101.992174 31.00956) (xy 102.027884 30.968347) (xy 102.057366 30.922471) (xy 102.080018 30.872866)
			(xy 102.095381 30.820543) (xy 102.103142 30.766566) (xy 102.103142 30.712034) (xy 102.095381 30.658057)
			(xy 102.080018 30.605734) (xy 102.057366 30.556129) (xy 102.027884 30.510253) (xy 101.992174 30.46904)
			(xy 101.950963 30.433328) (xy 101.905088 30.403844) (xy 101.855485 30.381189) (xy 101.803163 30.365823)
			(xy 101.749186 30.35806) (xy 101.72192 30.357572) (xy 100.85832 30.357572) (xy 100.831046 30.357966)
			(xy 100.777052 30.365727) (xy 100.724712 30.381093) (xy 100.675092 30.403751) (xy 100.629202 30.433241)
			(xy 100.587976 30.468961) (xy 100.552253 30.510186) (xy 100.522761 30.556074) (xy 100.5001 30.605693)
			(xy 100.484731 30.658032) (xy 100.476968 30.712026) (xy 92.50807 30.712026) (xy 92.50807 26.335787)
			(xy 99.092753 26.335787) (xy 99.092753 26.421537) (xy 99.100665 26.50692) (xy 99.116421 26.59121)
			(xy 99.139888 26.673686) (xy 99.170864 26.753645) (xy 99.209086 26.830405) (xy 99.254227 26.903311)
			(xy 99.305903 26.97174) (xy 99.363672 27.03511) (xy 99.427042 27.092879) (xy 99.495471 27.144555)
			(xy 99.568377 27.189696) (xy 99.645137 27.227918) (xy 99.725096 27.258894) (xy 99.807572 27.282361)
			(xy 99.891862 27.298117) (xy 99.977245 27.306029) (xy 100.062995 27.306029) (xy 100.148378 27.298117)
			(xy 100.232668 27.282361) (xy 100.315144 27.258894) (xy 100.395103 27.227918) (xy 100.471863 27.189696)
			(xy 100.544769 27.144555) (xy 100.613198 27.092879) (xy 100.676568 27.03511) (xy 100.734337 26.97174)
			(xy 100.786013 26.903311) (xy 100.831154 26.830405) (xy 100.869376 26.753645) (xy 100.900352 26.673686)
			(xy 100.923819 26.59121) (xy 100.939575 26.50692) (xy 100.947487 26.421537) (xy 100.947982 26.378662)
			(xy 100.947487 26.335787) (xy 101.632753 26.335787) (xy 101.632753 26.421537) (xy 101.640665 26.50692)
			(xy 101.656421 26.59121) (xy 101.679888 26.673686) (xy 101.710864 26.753645) (xy 101.749086 26.830405)
			(xy 101.794227 26.903311) (xy 101.845903 26.97174) (xy 101.903672 27.03511) (xy 101.967042 27.092879)
			(xy 102.035471 27.144555) (xy 102.108377 27.189696) (xy 102.185137 27.227918) (xy 102.265096 27.258894)
			(xy 102.347572 27.282361) (xy 102.431862 27.298117) (xy 102.517245 27.306029) (xy 102.602995 27.306029)
			(xy 102.688378 27.298117) (xy 102.772668 27.282361) (xy 102.855144 27.258894) (xy 102.935103 27.227918)
			(xy 103.011863 27.189696) (xy 103.084769 27.144555) (xy 103.153198 27.092879) (xy 103.216568 27.03511)
			(xy 103.274337 26.97174) (xy 103.326013 26.903311) (xy 103.371154 26.830405) (xy 103.409376 26.753645)
			(xy 103.440352 26.673686) (xy 103.463819 26.59121) (xy 103.479575 26.50692) (xy 103.487487 26.421537)
			(xy 103.487982 26.378662) (xy 103.487487 26.335787) (xy 103.479575 26.250404) (xy 103.463819 26.166114)
			(xy 103.440352 26.083638) (xy 103.409376 26.003679) (xy 103.371154 25.926919) (xy 103.326013 25.854013)
			(xy 103.274337 25.785584) (xy 103.216568 25.722214) (xy 103.153198 25.664445) (xy 103.084769 25.612769)
			(xy 103.011863 25.567628) (xy 102.935103 25.529406) (xy 102.855144 25.49843) (xy 102.772668 25.474963)
			(xy 102.688378 25.459207) (xy 102.602995 25.451295) (xy 102.517245 25.451295) (xy 102.431862 25.459207)
			(xy 102.347572 25.474963) (xy 102.265096 25.49843) (xy 102.185137 25.529406) (xy 102.108377 25.567628)
			(xy 102.035471 25.612769) (xy 101.967042 25.664445) (xy 101.903672 25.722214) (xy 101.845903 25.785584)
			(xy 101.794227 25.854013) (xy 101.749086 25.926919) (xy 101.710864 26.003679) (xy 101.679888 26.083638)
			(xy 101.656421 26.166114) (xy 101.640665 26.250404) (xy 101.632753 26.335787) (xy 100.947487 26.335787)
			(xy 100.939575 26.250404) (xy 100.923819 26.166114) (xy 100.900352 26.083638) (xy 100.869376 26.003679)
			(xy 100.831154 25.926919) (xy 100.786013 25.854013) (xy 100.734337 25.785584) (xy 100.676568 25.722214)
			(xy 100.613198 25.664445) (xy 100.544769 25.612769) (xy 100.471863 25.567628) (xy 100.395103 25.529406)
			(xy 100.315144 25.49843) (xy 100.232668 25.474963) (xy 100.148378 25.459207) (xy 100.062995 25.451295)
			(xy 99.977245 25.451295) (xy 99.891862 25.459207) (xy 99.807572 25.474963) (xy 99.725096 25.49843)
			(xy 99.645137 25.529406) (xy 99.568377 25.567628) (xy 99.495471 25.612769) (xy 99.427042 25.664445)
			(xy 99.363672 25.722214) (xy 99.305903 25.785584) (xy 99.254227 25.854013) (xy 99.209086 25.926919)
			(xy 99.170864 26.003679) (xy 99.139888 26.083638) (xy 99.116421 26.166114) (xy 99.100665 26.250404)
			(xy 99.092753 26.335787) (xy 92.50807 26.335787) (xy 92.50807 20.841513) (xy 99.085133 20.841513)
			(xy 99.085133 20.927263) (xy 99.093045 21.012646) (xy 99.108801 21.096936) (xy 99.132268 21.179412)
			(xy 99.163244 21.259371) (xy 99.201466 21.336131) (xy 99.246607 21.409037) (xy 99.298283 21.477466)
			(xy 99.356052 21.540836) (xy 99.419422 21.598605) (xy 99.487851 21.650281) (xy 99.560757 21.695422)
			(xy 99.637517 21.733644) (xy 99.717476 21.76462) (xy 99.799952 21.788087) (xy 99.884242 21.803843)
			(xy 99.969625 21.811755) (xy 100.055375 21.811755) (xy 100.140758 21.803843) (xy 100.225048 21.788087)
			(xy 100.307524 21.76462) (xy 100.387483 21.733644) (xy 100.464243 21.695422) (xy 100.537149 21.650281)
			(xy 100.605578 21.598605) (xy 100.668948 21.540836) (xy 100.726717 21.477466) (xy 100.778393 21.409037)
			(xy 100.823534 21.336131) (xy 100.861756 21.259371) (xy 100.892732 21.179412) (xy 100.916199 21.096936)
			(xy 100.931955 21.012646) (xy 100.939867 20.927263) (xy 100.940362 20.884388) (xy 100.939867 20.841513)
			(xy 101.625133 20.841513) (xy 101.625133 20.927263) (xy 101.633045 21.012646) (xy 101.648801 21.096936)
			(xy 101.672268 21.179412) (xy 101.703244 21.259371) (xy 101.741466 21.336131) (xy 101.786607 21.409037)
			(xy 101.838283 21.477466) (xy 101.896052 21.540836) (xy 101.959422 21.598605) (xy 102.027851 21.650281)
			(xy 102.100757 21.695422) (xy 102.177517 21.733644) (xy 102.257476 21.76462) (xy 102.339952 21.788087)
			(xy 102.424242 21.803843) (xy 102.509625 21.811755) (xy 102.595375 21.811755) (xy 102.680758 21.803843)
			(xy 102.765048 21.788087) (xy 102.847524 21.76462) (xy 102.927483 21.733644) (xy 103.004243 21.695422)
			(xy 103.077149 21.650281) (xy 103.145578 21.598605) (xy 103.208948 21.540836) (xy 103.266717 21.477466)
			(xy 103.318393 21.409037) (xy 103.363534 21.336131) (xy 103.401756 21.259371) (xy 103.432732 21.179412)
			(xy 103.456199 21.096936) (xy 103.471955 21.012646) (xy 103.479867 20.927263) (xy 103.480362 20.884388)
			(xy 103.479867 20.841513) (xy 104.165133 20.841513) (xy 104.165133 20.927263) (xy 104.173045 21.012646)
			(xy 104.188801 21.096936) (xy 104.212268 21.179412) (xy 104.243244 21.259371) (xy 104.281466 21.336131)
			(xy 104.326607 21.409037) (xy 104.378283 21.477466) (xy 104.436052 21.540836) (xy 104.499422 21.598605)
			(xy 104.567851 21.650281) (xy 104.640757 21.695422) (xy 104.717517 21.733644) (xy 104.797476 21.76462)
			(xy 104.879952 21.788087) (xy 104.964242 21.803843) (xy 105.049625 21.811755) (xy 105.135375 21.811755)
			(xy 105.220758 21.803843) (xy 105.305048 21.788087) (xy 105.387524 21.76462) (xy 105.467483 21.733644)
			(xy 105.544243 21.695422) (xy 105.617149 21.650281) (xy 105.685578 21.598605) (xy 105.748948 21.540836)
			(xy 105.806717 21.477466) (xy 105.858393 21.409037) (xy 105.903534 21.336131) (xy 105.941756 21.259371)
			(xy 105.972732 21.179412) (xy 105.996199 21.096936) (xy 106.011955 21.012646) (xy 106.019867 20.927263)
			(xy 106.020362 20.884388) (xy 106.019867 20.841513) (xy 106.011955 20.75613) (xy 105.996199 20.67184)
			(xy 105.972732 20.589364) (xy 105.941756 20.509405) (xy 105.903534 20.432645) (xy 105.858393 20.359739)
			(xy 105.806717 20.29131) (xy 105.748948 20.22794) (xy 105.685578 20.170171) (xy 105.617149 20.118495)
			(xy 105.544243 20.073354) (xy 105.467483 20.035132) (xy 105.387524 20.004156) (xy 105.305048 19.980689)
			(xy 105.220758 19.964933) (xy 105.135375 19.957021) (xy 105.049625 19.957021) (xy 104.964242 19.964933)
			(xy 104.879952 19.980689) (xy 104.797476 20.004156) (xy 104.717517 20.035132) (xy 104.640757 20.073354)
			(xy 104.567851 20.118495) (xy 104.499422 20.170171) (xy 104.436052 20.22794) (xy 104.378283 20.29131)
			(xy 104.326607 20.359739) (xy 104.281466 20.432645) (xy 104.243244 20.509405) (xy 104.212268 20.589364)
			(xy 104.188801 20.67184) (xy 104.173045 20.75613) (xy 104.165133 20.841513) (xy 103.479867 20.841513)
			(xy 103.471955 20.75613) (xy 103.456199 20.67184) (xy 103.432732 20.589364) (xy 103.401756 20.509405)
			(xy 103.363534 20.432645) (xy 103.318393 20.359739) (xy 103.266717 20.29131) (xy 103.208948 20.22794)
			(xy 103.145578 20.170171) (xy 103.077149 20.118495) (xy 103.004243 20.073354) (xy 102.927483 20.035132)
			(xy 102.847524 20.004156) (xy 102.765048 19.980689) (xy 102.680758 19.964933) (xy 102.595375 19.957021)
			(xy 102.509625 19.957021) (xy 102.424242 19.964933) (xy 102.339952 19.980689) (xy 102.257476 20.004156)
			(xy 102.177517 20.035132) (xy 102.100757 20.073354) (xy 102.027851 20.118495) (xy 101.959422 20.170171)
			(xy 101.896052 20.22794) (xy 101.838283 20.29131) (xy 101.786607 20.359739) (xy 101.741466 20.432645)
			(xy 101.703244 20.509405) (xy 101.672268 20.589364) (xy 101.648801 20.67184) (xy 101.633045 20.75613)
			(xy 101.625133 20.841513) (xy 100.939867 20.841513) (xy 100.931955 20.75613) (xy 100.916199 20.67184)
			(xy 100.892732 20.589364) (xy 100.861756 20.509405) (xy 100.823534 20.432645) (xy 100.778393 20.359739)
			(xy 100.726717 20.29131) (xy 100.668948 20.22794) (xy 100.605578 20.170171) (xy 100.537149 20.118495)
			(xy 100.464243 20.073354) (xy 100.387483 20.035132) (xy 100.307524 20.004156) (xy 100.225048 19.980689)
			(xy 100.140758 19.964933) (xy 100.055375 19.957021) (xy 99.969625 19.957021) (xy 99.884242 19.964933)
			(xy 99.799952 19.980689) (xy 99.717476 20.004156) (xy 99.637517 20.035132) (xy 99.560757 20.073354)
			(xy 99.487851 20.118495) (xy 99.419422 20.170171) (xy 99.356052 20.22794) (xy 99.298283 20.29131)
			(xy 99.246607 20.359739) (xy 99.201466 20.432645) (xy 99.163244 20.509405) (xy 99.132268 20.589364)
			(xy 99.108801 20.67184) (xy 99.093045 20.75613) (xy 99.085133 20.841513) (xy 92.50807 20.841513)
			(xy 92.50807 17.653) (xy 103.199692 17.653) (xy 104.450388 17.653) (xy 104.450388 16.887444) (xy 103.199692 16.887444)
			(xy 103.199692 17.653) (xy 92.50807 17.653) (xy 92.50807 14.491513) (xy 99.085133 14.491513) (xy 99.085133 14.577263)
			(xy 99.093045 14.662646) (xy 99.108801 14.746936) (xy 99.132268 14.829412) (xy 99.163244 14.909371)
			(xy 99.201466 14.986131) (xy 99.246607 15.059037) (xy 99.298283 15.127466) (xy 99.356052 15.190836)
			(xy 99.419422 15.248605) (xy 99.487851 15.300281) (xy 99.560757 15.345422) (xy 99.637517 15.383644)
			(xy 99.717476 15.41462) (xy 99.799952 15.438087) (xy 99.884242 15.453843) (xy 99.969625 15.461755)
			(xy 100.055375 15.461755) (xy 100.140758 15.453843) (xy 100.225048 15.438087) (xy 100.307524 15.41462)
			(xy 100.387483 15.383644) (xy 100.464243 15.345422) (xy 100.537149 15.300281) (xy 100.605578 15.248605)
			(xy 100.668948 15.190836) (xy 100.726717 15.127466) (xy 100.778393 15.059037) (xy 100.823534 14.986131)
			(xy 100.861756 14.909371) (xy 100.892732 14.829412) (xy 100.916199 14.746936) (xy 100.931955 14.662646)
			(xy 100.939867 14.577263) (xy 100.940362 14.534388) (xy 100.939867 14.491513) (xy 101.625133 14.491513)
			(xy 101.625133 14.577263) (xy 101.633045 14.662646) (xy 101.648801 14.746936) (xy 101.672268 14.829412)
			(xy 101.703244 14.909371) (xy 101.741466 14.986131) (xy 101.786607 15.059037) (xy 101.838283 15.127466)
			(xy 101.896052 15.190836) (xy 101.959422 15.248605) (xy 102.027851 15.300281) (xy 102.100757 15.345422)
			(xy 102.177517 15.383644) (xy 102.257476 15.41462) (xy 102.339952 15.438087) (xy 102.424242 15.453843)
			(xy 102.509625 15.461755) (xy 102.595375 15.461755) (xy 102.680758 15.453843) (xy 102.765048 15.438087)
			(xy 102.847524 15.41462) (xy 102.927483 15.383644) (xy 103.004243 15.345422) (xy 103.077149 15.300281)
			(xy 103.145578 15.248605) (xy 103.208948 15.190836) (xy 103.266717 15.127466) (xy 103.318393 15.059037)
			(xy 103.363534 14.986131) (xy 103.401756 14.909371) (xy 103.432732 14.829412) (xy 103.456199 14.746936)
			(xy 103.471955 14.662646) (xy 103.479867 14.577263) (xy 103.480362 14.534388) (xy 103.479867 14.491513)
			(xy 104.165133 14.491513) (xy 104.165133 14.577263) (xy 104.173045 14.662646) (xy 104.188801 14.746936)
			(xy 104.212268 14.829412) (xy 104.243244 14.909371) (xy 104.281466 14.986131) (xy 104.326607 15.059037)
			(xy 104.378283 15.127466) (xy 104.436052 15.190836) (xy 104.499422 15.248605) (xy 104.567851 15.300281)
			(xy 104.640757 15.345422) (xy 104.717517 15.383644) (xy 104.797476 15.41462) (xy 104.879952 15.438087)
			(xy 104.964242 15.453843) (xy 105.049625 15.461755) (xy 105.135375 15.461755) (xy 105.220758 15.453843)
			(xy 105.305048 15.438087) (xy 105.387524 15.41462) (xy 105.467483 15.383644) (xy 105.544243 15.345422)
			(xy 105.617149 15.300281) (xy 105.685578 15.248605) (xy 105.748948 15.190836) (xy 105.806717 15.127466)
			(xy 105.858393 15.059037) (xy 105.903534 14.986131) (xy 105.941756 14.909371) (xy 105.972732 14.829412)
			(xy 105.996199 14.746936) (xy 106.011955 14.662646) (xy 106.019867 14.577263) (xy 106.020362 14.534388)
			(xy 106.019867 14.491513) (xy 106.011955 14.40613) (xy 105.996199 14.32184) (xy 105.972732 14.239364)
			(xy 105.941756 14.159405) (xy 105.903534 14.082645) (xy 105.858393 14.009739) (xy 105.806717 13.94131)
			(xy 105.748948 13.87794) (xy 105.685578 13.820171) (xy 105.617149 13.768495) (xy 105.544243 13.723354)
			(xy 105.467483 13.685132) (xy 105.387524 13.654156) (xy 105.305048 13.630689) (xy 105.220758 13.614933)
			(xy 105.135375 13.607021) (xy 105.049625 13.607021) (xy 104.964242 13.614933) (xy 104.879952 13.630689)
			(xy 104.797476 13.654156) (xy 104.717517 13.685132) (xy 104.640757 13.723354) (xy 104.567851 13.768495)
			(xy 104.499422 13.820171) (xy 104.436052 13.87794) (xy 104.378283 13.94131) (xy 104.326607 14.009739)
			(xy 104.281466 14.082645) (xy 104.243244 14.159405) (xy 104.212268 14.239364) (xy 104.188801 14.32184)
			(xy 104.173045 14.40613) (xy 104.165133 14.491513) (xy 103.479867 14.491513) (xy 103.471955 14.40613)
			(xy 103.456199 14.32184) (xy 103.432732 14.239364) (xy 103.401756 14.159405) (xy 103.363534 14.082645)
			(xy 103.318393 14.009739) (xy 103.266717 13.94131) (xy 103.208948 13.87794) (xy 103.145578 13.820171)
			(xy 103.077149 13.768495) (xy 103.004243 13.723354) (xy 102.927483 13.685132) (xy 102.847524 13.654156)
			(xy 102.765048 13.630689) (xy 102.680758 13.614933) (xy 102.595375 13.607021) (xy 102.509625 13.607021)
			(xy 102.424242 13.614933) (xy 102.339952 13.630689) (xy 102.257476 13.654156) (xy 102.177517 13.685132)
			(xy 102.100757 13.723354) (xy 102.027851 13.768495) (xy 101.959422 13.820171) (xy 101.896052 13.87794)
			(xy 101.838283 13.94131) (xy 101.786607 14.009739) (xy 101.741466 14.082645) (xy 101.703244 14.159405)
			(xy 101.672268 14.239364) (xy 101.648801 14.32184) (xy 101.633045 14.40613) (xy 101.625133 14.491513)
			(xy 100.939867 14.491513) (xy 100.931955 14.40613) (xy 100.916199 14.32184) (xy 100.892732 14.239364)
			(xy 100.861756 14.159405) (xy 100.823534 14.082645) (xy 100.778393 14.009739) (xy 100.726717 13.94131)
			(xy 100.668948 13.87794) (xy 100.605578 13.820171) (xy 100.537149 13.768495) (xy 100.464243 13.723354)
			(xy 100.387483 13.685132) (xy 100.307524 13.654156) (xy 100.225048 13.630689) (xy 100.140758 13.614933)
			(xy 100.055375 13.607021) (xy 99.969625 13.607021) (xy 99.884242 13.614933) (xy 99.799952 13.630689)
			(xy 99.717476 13.654156) (xy 99.637517 13.685132) (xy 99.560757 13.723354) (xy 99.487851 13.768495)
			(xy 99.419422 13.820171) (xy 99.356052 13.87794) (xy 99.298283 13.94131) (xy 99.246607 14.009739)
			(xy 99.201466 14.082645) (xy 99.163244 14.159405) (xy 99.132268 14.239364) (xy 99.108801 14.32184)
			(xy 99.093045 14.40613) (xy 99.085133 14.491513) (xy 92.50807 14.491513) (xy 92.50807 -1.181049)
			(xy 93.729289 -1.181049) (xy 93.729289 -1.095299) (xy 93.737201 -1.009916) (xy 93.752957 -0.925626)
			(xy 93.776424 -0.84315) (xy 93.8074 -0.763191) (xy 93.845622 -0.686431) (xy 93.890763 -0.613525)
			(xy 93.942439 -0.545096) (xy 94.000208 -0.481726) (xy 94.063578 -0.423957) (xy 94.132007 -0.372281)
			(xy 94.204913 -0.32714) (xy 94.281673 -0.288918) (xy 94.361632 -0.257942) (xy 94.444108 -0.234475)
			(xy 94.528398 -0.218719) (xy 94.613781 -0.210807) (xy 94.699531 -0.210807) (xy 94.784914 -0.218719)
			(xy 94.869204 -0.234475) (xy 94.95168 -0.257942) (xy 95.031639 -0.288918) (xy 95.108399 -0.32714)
			(xy 95.181305 -0.372281) (xy 95.249734 -0.423957) (xy 95.313104 -0.481726) (xy 95.370873 -0.545096)
			(xy 95.422549 -0.613525) (xy 95.46769 -0.686431) (xy 95.505912 -0.763191) (xy 95.536888 -0.84315)
			(xy 95.560355 -0.925626) (xy 95.576111 -1.009916) (xy 95.584023 -1.095299) (xy 95.584518 -1.138174)
			(xy 95.584023 -1.181049) (xy 96.269289 -1.181049) (xy 96.269289 -1.095299) (xy 96.277201 -1.009916)
			(xy 96.292957 -0.925626) (xy 96.316424 -0.84315) (xy 96.3474 -0.763191) (xy 96.385622 -0.686431)
			(xy 96.430763 -0.613525) (xy 96.482439 -0.545096) (xy 96.540208 -0.481726) (xy 96.603578 -0.423957)
			(xy 96.672007 -0.372281) (xy 96.744913 -0.32714) (xy 96.821673 -0.288918) (xy 96.901632 -0.257942)
			(xy 96.984108 -0.234475) (xy 97.068398 -0.218719) (xy 97.153781 -0.210807) (xy 97.239531 -0.210807)
			(xy 97.324914 -0.218719) (xy 97.409204 -0.234475) (xy 97.49168 -0.257942) (xy 97.571639 -0.288918)
			(xy 97.648399 -0.32714) (xy 97.721305 -0.372281) (xy 97.789734 -0.423957) (xy 97.853104 -0.481726)
			(xy 97.910873 -0.545096) (xy 97.962549 -0.613525) (xy 98.00769 -0.686431) (xy 98.045912 -0.763191)
			(xy 98.076888 -0.84315) (xy 98.100355 -0.925626) (xy 98.116111 -1.009916) (xy 98.124023 -1.095299)
			(xy 98.124518 -1.138174) (xy 98.124023 -1.181049) (xy 98.116111 -1.266432) (xy 98.100355 -1.350722)
			(xy 98.076888 -1.433198) (xy 98.045912 -1.513157) (xy 98.00769 -1.589917) (xy 97.962549 -1.662823)
			(xy 97.910873 -1.731252) (xy 97.853104 -1.794622) (xy 97.789734 -1.852391) (xy 97.721305 -1.904067)
			(xy 97.648399 -1.949208) (xy 97.571639 -1.98743) (xy 97.49168 -2.018406) (xy 97.409204 -2.041873)
			(xy 97.324914 -2.057629) (xy 97.239531 -2.065541) (xy 97.153781 -2.065541) (xy 97.068398 -2.057629)
			(xy 96.984108 -2.041873) (xy 96.901632 -2.018406) (xy 96.821673 -1.98743) (xy 96.744913 -1.949208)
			(xy 96.672007 -1.904067) (xy 96.603578 -1.852391) (xy 96.540208 -1.794622) (xy 96.482439 -1.731252)
			(xy 96.430763 -1.662823) (xy 96.385622 -1.589917) (xy 96.3474 -1.513157) (xy 96.316424 -1.433198)
			(xy 96.292957 -1.350722) (xy 96.277201 -1.266432) (xy 96.269289 -1.181049) (xy 95.584023 -1.181049)
			(xy 95.576111 -1.266432) (xy 95.560355 -1.350722) (xy 95.536888 -1.433198) (xy 95.505912 -1.513157)
			(xy 95.46769 -1.589917) (xy 95.422549 -1.662823) (xy 95.370873 -1.731252) (xy 95.313104 -1.794622)
			(xy 95.249734 -1.852391) (xy 95.181305 -1.904067) (xy 95.108399 -1.949208) (xy 95.031639 -1.98743)
			(xy 94.95168 -2.018406) (xy 94.869204 -2.041873) (xy 94.784914 -2.057629) (xy 94.699531 -2.065541)
			(xy 94.613781 -2.065541) (xy 94.528398 -2.057629) (xy 94.444108 -2.041873) (xy 94.361632 -2.018406)
			(xy 94.281673 -1.98743) (xy 94.204913 -1.949208) (xy 94.132007 -1.904067) (xy 94.063578 -1.852391)
			(xy 94.000208 -1.794622) (xy 93.942439 -1.731252) (xy 93.890763 -1.662823) (xy 93.845622 -1.589917)
			(xy 93.8074 -1.513157) (xy 93.776424 -1.433198) (xy 93.752957 -1.350722) (xy 93.737201 -1.266432)
			(xy 93.729289 -1.181049) (xy 92.50807 -1.181049) (xy 92.50807 -3.127502) (xy 95.113348 -3.127502)
			(xy 95.113825 -3.100244) (xy 95.121581 -3.046282) (xy 95.136933 -2.993972) (xy 95.159571 -2.944378)
			(xy 95.189034 -2.898509) (xy 95.224723 -2.857297) (xy 95.265911 -2.821582) (xy 95.311761 -2.79209)
			(xy 95.361341 -2.769419) (xy 95.413641 -2.754033) (xy 95.467598 -2.746243) (xy 95.494856 -2.74574)
			(xy 96.358456 -2.74574) (xy 96.385721 -2.746197) (xy 96.439698 -2.753956) (xy 96.492019 -2.769322)
			(xy 96.541619 -2.791981) (xy 96.587487 -2.821473) (xy 96.628688 -2.857195) (xy 96.664382 -2.89842)
			(xy 96.693843 -2.944308) (xy 96.716469 -2.993923) (xy 96.731799 -3.046255) (xy 96.739521 -3.100236)
			(xy 96.739964 -3.127502) (xy 96.739454 -3.156045) (xy 96.730966 -3.212497) (xy 96.714165 -3.267055)
			(xy 96.689425 -3.318502) (xy 96.657299 -3.36569) (xy 96.618503 -3.407568) (xy 96.573902 -3.443199)
			(xy 96.549464 -3.457956) (xy 96.549464 -4.256532) (xy 95.298768 -4.256532) (xy 95.298768 -3.454908)
			(xy 95.274917 -3.44001) (xy 95.231453 -3.404328) (xy 95.193695 -3.362656) (xy 95.162458 -3.315895)
			(xy 95.138419 -3.265058) (xy 95.122098 -3.211245) (xy 95.113849 -3.155619) (xy 95.113348 -3.127502)
			(xy 92.50807 -3.127502) (xy 92.50807 -7.531049) (xy 93.729289 -7.531049) (xy 93.729289 -7.445299)
			(xy 93.737201 -7.359916) (xy 93.752957 -7.275626) (xy 93.776424 -7.19315) (xy 93.8074 -7.113191)
			(xy 93.845622 -7.036431) (xy 93.890763 -6.963525) (xy 93.942439 -6.895096) (xy 94.000208 -6.831726)
			(xy 94.063578 -6.773957) (xy 94.132007 -6.722281) (xy 94.204913 -6.67714) (xy 94.281673 -6.638918)
			(xy 94.361632 -6.607942) (xy 94.444108 -6.584475) (xy 94.528398 -6.568719) (xy 94.613781 -6.560807)
			(xy 94.699531 -6.560807) (xy 94.784914 -6.568719) (xy 94.869204 -6.584475) (xy 94.95168 -6.607942)
			(xy 95.031639 -6.638918) (xy 95.108399 -6.67714) (xy 95.181305 -6.722281) (xy 95.249734 -6.773957)
			(xy 95.313104 -6.831726) (xy 95.370873 -6.895096) (xy 95.422549 -6.963525) (xy 95.46769 -7.036431)
			(xy 95.505912 -7.113191) (xy 95.536888 -7.19315) (xy 95.560355 -7.275626) (xy 95.576111 -7.359916)
			(xy 95.584023 -7.445299) (xy 95.584518 -7.488174) (xy 95.584023 -7.531049) (xy 96.269289 -7.531049)
			(xy 96.269289 -7.445299) (xy 96.277201 -7.359916) (xy 96.292957 -7.275626) (xy 96.316424 -7.19315)
			(xy 96.3474 -7.113191) (xy 96.385622 -7.036431) (xy 96.430763 -6.963525) (xy 96.482439 -6.895096)
			(xy 96.540208 -6.831726) (xy 96.603578 -6.773957) (xy 96.672007 -6.722281) (xy 96.744913 -6.67714)
			(xy 96.821673 -6.638918) (xy 96.901632 -6.607942) (xy 96.984108 -6.584475) (xy 97.068398 -6.568719)
			(xy 97.153781 -6.560807) (xy 97.239531 -6.560807) (xy 97.324914 -6.568719) (xy 97.409204 -6.584475)
			(xy 97.49168 -6.607942) (xy 97.571639 -6.638918) (xy 97.648399 -6.67714) (xy 97.721305 -6.722281)
			(xy 97.789734 -6.773957) (xy 97.853104 -6.831726) (xy 97.910873 -6.895096) (xy 97.962549 -6.963525)
			(xy 98.00769 -7.036431) (xy 98.045912 -7.113191) (xy 98.076888 -7.19315) (xy 98.100355 -7.275626)
			(xy 98.116111 -7.359916) (xy 98.124023 -7.445299) (xy 98.124518 -7.488174) (xy 98.124023 -7.531049)
			(xy 98.116111 -7.616432) (xy 98.100355 -7.700722) (xy 98.076888 -7.783198) (xy 98.045912 -7.863157)
			(xy 98.00769 -7.939917) (xy 97.962549 -8.012823) (xy 97.910873 -8.081252) (xy 97.853104 -8.144622)
			(xy 97.789734 -8.202391) (xy 97.721305 -8.254067) (xy 97.648399 -8.299208) (xy 97.571639 -8.33743)
			(xy 97.49168 -8.368406) (xy 97.409204 -8.391873) (xy 97.324914 -8.407629) (xy 97.239531 -8.415541)
			(xy 97.153781 -8.415541) (xy 97.068398 -8.407629) (xy 96.984108 -8.391873) (xy 96.901632 -8.368406)
			(xy 96.821673 -8.33743) (xy 96.744913 -8.299208) (xy 96.672007 -8.254067) (xy 96.603578 -8.202391)
			(xy 96.540208 -8.144622) (xy 96.482439 -8.081252) (xy 96.430763 -8.012823) (xy 96.385622 -7.939917)
			(xy 96.3474 -7.863157) (xy 96.316424 -7.783198) (xy 96.292957 -7.700722) (xy 96.277201 -7.616432)
			(xy 96.269289 -7.531049) (xy 95.584023 -7.531049) (xy 95.576111 -7.616432) (xy 95.560355 -7.700722)
			(xy 95.536888 -7.783198) (xy 95.505912 -7.863157) (xy 95.46769 -7.939917) (xy 95.422549 -8.012823)
			(xy 95.370873 -8.081252) (xy 95.313104 -8.144622) (xy 95.249734 -8.202391) (xy 95.181305 -8.254067)
			(xy 95.108399 -8.299208) (xy 95.031639 -8.33743) (xy 94.95168 -8.368406) (xy 94.869204 -8.391873)
			(xy 94.784914 -8.407629) (xy 94.699531 -8.415541) (xy 94.613781 -8.415541) (xy 94.528398 -8.407629)
			(xy 94.444108 -8.391873) (xy 94.361632 -8.368406) (xy 94.281673 -8.33743) (xy 94.204913 -8.299208)
			(xy 94.132007 -8.254067) (xy 94.063578 -8.202391) (xy 94.000208 -8.144622) (xy 93.942439 -8.081252)
			(xy 93.890763 -8.012823) (xy 93.845622 -7.939917) (xy 93.8074 -7.863157) (xy 93.776424 -7.783198)
			(xy 93.752957 -7.700722) (xy 93.737201 -7.616432) (xy 93.729289 -7.531049) (xy 92.50807 -7.531049)
			(xy 92.50807 -13.055549) (xy 93.714049 -13.055549) (xy 93.714049 -12.969799) (xy 93.721961 -12.884416)
			(xy 93.737717 -12.800126) (xy 93.761184 -12.71765) (xy 93.79216 -12.637691) (xy 93.830382 -12.560931)
			(xy 93.875523 -12.488025) (xy 93.927199 -12.419596) (xy 93.984968 -12.356226) (xy 94.048338 -12.298457)
			(xy 94.116767 -12.246781) (xy 94.189673 -12.20164) (xy 94.266433 -12.163418) (xy 94.346392 -12.132442)
			(xy 94.428868 -12.108975) (xy 94.513158 -12.093219) (xy 94.598541 -12.085307) (xy 94.684291 -12.085307)
			(xy 94.769674 -12.093219) (xy 94.853964 -12.108975) (xy 94.93644 -12.132442) (xy 95.016399 -12.163418)
			(xy 95.093159 -12.20164) (xy 95.166065 -12.246781) (xy 95.234494 -12.298457) (xy 95.297864 -12.356226)
			(xy 95.355633 -12.419596) (xy 95.407309 -12.488025) (xy 95.45245 -12.560931) (xy 95.490672 -12.637691)
			(xy 95.521648 -12.71765) (xy 95.545115 -12.800126) (xy 95.560871 -12.884416) (xy 95.568783 -12.969799)
			(xy 95.569278 -13.012674) (xy 95.568783 -13.055549) (xy 96.254049 -13.055549) (xy 96.254049 -12.969799)
			(xy 96.261961 -12.884416) (xy 96.277717 -12.800126) (xy 96.301184 -12.71765) (xy 96.33216 -12.637691)
			(xy 96.370382 -12.560931) (xy 96.415523 -12.488025) (xy 96.467199 -12.419596) (xy 96.524968 -12.356226)
			(xy 96.588338 -12.298457) (xy 96.656767 -12.246781) (xy 96.729673 -12.20164) (xy 96.806433 -12.163418)
			(xy 96.886392 -12.132442) (xy 96.968868 -12.108975) (xy 97.053158 -12.093219) (xy 97.138541 -12.085307)
			(xy 97.224291 -12.085307) (xy 97.309674 -12.093219) (xy 97.393964 -12.108975) (xy 97.47644 -12.132442)
			(xy 97.556399 -12.163418) (xy 97.633159 -12.20164) (xy 97.706065 -12.246781) (xy 97.774494 -12.298457)
			(xy 97.837864 -12.356226) (xy 97.895633 -12.419596) (xy 97.947309 -12.488025) (xy 97.99245 -12.560931)
			(xy 98.030672 -12.637691) (xy 98.061648 -12.71765) (xy 98.085115 -12.800126) (xy 98.100871 -12.884416)
			(xy 98.108783 -12.969799) (xy 98.109278 -13.012674) (xy 98.108783 -13.055549) (xy 98.100871 -13.140932)
			(xy 98.085115 -13.225222) (xy 98.061648 -13.307698) (xy 98.030672 -13.387657) (xy 97.99245 -13.464417)
			(xy 97.947309 -13.537323) (xy 97.895633 -13.605752) (xy 97.837864 -13.669122) (xy 97.774494 -13.726891)
			(xy 97.706065 -13.778567) (xy 97.633159 -13.823708) (xy 97.556399 -13.86193) (xy 97.47644 -13.892906)
			(xy 97.393964 -13.916373) (xy 97.309674 -13.932129) (xy 97.224291 -13.940041) (xy 97.138541 -13.940041)
			(xy 97.053158 -13.932129) (xy 96.968868 -13.916373) (xy 96.886392 -13.892906) (xy 96.806433 -13.86193)
			(xy 96.729673 -13.823708) (xy 96.656767 -13.778567) (xy 96.588338 -13.726891) (xy 96.524968 -13.669122)
			(xy 96.467199 -13.605752) (xy 96.415523 -13.537323) (xy 96.370382 -13.464417) (xy 96.33216 -13.387657)
			(xy 96.301184 -13.307698) (xy 96.277717 -13.225222) (xy 96.261961 -13.140932) (xy 96.254049 -13.055549)
			(xy 95.568783 -13.055549) (xy 95.560871 -13.140932) (xy 95.545115 -13.225222) (xy 95.521648 -13.307698)
			(xy 95.490672 -13.387657) (xy 95.45245 -13.464417) (xy 95.407309 -13.537323) (xy 95.355633 -13.605752)
			(xy 95.297864 -13.669122) (xy 95.234494 -13.726891) (xy 95.166065 -13.778567) (xy 95.093159 -13.823708)
			(xy 95.016399 -13.86193) (xy 94.93644 -13.892906) (xy 94.853964 -13.916373) (xy 94.769674 -13.932129)
			(xy 94.684291 -13.940041) (xy 94.598541 -13.940041) (xy 94.513158 -13.932129) (xy 94.428868 -13.916373)
			(xy 94.346392 -13.892906) (xy 94.266433 -13.86193) (xy 94.189673 -13.823708) (xy 94.116767 -13.778567)
			(xy 94.048338 -13.726891) (xy 93.984968 -13.669122) (xy 93.927199 -13.605752) (xy 93.875523 -13.537323)
			(xy 93.830382 -13.464417) (xy 93.79216 -13.387657) (xy 93.761184 -13.307698) (xy 93.737717 -13.225222)
			(xy 93.721961 -13.140932) (xy 93.714049 -13.055549) (xy 92.50807 -13.055549) (xy 92.50807 -17.373346)
			(xy 95.098108 -17.373346) (xy 95.09862 -17.344802) (xy 95.107103 -17.288349) (xy 95.123901 -17.233789)
			(xy 95.14864 -17.182341) (xy 95.180766 -17.135152) (xy 95.219564 -17.093276) (xy 95.264168 -17.057646)
			(xy 95.288608 -17.042892) (xy 95.288608 -16.244316) (xy 96.539304 -16.244316) (xy 96.539304 -17.04594)
			(xy 96.563171 -17.060815) (xy 96.606635 -17.0965) (xy 96.644394 -17.138175) (xy 96.675629 -17.18494)
			(xy 96.699666 -17.235781) (xy 96.715983 -17.289598) (xy 96.724227 -17.345228) (xy 96.724724 -17.373346)
			(xy 96.724319 -17.400607) (xy 96.716557 -17.454573) (xy 96.701196 -17.506886) (xy 96.678551 -17.556482)
			(xy 96.64908 -17.602352) (xy 96.613384 -17.643564) (xy 96.572188 -17.679278) (xy 96.526331 -17.708769)
			(xy 96.476745 -17.731437) (xy 96.424439 -17.74682) (xy 96.370476 -17.754607) (xy 96.343216 -17.755108)
			(xy 95.479616 -17.755108) (xy 95.452352 -17.754629) (xy 95.398379 -17.746868) (xy 95.346061 -17.731501)
			(xy 95.296464 -17.708842) (xy 95.250599 -17.679352) (xy 95.209399 -17.643632) (xy 95.173705 -17.60241)
			(xy 95.144244 -17.556526) (xy 95.121616 -17.506915) (xy 95.106282 -17.454588) (xy 95.098554 -17.40061)
			(xy 95.098108 -17.373346) (xy 92.50807 -17.373346) (xy 92.50807 -19.405549) (xy 93.714049 -19.405549)
			(xy 93.714049 -19.319799) (xy 93.721961 -19.234416) (xy 93.737717 -19.150126) (xy 93.761184 -19.06765)
			(xy 93.79216 -18.987691) (xy 93.830382 -18.910931) (xy 93.875523 -18.838025) (xy 93.927199 -18.769596)
			(xy 93.984968 -18.706226) (xy 94.048338 -18.648457) (xy 94.116767 -18.596781) (xy 94.189673 -18.55164)
			(xy 94.266433 -18.513418) (xy 94.346392 -18.482442) (xy 94.428868 -18.458975) (xy 94.513158 -18.443219)
			(xy 94.598541 -18.435307) (xy 94.684291 -18.435307) (xy 94.769674 -18.443219) (xy 94.853964 -18.458975)
			(xy 94.93644 -18.482442) (xy 95.016399 -18.513418) (xy 95.093159 -18.55164) (xy 95.166065 -18.596781)
			(xy 95.234494 -18.648457) (xy 95.297864 -18.706226) (xy 95.355633 -18.769596) (xy 95.407309 -18.838025)
			(xy 95.45245 -18.910931) (xy 95.490672 -18.987691) (xy 95.521648 -19.06765) (xy 95.545115 -19.150126)
			(xy 95.560871 -19.234416) (xy 95.568783 -19.319799) (xy 95.569278 -19.362674) (xy 95.568783 -19.405549)
			(xy 96.254049 -19.405549) (xy 96.254049 -19.319799) (xy 96.261961 -19.234416) (xy 96.277717 -19.150126)
			(xy 96.301184 -19.06765) (xy 96.33216 -18.987691) (xy 96.370382 -18.910931) (xy 96.415523 -18.838025)
			(xy 96.467199 -18.769596) (xy 96.524968 -18.706226) (xy 96.588338 -18.648457) (xy 96.656767 -18.596781)
			(xy 96.729673 -18.55164) (xy 96.806433 -18.513418) (xy 96.886392 -18.482442) (xy 96.968868 -18.458975)
			(xy 97.053158 -18.443219) (xy 97.138541 -18.435307) (xy 97.224291 -18.435307) (xy 97.309674 -18.443219)
			(xy 97.393964 -18.458975) (xy 97.47644 -18.482442) (xy 97.556399 -18.513418) (xy 97.633159 -18.55164)
			(xy 97.706065 -18.596781) (xy 97.774494 -18.648457) (xy 97.837864 -18.706226) (xy 97.895633 -18.769596)
			(xy 97.947309 -18.838025) (xy 97.99245 -18.910931) (xy 98.030672 -18.987691) (xy 98.061648 -19.06765)
			(xy 98.085115 -19.150126) (xy 98.100871 -19.234416) (xy 98.108783 -19.319799) (xy 98.109278 -19.362674)
			(xy 98.108783 -19.405549) (xy 98.100871 -19.490932) (xy 98.085115 -19.575222) (xy 98.061648 -19.657698)
			(xy 98.030672 -19.737657) (xy 97.99245 -19.814417) (xy 97.947309 -19.887323) (xy 97.895633 -19.955752)
			(xy 97.837864 -20.019122) (xy 97.774494 -20.076891) (xy 97.706065 -20.128567) (xy 97.633159 -20.173708)
			(xy 97.556399 -20.21193) (xy 97.47644 -20.242906) (xy 97.393964 -20.266373) (xy 97.309674 -20.282129)
			(xy 97.224291 -20.290041) (xy 97.138541 -20.290041) (xy 97.053158 -20.282129) (xy 96.968868 -20.266373)
			(xy 96.886392 -20.242906) (xy 96.806433 -20.21193) (xy 96.729673 -20.173708) (xy 96.656767 -20.128567)
			(xy 96.588338 -20.076891) (xy 96.524968 -20.019122) (xy 96.467199 -19.955752) (xy 96.415523 -19.887323)
			(xy 96.370382 -19.814417) (xy 96.33216 -19.737657) (xy 96.301184 -19.657698) (xy 96.277717 -19.575222)
			(xy 96.261961 -19.490932) (xy 96.254049 -19.405549) (xy 95.568783 -19.405549) (xy 95.560871 -19.490932)
			(xy 95.545115 -19.575222) (xy 95.521648 -19.657698) (xy 95.490672 -19.737657) (xy 95.45245 -19.814417)
			(xy 95.407309 -19.887323) (xy 95.355633 -19.955752) (xy 95.297864 -20.019122) (xy 95.234494 -20.076891)
			(xy 95.166065 -20.128567) (xy 95.093159 -20.173708) (xy 95.016399 -20.21193) (xy 94.93644 -20.242906)
			(xy 94.853964 -20.266373) (xy 94.769674 -20.282129) (xy 94.684291 -20.290041) (xy 94.598541 -20.290041)
			(xy 94.513158 -20.282129) (xy 94.428868 -20.266373) (xy 94.346392 -20.242906) (xy 94.266433 -20.21193)
			(xy 94.189673 -20.173708) (xy 94.116767 -20.128567) (xy 94.048338 -20.076891) (xy 93.984968 -20.019122)
			(xy 93.927199 -19.955752) (xy 93.875523 -19.887323) (xy 93.830382 -19.814417) (xy 93.79216 -19.737657)
			(xy 93.761184 -19.657698) (xy 93.737717 -19.575222) (xy 93.721961 -19.490932) (xy 93.714049 -19.405549)
			(xy 92.50807 -19.405549) (xy 92.50807 -50.979527) (xy 99.085133 -50.979527) (xy 99.085133 -50.893777)
			(xy 99.093045 -50.808394) (xy 99.108801 -50.724104) (xy 99.132268 -50.641628) (xy 99.163244 -50.561669)
			(xy 99.201466 -50.484909) (xy 99.246607 -50.412003) (xy 99.298283 -50.343574) (xy 99.356052 -50.280204)
			(xy 99.419422 -50.222435) (xy 99.487851 -50.170759) (xy 99.560757 -50.125618) (xy 99.637517 -50.087396)
			(xy 99.717476 -50.05642) (xy 99.799952 -50.032953) (xy 99.884242 -50.017197) (xy 99.969625 -50.009285)
			(xy 100.055375 -50.009285) (xy 100.140758 -50.017197) (xy 100.225048 -50.032953) (xy 100.307524 -50.05642)
			(xy 100.387483 -50.087396) (xy 100.464243 -50.125618) (xy 100.537149 -50.170759) (xy 100.605578 -50.222435)
			(xy 100.668948 -50.280204) (xy 100.726717 -50.343574) (xy 100.778393 -50.412003) (xy 100.823534 -50.484909)
			(xy 100.861756 -50.561669) (xy 100.892732 -50.641628) (xy 100.916199 -50.724104) (xy 100.931955 -50.808394)
			(xy 100.939867 -50.893777) (xy 100.940362 -50.936652) (xy 100.939867 -50.979527) (xy 101.625133 -50.979527)
			(xy 101.625133 -50.893777) (xy 101.633045 -50.808394) (xy 101.648801 -50.724104) (xy 101.672268 -50.641628)
			(xy 101.703244 -50.561669) (xy 101.741466 -50.484909) (xy 101.786607 -50.412003) (xy 101.838283 -50.343574)
			(xy 101.896052 -50.280204) (xy 101.959422 -50.222435) (xy 102.027851 -50.170759) (xy 102.100757 -50.125618)
			(xy 102.177517 -50.087396) (xy 102.257476 -50.05642) (xy 102.339952 -50.032953) (xy 102.424242 -50.017197)
			(xy 102.509625 -50.009285) (xy 102.595375 -50.009285) (xy 102.680758 -50.017197) (xy 102.765048 -50.032953)
			(xy 102.847524 -50.05642) (xy 102.927483 -50.087396) (xy 103.004243 -50.125618) (xy 103.077149 -50.170759)
			(xy 103.145578 -50.222435) (xy 103.208948 -50.280204) (xy 103.266717 -50.343574) (xy 103.318393 -50.412003)
			(xy 103.363534 -50.484909) (xy 103.401756 -50.561669) (xy 103.432732 -50.641628) (xy 103.456199 -50.724104)
			(xy 103.471955 -50.808394) (xy 103.479867 -50.893777) (xy 103.480362 -50.936652) (xy 103.479867 -50.979527)
			(xy 104.165133 -50.979527) (xy 104.165133 -50.893777) (xy 104.173045 -50.808394) (xy 104.188801 -50.724104)
			(xy 104.212268 -50.641628) (xy 104.243244 -50.561669) (xy 104.281466 -50.484909) (xy 104.326607 -50.412003)
			(xy 104.378283 -50.343574) (xy 104.436052 -50.280204) (xy 104.499422 -50.222435) (xy 104.567851 -50.170759)
			(xy 104.640757 -50.125618) (xy 104.717517 -50.087396) (xy 104.797476 -50.05642) (xy 104.879952 -50.032953)
			(xy 104.964242 -50.017197) (xy 105.049625 -50.009285) (xy 105.135375 -50.009285) (xy 105.220758 -50.017197)
			(xy 105.305048 -50.032953) (xy 105.387524 -50.05642) (xy 105.467483 -50.087396) (xy 105.544243 -50.125618)
			(xy 105.617149 -50.170759) (xy 105.685578 -50.222435) (xy 105.748948 -50.280204) (xy 105.806717 -50.343574)
			(xy 105.858393 -50.412003) (xy 105.903534 -50.484909) (xy 105.941756 -50.561669) (xy 105.972732 -50.641628)
			(xy 105.996199 -50.724104) (xy 106.011955 -50.808394) (xy 106.019867 -50.893777) (xy 106.020362 -50.936652)
			(xy 106.019867 -50.979527) (xy 106.011955 -51.06491) (xy 105.996199 -51.1492) (xy 105.972732 -51.231676)
			(xy 105.941756 -51.311635) (xy 105.903534 -51.388395) (xy 105.858393 -51.461301) (xy 105.806717 -51.52973)
			(xy 105.748948 -51.5931) (xy 105.685578 -51.650869) (xy 105.617149 -51.702545) (xy 105.544243 -51.747686)
			(xy 105.467483 -51.785908) (xy 105.387524 -51.816884) (xy 105.305048 -51.840351) (xy 105.220758 -51.856107)
			(xy 105.135375 -51.864019) (xy 105.049625 -51.864019) (xy 104.964242 -51.856107) (xy 104.879952 -51.840351)
			(xy 104.797476 -51.816884) (xy 104.717517 -51.785908) (xy 104.640757 -51.747686) (xy 104.567851 -51.702545)
			(xy 104.499422 -51.650869) (xy 104.436052 -51.5931) (xy 104.378283 -51.52973) (xy 104.326607 -51.461301)
			(xy 104.281466 -51.388395) (xy 104.243244 -51.311635) (xy 104.212268 -51.231676) (xy 104.188801 -51.1492)
			(xy 104.173045 -51.06491) (xy 104.165133 -50.979527) (xy 103.479867 -50.979527) (xy 103.471955 -51.06491)
			(xy 103.456199 -51.1492) (xy 103.432732 -51.231676) (xy 103.401756 -51.311635) (xy 103.363534 -51.388395)
			(xy 103.318393 -51.461301) (xy 103.266717 -51.52973) (xy 103.208948 -51.5931) (xy 103.145578 -51.650869)
			(xy 103.077149 -51.702545) (xy 103.004243 -51.747686) (xy 102.927483 -51.785908) (xy 102.847524 -51.816884)
			(xy 102.765048 -51.840351) (xy 102.680758 -51.856107) (xy 102.595375 -51.864019) (xy 102.509625 -51.864019)
			(xy 102.424242 -51.856107) (xy 102.339952 -51.840351) (xy 102.257476 -51.816884) (xy 102.177517 -51.785908)
			(xy 102.100757 -51.747686) (xy 102.027851 -51.702545) (xy 101.959422 -51.650869) (xy 101.896052 -51.5931)
			(xy 101.838283 -51.52973) (xy 101.786607 -51.461301) (xy 101.741466 -51.388395) (xy 101.703244 -51.311635)
			(xy 101.672268 -51.231676) (xy 101.648801 -51.1492) (xy 101.633045 -51.06491) (xy 101.625133 -50.979527)
			(xy 100.939867 -50.979527) (xy 100.931955 -51.06491) (xy 100.916199 -51.1492) (xy 100.892732 -51.231676)
			(xy 100.861756 -51.311635) (xy 100.823534 -51.388395) (xy 100.778393 -51.461301) (xy 100.726717 -51.52973)
			(xy 100.668948 -51.5931) (xy 100.605578 -51.650869) (xy 100.537149 -51.702545) (xy 100.464243 -51.747686)
			(xy 100.387483 -51.785908) (xy 100.307524 -51.816884) (xy 100.225048 -51.840351) (xy 100.140758 -51.856107)
			(xy 100.055375 -51.864019) (xy 99.969625 -51.864019) (xy 99.884242 -51.856107) (xy 99.799952 -51.840351)
			(xy 99.717476 -51.816884) (xy 99.637517 -51.785908) (xy 99.560757 -51.747686) (xy 99.487851 -51.702545)
			(xy 99.419422 -51.650869) (xy 99.356052 -51.5931) (xy 99.298283 -51.52973) (xy 99.246607 -51.461301)
			(xy 99.201466 -51.388395) (xy 99.163244 -51.311635) (xy 99.132268 -51.231676) (xy 99.108801 -51.1492)
			(xy 99.093045 -51.06491) (xy 99.085133 -50.979527) (xy 92.50807 -50.979527) (xy 92.50807 -53.289708)
			(xy 103.194612 -53.289708) (xy 104.445308 -53.289708) (xy 104.445308 -54.055264) (xy 103.194612 -54.055264)
			(xy 103.194612 -53.289708) (xy 92.50807 -53.289708) (xy 92.50807 -57.329527) (xy 99.085133 -57.329527)
			(xy 99.085133 -57.243777) (xy 99.093045 -57.158394) (xy 99.108801 -57.074104) (xy 99.132268 -56.991628)
			(xy 99.163244 -56.911669) (xy 99.201466 -56.834909) (xy 99.246607 -56.762003) (xy 99.298283 -56.693574)
			(xy 99.356052 -56.630204) (xy 99.419422 -56.572435) (xy 99.487851 -56.520759) (xy 99.560757 -56.475618)
			(xy 99.637517 -56.437396) (xy 99.717476 -56.40642) (xy 99.799952 -56.382953) (xy 99.884242 -56.367197)
			(xy 99.969625 -56.359285) (xy 100.055375 -56.359285) (xy 100.140758 -56.367197) (xy 100.225048 -56.382953)
			(xy 100.307524 -56.40642) (xy 100.387483 -56.437396) (xy 100.464243 -56.475618) (xy 100.537149 -56.520759)
			(xy 100.605578 -56.572435) (xy 100.668948 -56.630204) (xy 100.726717 -56.693574) (xy 100.778393 -56.762003)
			(xy 100.823534 -56.834909) (xy 100.861756 -56.911669) (xy 100.892732 -56.991628) (xy 100.916199 -57.074104)
			(xy 100.931955 -57.158394) (xy 100.939867 -57.243777) (xy 100.940362 -57.286652) (xy 100.939867 -57.329527)
			(xy 101.625133 -57.329527) (xy 101.625133 -57.243777) (xy 101.633045 -57.158394) (xy 101.648801 -57.074104)
			(xy 101.672268 -56.991628) (xy 101.703244 -56.911669) (xy 101.741466 -56.834909) (xy 101.786607 -56.762003)
			(xy 101.838283 -56.693574) (xy 101.896052 -56.630204) (xy 101.959422 -56.572435) (xy 102.027851 -56.520759)
			(xy 102.100757 -56.475618) (xy 102.177517 -56.437396) (xy 102.257476 -56.40642) (xy 102.339952 -56.382953)
			(xy 102.424242 -56.367197) (xy 102.509625 -56.359285) (xy 102.595375 -56.359285) (xy 102.680758 -56.367197)
			(xy 102.765048 -56.382953) (xy 102.847524 -56.40642) (xy 102.927483 -56.437396) (xy 103.004243 -56.475618)
			(xy 103.077149 -56.520759) (xy 103.145578 -56.572435) (xy 103.208948 -56.630204) (xy 103.266717 -56.693574)
			(xy 103.318393 -56.762003) (xy 103.363534 -56.834909) (xy 103.401756 -56.911669) (xy 103.432732 -56.991628)
			(xy 103.456199 -57.074104) (xy 103.471955 -57.158394) (xy 103.479867 -57.243777) (xy 103.480362 -57.286652)
			(xy 103.479867 -57.329527) (xy 104.165133 -57.329527) (xy 104.165133 -57.243777) (xy 104.173045 -57.158394)
			(xy 104.188801 -57.074104) (xy 104.212268 -56.991628) (xy 104.243244 -56.911669) (xy 104.281466 -56.834909)
			(xy 104.326607 -56.762003) (xy 104.378283 -56.693574) (xy 104.436052 -56.630204) (xy 104.499422 -56.572435)
			(xy 104.567851 -56.520759) (xy 104.640757 -56.475618) (xy 104.717517 -56.437396) (xy 104.797476 -56.40642)
			(xy 104.879952 -56.382953) (xy 104.964242 -56.367197) (xy 105.049625 -56.359285) (xy 105.135375 -56.359285)
			(xy 105.220758 -56.367197) (xy 105.305048 -56.382953) (xy 105.387524 -56.40642) (xy 105.467483 -56.437396)
			(xy 105.544243 -56.475618) (xy 105.617149 -56.520759) (xy 105.685578 -56.572435) (xy 105.748948 -56.630204)
			(xy 105.806717 -56.693574) (xy 105.858393 -56.762003) (xy 105.903534 -56.834909) (xy 105.941756 -56.911669)
			(xy 105.972732 -56.991628) (xy 105.996199 -57.074104) (xy 106.011955 -57.158394) (xy 106.019867 -57.243777)
			(xy 106.020362 -57.286652) (xy 106.019867 -57.329527) (xy 106.011955 -57.41491) (xy 105.996199 -57.4992)
			(xy 105.972732 -57.581676) (xy 105.941756 -57.661635) (xy 105.903534 -57.738395) (xy 105.858393 -57.811301)
			(xy 105.806717 -57.87973) (xy 105.748948 -57.9431) (xy 105.685578 -58.000869) (xy 105.617149 -58.052545)
			(xy 105.544243 -58.097686) (xy 105.467483 -58.135908) (xy 105.387524 -58.166884) (xy 105.305048 -58.190351)
			(xy 105.220758 -58.206107) (xy 105.135375 -58.214019) (xy 105.049625 -58.214019) (xy 104.964242 -58.206107)
			(xy 104.879952 -58.190351) (xy 104.797476 -58.166884) (xy 104.717517 -58.135908) (xy 104.640757 -58.097686)
			(xy 104.567851 -58.052545) (xy 104.499422 -58.000869) (xy 104.436052 -57.9431) (xy 104.378283 -57.87973)
			(xy 104.326607 -57.811301) (xy 104.281466 -57.738395) (xy 104.243244 -57.661635) (xy 104.212268 -57.581676)
			(xy 104.188801 -57.4992) (xy 104.173045 -57.41491) (xy 104.165133 -57.329527) (xy 103.479867 -57.329527)
			(xy 103.471955 -57.41491) (xy 103.456199 -57.4992) (xy 103.432732 -57.581676) (xy 103.401756 -57.661635)
			(xy 103.363534 -57.738395) (xy 103.318393 -57.811301) (xy 103.266717 -57.87973) (xy 103.208948 -57.9431)
			(xy 103.145578 -58.000869) (xy 103.077149 -58.052545) (xy 103.004243 -58.097686) (xy 102.927483 -58.135908)
			(xy 102.847524 -58.166884) (xy 102.765048 -58.190351) (xy 102.680758 -58.206107) (xy 102.595375 -58.214019)
			(xy 102.509625 -58.214019) (xy 102.424242 -58.206107) (xy 102.339952 -58.190351) (xy 102.257476 -58.166884)
			(xy 102.177517 -58.135908) (xy 102.100757 -58.097686) (xy 102.027851 -58.052545) (xy 101.959422 -58.000869)
			(xy 101.896052 -57.9431) (xy 101.838283 -57.87973) (xy 101.786607 -57.811301) (xy 101.741466 -57.738395)
			(xy 101.703244 -57.661635) (xy 101.672268 -57.581676) (xy 101.648801 -57.4992) (xy 101.633045 -57.41491)
			(xy 101.625133 -57.329527) (xy 100.939867 -57.329527) (xy 100.931955 -57.41491) (xy 100.916199 -57.4992)
			(xy 100.892732 -57.581676) (xy 100.861756 -57.661635) (xy 100.823534 -57.738395) (xy 100.778393 -57.811301)
			(xy 100.726717 -57.87973) (xy 100.668948 -57.9431) (xy 100.605578 -58.000869) (xy 100.537149 -58.052545)
			(xy 100.464243 -58.097686) (xy 100.387483 -58.135908) (xy 100.307524 -58.166884) (xy 100.225048 -58.190351)
			(xy 100.140758 -58.206107) (xy 100.055375 -58.214019) (xy 99.969625 -58.214019) (xy 99.884242 -58.206107)
			(xy 99.799952 -58.190351) (xy 99.717476 -58.166884) (xy 99.637517 -58.135908) (xy 99.560757 -58.097686)
			(xy 99.487851 -58.052545) (xy 99.419422 -58.000869) (xy 99.356052 -57.9431) (xy 99.298283 -57.87973)
			(xy 99.246607 -57.811301) (xy 99.201466 -57.738395) (xy 99.163244 -57.661635) (xy 99.132268 -57.581676)
			(xy 99.108801 -57.4992) (xy 99.093045 -57.41491) (xy 99.085133 -57.329527) (xy 92.50807 -57.329527)
			(xy 92.50807 -62.793575) (xy 99.085133 -62.793575) (xy 99.085133 -62.707825) (xy 99.093045 -62.622442)
			(xy 99.108801 -62.538152) (xy 99.132268 -62.455676) (xy 99.163244 -62.375717) (xy 99.201466 -62.298957)
			(xy 99.246607 -62.226051) (xy 99.298283 -62.157622) (xy 99.356052 -62.094252) (xy 99.419422 -62.036483)
			(xy 99.487851 -61.984807) (xy 99.560757 -61.939666) (xy 99.637517 -61.901444) (xy 99.717476 -61.870468)
			(xy 99.799952 -61.847001) (xy 99.884242 -61.831245) (xy 99.969625 -61.823333) (xy 100.055375 -61.823333)
			(xy 100.140758 -61.831245) (xy 100.225048 -61.847001) (xy 100.307524 -61.870468) (xy 100.387483 -61.901444)
			(xy 100.464243 -61.939666) (xy 100.537149 -61.984807) (xy 100.605578 -62.036483) (xy 100.668948 -62.094252)
			(xy 100.726717 -62.157622) (xy 100.778393 -62.226051) (xy 100.823534 -62.298957) (xy 100.861756 -62.375717)
			(xy 100.892732 -62.455676) (xy 100.916199 -62.538152) (xy 100.931955 -62.622442) (xy 100.939867 -62.707825)
			(xy 100.940362 -62.7507) (xy 100.939867 -62.793575) (xy 101.625133 -62.793575) (xy 101.625133 -62.707825)
			(xy 101.633045 -62.622442) (xy 101.648801 -62.538152) (xy 101.672268 -62.455676) (xy 101.703244 -62.375717)
			(xy 101.741466 -62.298957) (xy 101.786607 -62.226051) (xy 101.838283 -62.157622) (xy 101.896052 -62.094252)
			(xy 101.959422 -62.036483) (xy 102.027851 -61.984807) (xy 102.100757 -61.939666) (xy 102.177517 -61.901444)
			(xy 102.257476 -61.870468) (xy 102.339952 -61.847001) (xy 102.424242 -61.831245) (xy 102.509625 -61.823333)
			(xy 102.595375 -61.823333) (xy 102.680758 -61.831245) (xy 102.765048 -61.847001) (xy 102.847524 -61.870468)
			(xy 102.927483 -61.901444) (xy 103.004243 -61.939666) (xy 103.077149 -61.984807) (xy 103.145578 -62.036483)
			(xy 103.208948 -62.094252) (xy 103.266717 -62.157622) (xy 103.318393 -62.226051) (xy 103.363534 -62.298957)
			(xy 103.401756 -62.375717) (xy 103.432732 -62.455676) (xy 103.456199 -62.538152) (xy 103.471955 -62.622442)
			(xy 103.479867 -62.707825) (xy 103.480362 -62.7507) (xy 103.479867 -62.793575) (xy 104.165133 -62.793575)
			(xy 104.165133 -62.707825) (xy 104.173045 -62.622442) (xy 104.188801 -62.538152) (xy 104.212268 -62.455676)
			(xy 104.243244 -62.375717) (xy 104.281466 -62.298957) (xy 104.326607 -62.226051) (xy 104.378283 -62.157622)
			(xy 104.436052 -62.094252) (xy 104.499422 -62.036483) (xy 104.567851 -61.984807) (xy 104.640757 -61.939666)
			(xy 104.717517 -61.901444) (xy 104.797476 -61.870468) (xy 104.879952 -61.847001) (xy 104.964242 -61.831245)
			(xy 105.049625 -61.823333) (xy 105.135375 -61.823333) (xy 105.220758 -61.831245) (xy 105.305048 -61.847001)
			(xy 105.387524 -61.870468) (xy 105.467483 -61.901444) (xy 105.544243 -61.939666) (xy 105.617149 -61.984807)
			(xy 105.685578 -62.036483) (xy 105.748948 -62.094252) (xy 105.806717 -62.157622) (xy 105.858393 -62.226051)
			(xy 105.903534 -62.298957) (xy 105.941756 -62.375717) (xy 105.972732 -62.455676) (xy 105.996199 -62.538152)
			(xy 106.011955 -62.622442) (xy 106.019867 -62.707825) (xy 106.020362 -62.7507) (xy 106.019867 -62.793575)
			(xy 106.011955 -62.878958) (xy 105.996199 -62.963248) (xy 105.972732 -63.045724) (xy 105.941756 -63.125683)
			(xy 105.903534 -63.202443) (xy 105.858393 -63.275349) (xy 105.806717 -63.343778) (xy 105.748948 -63.407148)
			(xy 105.685578 -63.464917) (xy 105.617149 -63.516593) (xy 105.544243 -63.561734) (xy 105.467483 -63.599956)
			(xy 105.387524 -63.630932) (xy 105.305048 -63.654399) (xy 105.220758 -63.670155) (xy 105.135375 -63.678067)
			(xy 105.049625 -63.678067) (xy 104.964242 -63.670155) (xy 104.879952 -63.654399) (xy 104.797476 -63.630932)
			(xy 104.717517 -63.599956) (xy 104.640757 -63.561734) (xy 104.567851 -63.516593) (xy 104.499422 -63.464917)
			(xy 104.436052 -63.407148) (xy 104.378283 -63.343778) (xy 104.326607 -63.275349) (xy 104.281466 -63.202443)
			(xy 104.243244 -63.125683) (xy 104.212268 -63.045724) (xy 104.188801 -62.963248) (xy 104.173045 -62.878958)
			(xy 104.165133 -62.793575) (xy 103.479867 -62.793575) (xy 103.471955 -62.878958) (xy 103.456199 -62.963248)
			(xy 103.432732 -63.045724) (xy 103.401756 -63.125683) (xy 103.363534 -63.202443) (xy 103.318393 -63.275349)
			(xy 103.266717 -63.343778) (xy 103.208948 -63.407148) (xy 103.145578 -63.464917) (xy 103.077149 -63.516593)
			(xy 103.004243 -63.561734) (xy 102.927483 -63.599956) (xy 102.847524 -63.630932) (xy 102.765048 -63.654399)
			(xy 102.680758 -63.670155) (xy 102.595375 -63.678067) (xy 102.509625 -63.678067) (xy 102.424242 -63.670155)
			(xy 102.339952 -63.654399) (xy 102.257476 -63.630932) (xy 102.177517 -63.599956) (xy 102.100757 -63.561734)
			(xy 102.027851 -63.516593) (xy 101.959422 -63.464917) (xy 101.896052 -63.407148) (xy 101.838283 -63.343778)
			(xy 101.786607 -63.275349) (xy 101.741466 -63.202443) (xy 101.703244 -63.125683) (xy 101.672268 -63.045724)
			(xy 101.648801 -62.963248) (xy 101.633045 -62.878958) (xy 101.625133 -62.793575) (xy 100.939867 -62.793575)
			(xy 100.931955 -62.878958) (xy 100.916199 -62.963248) (xy 100.892732 -63.045724) (xy 100.861756 -63.125683)
			(xy 100.823534 -63.202443) (xy 100.778393 -63.275349) (xy 100.726717 -63.343778) (xy 100.668948 -63.407148)
			(xy 100.605578 -63.464917) (xy 100.537149 -63.516593) (xy 100.464243 -63.561734) (xy 100.387483 -63.599956)
			(xy 100.307524 -63.630932) (xy 100.225048 -63.654399) (xy 100.140758 -63.670155) (xy 100.055375 -63.678067)
			(xy 99.969625 -63.678067) (xy 99.884242 -63.670155) (xy 99.799952 -63.654399) (xy 99.717476 -63.630932)
			(xy 99.637517 -63.599956) (xy 99.560757 -63.561734) (xy 99.487851 -63.516593) (xy 99.419422 -63.464917)
			(xy 99.356052 -63.407148) (xy 99.298283 -63.343778) (xy 99.246607 -63.275349) (xy 99.201466 -63.202443)
			(xy 99.163244 -63.125683) (xy 99.132268 -63.045724) (xy 99.108801 -62.963248) (xy 99.093045 -62.878958)
			(xy 99.085133 -62.793575) (xy 92.50807 -62.793575) (xy 92.50807 -65.982088) (xy 100.659692 -65.982088)
			(xy 101.910388 -65.982088) (xy 101.910388 -66.747644) (xy 100.659692 -66.747644) (xy 100.659692 -65.982088)
			(xy 92.50807 -65.982088) (xy 92.50807 -69.143575) (xy 99.085133 -69.143575) (xy 99.085133 -69.057825)
			(xy 99.093045 -68.972442) (xy 99.108801 -68.888152) (xy 99.132268 -68.805676) (xy 99.163244 -68.725717)
			(xy 99.201466 -68.648957) (xy 99.246607 -68.576051) (xy 99.298283 -68.507622) (xy 99.356052 -68.444252)
			(xy 99.419422 -68.386483) (xy 99.487851 -68.334807) (xy 99.560757 -68.289666) (xy 99.637517 -68.251444)
			(xy 99.717476 -68.220468) (xy 99.799952 -68.197001) (xy 99.884242 -68.181245) (xy 99.969625 -68.173333)
			(xy 100.055375 -68.173333) (xy 100.140758 -68.181245) (xy 100.225048 -68.197001) (xy 100.307524 -68.220468)
			(xy 100.387483 -68.251444) (xy 100.464243 -68.289666) (xy 100.537149 -68.334807) (xy 100.605578 -68.386483)
			(xy 100.668948 -68.444252) (xy 100.726717 -68.507622) (xy 100.778393 -68.576051) (xy 100.823534 -68.648957)
			(xy 100.861756 -68.725717) (xy 100.892732 -68.805676) (xy 100.916199 -68.888152) (xy 100.931955 -68.972442)
			(xy 100.939867 -69.057825) (xy 100.940362 -69.1007) (xy 100.939867 -69.143575) (xy 101.625133 -69.143575)
			(xy 101.625133 -69.057825) (xy 101.633045 -68.972442) (xy 101.648801 -68.888152) (xy 101.672268 -68.805676)
			(xy 101.703244 -68.725717) (xy 101.741466 -68.648957) (xy 101.786607 -68.576051) (xy 101.838283 -68.507622)
			(xy 101.896052 -68.444252) (xy 101.959422 -68.386483) (xy 102.027851 -68.334807) (xy 102.100757 -68.289666)
			(xy 102.177517 -68.251444) (xy 102.257476 -68.220468) (xy 102.339952 -68.197001) (xy 102.424242 -68.181245)
			(xy 102.509625 -68.173333) (xy 102.595375 -68.173333) (xy 102.680758 -68.181245) (xy 102.765048 -68.197001)
			(xy 102.847524 -68.220468) (xy 102.927483 -68.251444) (xy 103.004243 -68.289666) (xy 103.077149 -68.334807)
			(xy 103.145578 -68.386483) (xy 103.208948 -68.444252) (xy 103.266717 -68.507622) (xy 103.318393 -68.576051)
			(xy 103.363534 -68.648957) (xy 103.401756 -68.725717) (xy 103.432732 -68.805676) (xy 103.456199 -68.888152)
			(xy 103.471955 -68.972442) (xy 103.479867 -69.057825) (xy 103.480362 -69.1007) (xy 103.479867 -69.143575)
			(xy 104.165133 -69.143575) (xy 104.165133 -69.057825) (xy 104.173045 -68.972442) (xy 104.188801 -68.888152)
			(xy 104.212268 -68.805676) (xy 104.243244 -68.725717) (xy 104.281466 -68.648957) (xy 104.326607 -68.576051)
			(xy 104.378283 -68.507622) (xy 104.436052 -68.444252) (xy 104.499422 -68.386483) (xy 104.567851 -68.334807)
			(xy 104.640757 -68.289666) (xy 104.717517 -68.251444) (xy 104.797476 -68.220468) (xy 104.879952 -68.197001)
			(xy 104.964242 -68.181245) (xy 105.049625 -68.173333) (xy 105.135375 -68.173333) (xy 105.220758 -68.181245)
			(xy 105.305048 -68.197001) (xy 105.387524 -68.220468) (xy 105.467483 -68.251444) (xy 105.544243 -68.289666)
			(xy 105.617149 -68.334807) (xy 105.685578 -68.386483) (xy 105.748948 -68.444252) (xy 105.806717 -68.507622)
			(xy 105.858393 -68.576051) (xy 105.903534 -68.648957) (xy 105.941756 -68.725717) (xy 105.972732 -68.805676)
			(xy 105.996199 -68.888152) (xy 106.011955 -68.972442) (xy 106.019867 -69.057825) (xy 106.020362 -69.1007)
			(xy 106.019867 -69.143575) (xy 106.011955 -69.228958) (xy 105.996199 -69.313248) (xy 105.972732 -69.395724)
			(xy 105.941756 -69.475683) (xy 105.903534 -69.552443) (xy 105.858393 -69.625349) (xy 105.806717 -69.693778)
			(xy 105.748948 -69.757148) (xy 105.685578 -69.814917) (xy 105.617149 -69.866593) (xy 105.544243 -69.911734)
			(xy 105.467483 -69.949956) (xy 105.387524 -69.980932) (xy 105.305048 -70.004399) (xy 105.220758 -70.020155)
			(xy 105.135375 -70.028067) (xy 105.049625 -70.028067) (xy 104.964242 -70.020155) (xy 104.879952 -70.004399)
			(xy 104.797476 -69.980932) (xy 104.717517 -69.949956) (xy 104.640757 -69.911734) (xy 104.567851 -69.866593)
			(xy 104.499422 -69.814917) (xy 104.436052 -69.757148) (xy 104.378283 -69.693778) (xy 104.326607 -69.625349)
			(xy 104.281466 -69.552443) (xy 104.243244 -69.475683) (xy 104.212268 -69.395724) (xy 104.188801 -69.313248)
			(xy 104.173045 -69.228958) (xy 104.165133 -69.143575) (xy 103.479867 -69.143575) (xy 103.471955 -69.228958)
			(xy 103.456199 -69.313248) (xy 103.432732 -69.395724) (xy 103.401756 -69.475683) (xy 103.363534 -69.552443)
			(xy 103.318393 -69.625349) (xy 103.266717 -69.693778) (xy 103.208948 -69.757148) (xy 103.145578 -69.814917)
			(xy 103.077149 -69.866593) (xy 103.004243 -69.911734) (xy 102.927483 -69.949956) (xy 102.847524 -69.980932)
			(xy 102.765048 -70.004399) (xy 102.680758 -70.020155) (xy 102.595375 -70.028067) (xy 102.509625 -70.028067)
			(xy 102.424242 -70.020155) (xy 102.339952 -70.004399) (xy 102.257476 -69.980932) (xy 102.177517 -69.949956)
			(xy 102.100757 -69.911734) (xy 102.027851 -69.866593) (xy 101.959422 -69.814917) (xy 101.896052 -69.757148)
			(xy 101.838283 -69.693778) (xy 101.786607 -69.625349) (xy 101.741466 -69.552443) (xy 101.703244 -69.475683)
			(xy 101.672268 -69.395724) (xy 101.648801 -69.313248) (xy 101.633045 -69.228958) (xy 101.625133 -69.143575)
			(xy 100.939867 -69.143575) (xy 100.931955 -69.228958) (xy 100.916199 -69.313248) (xy 100.892732 -69.395724)
			(xy 100.861756 -69.475683) (xy 100.823534 -69.552443) (xy 100.778393 -69.625349) (xy 100.726717 -69.693778)
			(xy 100.668948 -69.757148) (xy 100.605578 -69.814917) (xy 100.537149 -69.866593) (xy 100.464243 -69.911734)
			(xy 100.387483 -69.949956) (xy 100.307524 -69.980932) (xy 100.225048 -70.004399) (xy 100.140758 -70.020155)
			(xy 100.055375 -70.028067) (xy 99.969625 -70.028067) (xy 99.884242 -70.020155) (xy 99.799952 -70.004399)
			(xy 99.717476 -69.980932) (xy 99.637517 -69.949956) (xy 99.560757 -69.911734) (xy 99.487851 -69.866593)
			(xy 99.419422 -69.814917) (xy 99.356052 -69.757148) (xy 99.298283 -69.693778) (xy 99.246607 -69.625349)
			(xy 99.201466 -69.552443) (xy 99.163244 -69.475683) (xy 99.132268 -69.395724) (xy 99.108801 -69.313248)
			(xy 99.093045 -69.228958) (xy 99.085133 -69.143575) (xy 92.50807 -69.143575) (xy 92.50807 -94.976137)
			(xy 93.729289 -94.976137) (xy 93.729289 -94.890387) (xy 93.737201 -94.805004) (xy 93.752957 -94.720714)
			(xy 93.776424 -94.638238) (xy 93.8074 -94.558279) (xy 93.845622 -94.481519) (xy 93.890763 -94.408613)
			(xy 93.942439 -94.340184) (xy 94.000208 -94.276814) (xy 94.063578 -94.219045) (xy 94.132007 -94.167369)
			(xy 94.204913 -94.122228) (xy 94.281673 -94.084006) (xy 94.361632 -94.05303) (xy 94.444108 -94.029563)
			(xy 94.528398 -94.013807) (xy 94.613781 -94.005895) (xy 94.699531 -94.005895) (xy 94.784914 -94.013807)
			(xy 94.869204 -94.029563) (xy 94.95168 -94.05303) (xy 95.031639 -94.084006) (xy 95.108399 -94.122228)
			(xy 95.181305 -94.167369) (xy 95.249734 -94.219045) (xy 95.313104 -94.276814) (xy 95.370873 -94.340184)
			(xy 95.422549 -94.408613) (xy 95.46769 -94.481519) (xy 95.505912 -94.558279) (xy 95.536888 -94.638238)
			(xy 95.560355 -94.720714) (xy 95.576111 -94.805004) (xy 95.584023 -94.890387) (xy 95.584518 -94.933262)
			(xy 95.584023 -94.976137) (xy 96.269289 -94.976137) (xy 96.269289 -94.890387) (xy 96.277201 -94.805004)
			(xy 96.292957 -94.720714) (xy 96.316424 -94.638238) (xy 96.3474 -94.558279) (xy 96.385622 -94.481519)
			(xy 96.430763 -94.408613) (xy 96.482439 -94.340184) (xy 96.540208 -94.276814) (xy 96.603578 -94.219045)
			(xy 96.672007 -94.167369) (xy 96.744913 -94.122228) (xy 96.821673 -94.084006) (xy 96.901632 -94.05303)
			(xy 96.984108 -94.029563) (xy 97.068398 -94.013807) (xy 97.153781 -94.005895) (xy 97.239531 -94.005895)
			(xy 97.324914 -94.013807) (xy 97.409204 -94.029563) (xy 97.49168 -94.05303) (xy 97.571639 -94.084006)
			(xy 97.648399 -94.122228) (xy 97.721305 -94.167369) (xy 97.789734 -94.219045) (xy 97.853104 -94.276814)
			(xy 97.910873 -94.340184) (xy 97.962549 -94.408613) (xy 98.00769 -94.481519) (xy 98.045912 -94.558279)
			(xy 98.076888 -94.638238) (xy 98.100355 -94.720714) (xy 98.116111 -94.805004) (xy 98.124023 -94.890387)
			(xy 98.124518 -94.933262) (xy 98.124023 -94.976137) (xy 98.116111 -95.06152) (xy 98.100355 -95.14581)
			(xy 98.076888 -95.228286) (xy 98.045912 -95.308245) (xy 98.00769 -95.385005) (xy 97.962549 -95.457911)
			(xy 97.910873 -95.52634) (xy 97.853104 -95.58971) (xy 97.789734 -95.647479) (xy 97.721305 -95.699155)
			(xy 97.648399 -95.744296) (xy 97.571639 -95.782518) (xy 97.49168 -95.813494) (xy 97.409204 -95.836961)
			(xy 97.324914 -95.852717) (xy 97.239531 -95.860629) (xy 97.153781 -95.860629) (xy 97.068398 -95.852717)
			(xy 96.984108 -95.836961) (xy 96.901632 -95.813494) (xy 96.821673 -95.782518) (xy 96.744913 -95.744296)
			(xy 96.672007 -95.699155) (xy 96.603578 -95.647479) (xy 96.540208 -95.58971) (xy 96.482439 -95.52634)
			(xy 96.430763 -95.457911) (xy 96.385622 -95.385005) (xy 96.3474 -95.308245) (xy 96.316424 -95.228286)
			(xy 96.292957 -95.14581) (xy 96.277201 -95.06152) (xy 96.269289 -94.976137) (xy 95.584023 -94.976137)
			(xy 95.576111 -95.06152) (xy 95.560355 -95.14581) (xy 95.536888 -95.228286) (xy 95.505912 -95.308245)
			(xy 95.46769 -95.385005) (xy 95.422549 -95.457911) (xy 95.370873 -95.52634) (xy 95.313104 -95.58971)
			(xy 95.249734 -95.647479) (xy 95.181305 -95.699155) (xy 95.108399 -95.744296) (xy 95.031639 -95.782518)
			(xy 94.95168 -95.813494) (xy 94.869204 -95.836961) (xy 94.784914 -95.852717) (xy 94.699531 -95.860629)
			(xy 94.613781 -95.860629) (xy 94.528398 -95.852717) (xy 94.444108 -95.836961) (xy 94.361632 -95.813494)
			(xy 94.281673 -95.782518) (xy 94.204913 -95.744296) (xy 94.132007 -95.699155) (xy 94.063578 -95.647479)
			(xy 94.000208 -95.58971) (xy 93.942439 -95.52634) (xy 93.890763 -95.457911) (xy 93.845622 -95.385005)
			(xy 93.8074 -95.308245) (xy 93.776424 -95.228286) (xy 93.752957 -95.14581) (xy 93.737201 -95.06152)
			(xy 93.729289 -94.976137) (xy 92.50807 -94.976137) (xy 92.50807 -96.92259) (xy 95.113348 -96.92259)
			(xy 95.113814 -96.895331) (xy 95.121571 -96.841369) (xy 95.136925 -96.789059) (xy 95.159565 -96.739465)
			(xy 95.189029 -96.693596) (xy 95.224719 -96.652385) (xy 95.265908 -96.61667) (xy 95.311759 -96.587177)
			(xy 95.361339 -96.564507) (xy 95.41364 -96.549121) (xy 95.467598 -96.541331) (xy 95.494856 -96.540828)
			(xy 96.358456 -96.540828) (xy 96.385721 -96.541297) (xy 96.439696 -96.549056) (xy 96.492016 -96.564421)
			(xy 96.541615 -96.587079) (xy 96.587483 -96.61657) (xy 96.628684 -96.652291) (xy 96.664378 -96.693514)
			(xy 96.693839 -96.739401) (xy 96.716465 -96.789015) (xy 96.731797 -96.841345) (xy 96.73952 -96.895325)
			(xy 96.739964 -96.92259) (xy 96.739444 -96.951133) (xy 96.730958 -97.007584) (xy 96.714159 -97.062142)
			(xy 96.689421 -97.113589) (xy 96.657296 -97.160777) (xy 96.618501 -97.202655) (xy 96.573902 -97.238287)
			(xy 96.549464 -97.253044) (xy 96.549464 -98.05162) (xy 95.298768 -98.05162) (xy 95.298768 -97.249996)
			(xy 95.274911 -97.235106) (xy 95.231448 -97.199423) (xy 95.19369 -97.157749) (xy 95.162454 -97.110987)
			(xy 95.138416 -97.060149) (xy 95.122096 -97.006334) (xy 95.113848 -96.950707) (xy 95.113348 -96.92259)
			(xy 92.50807 -96.92259) (xy 92.50807 -101.326137) (xy 93.729289 -101.326137) (xy 93.729289 -101.240387)
			(xy 93.737201 -101.155004) (xy 93.752957 -101.070714) (xy 93.776424 -100.988238) (xy 93.8074 -100.908279)
			(xy 93.845622 -100.831519) (xy 93.890763 -100.758613) (xy 93.942439 -100.690184) (xy 94.000208 -100.626814)
			(xy 94.063578 -100.569045) (xy 94.132007 -100.517369) (xy 94.204913 -100.472228) (xy 94.281673 -100.434006)
			(xy 94.361632 -100.40303) (xy 94.444108 -100.379563) (xy 94.528398 -100.363807) (xy 94.613781 -100.355895)
			(xy 94.699531 -100.355895) (xy 94.784914 -100.363807) (xy 94.869204 -100.379563) (xy 94.95168 -100.40303)
			(xy 95.031639 -100.434006) (xy 95.108399 -100.472228) (xy 95.181305 -100.517369) (xy 95.249734 -100.569045)
			(xy 95.313104 -100.626814) (xy 95.370873 -100.690184) (xy 95.422549 -100.758613) (xy 95.46769 -100.831519)
			(xy 95.505912 -100.908279) (xy 95.536888 -100.988238) (xy 95.560355 -101.070714) (xy 95.576111 -101.155004)
			(xy 95.584023 -101.240387) (xy 95.584518 -101.283262) (xy 95.584023 -101.326137) (xy 96.269289 -101.326137)
			(xy 96.269289 -101.240387) (xy 96.277201 -101.155004) (xy 96.292957 -101.070714) (xy 96.316424 -100.988238)
			(xy 96.3474 -100.908279) (xy 96.385622 -100.831519) (xy 96.430763 -100.758613) (xy 96.482439 -100.690184)
			(xy 96.540208 -100.626814) (xy 96.603578 -100.569045) (xy 96.672007 -100.517369) (xy 96.744913 -100.472228)
			(xy 96.821673 -100.434006) (xy 96.901632 -100.40303) (xy 96.984108 -100.379563) (xy 97.068398 -100.363807)
			(xy 97.153781 -100.355895) (xy 97.239531 -100.355895) (xy 97.324914 -100.363807) (xy 97.409204 -100.379563)
			(xy 97.49168 -100.40303) (xy 97.571639 -100.434006) (xy 97.648399 -100.472228) (xy 97.721305 -100.517369)
			(xy 97.789734 -100.569045) (xy 97.853104 -100.626814) (xy 97.910873 -100.690184) (xy 97.962549 -100.758613)
			(xy 98.00769 -100.831519) (xy 98.045912 -100.908279) (xy 98.076888 -100.988238) (xy 98.100355 -101.070714)
			(xy 98.116111 -101.155004) (xy 98.124023 -101.240387) (xy 98.124518 -101.283262) (xy 98.124023 -101.326137)
			(xy 98.122681 -101.340615) (xy 99.085133 -101.340615) (xy 99.085133 -101.254865) (xy 99.093045 -101.169482)
			(xy 99.108801 -101.085192) (xy 99.132268 -101.002716) (xy 99.163244 -100.922757) (xy 99.201466 -100.845997)
			(xy 99.246607 -100.773091) (xy 99.298283 -100.704662) (xy 99.356052 -100.641292) (xy 99.419422 -100.583523)
			(xy 99.487851 -100.531847) (xy 99.560757 -100.486706) (xy 99.637517 -100.448484) (xy 99.717476 -100.417508)
			(xy 99.799952 -100.394041) (xy 99.884242 -100.378285) (xy 99.969625 -100.370373) (xy 100.055375 -100.370373)
			(xy 100.140758 -100.378285) (xy 100.225048 -100.394041) (xy 100.307524 -100.417508) (xy 100.387483 -100.448484)
			(xy 100.464243 -100.486706) (xy 100.537149 -100.531847) (xy 100.605578 -100.583523) (xy 100.668948 -100.641292)
			(xy 100.726717 -100.704662) (xy 100.778393 -100.773091) (xy 100.823534 -100.845997) (xy 100.861756 -100.922757)
			(xy 100.892732 -101.002716) (xy 100.916199 -101.085192) (xy 100.931955 -101.169482) (xy 100.939867 -101.254865)
			(xy 100.940362 -101.29774) (xy 100.939867 -101.340615) (xy 101.625133 -101.340615) (xy 101.625133 -101.254865)
			(xy 101.633045 -101.169482) (xy 101.648801 -101.085192) (xy 101.672268 -101.002716) (xy 101.703244 -100.922757)
			(xy 101.741466 -100.845997) (xy 101.786607 -100.773091) (xy 101.838283 -100.704662) (xy 101.896052 -100.641292)
			(xy 101.959422 -100.583523) (xy 102.027851 -100.531847) (xy 102.100757 -100.486706) (xy 102.177517 -100.448484)
			(xy 102.257476 -100.417508) (xy 102.339952 -100.394041) (xy 102.424242 -100.378285) (xy 102.509625 -100.370373)
			(xy 102.595375 -100.370373) (xy 102.680758 -100.378285) (xy 102.765048 -100.394041) (xy 102.847524 -100.417508)
			(xy 102.927483 -100.448484) (xy 103.004243 -100.486706) (xy 103.077149 -100.531847) (xy 103.145578 -100.583523)
			(xy 103.208948 -100.641292) (xy 103.266717 -100.704662) (xy 103.318393 -100.773091) (xy 103.363534 -100.845997)
			(xy 103.401756 -100.922757) (xy 103.432732 -101.002716) (xy 103.456199 -101.085192) (xy 103.471955 -101.169482)
			(xy 103.479867 -101.254865) (xy 103.480362 -101.29774) (xy 103.479867 -101.340615) (xy 104.165133 -101.340615)
			(xy 104.165133 -101.254865) (xy 104.173045 -101.169482) (xy 104.188801 -101.085192) (xy 104.212268 -101.002716)
			(xy 104.243244 -100.922757) (xy 104.281466 -100.845997) (xy 104.326607 -100.773091) (xy 104.378283 -100.704662)
			(xy 104.436052 -100.641292) (xy 104.499422 -100.583523) (xy 104.567851 -100.531847) (xy 104.640757 -100.486706)
			(xy 104.717517 -100.448484) (xy 104.797476 -100.417508) (xy 104.879952 -100.394041) (xy 104.964242 -100.378285)
			(xy 105.049625 -100.370373) (xy 105.135375 -100.370373) (xy 105.220758 -100.378285) (xy 105.305048 -100.394041)
			(xy 105.387524 -100.417508) (xy 105.467483 -100.448484) (xy 105.544243 -100.486706) (xy 105.617149 -100.531847)
			(xy 105.685578 -100.583523) (xy 105.748948 -100.641292) (xy 105.806717 -100.704662) (xy 105.858393 -100.773091)
			(xy 105.903534 -100.845997) (xy 105.941756 -100.922757) (xy 105.972732 -101.002716) (xy 105.996199 -101.085192)
			(xy 106.011955 -101.169482) (xy 106.019867 -101.254865) (xy 106.020362 -101.29774) (xy 106.019867 -101.340615)
			(xy 106.011955 -101.425998) (xy 105.996199 -101.510288) (xy 105.972732 -101.592764) (xy 105.941756 -101.672723)
			(xy 105.903534 -101.749483) (xy 105.858393 -101.822389) (xy 105.806717 -101.890818) (xy 105.748948 -101.954188)
			(xy 105.685578 -102.011957) (xy 105.617149 -102.063633) (xy 105.544243 -102.108774) (xy 105.467483 -102.146996)
			(xy 105.387524 -102.177972) (xy 105.305048 -102.201439) (xy 105.220758 -102.217195) (xy 105.135375 -102.225107)
			(xy 105.049625 -102.225107) (xy 104.964242 -102.217195) (xy 104.879952 -102.201439) (xy 104.797476 -102.177972)
			(xy 104.717517 -102.146996) (xy 104.640757 -102.108774) (xy 104.567851 -102.063633) (xy 104.499422 -102.011957)
			(xy 104.436052 -101.954188) (xy 104.378283 -101.890818) (xy 104.326607 -101.822389) (xy 104.281466 -101.749483)
			(xy 104.243244 -101.672723) (xy 104.212268 -101.592764) (xy 104.188801 -101.510288) (xy 104.173045 -101.425998)
			(xy 104.165133 -101.340615) (xy 103.479867 -101.340615) (xy 103.471955 -101.425998) (xy 103.456199 -101.510288)
			(xy 103.432732 -101.592764) (xy 103.401756 -101.672723) (xy 103.363534 -101.749483) (xy 103.318393 -101.822389)
			(xy 103.266717 -101.890818) (xy 103.208948 -101.954188) (xy 103.145578 -102.011957) (xy 103.077149 -102.063633)
			(xy 103.004243 -102.108774) (xy 102.927483 -102.146996) (xy 102.847524 -102.177972) (xy 102.765048 -102.201439)
			(xy 102.680758 -102.217195) (xy 102.595375 -102.225107) (xy 102.509625 -102.225107) (xy 102.424242 -102.217195)
			(xy 102.339952 -102.201439) (xy 102.257476 -102.177972) (xy 102.177517 -102.146996) (xy 102.100757 -102.108774)
			(xy 102.027851 -102.063633) (xy 101.959422 -102.011957) (xy 101.896052 -101.954188) (xy 101.838283 -101.890818)
			(xy 101.786607 -101.822389) (xy 101.741466 -101.749483) (xy 101.703244 -101.672723) (xy 101.672268 -101.592764)
			(xy 101.648801 -101.510288) (xy 101.633045 -101.425998) (xy 101.625133 -101.340615) (xy 100.939867 -101.340615)
			(xy 100.931955 -101.425998) (xy 100.916199 -101.510288) (xy 100.892732 -101.592764) (xy 100.861756 -101.672723)
			(xy 100.823534 -101.749483) (xy 100.778393 -101.822389) (xy 100.726717 -101.890818) (xy 100.668948 -101.954188)
			(xy 100.605578 -102.011957) (xy 100.537149 -102.063633) (xy 100.464243 -102.108774) (xy 100.387483 -102.146996)
			(xy 100.307524 -102.177972) (xy 100.225048 -102.201439) (xy 100.140758 -102.217195) (xy 100.055375 -102.225107)
			(xy 99.969625 -102.225107) (xy 99.884242 -102.217195) (xy 99.799952 -102.201439) (xy 99.717476 -102.177972)
			(xy 99.637517 -102.146996) (xy 99.560757 -102.108774) (xy 99.487851 -102.063633) (xy 99.419422 -102.011957)
			(xy 99.356052 -101.954188) (xy 99.298283 -101.890818) (xy 99.246607 -101.822389) (xy 99.201466 -101.749483)
			(xy 99.163244 -101.672723) (xy 99.132268 -101.592764) (xy 99.108801 -101.510288) (xy 99.093045 -101.425998)
			(xy 99.085133 -101.340615) (xy 98.122681 -101.340615) (xy 98.116111 -101.41152) (xy 98.100355 -101.49581)
			(xy 98.076888 -101.578286) (xy 98.045912 -101.658245) (xy 98.00769 -101.735005) (xy 97.962549 -101.807911)
			(xy 97.910873 -101.87634) (xy 97.853104 -101.93971) (xy 97.789734 -101.997479) (xy 97.721305 -102.049155)
			(xy 97.648399 -102.094296) (xy 97.571639 -102.132518) (xy 97.49168 -102.163494) (xy 97.409204 -102.186961)
			(xy 97.324914 -102.202717) (xy 97.239531 -102.210629) (xy 97.153781 -102.210629) (xy 97.068398 -102.202717)
			(xy 96.984108 -102.186961) (xy 96.901632 -102.163494) (xy 96.821673 -102.132518) (xy 96.744913 -102.094296)
			(xy 96.672007 -102.049155) (xy 96.603578 -101.997479) (xy 96.540208 -101.93971) (xy 96.482439 -101.87634)
			(xy 96.430763 -101.807911) (xy 96.385622 -101.735005) (xy 96.3474 -101.658245) (xy 96.316424 -101.578286)
			(xy 96.292957 -101.49581) (xy 96.277201 -101.41152) (xy 96.269289 -101.326137) (xy 95.584023 -101.326137)
			(xy 95.576111 -101.41152) (xy 95.560355 -101.49581) (xy 95.536888 -101.578286) (xy 95.505912 -101.658245)
			(xy 95.46769 -101.735005) (xy 95.422549 -101.807911) (xy 95.370873 -101.87634) (xy 95.313104 -101.93971)
			(xy 95.249734 -101.997479) (xy 95.181305 -102.049155) (xy 95.108399 -102.094296) (xy 95.031639 -102.132518)
			(xy 94.95168 -102.163494) (xy 94.869204 -102.186961) (xy 94.784914 -102.202717) (xy 94.699531 -102.210629)
			(xy 94.613781 -102.210629) (xy 94.528398 -102.202717) (xy 94.444108 -102.186961) (xy 94.361632 -102.163494)
			(xy 94.281673 -102.132518) (xy 94.204913 -102.094296) (xy 94.132007 -102.049155) (xy 94.063578 -101.997479)
			(xy 94.000208 -101.93971) (xy 93.942439 -101.87634) (xy 93.890763 -101.807911) (xy 93.845622 -101.735005)
			(xy 93.8074 -101.658245) (xy 93.776424 -101.578286) (xy 93.752957 -101.49581) (xy 93.737201 -101.41152)
			(xy 93.729289 -101.326137) (xy 92.50807 -101.326137) (xy 92.50807 -103.650796) (xy 100.654612 -103.650796)
			(xy 101.905308 -103.650796) (xy 101.905308 -104.416352) (xy 100.654612 -104.416352) (xy 100.654612 -103.650796)
			(xy 92.50807 -103.650796) (xy 92.50807 -107.690615) (xy 99.085133 -107.690615) (xy 99.085133 -107.604865)
			(xy 99.093045 -107.519482) (xy 99.108801 -107.435192) (xy 99.132268 -107.352716) (xy 99.163244 -107.272757)
			(xy 99.201466 -107.195997) (xy 99.246607 -107.123091) (xy 99.298283 -107.054662) (xy 99.356052 -106.991292)
			(xy 99.419422 -106.933523) (xy 99.487851 -106.881847) (xy 99.560757 -106.836706) (xy 99.637517 -106.798484)
			(xy 99.717476 -106.767508) (xy 99.799952 -106.744041) (xy 99.884242 -106.728285) (xy 99.969625 -106.720373)
			(xy 100.055375 -106.720373) (xy 100.140758 -106.728285) (xy 100.225048 -106.744041) (xy 100.307524 -106.767508)
			(xy 100.387483 -106.798484) (xy 100.464243 -106.836706) (xy 100.537149 -106.881847) (xy 100.605578 -106.933523)
			(xy 100.668948 -106.991292) (xy 100.726717 -107.054662) (xy 100.778393 -107.123091) (xy 100.823534 -107.195997)
			(xy 100.861756 -107.272757) (xy 100.892732 -107.352716) (xy 100.916199 -107.435192) (xy 100.931955 -107.519482)
			(xy 100.939867 -107.604865) (xy 100.940362 -107.64774) (xy 100.939867 -107.690615) (xy 101.625133 -107.690615)
			(xy 101.625133 -107.604865) (xy 101.633045 -107.519482) (xy 101.648801 -107.435192) (xy 101.672268 -107.352716)
			(xy 101.703244 -107.272757) (xy 101.741466 -107.195997) (xy 101.786607 -107.123091) (xy 101.838283 -107.054662)
			(xy 101.896052 -106.991292) (xy 101.959422 -106.933523) (xy 102.027851 -106.881847) (xy 102.100757 -106.836706)
			(xy 102.177517 -106.798484) (xy 102.257476 -106.767508) (xy 102.339952 -106.744041) (xy 102.424242 -106.728285)
			(xy 102.509625 -106.720373) (xy 102.595375 -106.720373) (xy 102.680758 -106.728285) (xy 102.765048 -106.744041)
			(xy 102.847524 -106.767508) (xy 102.927483 -106.798484) (xy 103.004243 -106.836706) (xy 103.077149 -106.881847)
			(xy 103.145578 -106.933523) (xy 103.208948 -106.991292) (xy 103.266717 -107.054662) (xy 103.318393 -107.123091)
			(xy 103.363534 -107.195997) (xy 103.401756 -107.272757) (xy 103.432732 -107.352716) (xy 103.456199 -107.435192)
			(xy 103.471955 -107.519482) (xy 103.479867 -107.604865) (xy 103.480362 -107.64774) (xy 103.479867 -107.690615)
			(xy 104.165133 -107.690615) (xy 104.165133 -107.604865) (xy 104.173045 -107.519482) (xy 104.188801 -107.435192)
			(xy 104.212268 -107.352716) (xy 104.243244 -107.272757) (xy 104.281466 -107.195997) (xy 104.326607 -107.123091)
			(xy 104.378283 -107.054662) (xy 104.436052 -106.991292) (xy 104.499422 -106.933523) (xy 104.567851 -106.881847)
			(xy 104.640757 -106.836706) (xy 104.717517 -106.798484) (xy 104.797476 -106.767508) (xy 104.879952 -106.744041)
			(xy 104.964242 -106.728285) (xy 105.049625 -106.720373) (xy 105.135375 -106.720373) (xy 105.220758 -106.728285)
			(xy 105.305048 -106.744041) (xy 105.387524 -106.767508) (xy 105.467483 -106.798484) (xy 105.544243 -106.836706)
			(xy 105.617149 -106.881847) (xy 105.685578 -106.933523) (xy 105.748948 -106.991292) (xy 105.806717 -107.054662)
			(xy 105.858393 -107.123091) (xy 105.903534 -107.195997) (xy 105.941756 -107.272757) (xy 105.972732 -107.352716)
			(xy 105.996199 -107.435192) (xy 106.011955 -107.519482) (xy 106.019867 -107.604865) (xy 106.020362 -107.64774)
			(xy 106.019867 -107.690615) (xy 106.011955 -107.775998) (xy 105.996199 -107.860288) (xy 105.972732 -107.942764)
			(xy 105.941756 -108.022723) (xy 105.903534 -108.099483) (xy 105.858393 -108.172389) (xy 105.806717 -108.240818)
			(xy 105.748948 -108.304188) (xy 105.685578 -108.361957) (xy 105.617149 -108.413633) (xy 105.544243 -108.458774)
			(xy 105.467483 -108.496996) (xy 105.387524 -108.527972) (xy 105.305048 -108.551439) (xy 105.220758 -108.567195)
			(xy 105.135375 -108.575107) (xy 105.049625 -108.575107) (xy 104.964242 -108.567195) (xy 104.879952 -108.551439)
			(xy 104.797476 -108.527972) (xy 104.717517 -108.496996) (xy 104.640757 -108.458774) (xy 104.567851 -108.413633)
			(xy 104.499422 -108.361957) (xy 104.436052 -108.304188) (xy 104.378283 -108.240818) (xy 104.326607 -108.172389)
			(xy 104.281466 -108.099483) (xy 104.243244 -108.022723) (xy 104.212268 -107.942764) (xy 104.188801 -107.860288)
			(xy 104.173045 -107.775998) (xy 104.165133 -107.690615) (xy 103.479867 -107.690615) (xy 103.471955 -107.775998)
			(xy 103.456199 -107.860288) (xy 103.432732 -107.942764) (xy 103.401756 -108.022723) (xy 103.363534 -108.099483)
			(xy 103.318393 -108.172389) (xy 103.266717 -108.240818) (xy 103.208948 -108.304188) (xy 103.145578 -108.361957)
			(xy 103.077149 -108.413633) (xy 103.004243 -108.458774) (xy 102.927483 -108.496996) (xy 102.847524 -108.527972)
			(xy 102.765048 -108.551439) (xy 102.680758 -108.567195) (xy 102.595375 -108.575107) (xy 102.509625 -108.575107)
			(xy 102.424242 -108.567195) (xy 102.339952 -108.551439) (xy 102.257476 -108.527972) (xy 102.177517 -108.496996)
			(xy 102.100757 -108.458774) (xy 102.027851 -108.413633) (xy 101.959422 -108.361957) (xy 101.896052 -108.304188)
			(xy 101.838283 -108.240818) (xy 101.786607 -108.172389) (xy 101.741466 -108.099483) (xy 101.703244 -108.022723)
			(xy 101.672268 -107.942764) (xy 101.648801 -107.860288) (xy 101.633045 -107.775998) (xy 101.625133 -107.690615)
			(xy 100.939867 -107.690615) (xy 100.931955 -107.775998) (xy 100.916199 -107.860288) (xy 100.892732 -107.942764)
			(xy 100.861756 -108.022723) (xy 100.823534 -108.099483) (xy 100.778393 -108.172389) (xy 100.726717 -108.240818)
			(xy 100.668948 -108.304188) (xy 100.605578 -108.361957) (xy 100.537149 -108.413633) (xy 100.464243 -108.458774)
			(xy 100.387483 -108.496996) (xy 100.307524 -108.527972) (xy 100.225048 -108.551439) (xy 100.140758 -108.567195)
			(xy 100.055375 -108.575107) (xy 99.969625 -108.575107) (xy 99.884242 -108.567195) (xy 99.799952 -108.551439)
			(xy 99.717476 -108.527972) (xy 99.637517 -108.496996) (xy 99.560757 -108.458774) (xy 99.487851 -108.413633)
			(xy 99.419422 -108.361957) (xy 99.356052 -108.304188) (xy 99.298283 -108.240818) (xy 99.246607 -108.172389)
			(xy 99.201466 -108.099483) (xy 99.163244 -108.022723) (xy 99.132268 -107.942764) (xy 99.108801 -107.860288)
			(xy 99.093045 -107.775998) (xy 99.085133 -107.690615) (xy 92.50807 -107.690615) (xy 92.50807 -115.464644)
			(xy 115.904253 -115.464644) (xy 115.904253 -115.335504) (xy 115.912203 -115.206609) (xy 115.928073 -115.078449)
			(xy 115.951802 -114.951508) (xy 115.983301 -114.826269) (xy 116.02245 -114.703206) (xy 116.069101 -114.582787)
			(xy 116.123076 -114.465468) (xy 116.184171 -114.351694) (xy 116.252154 -114.241897) (xy 116.326768 -114.136494)
			(xy 116.407729 -114.035884) (xy 116.494729 -113.940449) (xy 116.58744 -113.85055) (xy 116.68551 -113.766529)
			(xy 116.788565 -113.688705) (xy 116.896216 -113.617373) (xy 117.008055 -113.552803) (xy 117.123656 -113.495241)
			(xy 117.242581 -113.444904) (xy 117.36438 -113.401984) (xy 117.48859 -113.366643) (xy 117.614739 -113.339016)
			(xy 117.742351 -113.319207) (xy 117.87094 -113.307291) (xy 118.000018 -113.303315) (xy 118.129096 -113.307291)
			(xy 118.257685 -113.319207) (xy 118.385297 -113.339016) (xy 118.511446 -113.366643) (xy 118.635656 -113.401984)
			(xy 118.757455 -113.444904) (xy 118.87638 -113.495241) (xy 118.991981 -113.552803) (xy 119.10382 -113.617373)
			(xy 119.211471 -113.688705) (xy 119.314526 -113.766529) (xy 119.412596 -113.85055) (xy 119.505307 -113.940449)
			(xy 119.592307 -114.035884) (xy 119.673268 -114.136494) (xy 119.747882 -114.241897) (xy 119.815865 -114.351694)
			(xy 119.87696 -114.465468) (xy 119.930935 -114.582787) (xy 119.977586 -114.703206) (xy 120.016735 -114.826269)
			(xy 120.048234 -114.951508) (xy 120.071963 -115.078449) (xy 120.087833 -115.206609) (xy 120.095783 -115.335504)
			(xy 120.09628 -115.400074) (xy 120.095783 -115.464644) (xy 120.087833 -115.593539) (xy 120.071963 -115.721699)
			(xy 120.048234 -115.84864) (xy 120.016735 -115.973879) (xy 119.977586 -116.096942) (xy 119.930935 -116.217361)
			(xy 119.87696 -116.33468) (xy 119.815865 -116.448454) (xy 119.747882 -116.558251) (xy 119.673268 -116.663654)
			(xy 119.592307 -116.764264) (xy 119.505307 -116.859699) (xy 119.412596 -116.949598) (xy 119.314526 -117.033619)
			(xy 119.211471 -117.111443) (xy 119.10382 -117.182775) (xy 118.991981 -117.247345) (xy 118.87638 -117.304907)
			(xy 118.757455 -117.355244) (xy 118.635656 -117.398164) (xy 118.511446 -117.433505) (xy 118.385297 -117.461132)
			(xy 118.257685 -117.480941) (xy 118.129096 -117.492857) (xy 118.000018 -117.496834) (xy 117.87094 -117.492857)
			(xy 117.742351 -117.480941) (xy 117.614739 -117.461132) (xy 117.48859 -117.433505) (xy 117.36438 -117.398164)
			(xy 117.242581 -117.355244) (xy 117.123656 -117.304907) (xy 117.008055 -117.247345) (xy 116.896216 -117.182775)
			(xy 116.788565 -117.111443) (xy 116.68551 -117.033619) (xy 116.58744 -116.949598) (xy 116.494729 -116.859699)
			(xy 116.407729 -116.764264) (xy 116.326768 -116.663654) (xy 116.252154 -116.558251) (xy 116.184171 -116.448454)
			(xy 116.123076 -116.33468) (xy 116.069101 -116.217361) (xy 116.02245 -116.096942) (xy 115.983301 -115.973879)
			(xy 115.951802 -115.84864) (xy 115.928073 -115.721699) (xy 115.912203 -115.593539) (xy 115.904253 -115.464644)
			(xy 92.50807 -115.464644) (xy 92.50807 -118.400068) (xy 92.508591 -118.455876) (xy 92.516929 -118.567181)
			(xy 92.533562 -118.677551) (xy 92.558397 -118.78637) (xy 92.591294 -118.893028) (xy 92.63207 -118.99693)
			(xy 92.680497 -119.097494) (xy 92.736303 -119.194158) (xy 92.799176 -119.286381) (xy 92.868766 -119.373648)
			(xy 92.944683 -119.45547) (xy 93.026502 -119.531391) (xy 93.113766 -119.600984) (xy 93.205986 -119.663862)
			(xy 93.302648 -119.719673) (xy 93.40321 -119.768103) (xy 93.50711 -119.808884) (xy 93.613767 -119.841786)
			(xy 93.722584 -119.866625) (xy 93.832954 -119.883263) (xy 93.944258 -119.891607) (xy 94.000066 -119.892064)
		)
		(stroke
			(width 0)
			(type solid)
		)
		(fill yes)
		(layer "In1.Cu")
		(net "GND_P1")
	)
	(gr_poly
		(pts
			(xy 22.70379 -79.435198) (xy 22.70379 -76.3016) (xy 21.81352 -75.41133) (xy 19.096228 -75.41133)
			(xy 18.927064 -75.580494) (xy 18.927064 -79.031592) (xy 19.408902 -79.51343) (xy 22.625558 -79.51343)
		)
		(stroke
			(width 0)
			(type solid)
		)
		(fill yes)
		(layer "In2.Cu")
		(net "GND")
	)
	(gr_poly
		(pts
			(xy 80.255364 -118.737634) (xy 80.255364 -115.252754) (xy 80.174338 -115.171728) (xy 79.865474 -115.171728)
			(xy 79.748126 -115.289076) (xy 79.748126 -118.718584) (xy 79.85379 -118.824248) (xy 80.16875 -118.824248)
		)
		(stroke
			(width 0)
			(type solid)
		)
		(fill yes)
		(layer "In2.Cu")
		(net "GND")
	)
	(gr_poly
		(pts
			(xy 76.221844 -117.139466) (xy 76.221844 -113.814098) (xy 76.859892 -113.17605) (xy 83.762342 -113.17605)
			(xy 84.430616 -112.507776)
			(arc
				(start 84.430616 -110.06836)
				(mid 84.427244 -110.00096)
				(end 84.426044 -109.933486)
			)
			(arc
				(start 84.426044 -109.933486)
				(mid 84.427245 -109.866012)
				(end 84.430616 -109.798612)
			)
			(xy 84.430616 -109.038136) (xy 85.68817 -107.780582) (xy 85.68817 -103.115364) (xy 85.536024 -102.963218)
			(xy 80.373982 -102.963218) (xy 79.7687 -103.5685) (xy 79.7687 -109.309662) (xy 78.227174 -110.851188)
			(xy 75.244706 -110.851188) (xy 74.866246 -111.229648) (xy 74.866246 -117.131846) (xy 74.977498 -117.243098)
			(xy 76.118212 -117.243098)
		)
		(stroke
			(width 0)
			(type solid)
		)
		(fill yes)
		(layer "In2.Cu")
		(net "P12V_AUX")
	)
	(gr_poly
		(pts
			(arc
				(start 15.526512 -79.970122)
				(mid 15.238476 -79.970122)
				(end 15.526512 -79.970122)
			)
		)
		(stroke
			(width 0)
			(type solid)
		)
		(fill yes)
		(layer "In2.Cu")
		(net "GND")
	)
	(gr_poly
		(pts
			(xy 58.76417 -29.063188) (xy 58.76417 -28.445714)
			(arc
				(start 58.726324 -28.435808)
				(mid 58.442939 -28.067)
				(end 58.726324 -27.698192)
			)
			(xy 58.76417 -27.688286) (xy 58.76417 -26.814018) (xy 58.711084 -26.760932) (xy 58.565796 -26.760932)
			(xy 58.563764 -26.7589) (xy 55.583582 -26.7589) (xy 55.359808 -26.982674) (xy 55.359808 -27.601672)
			(xy 55.62346 -27.86507) (xy 55.62346 -29.101034) (xy 55.703978 -29.181552) (xy 58.645552 -29.181552)
		)
		(stroke
			(width 0)
			(type solid)
		)
		(fill yes)
		(layer "In2.Cu")
		(net "GND")
	)
	(gr_poly
		(pts
			(xy 10.257028 -118.783354)
			(arc
				(start 10.257028 -114.799872)
				(mid 10.552301 -114.087273)
				(end 11.2649 -113.792)
			)
			(xy 11.677904 -113.792) (xy 11.769344 -113.70056) (xy 11.769344 -113.376456) (xy 11.677396 -113.284508)
			(arc
				(start 11.2649 -113.284508)
				(mid 10.193376 -113.728348)
				(end 9.749536 -114.799872)
			)
			(xy 9.749536 -118.76532) (xy 9.862312 -118.878096) (xy 10.162286 -118.878096)
		)
		(stroke
			(width 0)
			(type solid)
		)
		(fill yes)
		(layer "In2.Cu")
		(net "GND")
	)
	(gr_poly
		(pts
			(xy 40.775636 -57.70372) (xy 40.775636 -56.356504) (xy 40.776218 -56.329655) (xy 40.785889 -56.276835)
			(xy 40.804917 -56.22662) (xy 40.818308 -56.203342) (xy 40.820554 -56.176968) (xy 40.831412 -56.125161)
			(xy 40.84933 -56.075354) (xy 40.873963 -56.028503) (xy 40.904839 -55.985509) (xy 40.941364 -55.947198)
			(xy 40.982836 -55.914307) (xy 41.028459 -55.887466) (xy 41.05275 -55.876952) (xy 41.062148 -55.873142)
			(xy 41.09085 -55.84444) (xy 41.474644 -55.84444) (xy 41.58615 -55.732934) (xy 41.58615 -55.39867)
			(xy 41.502076 -55.314596) (xy 40.894762 -55.314596) (xy 39.919402 -54.339236) (xy 39.526464 -54.339236)
			(xy 39.512849 -54.339674) (xy 39.486589 -54.346878) (xy 39.463165 -54.360765) (xy 39.444243 -54.380346)
			(xy 39.431167 -54.404232) (xy 39.424866 -54.430723) (xy 39.425789 -54.457938) (xy 39.429436 -54.471062)
			(xy 39.437509 -54.498749) (xy 39.446185 -54.555764) (xy 39.446708 -54.5846) (xy 39.44619 -54.613304)
			(xy 39.437591 -54.670064) (xy 39.420586 -54.724896) (xy 39.39556 -54.776562) (xy 39.363078 -54.823897)
			(xy 39.343838 -54.845204) (xy 39.334071 -54.856403) (xy 39.320888 -54.883018) (xy 39.315912 -54.9123)
			(xy 39.319565 -54.941776) (xy 39.331538 -54.968958) (xy 39.34079 -54.980586) (xy 39.357999 -55.001401)
			(xy 39.38699 -55.046968) (xy 39.40926 -55.09617) (xy 39.424365 -55.148022) (xy 39.432001 -55.201486)
			(xy 39.432484 -55.22849) (xy 39.431998 -55.255741) (xy 39.424242 -55.309689) (xy 39.408887 -55.361984)
			(xy 39.386245 -55.411561) (xy 39.356779 -55.457411) (xy 39.321088 -55.498602) (xy 39.279897 -55.534293)
			(xy 39.234047 -55.563759) (xy 39.18447 -55.586401) (xy 39.132175 -55.601756) (xy 39.078227 -55.609512)
			(xy 39.023725 -55.609512) (xy 38.969777 -55.601756) (xy 38.917482 -55.586401) (xy 38.867905 -55.563759)
			(xy 38.822055 -55.534293) (xy 38.780864 -55.498602) (xy 38.745173 -55.457411) (xy 38.715707 -55.411561)
			(xy 38.693065 -55.361984) (xy 38.67771 -55.309689) (xy 38.669954 -55.255741) (xy 38.669468 -55.22849)
			(xy 38.669987 -55.199787) (xy 38.678589 -55.143029) (xy 38.695597 -55.0882) (xy 38.720628 -55.036538)
			(xy 38.753116 -54.989209) (xy 38.772338 -54.967886) (xy 38.782097 -54.956684) (xy 38.795268 -54.930069)
			(xy 38.800237 -54.900792) (xy 38.796585 -54.871322) (xy 38.78462 -54.844143) (xy 38.775386 -54.832504)
			(xy 38.757107 -54.810369) (xy 38.726712 -54.761673) (xy 38.703947 -54.708976) (xy 38.689327 -54.653466)
			(xy 38.685724 -54.624986) (xy 38.683611 -54.610194) (xy 38.67197 -54.58269) (xy 38.652867 -54.559733)
			(xy 38.627936 -54.543288) (xy 38.599313 -54.534762) (xy 38.584378 -54.534308) (xy 38.5826 -54.534308)
			(xy 38.553699 -54.533774) (xy 38.496558 -54.525052) (xy 38.441388 -54.507808) (xy 38.389452 -54.482436)
			(xy 38.341938 -54.449518) (xy 38.299936 -54.409808) (xy 38.264407 -54.364214) (xy 38.24986 -54.339236)
			(xy 35.451288 -54.339236) (xy 35.439604 -54.374034) (xy 35.430316 -54.400561) (xy 35.405048 -54.450765)
			(xy 35.372688 -54.496717) (xy 35.333935 -54.537424) (xy 35.289628 -54.572003) (xy 35.240726 -54.599707)
			(xy 35.188289 -54.619935) (xy 35.133451 -54.63225) (xy 35.0774 -54.636385) (xy 35.021349 -54.63225)
			(xy 34.966511 -54.619935) (xy 34.914074 -54.599707) (xy 34.865172 -54.572003) (xy 34.820865 -54.537424)
			(xy 34.782112 -54.496717) (xy 34.749752 -54.450765) (xy 34.724484 -54.400561) (xy 34.715196 -54.374034)
			(xy 34.703512 -54.339236) (xy 33.671764 -54.339236) (xy 33.274 -54.737) (xy 33.274 -54.9402) (xy 35.762182 -54.9402)
			(xy 35.766253 -54.884578) (xy 35.778379 -54.830141) (xy 35.798302 -54.77805) (xy 35.825598 -54.729415)
			(xy 35.859684 -54.685272) (xy 35.899833 -54.646563) (xy 35.945191 -54.614112) (xy 35.994791 -54.588611)
			(xy 36.047575 -54.570604) (xy 36.102418 -54.560474) (xy 36.158152 -54.558437) (xy 36.213589 -54.564537)
			(xy 36.267546 -54.578643) (xy 36.318875 -54.600455) (xy 36.366481 -54.629509) (xy 36.409349 -54.665184)
			(xy 36.446566 -54.706721) (xy 36.477339 -54.753234) (xy 36.501011 -54.803731) (xy 36.517079 -54.857138)
			(xy 36.525199 -54.912314) (xy 36.525708 -54.9402) (xy 36.525476 -54.9529) (xy 36.701982 -54.9529)
			(xy 36.706053 -54.897278) (xy 36.718179 -54.842841) (xy 36.738102 -54.79075) (xy 36.765398 -54.742115)
			(xy 36.799484 -54.697972) (xy 36.839633 -54.659263) (xy 36.884991 -54.626812) (xy 36.934591 -54.601311)
			(xy 36.987375 -54.583304) (xy 37.042218 -54.573174) (xy 37.097952 -54.571137) (xy 37.153389 -54.577237)
			(xy 37.207346 -54.591343) (xy 37.258675 -54.613155) (xy 37.306281 -54.642209) (xy 37.349149 -54.677884)
			(xy 37.386366 -54.719421) (xy 37.417139 -54.765934) (xy 37.440811 -54.816431) (xy 37.456879 -54.869838)
			(xy 37.464999 -54.925014) (xy 37.465508 -54.9529) (xy 37.464999 -54.980786) (xy 37.456879 -55.035962)
			(xy 37.440811 -55.089369) (xy 37.417139 -55.139866) (xy 37.386366 -55.186379) (xy 37.349149 -55.227916)
			(xy 37.306281 -55.263591) (xy 37.258675 -55.292645) (xy 37.207346 -55.314457) (xy 37.153389 -55.328563)
			(xy 37.097952 -55.334663) (xy 37.042218 -55.332626) (xy 36.987375 -55.322496) (xy 36.934591 -55.304489)
			(xy 36.884991 -55.278988) (xy 36.839633 -55.246537) (xy 36.799484 -55.207828) (xy 36.765398 -55.163685)
			(xy 36.738102 -55.11505) (xy 36.718179 -55.062959) (xy 36.706053 -55.008522) (xy 36.701982 -54.9529)
			(xy 36.525476 -54.9529) (xy 36.525199 -54.968086) (xy 36.517079 -55.023262) (xy 36.501011 -55.076669)
			(xy 36.477339 -55.127166) (xy 36.446566 -55.173679) (xy 36.409349 -55.215216) (xy 36.366481 -55.250891)
			(xy 36.318875 -55.279945) (xy 36.267546 -55.301757) (xy 36.213589 -55.315863) (xy 36.158152 -55.321963)
			(xy 36.102418 -55.319926) (xy 36.047575 -55.309796) (xy 35.994791 -55.291789) (xy 35.945191 -55.266288)
			(xy 35.899833 -55.233837) (xy 35.859684 -55.195128) (xy 35.825598 -55.150985) (xy 35.798302 -55.10235)
			(xy 35.778379 -55.050259) (xy 35.766253 -54.995822) (xy 35.762182 -54.9402) (xy 33.274 -54.9402)
			(xy 33.274 -56.515) (xy 33.481772 -56.722772) (xy 33.679384 -56.722772) (xy 33.866582 -56.535574)
			(xy 33.88336 -56.519425) (xy 33.921048 -56.492074) (xy 33.962553 -56.470959) (xy 34.00685 -56.456599)
			(xy 34.052848 -56.449348) (xy 34.076132 -56.44896) (xy 34.448496 -56.44896) (xy 34.471777 -56.449377)
			(xy 34.517771 -56.456629) (xy 34.562065 -56.470988) (xy 34.603566 -56.492098) (xy 34.641254 -56.519442)
			(xy 34.658046 -56.535574) (xy 34.845244 -56.722772) (xy 35.762184 -56.722772) (xy 35.780387 -56.701477)
			(xy 35.82197 -56.663939) (xy 35.868598 -56.632891) (xy 35.919268 -56.609) (xy 35.972889 -56.592781)
			(xy 36.028306 -56.584583) (xy 36.084326 -56.584583) (xy 36.139743 -56.592781) (xy 36.193364 -56.609)
			(xy 36.244034 -56.632891) (xy 36.290662 -56.663939) (xy 36.332245 -56.701477) (xy 36.350448 -56.722772)
			(xy 36.848542 -56.722772) (xy 36.862045 -56.699147) (xy 36.894717 -56.655633) (xy 36.933242 -56.617204)
			(xy 36.976835 -56.584638) (xy 37.024614 -56.558597) (xy 37.075609 -56.53961) (xy 37.128784 -56.528061)
			(xy 37.18306 -56.524185) (xy 37.237336 -56.528061) (xy 37.290511 -56.53961) (xy 37.341506 -56.558597)
			(xy 37.389285 -56.584638) (xy 37.432878 -56.617204) (xy 37.471403 -56.655633) (xy 37.504075 -56.699147)
			(xy 37.517578 -56.722772) (xy 38.804088 -56.722772) (xy 39.778432 -57.697116) (xy 40.65778 -57.697116)
			(xy 40.72001 -57.759092)
		)
		(stroke
			(width 0)
			(type solid)
		)
		(fill yes)
		(layer "In2.Cu")
		(net "P3V3_AUX")
	)
	(gr_poly
		(pts
			(xy 74.64806 -73.58634) (xy 74.64806 -69.644768) (xy 74.738992 -69.553836) (xy 74.738992 -67.818)
			(xy 74.74077 -67.78117) (xy 74.742548 -67.757548) (xy 73.2028 -66.2178) (xy 71.247 -66.2178) (xy 70.1294 -67.3354)
			(xy 70.1294 -68.554346) (xy 71.217788 -68.554346) (xy 71.221859 -68.498724) (xy 71.233985 -68.444287)
			(xy 71.253908 -68.392196) (xy 71.281204 -68.343561) (xy 71.31529 -68.299418) (xy 71.355439 -68.260709)
			(xy 71.400797 -68.228258) (xy 71.450397 -68.202757) (xy 71.503181 -68.18475) (xy 71.558024 -68.17462)
			(xy 71.613758 -68.172583) (xy 71.669195 -68.178683) (xy 71.723152 -68.192789) (xy 71.774481 -68.214601)
			(xy 71.822087 -68.243655) (xy 71.864955 -68.27933) (xy 71.902172 -68.320867) (xy 71.932945 -68.36738)
			(xy 71.956617 -68.417877) (xy 71.972685 -68.471284) (xy 71.980805 -68.52646) (xy 71.981314 -68.554346)
			(xy 72.239376 -68.554346) (xy 72.243447 -68.498724) (xy 72.255573 -68.444287) (xy 72.275496 -68.392196)
			(xy 72.302792 -68.343561) (xy 72.336878 -68.299418) (xy 72.377027 -68.260709) (xy 72.422385 -68.228258)
			(xy 72.471985 -68.202757) (xy 72.524769 -68.18475) (xy 72.579612 -68.17462) (xy 72.635346 -68.172583)
			(xy 72.690783 -68.178683) (xy 72.74474 -68.192789) (xy 72.796069 -68.214601) (xy 72.843675 -68.243655)
			(xy 72.886543 -68.27933) (xy 72.92376 -68.320867) (xy 72.954533 -68.36738) (xy 72.978205 -68.417877)
			(xy 72.994273 -68.471284) (xy 73.002393 -68.52646) (xy 73.002902 -68.554346) (xy 73.002393 -68.582232)
			(xy 72.994273 -68.637408) (xy 72.978205 -68.690815) (xy 72.954533 -68.741312) (xy 72.92376 -68.787825)
			(xy 72.886543 -68.829362) (xy 72.843675 -68.865037) (xy 72.796069 -68.894091) (xy 72.74474 -68.915903)
			(xy 72.690783 -68.930009) (xy 72.635346 -68.936109) (xy 72.579612 -68.934072) (xy 72.524769 -68.923942)
			(xy 72.471985 -68.905935) (xy 72.422385 -68.880434) (xy 72.377027 -68.847983) (xy 72.336878 -68.809274)
			(xy 72.302792 -68.765131) (xy 72.275496 -68.716496) (xy 72.255573 -68.664405) (xy 72.243447 -68.609968)
			(xy 72.239376 -68.554346) (xy 71.981314 -68.554346) (xy 71.980805 -68.582232) (xy 71.972685 -68.637408)
			(xy 71.956617 -68.690815) (xy 71.932945 -68.741312) (xy 71.902172 -68.787825) (xy 71.864955 -68.829362)
			(xy 71.822087 -68.865037) (xy 71.774481 -68.894091) (xy 71.723152 -68.915903) (xy 71.669195 -68.930009)
			(xy 71.613758 -68.936109) (xy 71.558024 -68.934072) (xy 71.503181 -68.923942) (xy 71.450397 -68.905935)
			(xy 71.400797 -68.880434) (xy 71.355439 -68.847983) (xy 71.31529 -68.809274) (xy 71.281204 -68.765131)
			(xy 71.253908 -68.716496) (xy 71.233985 -68.664405) (xy 71.221859 -68.609968) (xy 71.217788 -68.554346)
			(xy 70.1294 -68.554346) (xy 70.1294 -69.0118) (xy 68.4784 -70.6628) (xy 68.4784 -71.037749) (xy 71.478404 -71.037749)
			(xy 71.478404 -70.983251) (xy 71.48616 -70.929307) (xy 71.501514 -70.877017) (xy 71.524153 -70.827443)
			(xy 71.553617 -70.781596) (xy 71.589305 -70.740409) (xy 71.630492 -70.70472) (xy 71.676338 -70.675256)
			(xy 71.725911 -70.652616) (xy 71.778202 -70.637261) (xy 71.832145 -70.629505) (xy 71.859394 -70.629018)
			(xy 71.888311 -70.629534) (xy 71.945483 -70.638263) (xy 72.000682 -70.655521) (xy 72.052644 -70.680913)
			(xy 72.100177 -70.713857) (xy 72.142194 -70.753598) (xy 72.160384 -70.776084) (xy 72.170281 -70.787889)
			(xy 72.195605 -70.805408) (xy 72.224998 -70.814584) (xy 72.25579 -70.814584) (xy 72.285183 -70.805408)
			(xy 72.310507 -70.787889) (xy 72.320404 -70.776084) (xy 72.338589 -70.753595) (xy 72.38061 -70.713861)
			(xy 72.428147 -70.680923) (xy 72.480109 -70.655536) (xy 72.535307 -70.638281) (xy 72.592478 -70.629553)
			(xy 72.621394 -70.629018) (xy 72.648649 -70.629428) (xy 72.702604 -70.637185) (xy 72.754907 -70.652542)
			(xy 72.804491 -70.675186) (xy 72.850348 -70.704655) (xy 72.891544 -70.740352) (xy 72.927241 -70.781547)
			(xy 72.956712 -70.827404) (xy 72.979356 -70.876988) (xy 72.994713 -70.92929) (xy 73.002471 -70.983245)
			(xy 73.002471 -71.037755) (xy 72.994713 -71.09171) (xy 72.979356 -71.144012) (xy 72.956712 -71.193596)
			(xy 72.927241 -71.239453) (xy 72.891544 -71.280648) (xy 72.850348 -71.316345) (xy 72.804491 -71.345814)
			(xy 72.754907 -71.368458) (xy 72.702604 -71.383815) (xy 72.648649 -71.391572) (xy 72.621394 -71.392034)
			(xy 72.592476 -71.391545) (xy 72.535302 -71.382813) (xy 72.480102 -71.365551) (xy 72.428139 -71.340154)
			(xy 72.380606 -71.307204) (xy 72.338592 -71.267457) (xy 72.320404 -71.244968) (xy 72.310507 -71.233163)
			(xy 72.285183 -71.215644) (xy 72.25579 -71.206468) (xy 72.224998 -71.206468) (xy 72.195605 -71.215644)
			(xy 72.170281 -71.233163) (xy 72.160384 -71.244968) (xy 72.142194 -71.267452) (xy 72.100175 -71.307189)
			(xy 72.05264 -71.340129) (xy 72.000679 -71.365517) (xy 71.94548 -71.382773) (xy 71.88831 -71.3915)
			(xy 71.859394 -71.392034) (xy 71.832145 -71.391495) (xy 71.778202 -71.383739) (xy 71.725911 -71.368384)
			(xy 71.676338 -71.345744) (xy 71.630492 -71.31628) (xy 71.589305 -71.280591) (xy 71.553617 -71.239404)
			(xy 71.524153 -71.193557) (xy 71.501514 -71.143983) (xy 71.48616 -71.091693) (xy 71.478404 -71.037749)
			(xy 68.4784 -71.037749) (xy 68.4784 -73.059544) (xy 71.217788 -73.059544) (xy 71.221859 -73.003922)
			(xy 71.233985 -72.949485) (xy 71.253908 -72.897394) (xy 71.281204 -72.848759) (xy 71.31529 -72.804616)
			(xy 71.355439 -72.765907) (xy 71.400797 -72.733456) (xy 71.450397 -72.707955) (xy 71.503181 -72.689948)
			(xy 71.558024 -72.679818) (xy 71.613758 -72.677781) (xy 71.669195 -72.683881) (xy 71.723152 -72.697987)
			(xy 71.774481 -72.719799) (xy 71.822087 -72.748853) (xy 71.864955 -72.784528) (xy 71.902172 -72.826065)
			(xy 71.932945 -72.872578) (xy 71.956617 -72.923075) (xy 71.972685 -72.976482) (xy 71.980805 -73.031658)
			(xy 71.98086 -73.034652) (xy 72.707752 -73.034652) (xy 72.711823 -72.97903) (xy 72.723949 -72.924593)
			(xy 72.743872 -72.872502) (xy 72.771168 -72.823867) (xy 72.805254 -72.779724) (xy 72.845403 -72.741015)
			(xy 72.890761 -72.708564) (xy 72.940361 -72.683063) (xy 72.993145 -72.665056) (xy 73.047988 -72.654926)
			(xy 73.103722 -72.652889) (xy 73.159159 -72.658989) (xy 73.213116 -72.673095) (xy 73.264445 -72.694907)
			(xy 73.312051 -72.723961) (xy 73.354919 -72.759636) (xy 73.392136 -72.801173) (xy 73.422909 -72.847686)
			(xy 73.446581 -72.898183) (xy 73.462649 -72.95159) (xy 73.470769 -73.006766) (xy 73.471278 -73.034652)
			(xy 73.470769 -73.062538) (xy 73.462649 -73.117714) (xy 73.446581 -73.171121) (xy 73.422909 -73.221618)
			(xy 73.392136 -73.268131) (xy 73.354919 -73.309668) (xy 73.312051 -73.345343) (xy 73.264445 -73.374397)
			(xy 73.213116 -73.396209) (xy 73.159159 -73.410315) (xy 73.103722 -73.416415) (xy 73.047988 -73.414378)
			(xy 72.993145 -73.404248) (xy 72.940361 -73.386241) (xy 72.890761 -73.36074) (xy 72.845403 -73.328289)
			(xy 72.805254 -73.28958) (xy 72.771168 -73.245437) (xy 72.743872 -73.196802) (xy 72.723949 -73.144711)
			(xy 72.711823 -73.090274) (xy 72.707752 -73.034652) (xy 71.98086 -73.034652) (xy 71.981314 -73.059544)
			(xy 71.980805 -73.08743) (xy 71.972685 -73.142606) (xy 71.956617 -73.196013) (xy 71.932945 -73.24651)
			(xy 71.902172 -73.293023) (xy 71.864955 -73.33456) (xy 71.822087 -73.370235) (xy 71.774481 -73.399289)
			(xy 71.723152 -73.421101) (xy 71.669195 -73.435207) (xy 71.613758 -73.441307) (xy 71.558024 -73.43927)
			(xy 71.503181 -73.42914) (xy 71.450397 -73.411133) (xy 71.400797 -73.385632) (xy 71.355439 -73.353181)
			(xy 71.31529 -73.314472) (xy 71.281204 -73.270329) (xy 71.253908 -73.221694) (xy 71.233985 -73.169603)
			(xy 71.221859 -73.115166) (xy 71.217788 -73.059544) (xy 68.4784 -73.059544) (xy 68.4784 -73.202292)
			(xy 69.2912 -74.015092) (xy 72.191626 -74.015092) (xy 72.205596 -74.0156) (xy 72.206612 -74.0156)
			(xy 74.2188 -74.0156)
		)
		(stroke
			(width 0)
			(type solid)
		)
		(fill yes)
		(layer "In2.Cu")
		(net "P1V8_AUX")
	)
	(gr_poly
		(pts
			(xy 49.657 -17.5768) (xy 49.657 -14.859) (xy 49.24044 -14.44244) (xy 49.230534 -14.432788) (xy 47.0662 -12.268708)
			(xy 38.862 -12.268708) (xy 37.846 -13.284708) (xy 37.846 -13.417248) (xy 41.210697 -13.417248) (xy 41.210697 -13.342672)
			(xy 41.218492 -13.268505) (xy 41.233997 -13.195559) (xy 41.257043 -13.124633) (xy 41.287375 -13.056505)
			(xy 41.324663 -12.991921) (xy 41.368498 -12.931588) (xy 41.418399 -12.876167) (xy 41.473819 -12.826266)
			(xy 41.534152 -12.782432) (xy 41.598737 -12.745144) (xy 41.666865 -12.714812) (xy 41.737791 -12.691767)
			(xy 41.810737 -12.676262) (xy 41.884904 -12.668467) (xy 41.922192 -12.667996) (xy 43.922188 -12.667996)
			(xy 43.959474 -12.668551) (xy 44.033637 -12.676344) (xy 44.106579 -12.691848) (xy 44.177502 -12.714891)
			(xy 44.245627 -12.745221) (xy 44.310208 -12.782506) (xy 44.370538 -12.826338) (xy 44.425956 -12.876235)
			(xy 44.475855 -12.931652) (xy 44.519687 -12.991982) (xy 44.556974 -13.056563) (xy 44.587305 -13.124687)
			(xy 44.610349 -13.195609) (xy 44.625854 -13.268551) (xy 44.633649 -13.342714) (xy 44.633649 -13.417141)
			(xy 45.736251 -13.417141) (xy 45.736251 -13.342775) (xy 45.744292 -13.268844) (xy 45.760278 -13.196216)
			(xy 45.784024 -13.125743) (xy 45.815249 -13.058249) (xy 45.853589 -12.994528) (xy 45.898594 -12.935325)
			(xy 45.949736 -12.881336) (xy 46.006415 -12.833192) (xy 46.067967 -12.791458) (xy 46.133671 -12.756624)
			(xy 46.202756 -12.729098) (xy 46.274412 -12.709203) (xy 46.347799 -12.697172) (xy 46.422056 -12.693146)
			(xy 46.496313 -12.697172) (xy 46.5697 -12.709203) (xy 46.641356 -12.729098) (xy 46.710441 -12.756624)
			(xy 46.776145 -12.791458) (xy 46.837697 -12.833192) (xy 46.894376 -12.881336) (xy 46.945518 -12.935325)
			(xy 46.990523 -12.994528) (xy 47.028863 -13.058249) (xy 47.060088 -13.125743) (xy 47.083834 -13.196216)
			(xy 47.09982 -13.268844) (xy 47.107861 -13.342775) (xy 47.108364 -13.379958) (xy 47.107861 -13.417141)
			(xy 47.09982 -13.491072) (xy 47.083834 -13.5637) (xy 47.060088 -13.634173) (xy 47.028863 -13.701667)
			(xy 46.990523 -13.765388) (xy 46.945518 -13.824591) (xy 46.894376 -13.87858) (xy 46.837697 -13.926724)
			(xy 46.776145 -13.968458) (xy 46.710441 -14.003292) (xy 46.641356 -14.030818) (xy 46.5697 -14.050713)
			(xy 46.496313 -14.062744) (xy 46.422056 -14.06677) (xy 46.347799 -14.062744) (xy 46.274412 -14.050713)
			(xy 46.202756 -14.030818) (xy 46.133671 -14.003292) (xy 46.067967 -13.968458) (xy 46.006415 -13.926724)
			(xy 45.949736 -13.87858) (xy 45.898594 -13.824591) (xy 45.853589 -13.765388) (xy 45.815249 -13.701667)
			(xy 45.784024 -13.634173) (xy 45.760278 -13.5637) (xy 45.744292 -13.491072) (xy 45.736251 -13.417141)
			(xy 44.633649 -13.417141) (xy 44.633649 -13.417286) (xy 44.625854 -13.491449) (xy 44.610349 -13.564391)
			(xy 44.587305 -13.635313) (xy 44.556974 -13.703437) (xy 44.519687 -13.768018) (xy 44.475855 -13.828348)
			(xy 44.425956 -13.883765) (xy 44.370538 -13.933662) (xy 44.310208 -13.977494) (xy 44.245627 -14.014779)
			(xy 44.177502 -14.045109) (xy 44.106579 -14.068152) (xy 44.033637 -14.083656) (xy 43.959474 -14.091449)
			(xy 43.922188 -14.09192) (xy 41.922192 -14.09192) (xy 41.884904 -14.091453) (xy 41.810737 -14.083658)
			(xy 41.737791 -14.068153) (xy 41.666865 -14.045108) (xy 41.598737 -14.014776) (xy 41.534152 -13.977488)
			(xy 41.473819 -13.933654) (xy 41.418399 -13.883753) (xy 41.368498 -13.828332) (xy 41.324663 -13.767999)
			(xy 41.287375 -13.703415) (xy 41.257043 -13.635287) (xy 41.233997 -13.564361) (xy 41.218492 -13.491415)
			(xy 41.210697 -13.417248) (xy 37.846 -13.417248) (xy 37.846 -14.917388) (xy 38.210708 -14.917388)
			(xy 38.210708 -14.842812) (xy 38.218503 -14.768646) (xy 38.234008 -14.6957) (xy 38.257053 -14.624775)
			(xy 38.287386 -14.556647) (xy 38.324673 -14.492062) (xy 38.368507 -14.43173) (xy 38.418408 -14.376309)
			(xy 38.473828 -14.326409) (xy 38.534161 -14.282574) (xy 38.598745 -14.245287) (xy 38.666873 -14.214954)
			(xy 38.737798 -14.191909) (xy 38.810744 -14.176403) (xy 38.88491 -14.168608) (xy 38.922198 -14.16812)
			(xy 40.922194 -14.16812) (xy 40.959481 -14.168627) (xy 41.033646 -14.176422) (xy 41.106591 -14.191926)
			(xy 41.177515 -14.21497) (xy 41.245641 -14.245301) (xy 41.310224 -14.282588) (xy 41.370556 -14.326421)
			(xy 41.425975 -14.37632) (xy 41.475875 -14.431739) (xy 41.519709 -14.492071) (xy 41.556996 -14.556653)
			(xy 41.587328 -14.62478) (xy 41.610373 -14.695704) (xy 41.625877 -14.768648) (xy 41.633673 -14.842813)
			(xy 41.633673 -14.917265) (xy 42.236385 -14.917265) (xy 42.236385 -14.842899) (xy 42.244426 -14.768968)
			(xy 42.260412 -14.69634) (xy 42.284158 -14.625867) (xy 42.315383 -14.558373) (xy 42.353723 -14.494652)
			(xy 42.398728 -14.435449) (xy 42.44987 -14.38146) (xy 42.506549 -14.333316) (xy 42.568101 -14.291582)
			(xy 42.633805 -14.256748) (xy 42.70289 -14.229222) (xy 42.774546 -14.209327) (xy 42.847933 -14.197296)
			(xy 42.92219 -14.19327) (xy 42.996447 -14.197296) (xy 43.069834 -14.209327) (xy 43.14149 -14.229222)
			(xy 43.210575 -14.256748) (xy 43.276279 -14.291582) (xy 43.337831 -14.333316) (xy 43.39451 -14.38146)
			(xy 43.445652 -14.435449) (xy 43.490657 -14.494652) (xy 43.528997 -14.558373) (xy 43.560222 -14.625867)
			(xy 43.583968 -14.69634) (xy 43.599954 -14.768968) (xy 43.607995 -14.842899) (xy 43.608498 -14.880082)
			(xy 43.607995 -14.917265) (xy 43.607982 -14.917387) (xy 44.210708 -14.917387) (xy 44.210708 -14.842813)
			(xy 44.218503 -14.768647) (xy 44.234008 -14.695702) (xy 44.257052 -14.624777) (xy 44.287384 -14.55665)
			(xy 44.324671 -14.492066) (xy 44.368504 -14.431734) (xy 44.418404 -14.376314) (xy 44.473823 -14.326413)
			(xy 44.534154 -14.282578) (xy 44.598737 -14.24529) (xy 44.666864 -14.214957) (xy 44.737788 -14.191911)
			(xy 44.810733 -14.176405) (xy 44.884899 -14.168609) (xy 44.922186 -14.16812) (xy 46.922182 -14.16812)
			(xy 46.959469 -14.168626) (xy 47.033636 -14.17642) (xy 47.106581 -14.191923) (xy 47.177506 -14.214967)
			(xy 47.245634 -14.245298) (xy 47.310218 -14.282584) (xy 47.370551 -14.326417) (xy 47.425971 -14.376316)
			(xy 47.475872 -14.431735) (xy 47.519706 -14.492067) (xy 47.556994 -14.55665) (xy 47.587327 -14.624777)
			(xy 47.610372 -14.695702) (xy 47.625877 -14.768647) (xy 47.633673 -14.842813) (xy 47.633673 -14.917387)
			(xy 47.625877 -14.991553) (xy 47.610372 -15.064498) (xy 47.587327 -15.135423) (xy 47.556994 -15.20355)
			(xy 47.519706 -15.268133) (xy 47.475872 -15.328465) (xy 47.425971 -15.383884) (xy 47.370551 -15.433783)
			(xy 47.310218 -15.477616) (xy 47.245634 -15.514902) (xy 47.177506 -15.545233) (xy 47.106581 -15.568277)
			(xy 47.033636 -15.58378) (xy 46.959469 -15.591574) (xy 46.922182 -15.592044) (xy 44.922186 -15.592044)
			(xy 44.884899 -15.591591) (xy 44.810733 -15.583795) (xy 44.737788 -15.568289) (xy 44.666864 -15.545243)
			(xy 44.598737 -15.51491) (xy 44.534154 -15.477622) (xy 44.473823 -15.433787) (xy 44.418404 -15.383886)
			(xy 44.368504 -15.328466) (xy 44.324671 -15.268134) (xy 44.287384 -15.20355) (xy 44.257052 -15.135423)
			(xy 44.234008 -15.064498) (xy 44.218503 -14.991553) (xy 44.210708 -14.917387) (xy 43.607982 -14.917387)
			(xy 43.599954 -14.991196) (xy 43.583968 -15.063824) (xy 43.560222 -15.134297) (xy 43.528997 -15.201791)
			(xy 43.490657 -15.265512) (xy 43.445652 -15.324715) (xy 43.39451 -15.378704) (xy 43.337831 -15.426848)
			(xy 43.276279 -15.468582) (xy 43.210575 -15.503416) (xy 43.14149 -15.530942) (xy 43.069834 -15.550837)
			(xy 42.996447 -15.562868) (xy 42.92219 -15.566894) (xy 42.847933 -15.562868) (xy 42.774546 -15.550837)
			(xy 42.70289 -15.530942) (xy 42.633805 -15.503416) (xy 42.568101 -15.468582) (xy 42.506549 -15.426848)
			(xy 42.44987 -15.378704) (xy 42.398728 -15.324715) (xy 42.353723 -15.265512) (xy 42.315383 -15.201791)
			(xy 42.284158 -15.134297) (xy 42.260412 -15.063824) (xy 42.244426 -14.991196) (xy 42.236385 -14.917265)
			(xy 41.633673 -14.917265) (xy 41.633673 -14.917387) (xy 41.625877 -14.991552) (xy 41.610373 -15.064496)
			(xy 41.587328 -15.13542) (xy 41.556996 -15.203547) (xy 41.519709 -15.268129) (xy 41.475875 -15.328461)
			(xy 41.425975 -15.38388) (xy 41.370556 -15.433779) (xy 41.310224 -15.477612) (xy 41.245641 -15.514899)
			(xy 41.177515 -15.54523) (xy 41.106591 -15.568274) (xy 41.033646 -15.583778) (xy 40.959481 -15.591573)
			(xy 40.922194 -15.592044) (xy 38.922198 -15.592044) (xy 38.88491 -15.591592) (xy 38.810744 -15.583797)
			(xy 38.737798 -15.568291) (xy 38.666873 -15.545246) (xy 38.598745 -15.514913) (xy 38.534161 -15.477626)
			(xy 38.473828 -15.433791) (xy 38.418408 -15.383891) (xy 38.368507 -15.32847) (xy 38.324673 -15.268138)
			(xy 38.287386 -15.203553) (xy 38.257053 -15.135425) (xy 38.234008 -15.0645) (xy 38.218503 -14.991554)
			(xy 38.210708 -14.917388) (xy 37.846 -14.917388) (xy 37.846 -16.3068) (xy 38.4556 -16.9164) (xy 43.8404 -16.9164)
			(xy 44.8818 -17.9578) (xy 49.276 -17.9578)
		)
		(stroke
			(width 0)
			(type solid)
		)
		(fill yes)
		(layer "In2.Cu")
		(net "P5V_USB_REAR")
	)
	(gr_poly
		(pts
			(xy 30.7086 -59.0804) (xy 31.2166 -59.0804) (xy 31.7246 -58.5724) (xy 31.7246 -57.7088) (xy 31.59506 -57.57926)
			(xy 31.572454 -57.580276) (xy 31.553404 -57.580784) (xy 31.526502 -57.580324) (xy 31.473232 -57.572766)
			(xy 31.421551 -57.557801) (xy 31.372485 -57.535724) (xy 31.327006 -57.506974) (xy 31.286018 -57.47212)
			(xy 31.250331 -57.431854) (xy 31.220655 -57.386975) (xy 31.197577 -57.338371) (xy 31.189168 -57.312814)
			(xy 31.177992 -57.277) (xy 30.60573 -57.277) (xy 29.983176 -57.8993) (xy 29.970977 -57.911199) (xy 29.94464 -57.932825)
			(xy 29.930598 -57.94248) (xy 29.67609 -58.11266) (xy 29.664019 -58.121401) (xy 29.645139 -58.144442)
			(xy 29.633693 -58.171944) (xy 29.630651 -58.201577) (xy 29.636271 -58.230831) (xy 29.650077 -58.257227)
			(xy 29.670899 -58.27853) (xy 29.68371 -58.286142) (xy 29.709008 -58.300641) (xy 29.755276 -58.336123)
			(xy 29.795607 -58.378231) (xy 29.829061 -58.425986) (xy 29.854859 -58.478275) (xy 29.872401 -58.53388)
			(xy 29.881279 -58.591507) (xy 29.88183 -58.62066) (xy 29.881344 -58.647911) (xy 29.873588 -58.701859)
			(xy 29.858233 -58.754154) (xy 29.835591 -58.803731) (xy 29.806125 -58.849581) (xy 29.770434 -58.890772)
			(xy 29.729243 -58.926463) (xy 29.683393 -58.955929) (xy 29.633816 -58.978571) (xy 29.581521 -58.993926)
			(xy 29.527573 -59.001682) (xy 29.473071 -59.001682) (xy 29.419123 -58.993926) (xy 29.366828 -58.978571)
			(xy 29.317251 -58.955929) (xy 29.271401 -58.926463) (xy 29.23021 -58.890772) (xy 29.194519 -58.849581)
			(xy 29.165053 -58.803731) (xy 29.142411 -58.754154) (xy 29.127056 -58.701859) (xy 29.1193 -58.647911)
			(xy 29.118814 -58.62066) (xy 29.120592 -58.58383) (xy 29.12237 -58.565542) (xy 29.084016 -58.508392)
			(xy 29.021532 -58.550048) (xy 29.007264 -58.559382) (xy 28.977239 -58.575541) (xy 28.961588 -58.582306)
			(xy 28.67533 -58.70067) (xy 28.6258 -58.7502) (xy 28.55595 -58.7502) (xy 27.849068 -59.043062) (xy 27.827918 -59.051367)
			(xy 27.784005 -59.063039) (xy 27.738946 -59.068895) (xy 27.716226 -59.069224) (xy 25.585928 -59.069224)
			(xy 25.563206 -59.068919) (xy 25.518141 -59.063079) (xy 25.474229 -59.05139) (xy 25.453086 -59.043062)
			(xy 24.746204 -58.7502) (xy 24.4602 -58.7502) (xy 24.258016 -58.548016) (xy 24.049228 -58.461656)
			(xy 24.028376 -58.452595) (xy 23.989037 -58.4298) (xy 23.95301 -58.402065) (xy 23.936706 -58.386218)
			(xy 23.580852 -58.030364) (xy 22.572218 -58.030364) (xy 22.544954 -58.029824) (xy 22.491099 -58.021286)
			(xy 22.439241 -58.004434) (xy 22.390656 -57.979681) (xy 22.346538 -57.947637) (xy 22.326854 -57.928764)
			(xy 21.844254 -57.446164) (xy 17.6276 -57.446164) (xy 17.600334 -57.44563) (xy 17.546472 -57.437103)
			(xy 17.494606 -57.42026) (xy 17.446012 -57.395515) (xy 17.401884 -57.363476) (xy 17.382236 -57.344564)
			(xy 17.314418 -57.277) (xy 15.875 -57.277) (xy 14.1478 -55.5498) (xy 14.1478 -53.280564) (xy 14.146022 -53.27396)
			(xy 14.139603 -53.249117) (xy 14.132718 -53.19827) (xy 14.132306 -53.172614) (xy 14.132306 -53.168296)
			(xy 14.13256 -53.14696) (xy 13.716 -52.7304) (xy 13.081 -52.7304) (xy 12.5984 -53.213) (xy 12.5984 -56.7944)
			(xy 14.15415 -58.35015) (xy 16.813782 -58.35015) (xy 16.817853 -58.294528) (xy 16.829979 -58.240091)
			(xy 16.849902 -58.188) (xy 16.877198 -58.139365) (xy 16.911284 -58.095222) (xy 16.951433 -58.056513)
			(xy 16.996791 -58.024062) (xy 17.046391 -57.998561) (xy 17.099175 -57.980554) (xy 17.154018 -57.970424)
			(xy 17.209752 -57.968387) (xy 17.265189 -57.974487) (xy 17.319146 -57.988593) (xy 17.370475 -58.010405)
			(xy 17.418081 -58.039459) (xy 17.460949 -58.075134) (xy 17.498166 -58.116671) (xy 17.528939 -58.163184)
			(xy 17.552611 -58.213681) (xy 17.568679 -58.267088) (xy 17.576799 -58.322264) (xy 17.577308 -58.35015)
			(xy 17.576799 -58.378036) (xy 17.568679 -58.433212) (xy 17.552611 -58.486619) (xy 17.528939 -58.537116)
			(xy 17.498166 -58.583629) (xy 17.460949 -58.625166) (xy 17.418081 -58.660841) (xy 17.370475 -58.689895)
			(xy 17.319146 -58.711707) (xy 17.265189 -58.725813) (xy 17.209752 -58.731913) (xy 17.154018 -58.729876)
			(xy 17.099175 -58.719746) (xy 17.046391 -58.701739) (xy 16.996791 -58.676238) (xy 16.951433 -58.643787)
			(xy 16.911284 -58.605078) (xy 16.877198 -58.560935) (xy 16.849902 -58.5123) (xy 16.829979 -58.460209)
			(xy 16.817853 -58.405772) (xy 16.813782 -58.35015) (xy 14.15415 -58.35015) (xy 15.35557 -59.55157)
			(xy 15.363444 -59.55538) (xy 15.387299 -59.567043) (xy 15.431813 -59.595994) (xy 15.471879 -59.63084)
			(xy 15.506722 -59.670909) (xy 15.53567 -59.715424) (xy 15.54734 -59.739276) (xy 15.55115 -59.74715)
			(xy 15.621 -59.817) (xy 17.920462 -59.817) (xy 17.933162 -59.784742) (xy 17.947132 -59.7535) (xy 17.952466 -59.73064)
			(xy 17.920462 -59.683396) (xy 17.894021 -59.672517) (xy 17.844471 -59.643993) (xy 17.799733 -59.608394)
			(xy 17.760808 -59.566517) (xy 17.72857 -59.5193) (xy 17.703739 -59.4678) (xy 17.686872 -59.413171)
			(xy 17.678346 -59.356637) (xy 17.677892 -59.32805) (xy 17.678378 -59.300799) (xy 17.686134 -59.246851)
			(xy 17.701489 -59.194556) (xy 17.724131 -59.144979) (xy 17.753597 -59.099129) (xy 17.789288 -59.057938)
			(xy 17.830479 -59.022247) (xy 17.876329 -58.992781) (xy 17.925906 -58.970139) (xy 17.978201 -58.954784)
			(xy 18.032149 -58.947028) (xy 18.086651 -58.947028) (xy 18.140599 -58.954784) (xy 18.192894 -58.970139)
			(xy 18.242471 -58.992781) (xy 18.288321 -59.022247) (xy 18.329512 -59.057938) (xy 18.365203 -59.099129)
			(xy 18.394669 -59.144979) (xy 18.417311 -59.194556) (xy 18.432666 -59.246851) (xy 18.440422 -59.300799)
			(xy 18.440908 -59.32805) (xy 18.440131 -59.362132) (xy 18.427992 -59.429207) (xy 18.416778 -59.4614)
			(xy 18.412077 -59.475355) (xy 18.410048 -59.50472) (xy 18.416484 -59.533442) (xy 18.430851 -59.559132)
			(xy 18.440052 -59.56808) (xy 28.116782 -59.56808) (xy 28.120853 -59.512458) (xy 28.132979 -59.458021)
			(xy 28.152902 -59.40593) (xy 28.180198 -59.357295) (xy 28.214284 -59.313152) (xy 28.254433 -59.274443)
			(xy 28.299791 -59.241992) (xy 28.349391 -59.216491) (xy 28.402175 -59.198484) (xy 28.457018 -59.188354)
			(xy 28.512752 -59.186317) (xy 28.568189 -59.192417) (xy 28.622146 -59.206523) (xy 28.673475 -59.228335)
			(xy 28.721081 -59.257389) (xy 28.763949 -59.293064) (xy 28.801166 -59.334601) (xy 28.831939 -59.381114)
			(xy 28.855611 -59.431611) (xy 28.871679 -59.485018) (xy 28.879799 -59.540194) (xy 28.880308 -59.56808)
			(xy 28.879799 -59.595966) (xy 28.871679 -59.651142) (xy 28.855611 -59.704549) (xy 28.831939 -59.755046)
			(xy 28.801166 -59.801559) (xy 28.763949 -59.843096) (xy 28.721081 -59.878771) (xy 28.673475 -59.907825)
			(xy 28.622146 -59.929637) (xy 28.568189 -59.943743) (xy 28.512752 -59.949843) (xy 28.457018 -59.947806)
			(xy 28.402175 -59.937676) (xy 28.349391 -59.919669) (xy 28.299791 -59.894168) (xy 28.254433 -59.861717)
			(xy 28.214284 -59.823008) (xy 28.180198 -59.778865) (xy 28.152902 -59.73023) (xy 28.132979 -59.678139)
			(xy 28.120853 -59.623702) (xy 28.116782 -59.56808) (xy 18.440052 -59.56808) (xy 18.451953 -59.579653)
			(xy 18.464784 -59.586876) (xy 18.488665 -59.599909) (xy 18.532805 -59.631711) (xy 18.571982 -59.669458)
			(xy 18.605403 -59.712385) (xy 18.63239 -59.759623) (xy 18.642838 -59.784742) (xy 18.655538 -59.817)
			(xy 21.082 -59.817) (xy 21.243036 -59.978036) (xy 21.52523 -59.978036) (xy 21.5392 -59.977782) (xy 21.560505 -59.978163)
			(xy 21.602593 -59.984799) (xy 21.643125 -59.997939) (xy 21.681101 -60.01726) (xy 21.715586 -60.042285)
			(xy 21.73097 -60.05703) (xy 21.74494 -60.071) (xy 21.902166 -60.071) (xy 21.917226 -60.047978) (xy 21.952914 -60.006113)
			(xy 21.994246 -59.969809) (xy 22.040364 -59.939819) (xy 22.090311 -59.916765) (xy 22.143053 -59.901124)
			(xy 22.197494 -59.893222) (xy 22.252506 -59.893222) (xy 22.306947 -59.901124) (xy 22.359689 -59.916765)
			(xy 22.409636 -59.939819) (xy 22.455754 -59.969809) (xy 22.497086 -60.006113) (xy 22.532774 -60.047978)
			(xy 22.547834 -60.071) (xy 24.711914 -60.071) (xy 24.725122 -60.04052) (xy 24.736627 -60.01535) (xy 24.76583 -59.968344)
			(xy 24.801519 -59.926049) (xy 24.842943 -59.889355) (xy 24.889235 -59.85903) (xy 24.939422 -59.835712)
			(xy 24.992451 -59.819889) (xy 25.04721 -59.811894) (xy 25.10255 -59.811894) (xy 25.157309 -59.819889)
			(xy 25.210338 -59.835712) (xy 25.260525 -59.85903) (xy 25.306817 -59.889355) (xy 25.348241 -59.926049)
			(xy 25.38393 -59.968344) (xy 25.413133 -60.01535) (xy 25.424638 -60.04052) (xy 25.437846 -60.071)
			(xy 26.004012 -60.071) (xy 26.022134 -60.047691) (xy 26.064359 -60.006426) (xy 26.112441 -59.972164)
			(xy 26.165231 -59.945725) (xy 26.221465 -59.92774) (xy 26.2798 -59.918641) (xy 26.30932 -59.918092)
			(xy 26.33657 -59.918579) (xy 26.390516 -59.926338) (xy 26.442808 -59.941695) (xy 26.492383 -59.964337)
			(xy 26.538231 -59.993804) (xy 26.579419 -60.029495) (xy 26.615108 -60.070685) (xy 26.644572 -60.116535)
			(xy 26.667212 -60.166111) (xy 26.682566 -60.218404) (xy 26.690322 -60.27235) (xy 26.690828 -60.2996)
			(xy 26.691248 -60.309619) (xy 26.698919 -60.328131) (xy 26.713092 -60.342297) (xy 26.731609 -60.349957)
			(xy 26.741628 -60.3504) (xy 29.4386 -60.3504)
		)
		(stroke
			(width 0)
			(type solid)
		)
		(fill yes)
		(layer "In2.Cu")
		(net "P12V_AUX")
	)
	(gr_poly
		(pts
			(xy 84.492084 -118.78056)
			(arc
				(start 84.492084 -114.799872)
				(mid 84.787357 -114.087273)
				(end 85.499956 -113.792)
			)
			(arc
				(start 88.000078 -113.792)
				(mid 89.055078 -113.355004)
				(end 89.492074 -112.300004)
			)
			(xy 89.492074 -85.508084)
			(arc
				(start 87.749888 -85.508084)
				(mid 87.037379 -85.212795)
				(end 86.742016 -84.500212)
			)
			(arc
				(start 86.742016 -81.999836)
				(mid 87.037289 -81.287237)
				(end 87.749888 -80.991964)
			)
			(xy 89.492074 -80.991964)
			(arc
				(start 89.492074 -1.999996)
				(mid 89.055078 -0.944996)
				(end 88.000078 -0.508)
			)
			(arc
				(start 1.999996 -0.508)
				(mid 0.944996 -0.944996)
				(end 0.508 -1.999996)
			)
			(xy 0.508 -80.991964)
			(arc
				(start 2.249932 -80.991964)
				(mid 2.962785 -81.287237)
				(end 3.258058 -82.00009)
			)
			(arc
				(start 3.258058 -84.499958)
				(mid 2.962785 -85.212811)
				(end 2.249932 -85.508084)
			)
			(xy 0.508 -85.508084)
			(arc
				(start 0.508 -112.300004)
				(mid 0.944996 -113.355004)
				(end 1.999996 -113.792)
			)
			(arc
				(start 4.500118 -113.792)
				(mid 5.212717 -114.087273)
				(end 5.50799 -114.799872)
			)
			(xy 5.50799 -118.71071) (xy 5.621528 -118.824248) (xy 5.936488 -118.824248) (xy 6.015228 -118.745508)
			(arc
				(start 6.015228 -114.799872)
				(mid 5.571478 -113.728438)
				(end 4.500118 -113.284508)
			)
			(arc
				(start 1.999996 -113.284508)
				(mid 1.303847 -112.996153)
				(end 1.015492 -112.300004)
			)
			(xy 1.015492 -86.015576)
			(arc
				(start 2.249932 -86.015576)
				(mid 3.30937 -85.583541)
				(end 3.764788 -84.533994)
			)
			(arc
				(start 3.764788 -81.9658)
				(mid 3.647195 -81.413419)
				(end 3.335528 -80.942434)
			)
			(arc
				(start 3.307334 -80.91424)
				(mid 2.820638 -80.596002)
				(end 2.249932 -80.484472)
			)
			(xy 1.015492 -80.484472) (xy 1.015492 -78.507336) (xy 1.014984 -78.493112) (xy 1.014984 -30.615636)
			(xy 1.015492 -30.601412)
			(arc
				(start 1.015492 -1.999996)
				(mid 1.303847 -1.303847)
				(end 1.999996 -1.015492)
			)
			(xy 63.713614 -1.015492) (xy 76.606908 -1.015492)
			(arc
				(start 88.000078 -1.015492)
				(mid 88.696317 -1.303831)
				(end 88.984836 -1.999996)
			)
			(xy 88.984836 -80.484472)
			(arc
				(start 87.749888 -80.484472)
				(mid 86.690537 -80.916524)
				(end 86.235032 -81.966054)
			)
			(arc
				(start 86.235032 -84.533994)
				(mid 86.690451 -85.583612)
				(end 87.749888 -86.015576)
			)
			(xy 88.984836 -86.015576)
			(arc
				(start 88.984836 -112.300004)
				(mid 88.696571 -112.996064)
				(end 88.000586 -113.284508)
			)
			(arc
				(start 85.499956 -113.284508)
				(mid 84.428432 -113.728348)
				(end 83.984592 -114.799872)
			)
			(xy 83.984592 -118.768114) (xy 84.094574 -118.878096) (xy 84.394548 -118.878096)
		)
		(stroke
			(width 0)
			(type solid)
		)
		(fill yes)
		(layer "In2.Cu")
		(net "GND")
	)
	(gr_poly
		(pts
			(xy 22.046692 -37.516308) (xy 22.046692 -36.366196) (xy 22.018752 -36.338002) (xy 22.018498 -36.337748)
			(xy 22.001226 -36.318952) (xy 21.992844 -36.308792) (xy 21.980839 -36.293667) (xy 21.960825 -36.260644)
			(xy 21.952966 -36.243006) (xy 21.952204 -36.241228) (xy 21.944419 -36.222064) (xy 21.934089 -36.182011)
			(xy 21.93163 -36.161472) (xy 21.931376 -36.158932) (xy 21.931376 -36.158678) (xy 21.93036 -36.147756)
			(xy 21.93036 -36.14674) (xy 21.930106 -36.143438) (xy 21.930106 -36.14293) (xy 21.928836 -36.116514)
			(xy 21.928836 -34.123122) (xy 21.930614 -34.092388) (xy 21.931884 -34.081466) (xy 21.935413 -34.05585)
			(xy 21.950967 -34.006543) (xy 21.975607 -33.961089) (xy 21.991574 -33.94075) (xy 21.999702 -33.931098)
			(xy 21.999956 -33.930844) (xy 22.017482 -33.911286) (xy 22.406102 -33.522666) (xy 22.428454 -33.5026)
			(xy 22.437344 -33.495488) (xy 22.457424 -33.480174) (xy 22.502033 -33.456518) (xy 22.550249 -33.441522)
			(xy 22.575266 -33.438084) (xy 22.586188 -33.436814) (xy 22.616922 -33.435036) (xy 22.825964 -33.435036)
			(xy 24.638 -31.623) (xy 24.638 -21.711412) (xy 24.045672 -21.119084) (xy 23.68042 -21.119084) (xy 23.666649 -21.12022)
			(xy 23.640434 -21.128917) (xy 23.617509 -21.144321) (xy 23.59955 -21.165306) (xy 23.587872 -21.190335)
			(xy 23.583329 -21.217579) (xy 23.584408 -21.231352) (xy 23.585375 -21.241293) (xy 23.586391 -21.261242)
			(xy 23.58644 -21.27123) (xy 23.585904 -21.300145) (xy 23.577172 -21.357312) (xy 23.559913 -21.412507)
			(xy 23.534521 -21.464465) (xy 23.50158 -21.511996) (xy 23.461842 -21.554011) (xy 23.439374 -21.57222)
			(xy 23.427577 -21.58212) (xy 23.410075 -21.607441) (xy 23.400911 -21.636827) (xy 23.400916 -21.667609)
			(xy 23.410091 -21.696992) (xy 23.427603 -21.722307) (xy 23.439374 -21.73224) (xy 23.460153 -21.748994)
			(xy 23.497277 -21.787348) (xy 23.528691 -21.830502) (xy 23.553784 -21.877614) (xy 23.572065 -21.927763)
			(xy 23.583178 -21.979971) (xy 23.586904 -22.033218) (xy 23.583172 -22.086465) (xy 23.572055 -22.138672)
			(xy 23.553769 -22.18882) (xy 23.528672 -22.235929) (xy 23.497253 -22.27908) (xy 23.460126 -22.31743)
			(xy 23.439374 -22.33422) (xy 23.427577 -22.34412) (xy 23.410075 -22.369441) (xy 23.400911 -22.398827)
			(xy 23.400916 -22.429609) (xy 23.410091 -22.458992) (xy 23.427603 -22.484307) (xy 23.439374 -22.49424)
			(xy 23.460153 -22.510994) (xy 23.497277 -22.549348) (xy 23.528691 -22.592502) (xy 23.553784 -22.639614)
			(xy 23.572065 -22.689763) (xy 23.583178 -22.741971) (xy 23.586904 -22.795218) (xy 23.583172 -22.848465)
			(xy 23.572055 -22.900672) (xy 23.553769 -22.95082) (xy 23.528672 -22.997929) (xy 23.497253 -23.04108)
			(xy 23.460126 -23.07943) (xy 23.439374 -23.09622) (xy 23.427577 -23.10612) (xy 23.410075 -23.131441)
			(xy 23.400911 -23.160827) (xy 23.400916 -23.191609) (xy 23.410091 -23.220992) (xy 23.427603 -23.246307)
			(xy 23.439374 -23.25624) (xy 23.461861 -23.274429) (xy 23.501604 -23.316445) (xy 23.534548 -23.363978)
			(xy 23.55994 -23.415941) (xy 23.577197 -23.47114) (xy 23.585923 -23.528313) (xy 23.58644 -23.55723)
			(xy 23.585954 -23.584481) (xy 23.578198 -23.638429) (xy 23.562843 -23.690724) (xy 23.540201 -23.740301)
			(xy 23.510735 -23.786151) (xy 23.475044 -23.827342) (xy 23.433853 -23.863033) (xy 23.388003 -23.892499)
			(xy 23.338426 -23.915141) (xy 23.286131 -23.930496) (xy 23.232183 -23.938252) (xy 23.177681 -23.938252)
			(xy 23.123733 -23.930496) (xy 23.071438 -23.915141) (xy 23.021861 -23.892499) (xy 22.976011 -23.863033)
			(xy 22.93482 -23.827342) (xy 22.899129 -23.786151) (xy 22.869663 -23.740301) (xy 22.847021 -23.690724)
			(xy 22.831666 -23.638429) (xy 22.82391 -23.584481) (xy 22.823424 -23.55723) (xy 22.823956 -23.528313)
			(xy 22.832679 -23.471139) (xy 22.849931 -23.415938) (xy 22.875316 -23.363971) (xy 22.908252 -23.316431)
			(xy 22.947985 -23.274406) (xy 22.97049 -23.25624) (xy 22.9823 -23.246342) (xy 22.999825 -23.221016)
			(xy 23.009008 -23.191618) (xy 23.009014 -23.160819) (xy 22.999842 -23.131417) (xy 22.982325 -23.106085)
			(xy 22.97049 -23.09622) (xy 22.949703 -23.079468) (xy 22.912566 -23.041115) (xy 22.881138 -22.99796)
			(xy 22.856033 -22.950844) (xy 22.837742 -22.900689) (xy 22.826621 -22.848474) (xy 22.822888 -22.795218)
			(xy 22.826616 -22.741962) (xy 22.837731 -22.689746) (xy 22.856018 -22.639589) (xy 22.881118 -22.592472)
			(xy 22.912542 -22.549313) (xy 22.949676 -22.510957) (xy 22.97049 -22.49424) (xy 22.9823 -22.484342)
			(xy 22.999825 -22.459016) (xy 23.009008 -22.429618) (xy 23.009014 -22.398819) (xy 22.999842 -22.369417)
			(xy 22.982325 -22.344085) (xy 22.97049 -22.33422) (xy 22.949703 -22.317468) (xy 22.912566 -22.279115)
			(xy 22.881138 -22.23596) (xy 22.856033 -22.188844) (xy 22.837742 -22.138689) (xy 22.826621 -22.086474)
			(xy 22.822888 -22.033218) (xy 22.826616 -21.979962) (xy 22.837731 -21.927746) (xy 22.856018 -21.877589)
			(xy 22.881118 -21.830472) (xy 22.912542 -21.787313) (xy 22.949676 -21.748957) (xy 22.97049 -21.73224)
			(xy 22.9823 -21.722342) (xy 22.999825 -21.697016) (xy 23.009008 -21.667618) (xy 23.009014 -21.636819)
			(xy 22.999842 -21.607417) (xy 22.982325 -21.582085) (xy 22.97049 -21.57222) (xy 22.948007 -21.554029)
			(xy 22.908272 -21.512011) (xy 22.875336 -21.464476) (xy 22.849952 -21.412514) (xy 22.832703 -21.357315)
			(xy 22.823983 -21.300146) (xy 22.823424 -21.27123) (xy 22.823477 -21.261242) (xy 22.824496 -21.241293)
			(xy 22.825456 -21.231352) (xy 22.826446 -21.217578) (xy 22.821888 -21.190353) (xy 22.810217 -21.165338)
			(xy 22.792283 -21.144354) (xy 22.76939 -21.12893) (xy 22.743207 -21.120188) (xy 22.729444 -21.119084)
			(xy 19.468846 -21.119084) (xy 19.454628 -21.119562) (xy 19.427296 -21.127409) (xy 19.403183 -21.14248)
			(xy 19.384153 -21.163609) (xy 19.371679 -21.189163) (xy 19.366726 -21.217164) (xy 19.367754 -21.231352)
			(xy 19.36872 -21.241293) (xy 19.369737 -21.261242) (xy 19.369786 -21.27123) (xy 19.36925 -21.300146)
			(xy 19.360519 -21.357314) (xy 19.343261 -21.41251) (xy 19.317872 -21.46447) (xy 19.284933 -21.512004)
			(xy 19.245198 -21.554023) (xy 19.22272 -21.57222) (xy 19.210919 -21.582117) (xy 19.193409 -21.607438)
			(xy 19.18424 -21.636826) (xy 19.184245 -21.667611) (xy 19.193425 -21.696996) (xy 19.210944 -21.72231)
			(xy 19.22272 -21.73224) (xy 19.243502 -21.748993) (xy 19.28063 -21.787345) (xy 19.312049 -21.830498)
			(xy 19.337145 -21.87761) (xy 19.355429 -21.92776) (xy 19.366543 -21.979969) (xy 19.37027 -22.033218)
			(xy 19.366538 -22.086467) (xy 19.355419 -22.138676) (xy 19.33713 -22.188824) (xy 19.312029 -22.235933)
			(xy 19.280606 -22.279084) (xy 19.243474 -22.317432) (xy 19.22272 -22.33422) (xy 19.210919 -22.344117)
			(xy 19.193409 -22.369438) (xy 19.18424 -22.398826) (xy 19.184245 -22.429611) (xy 19.193425 -22.458996)
			(xy 19.210944 -22.48431) (xy 19.22272 -22.49424) (xy 19.243502 -22.510993) (xy 19.28063 -22.549345)
			(xy 19.312049 -22.592498) (xy 19.337145 -22.63961) (xy 19.355429 -22.68976) (xy 19.366543 -22.741969)
			(xy 19.37027 -22.795218) (xy 19.366538 -22.848467) (xy 19.355419 -22.900676) (xy 19.33713 -22.950824)
			(xy 19.312029 -22.997933) (xy 19.280606 -23.041084) (xy 19.243474 -23.079432) (xy 19.22272 -23.09622)
			(xy 19.210919 -23.106117) (xy 19.193409 -23.131438) (xy 19.18424 -23.160826) (xy 19.184245 -23.191611)
			(xy 19.193425 -23.220996) (xy 19.210944 -23.24631) (xy 19.22272 -23.25624) (xy 19.245204 -23.274431)
			(xy 19.284943 -23.316448) (xy 19.317884 -23.363982) (xy 19.343272 -23.415944) (xy 19.360526 -23.471143)
			(xy 19.369251 -23.528314) (xy 19.369786 -23.55723) (xy 19.3693 -23.584481) (xy 19.361544 -23.638429)
			(xy 19.346189 -23.690724) (xy 19.323547 -23.740301) (xy 19.294081 -23.786151) (xy 19.25839 -23.827342)
			(xy 19.217199 -23.863033) (xy 19.171349 -23.892499) (xy 19.121772 -23.915141) (xy 19.069477 -23.930496)
			(xy 19.015529 -23.938252) (xy 18.961027 -23.938252) (xy 18.907079 -23.930496) (xy 18.854784 -23.915141)
			(xy 18.805207 -23.892499) (xy 18.759357 -23.863033) (xy 18.718166 -23.827342) (xy 18.682475 -23.786151)
			(xy 18.653009 -23.740301) (xy 18.630367 -23.690724) (xy 18.615012 -23.638429) (xy 18.607256 -23.584481)
			(xy 18.60677 -23.55723) (xy 18.607302 -23.528313) (xy 18.616026 -23.471141) (xy 18.633279 -23.41594)
			(xy 18.658666 -23.363976) (xy 18.691605 -23.316439) (xy 18.731341 -23.274418) (xy 18.753836 -23.25624)
			(xy 18.76565 -23.246345) (xy 18.783186 -23.22102) (xy 18.792374 -23.19162) (xy 18.792379 -23.160817)
			(xy 18.783202 -23.131413) (xy 18.765676 -23.106082) (xy 18.753836 -23.09622) (xy 18.733052 -23.079466)
			(xy 18.69592 -23.041111) (xy 18.664496 -22.997955) (xy 18.639395 -22.95084) (xy 18.621106 -22.900686)
			(xy 18.609987 -22.848472) (xy 18.606255 -22.795218) (xy 18.609982 -22.741964) (xy 18.621096 -22.68975)
			(xy 18.63938 -22.639594) (xy 18.664476 -22.592476) (xy 18.695896 -22.549317) (xy 18.733025 -22.510959)
			(xy 18.753836 -22.49424) (xy 18.765557 -22.484444) (xy 18.783005 -22.459388) (xy 18.792269 -22.430294)
			(xy 18.792519 -22.399762) (xy 18.783734 -22.37052) (xy 18.766698 -22.345181) (xy 18.755106 -22.335236)
			(xy 18.732437 -22.317053) (xy 18.692349 -22.274984) (xy 18.659107 -22.22732) (xy 18.633482 -22.175164)
			(xy 18.616064 -22.119725) (xy 18.607259 -22.062285) (xy 18.60677 -22.03323) (xy 18.606823 -22.023242)
			(xy 18.607842 -22.003293) (xy 18.608802 -21.993352) (xy 18.60931 -21.988526) (xy 18.613419 -21.958577)
			(xy 18.629878 -21.900413) (xy 18.655311 -21.845575) (xy 18.689082 -21.795441) (xy 18.730344 -21.751265)
			(xy 18.753836 -21.73224) (xy 18.76565 -21.722345) (xy 18.783186 -21.69702) (xy 18.792374 -21.66762)
			(xy 18.792379 -21.636817) (xy 18.783202 -21.607413) (xy 18.765676 -21.582082) (xy 18.753836 -21.57222)
			(xy 18.731351 -21.55403) (xy 18.691612 -21.512014) (xy 18.658671 -21.464479) (xy 18.633284 -21.412517)
			(xy 18.616033 -21.357318) (xy 18.607312 -21.300146) (xy 18.60677 -21.27123) (xy 18.606823 -21.261242)
			(xy 18.607842 -21.241293) (xy 18.608802 -21.231352) (xy 18.609823 -21.217163) (xy 18.604889 -21.189159)
			(xy 18.592422 -21.163602) (xy 18.57339 -21.142475) (xy 18.549268 -21.127418) (xy 18.521928 -21.119598)
			(xy 18.50771 -21.119084) (xy 18.476976 -21.119084) (xy 16.47444 -23.12162) (xy 16.47444 -27.619452)
			(xy 16.702278 -28.169362) (xy 16.713911 -28.198789) (xy 16.730302 -28.259905) (xy 16.73859 -28.322636)
			(xy 16.739108 -28.354274) (xy 16.739108 -28.594812) (xy 17.054374 -29.5148) (xy 23.112982 -29.5148)
			(xy 23.117053 -29.459178) (xy 23.129179 -29.404741) (xy 23.149102 -29.35265) (xy 23.176398 -29.304015)
			(xy 23.210484 -29.259872) (xy 23.250633 -29.221163) (xy 23.295991 -29.188712) (xy 23.345591 -29.163211)
			(xy 23.398375 -29.145204) (xy 23.453218 -29.135074) (xy 23.508952 -29.133037) (xy 23.564389 -29.139137)
			(xy 23.618346 -29.153243) (xy 23.669675 -29.175055) (xy 23.717281 -29.204109) (xy 23.760149 -29.239784)
			(xy 23.797366 -29.281321) (xy 23.828139 -29.327834) (xy 23.851811 -29.378331) (xy 23.867879 -29.431738)
			(xy 23.875999 -29.486914) (xy 23.876508 -29.5148) (xy 23.875999 -29.542686) (xy 23.867879 -29.597862)
			(xy 23.851811 -29.651269) (xy 23.828139 -29.701766) (xy 23.797366 -29.748279) (xy 23.760149 -29.789816)
			(xy 23.717281 -29.825491) (xy 23.669675 -29.854545) (xy 23.618346 -29.876357) (xy 23.564389 -29.890463)
			(xy 23.508952 -29.896563) (xy 23.453218 -29.894526) (xy 23.398375 -29.884396) (xy 23.345591 -29.866389)
			(xy 23.295991 -29.840888) (xy 23.250633 -29.808437) (xy 23.210484 -29.769728) (xy 23.176398 -29.725585)
			(xy 23.149102 -29.67695) (xy 23.129179 -29.624859) (xy 23.117053 -29.570422) (xy 23.112982 -29.5148)
			(xy 17.054374 -29.5148) (xy 17.306795 -30.2514) (xy 21.639782 -30.2514) (xy 21.643853 -30.195778)
			(xy 21.655979 -30.141341) (xy 21.675902 -30.08925) (xy 21.703198 -30.040615) (xy 21.737284 -29.996472)
			(xy 21.777433 -29.957763) (xy 21.822791 -29.925312) (xy 21.872391 -29.899811) (xy 21.925175 -29.881804)
			(xy 21.980018 -29.871674) (xy 22.035752 -29.869637) (xy 22.091189 -29.875737) (xy 22.145146 -29.889843)
			(xy 22.196475 -29.911655) (xy 22.244081 -29.940709) (xy 22.286949 -29.976384) (xy 22.324166 -30.017921)
			(xy 22.354939 -30.064434) (xy 22.378611 -30.114931) (xy 22.394679 -30.168338) (xy 22.402799 -30.223514)
			(xy 22.403308 -30.2514) (xy 22.402799 -30.279286) (xy 22.394679 -30.334462) (xy 22.378611 -30.387869)
			(xy 22.354939 -30.438366) (xy 22.324166 -30.484879) (xy 22.286949 -30.526416) (xy 22.244081 -30.562091)
			(xy 22.196475 -30.591145) (xy 22.145146 -30.612957) (xy 22.091189 -30.627063) (xy 22.035752 -30.633163)
			(xy 21.980018 -30.631126) (xy 21.925175 -30.620996) (xy 21.872391 -30.602989) (xy 21.822791 -30.577488)
			(xy 21.777433 -30.545037) (xy 21.737284 -30.506328) (xy 21.703198 -30.462185) (xy 21.675902 -30.41355)
			(xy 21.655979 -30.361459) (xy 21.643853 -30.307022) (xy 21.639782 -30.2514) (xy 17.306795 -30.2514)
			(xy 17.431004 -30.613858) (xy 17.431004 -32.520128) (xy 17.431512 -32.5374) (xy 17.431004 -32.554672)
			(xy 17.431004 -34.790126) (xy 17.098264 -35.122866) (xy 17.098264 -39.069264) (xy 17.153636 -39.124636)
			(xy 18.150078 -39.124636) (xy 18.180812 -39.126414) (xy 18.191734 -39.127684) (xy 18.21735 -39.131213)
			(xy 18.266657 -39.146767) (xy 18.312111 -39.171407) (xy 18.33245 -39.187374) (xy 18.342102 -39.195502)
			(xy 18.342356 -39.195756) (xy 18.361914 -39.213282) (xy 19.026632 -39.878) (xy 19.685 -39.878)
		)
		(stroke
			(width 0)
			(type solid)
		)
		(fill yes)
		(layer "In2.Cu")
		(net "GND")
	)
	(gr_poly
		(pts
			(xy 54.09565 -68.26885) (xy 54.113684 -68.25234) (xy 54.348634 -68.01739) (xy 54.348634 -66.799968)
			(xy 54.305708 -66.793364) (xy 54.279083 -66.788729) (xy 54.2274 -66.772937) (xy 54.178462 -66.750009)
			(xy 54.13325 -66.720406) (xy 54.092667 -66.684718) (xy 54.057526 -66.643661) (xy 54.02853 -66.598057)
			(xy 54.006259 -66.548817) (xy 53.99116 -66.496927) (xy 53.983533 -66.443425) (xy 53.983532 -66.389383)
			(xy 53.991158 -66.335882) (xy 54.006256 -66.283991) (xy 54.028526 -66.234751) (xy 54.057521 -66.189146)
			(xy 54.092661 -66.148088) (xy 54.133243 -66.1124) (xy 54.178455 -66.082795) (xy 54.227392 -66.059866)
			(xy 54.279075 -66.044072) (xy 54.305708 -66.039492) (xy 54.348634 -66.032888) (xy 54.348634 -62.253114)
			(xy 54.330866 -62.232123) (xy 54.300916 -62.185998) (xy 54.277894 -62.136054) (xy 54.262276 -62.083323)
			(xy 54.254385 -62.028897) (xy 54.254385 -61.973903) (xy 54.262276 -61.919477) (xy 54.277894 -61.866746)
			(xy 54.300916 -61.816802) (xy 54.330866 -61.770677) (xy 54.348634 -61.749686) (xy 54.348634 -61.453776)
			(xy 52.086002 -59.191144) (xy 52.076101 -59.181854) (xy 52.052532 -59.1684) (xy 52.026252 -59.161624)
			(xy 51.999115 -59.162004) (xy 51.973035 -59.169512) (xy 51.94985 -59.18362) (xy 51.940206 -59.193176)
			(xy 51.921333 -59.212432) (xy 51.878485 -59.245155) (xy 51.830894 -59.27049) (xy 51.779823 -59.287767)
			(xy 51.726625 -59.296527) (xy 51.699668 -59.297062) (xy 51.673682 -59.296576) (xy 51.62235 -59.288441)
			(xy 51.572922 -59.272375) (xy 51.526617 -59.248775) (xy 51.484574 -59.218222) (xy 51.447828 -59.181467)
			(xy 51.417284 -59.139416) (xy 51.393695 -59.093105) (xy 51.377641 -59.043674) (xy 51.369517 -58.99234)
			(xy 51.36896 -58.966354) (xy 51.369462 -58.940119) (xy 51.377758 -58.88831) (xy 51.38547 -58.86323)
			(xy 51.389331 -58.850051) (xy 51.390646 -58.822631) (xy 51.384602 -58.795853) (xy 51.371639 -58.771656)
			(xy 51.352693 -58.75179) (xy 51.329137 -58.737695) (xy 51.302676 -58.730389) (xy 51.28895 -58.72988)
			(xy 51.18227 -58.72988) (xy 51.18227 -58.793888) (xy 51.18862 -58.805318) (xy 51.201757 -58.830108)
			(xy 51.220417 -58.883013) (xy 51.229903 -58.938305) (xy 51.23053 -58.966354) (xy 51.23002 -58.992341)
			(xy 51.22189 -59.043676) (xy 51.205829 -59.093106) (xy 51.182233 -59.139416) (xy 51.151683 -59.181464)
			(xy 51.114932 -59.218215) (xy 51.072884 -59.248765) (xy 51.026574 -59.272361) (xy 50.977144 -59.288422)
			(xy 50.925809 -59.296552) (xy 50.873835 -59.296552) (xy 50.8225 -59.288422) (xy 50.77307 -59.272361)
			(xy 50.72676 -59.248765) (xy 50.684712 -59.218215) (xy 50.647961 -59.181464) (xy 50.617411 -59.139416)
			(xy 50.593815 -59.093106) (xy 50.577754 -59.043676) (xy 50.569624 -58.992341) (xy 50.569114 -58.966354)
			(xy 50.569616 -58.940119) (xy 50.57791 -58.88831) (xy 50.585624 -58.86323) (xy 50.589484 -58.850049)
			(xy 50.590796 -58.822625) (xy 50.584753 -58.795843) (xy 50.571791 -58.771641) (xy 50.552848 -58.751768)
			(xy 50.529293 -58.737663) (xy 50.502831 -58.730345) (xy 50.489104 -58.72988) (xy 49.978564 -58.72988)
			(xy 49.978564 -59.334654) (xy 49.979053 -59.348333) (xy 49.986403 -59.374688) (xy 50.000481 -59.398149)
			(xy 50.020277 -59.417035) (xy 50.044375 -59.429993) (xy 50.071047 -59.436095) (xy 50.084736 -59.436)
			(xy 50.099722 -59.435746) (xy 50.125712 -59.436257) (xy 50.177051 -59.444392) (xy 50.226485 -59.460457)
			(xy 50.272798 -59.484057) (xy 50.314849 -59.514612) (xy 50.351603 -59.551368) (xy 50.382154 -59.593421)
			(xy 50.405752 -59.639735) (xy 50.421813 -59.689171) (xy 50.429944 -59.74051) (xy 50.429944 -59.792441)
			(xy 51.36947 -59.792441) (xy 51.36947 -59.740467) (xy 51.3776 -59.689132) (xy 51.393661 -59.639702)
			(xy 51.417257 -59.593392) (xy 51.447807 -59.551344) (xy 51.484558 -59.514593) (xy 51.526606 -59.484043)
			(xy 51.572916 -59.460447) (xy 51.622346 -59.444386) (xy 51.673681 -59.436256) (xy 51.725655 -59.436256)
			(xy 51.77699 -59.444386) (xy 51.82642 -59.460447) (xy 51.87273 -59.484043) (xy 51.914778 -59.514593)
			(xy 51.951529 -59.551344) (xy 51.982079 -59.593392) (xy 52.005675 -59.639702) (xy 52.021736 -59.689132)
			(xy 52.029866 -59.740467) (xy 52.030376 -59.766454) (xy 52.029866 -59.792441) (xy 52.021736 -59.843776)
			(xy 52.005675 -59.893206) (xy 51.982079 -59.939516) (xy 51.951529 -59.981564) (xy 51.914778 -60.018315)
			(xy 51.87273 -60.048865) (xy 51.82642 -60.072461) (xy 51.77699 -60.088522) (xy 51.725655 -60.096652)
			(xy 51.673681 -60.096652) (xy 51.622346 -60.088522) (xy 51.572916 -60.072461) (xy 51.526606 -60.048865)
			(xy 51.484558 -60.018315) (xy 51.447807 -59.981564) (xy 51.417257 -59.939516) (xy 51.393661 -59.893206)
			(xy 51.3776 -59.843776) (xy 51.36947 -59.792441) (xy 50.429944 -59.792441) (xy 50.429944 -59.79249)
			(xy 50.421813 -59.843829) (xy 50.405752 -59.893265) (xy 50.382154 -59.939579) (xy 50.351603 -59.981632)
			(xy 50.314849 -60.018388) (xy 50.272798 -60.048943) (xy 50.226485 -60.072543) (xy 50.177051 -60.088608)
			(xy 50.125712 -60.096743) (xy 50.099722 -60.097162) (xy 50.084393 -60.097015) (xy 50.053862 -60.09422)
			(xy 50.038762 -60.091574) (xy 50.03419 -60.090558) (xy 49.978564 -60.090558) (xy 49.978564 -60.1472)
			(xy 49.978146 -60.170481) (xy 49.970892 -60.216473) (xy 49.95653 -60.260763) (xy 49.935415 -60.302261)
			(xy 49.908067 -60.339944) (xy 49.89195 -60.35675) (xy 49.69129 -60.55741) (xy 49.69129 -60.63742)
			(xy 49.691747 -60.652174) (xy 49.700107 -60.680469) (xy 49.716211 -60.705192) (xy 49.738712 -60.724277)
			(xy 49.765731 -60.73613) (xy 49.795012 -60.73976) (xy 49.824107 -60.734865) (xy 49.837594 -60.72886)
			(xy 49.862075 -60.717421) (xy 49.913632 -60.70125) (xy 49.967041 -60.69306) (xy 49.994058 -60.692538)
			(xy 50.020708 -60.693008) (xy 50.073413 -60.700946) (xy 50.124346 -60.716652) (xy 50.172369 -60.739773)
			(xy 50.216409 -60.769795) (xy 50.255482 -60.806045) (xy 50.288716 -60.847715) (xy 50.315368 -60.893872)
			(xy 50.334842 -60.943487) (xy 50.346703 -60.99545) (xy 50.350686 -61.0486) (xy 50.346703 -61.10175)
			(xy 50.334842 -61.153713) (xy 50.315368 -61.203328) (xy 50.288716 -61.249485) (xy 50.255482 -61.291155)
			(xy 50.216409 -61.327405) (xy 50.172369 -61.357427) (xy 50.124346 -61.380548) (xy 50.073413 -61.396254)
			(xy 50.020708 -61.404192) (xy 49.994058 -61.404754) (xy 49.967041 -61.404236) (xy 49.913632 -61.396042)
			(xy 49.862071 -61.379878) (xy 49.837594 -61.368432) (xy 49.824128 -61.36239) (xy 49.795029 -61.357524)
			(xy 49.765753 -61.361174) (xy 49.738739 -61.373034) (xy 49.716239 -61.392117) (xy 49.700127 -61.416832)
			(xy 49.691748 -61.44512) (xy 49.69129 -61.459872) (xy 49.69129 -61.632338) (xy 50.631598 -62.572646)
			(xy 50.644552 -62.576202) (xy 50.671606 -62.584161) (xy 50.723189 -62.606944) (xy 50.770856 -62.637073)
			(xy 50.813568 -62.673892) (xy 50.850394 -62.716598) (xy 50.88053 -62.764261) (xy 50.90332 -62.815841)
			(xy 50.911252 -62.842902) (xy 50.914808 -62.855856) (xy 51.028346 -62.969394) (xy 51.954936 -62.969394)
			(xy 51.959007 -62.913772) (xy 51.971133 -62.859335) (xy 51.991056 -62.807244) (xy 52.018352 -62.758609)
			(xy 52.052438 -62.714466) (xy 52.092587 -62.675757) (xy 52.137945 -62.643306) (xy 52.187545 -62.617805)
			(xy 52.240329 -62.599798) (xy 52.295172 -62.589668) (xy 52.350906 -62.587631) (xy 52.406343 -62.593731)
			(xy 52.4603 -62.607837) (xy 52.511629 -62.629649) (xy 52.559235 -62.658703) (xy 52.602103 -62.694378)
			(xy 52.63932 -62.735915) (xy 52.670093 -62.782428) (xy 52.693765 -62.832925) (xy 52.709833 -62.886332)
			(xy 52.717953 -62.941508) (xy 52.718462 -62.969394) (xy 52.717953 -62.99728) (xy 52.709833 -63.052456)
			(xy 52.693765 -63.105863) (xy 52.670093 -63.15636) (xy 52.63932 -63.202873) (xy 52.602103 -63.24441)
			(xy 52.559235 -63.280085) (xy 52.511629 -63.309139) (xy 52.4603 -63.330951) (xy 52.406343 -63.345057)
			(xy 52.350906 -63.351157) (xy 52.295172 -63.34912) (xy 52.240329 -63.33899) (xy 52.187545 -63.320983)
			(xy 52.137945 -63.295482) (xy 52.092587 -63.263031) (xy 52.052438 -63.224322) (xy 52.018352 -63.180179)
			(xy 51.991056 -63.131544) (xy 51.971133 -63.079453) (xy 51.959007 -63.025016) (xy 51.954936 -62.969394)
			(xy 51.028346 -62.969394) (xy 51.847496 -63.788544) (xy 51.847496 -64.436244) (xy 51.94681 -64.535558)
			(xy 51.954069 -64.542952) (xy 51.967667 -64.558589) (xy 51.973988 -64.5668) (xy 51.982767 -64.577675)
			(xy 52.005029 -64.594556) (xy 52.03103 -64.60478) (xy 52.058828 -64.607586) (xy 52.086347 -64.602762)
			(xy 52.111534 -64.59067) (xy 52.122324 -64.581786) (xy 52.143341 -64.563885) (xy 52.189563 -64.533697)
			(xy 52.239654 -64.510486) (xy 52.292566 -64.494738) (xy 52.347197 -64.486781) (xy 52.3748 -64.486282)
			(xy 52.402052 -64.486768) (xy 52.456 -64.494524) (xy 52.508295 -64.509879) (xy 52.557873 -64.53252)
			(xy 52.603724 -64.561986) (xy 52.644915 -64.597678) (xy 52.680608 -64.638868) (xy 52.710075 -64.684718)
			(xy 52.732717 -64.734296) (xy 52.748074 -64.78659) (xy 52.755832 -64.840539) (xy 52.756308 -64.86779)
			(xy 52.755838 -64.895061) (xy 52.748062 -64.949046) (xy 52.732681 -65.001375) (xy 52.710009 -65.050981)
			(xy 52.680506 -65.096856) (xy 52.644775 -65.138064) (xy 52.603542 -65.173766) (xy 52.557647 -65.203237)
			(xy 52.533042 -65.215008) (xy 52.51923 -65.221862) (xy 52.496235 -65.242382) (xy 52.480404 -65.268825)
			(xy 52.473175 -65.298785) (xy 52.475207 -65.329538) (xy 52.486315 -65.358286) (xy 52.49545 -65.37071)
			(xy 52.511111 -65.39103) (xy 52.537416 -65.435076) (xy 52.557573 -65.482254) (xy 52.571217 -65.531709)
			(xy 52.578101 -65.582548) (xy 52.578508 -65.6082) (xy 52.578022 -65.635451) (xy 52.570266 -65.689399)
			(xy 52.554911 -65.741694) (xy 52.532269 -65.791271) (xy 52.502803 -65.837121) (xy 52.467112 -65.878312)
			(xy 52.425921 -65.914003) (xy 52.380071 -65.943469) (xy 52.330494 -65.966111) (xy 52.278199 -65.981466)
			(xy 52.224251 -65.989222) (xy 52.197 -65.989708) (xy 52.169067 -65.989221) (xy 52.113798 -65.981078)
			(xy 52.060307 -65.964966) (xy 52.009735 -65.941229) (xy 51.98618 -65.926208) (xy 51.977499 -65.939353)
			(xy 51.957771 -65.963916) (xy 51.94681 -65.97523) (xy 51.49469 -66.42735) (xy 51.483766 -66.437984)
			(xy 51.460097 -66.457199) (xy 51.447446 -66.465704) (xy 51.40071 -66.51244) (xy 51.411886 -66.54292)
			(xy 51.422889 -66.574826) (xy 51.434766 -66.641258) (xy 51.435508 -66.675) (xy 51.435023 -66.702569)
			(xy 51.427087 -66.757133) (xy 51.411382 -66.809986) (xy 51.388233 -66.860029) (xy 51.358124 -66.90622)
			(xy 51.340258 -66.927222) (xy 51.330453 -66.939216) (xy 51.317911 -66.967526) (xy 51.314399 -66.998291)
			(xy 51.320235 -67.0287) (xy 51.334889 -67.055977) (xy 51.345592 -67.067176) (xy 51.363496 -67.085197)
			(xy 51.394862 -67.125155) (xy 51.420649 -67.168921) (xy 51.4404 -67.215723) (xy 51.453765 -67.264732)
			(xy 51.460509 -67.315081) (xy 51.460908 -67.34048) (xy 51.460382 -67.368854) (xy 51.451967 -67.424975)
			(xy 51.435333 -67.479231) (xy 51.410847 -67.530425) (xy 51.379051 -67.577429) (xy 51.36104 -67.59702)
			(xy 51.916582 -67.59702) (xy 51.920653 -67.541398) (xy 51.932779 -67.486961) (xy 51.952702 -67.43487)
			(xy 51.979998 -67.386235) (xy 52.014084 -67.342092) (xy 52.054233 -67.303383) (xy 52.099591 -67.270932)
			(xy 52.149191 -67.245431) (xy 52.201975 -67.227424) (xy 52.256818 -67.217294) (xy 52.312552 -67.215257)
			(xy 52.367989 -67.221357) (xy 52.421946 -67.235463) (xy 52.473275 -67.257275) (xy 52.520881 -67.286329)
			(xy 52.563749 -67.322004) (xy 52.600966 -67.363541) (xy 52.631739 -67.410054) (xy 52.655411 -67.460551)
			(xy 52.671479 -67.513958) (xy 52.679599 -67.569134) (xy 52.680108 -67.59702) (xy 52.679599 -67.624906)
			(xy 52.671479 -67.680082) (xy 52.655411 -67.733489) (xy 52.631739 -67.783986) (xy 52.600966 -67.830499)
			(xy 52.563749 -67.872036) (xy 52.537116 -67.8942) (xy 53.279292 -67.8942) (xy 53.283363 -67.838578)
			(xy 53.295489 -67.784141) (xy 53.315412 -67.73205) (xy 53.342708 -67.683415) (xy 53.376794 -67.639272)
			(xy 53.416943 -67.600563) (xy 53.462301 -67.568112) (xy 53.511901 -67.542611) (xy 53.564685 -67.524604)
			(xy 53.619528 -67.514474) (xy 53.675262 -67.512437) (xy 53.730699 -67.518537) (xy 53.784656 -67.532643)
			(xy 53.835985 -67.554455) (xy 53.883591 -67.583509) (xy 53.926459 -67.619184) (xy 53.963676 -67.660721)
			(xy 53.994449 -67.707234) (xy 54.018121 -67.757731) (xy 54.034189 -67.811138) (xy 54.042309 -67.866314)
			(xy 54.042818 -67.8942) (xy 54.042309 -67.922086) (xy 54.034189 -67.977262) (xy 54.018121 -68.030669)
			(xy 53.994449 -68.081166) (xy 53.963676 -68.127679) (xy 53.926459 -68.169216) (xy 53.883591 -68.204891)
			(xy 53.835985 -68.233945) (xy 53.784656 -68.255757) (xy 53.730699 -68.269863) (xy 53.675262 -68.275963)
			(xy 53.619528 -68.273926) (xy 53.564685 -68.263796) (xy 53.511901 -68.245789) (xy 53.462301 -68.220288)
			(xy 53.416943 -68.187837) (xy 53.376794 -68.149128) (xy 53.342708 -68.104985) (xy 53.315412 -68.05635)
			(xy 53.295489 -68.004259) (xy 53.283363 -67.949822) (xy 53.279292 -67.8942) (xy 52.537116 -67.8942)
			(xy 52.520881 -67.907711) (xy 52.473275 -67.936765) (xy 52.421946 -67.958577) (xy 52.367989 -67.972683)
			(xy 52.312552 -67.978783) (xy 52.256818 -67.976746) (xy 52.201975 -67.966616) (xy 52.149191 -67.948609)
			(xy 52.099591 -67.923108) (xy 52.054233 -67.890657) (xy 52.014084 -67.851948) (xy 51.979998 -67.807805)
			(xy 51.952702 -67.75917) (xy 51.932779 -67.707079) (xy 51.920653 -67.652642) (xy 51.916582 -67.59702)
			(xy 51.36104 -67.59702) (xy 51.340644 -67.619206) (xy 51.296474 -67.654834) (xy 51.247514 -67.683529)
			(xy 51.194846 -67.704656) (xy 51.139629 -67.717751) (xy 51.111404 -67.720718) (xy 51.096403 -67.722568)
			(xy 51.06838 -67.733853) (xy 51.044873 -67.752827) (xy 51.027929 -67.777838) (xy 51.019027 -67.806707)
			(xy 51.01844 -67.82181) (xy 51.01844 -68.638928) (xy 51.211226 -68.831714) (xy 53.532786 -68.831714)
		)
		(stroke
			(width 0)
			(type solid)
		)
		(fill yes)
		(layer "In2.Cu")
		(net "P3V3_SENSOR")
	)
	(gr_poly
		(pts
			(xy 58.433208 -45.564044) (xy 58.533284 -45.463714) (xy 58.533284 -45.211238) (xy 58.887868 -44.856654)
			(xy 58.887868 -43.309794) (xy 58.84418 -43.303444) (xy 58.818201 -43.29928) (xy 58.767919 -43.2838)
			(xy 58.720723 -43.260554) (xy 58.677802 -43.230127) (xy 58.640242 -43.193289) (xy 58.608988 -43.150967)
			(xy 58.58483 -43.10423) (xy 58.568378 -43.054258) (xy 58.560047 -43.002311) (xy 58.560046 -42.9497)
			(xy 58.568376 -42.897753) (xy 58.584826 -42.84778) (xy 58.608983 -42.801042) (xy 58.640235 -42.758719)
			(xy 58.677794 -42.721879) (xy 58.720713 -42.691452) (xy 58.767909 -42.668204) (xy 58.818191 -42.652723)
			(xy 58.84418 -42.648632) (xy 58.887868 -42.642282) (xy 58.887868 -42.509694) (xy 58.84418 -42.503344)
			(xy 58.818201 -42.49918) (xy 58.767919 -42.4837) (xy 58.720723 -42.460454) (xy 58.677802 -42.430027)
			(xy 58.640242 -42.393189) (xy 58.608988 -42.350867) (xy 58.58483 -42.30413) (xy 58.568378 -42.254158)
			(xy 58.560047 -42.202211) (xy 58.560046 -42.1496) (xy 58.568376 -42.097653) (xy 58.584826 -42.04768)
			(xy 58.608983 -42.000942) (xy 58.640235 -41.958619) (xy 58.677794 -41.921779) (xy 58.720713 -41.891352)
			(xy 58.767909 -41.868104) (xy 58.818191 -41.852623) (xy 58.84418 -41.848532) (xy 58.887868 -41.842182)
			(xy 58.887868 -41.709848) (xy 58.84418 -41.703498) (xy 58.818198 -41.699335) (xy 58.767908 -41.68386)
			(xy 58.720702 -41.660619) (xy 58.67777 -41.630199) (xy 58.640195 -41.593367) (xy 58.608923 -41.551051)
			(xy 58.584745 -41.504319) (xy 58.568268 -41.454349) (xy 58.559909 -41.4024) (xy 58.559446 -41.376092)
			(xy 58.559972 -41.349673) (xy 58.568392 -41.297511) (xy 58.585 -41.247352) (xy 58.609373 -41.200472)
			(xy 58.640891 -41.158064) (xy 58.678753 -41.121209) (xy 58.721993 -41.090844) (xy 58.769512 -41.067741)
			(xy 58.820101 -41.05249) (xy 58.846212 -41.048432) (xy 58.890154 -41.042336) (xy 58.890154 -40.909748)
			(xy 58.846212 -40.903652) (xy 58.820086 -40.899645) (xy 58.769475 -40.884412) (xy 58.721933 -40.86132)
			(xy 58.678672 -40.830956) (xy 58.640793 -40.794096) (xy 58.609262 -40.751678) (xy 58.584883 -40.704783)
			(xy 58.568277 -40.654606) (xy 58.559867 -40.602426) (xy 58.559867 -40.549572) (xy 58.568278 -40.497392)
			(xy 58.584884 -40.447215) (xy 58.609264 -40.400321) (xy 58.640794 -40.357903) (xy 58.678673 -40.321042)
			(xy 58.721935 -40.290679) (xy 58.769477 -40.267587) (xy 58.820088 -40.252355) (xy 58.846212 -40.248332)
			(xy 58.890154 -40.242236) (xy 58.890154 -40.109902) (xy 58.846212 -40.103806) (xy 58.820084 -40.099805)
			(xy 58.769471 -40.08458) (xy 58.721926 -40.061491) (xy 58.678664 -40.031128) (xy 58.640788 -39.994264)
			(xy 58.609263 -39.951841) (xy 58.584894 -39.90494) (xy 58.568303 -39.854757) (xy 58.559913 -39.802573)
			(xy 58.559446 -39.776146) (xy 58.559911 -39.751013) (xy 58.567515 -39.701325) (xy 58.582554 -39.653361)
			(xy 58.604682 -39.608227) (xy 58.633388 -39.566963) (xy 58.668011 -39.530522) (xy 58.707752 -39.499742)
			(xy 58.751695 -39.475335) (xy 58.798827 -39.457862) (xy 58.848061 -39.447727) (xy 58.873136 -39.445946)
			(xy 58.89244 -39.44493) (xy 59.359038 -38.978332) (xy 59.360054 -38.959028) (xy 59.361819 -38.933954)
			(xy 59.371977 -38.884729) (xy 59.389466 -38.837606) (xy 59.413882 -38.793672) (xy 59.444664 -38.753938)
			(xy 59.481103 -38.719318) (xy 59.522361 -38.69061) (xy 59.567486 -38.668473) (xy 59.615442 -38.653419)
			(xy 59.665123 -38.645792) (xy 59.690254 -38.645338) (xy 59.716861 -38.645889) (xy 59.769385 -38.654442)
			(xy 59.819865 -38.671287) (xy 59.84367 -38.683184) (xy 59.87669 -38.700456) (xy 62.426088 -36.151058)
			(xy 67.843908 -36.151058) (xy 67.857123 -36.150637) (xy 67.882668 -36.14385) (xy 67.905614 -36.130733)
			(xy 67.924424 -36.112165) (xy 67.937838 -36.089391) (xy 67.944956 -36.063937) (xy 67.945508 -36.050728)
			(xy 67.946303 -36.02369) (xy 67.954584 -35.970236) (xy 67.970331 -35.918488) (xy 67.99323 -35.869483)
			(xy 68.02282 -35.824202) (xy 68.058508 -35.783555) (xy 68.09958 -35.748356) (xy 68.145212 -35.719311)
			(xy 68.194488 -35.697001) (xy 68.246421 -35.681875) (xy 68.29997 -35.674236) (xy 68.354062 -35.674236)
			(xy 68.407611 -35.681875) (xy 68.459544 -35.697001) (xy 68.50882 -35.719311) (xy 68.554452 -35.748356)
			(xy 68.595524 -35.783555) (xy 68.631212 -35.824202) (xy 68.660802 -35.869483) (xy 68.683701 -35.918488)
			(xy 68.699448 -35.970236) (xy 68.707729 -36.02369) (xy 68.708524 -36.050728) (xy 68.709105 -36.063939)
			(xy 68.716204 -36.089401) (xy 68.729607 -36.112184) (xy 68.748413 -36.13076) (xy 68.77136 -36.14388)
			(xy 68.796907 -36.150665) (xy 68.810124 -36.151058) (xy 70.107048 -36.151058) (xy 70.262496 -35.99561)
			(xy 70.262496 -34.94278) (xy 69.922136 -34.60242) (xy 63.744348 -34.60242) (xy 63.744348 -34.746692)
			(xy 63.363348 -34.746692) (xy 63.363348 -34.60242) (xy 62.726824 -34.60242) (xy 62.726824 -34.746692)
			(xy 62.345316 -34.746692) (xy 62.345316 -34.60242) (xy 61.313822 -34.60242) (xy 60.515246 -35.400996)
			(xy 62.285372 -35.400996) (xy 62.285372 -35.26028) (xy 62.345316 -35.26028) (xy 62.345316 -34.995104)
			(xy 62.726824 -34.995104) (xy 62.726824 -35.26028) (xy 62.786768 -35.26028) (xy 62.786768 -35.400996)
			(xy 63.303404 -35.400996) (xy 63.303404 -35.26028) (xy 63.363348 -35.26028) (xy 63.363348 -34.995104)
			(xy 63.744348 -34.995104) (xy 63.744348 -35.26028) (xy 63.804292 -35.26028) (xy 63.804292 -35.400996)
			(xy 63.803918 -35.414085) (xy 63.79711 -35.439363) (xy 63.783962 -35.462) (xy 63.765378 -35.480439)
			(xy 63.742639 -35.493409) (xy 63.717308 -35.500018) (xy 63.704216 -35.50031) (xy 63.703962 -35.500056)
			(xy 63.403734 -35.500056) (xy 63.40348 -35.50031) (xy 63.39039 -35.500001) (xy 63.365065 -35.493392)
			(xy 63.34233 -35.480424) (xy 63.32375 -35.461989) (xy 63.310605 -35.439356) (xy 63.303799 -35.414083)
			(xy 63.303404 -35.400996) (xy 62.786768 -35.400996) (xy 62.786418 -35.414109) (xy 62.779586 -35.439429)
			(xy 62.766393 -35.462094) (xy 62.74775 -35.480539) (xy 62.724946 -35.49349) (xy 62.699554 -35.500052)
			(xy 62.686438 -35.50031) (xy 62.686184 -35.500056) (xy 62.385956 -35.500056) (xy 62.385702 -35.50031)
			(xy 62.372589 -35.500057) (xy 62.347208 -35.493485) (xy 62.324414 -35.480528) (xy 62.305782 -35.462082)
			(xy 62.292597 -35.43942) (xy 62.285769 -35.414105) (xy 62.285372 -35.400996) (xy 60.515246 -35.400996)
			(xy 60.10148 -35.814762) (xy 61.135512 -35.814762) (xy 61.139583 -35.75914) (xy 61.151709 -35.704703)
			(xy 61.171632 -35.652612) (xy 61.198928 -35.603977) (xy 61.233014 -35.559834) (xy 61.273163 -35.521125)
			(xy 61.318521 -35.488674) (xy 61.368121 -35.463173) (xy 61.420905 -35.445166) (xy 61.475748 -35.435036)
			(xy 61.531482 -35.432999) (xy 61.586919 -35.439099) (xy 61.640876 -35.453205) (xy 61.692205 -35.475017)
			(xy 61.739811 -35.504071) (xy 61.782679 -35.539746) (xy 61.819896 -35.581283) (xy 61.850669 -35.627796)
			(xy 61.874341 -35.678293) (xy 61.890409 -35.7317) (xy 61.898529 -35.786876) (xy 61.899038 -35.814762)
			(xy 61.898529 -35.842648) (xy 61.890409 -35.897824) (xy 61.874341 -35.951231) (xy 61.850669 -36.001728)
			(xy 61.819896 -36.048241) (xy 61.782679 -36.089778) (xy 61.739811 -36.125453) (xy 61.692205 -36.154507)
			(xy 61.640876 -36.176319) (xy 61.586919 -36.190425) (xy 61.531482 -36.196525) (xy 61.475748 -36.194488)
			(xy 61.420905 -36.184358) (xy 61.368121 -36.166351) (xy 61.318521 -36.14085) (xy 61.273163 -36.108399)
			(xy 61.233014 -36.06969) (xy 61.198928 -36.025547) (xy 61.171632 -35.976912) (xy 61.151709 -35.924821)
			(xy 61.139583 -35.870384) (xy 61.135512 -35.814762) (xy 60.10148 -35.814762) (xy 58.099706 -37.816536)
			(xy 58.643518 -37.816536) (xy 58.647589 -37.760914) (xy 58.659715 -37.706477) (xy 58.679638 -37.654386)
			(xy 58.706934 -37.605751) (xy 58.74102 -37.561608) (xy 58.781169 -37.522899) (xy 58.826527 -37.490448)
			(xy 58.876127 -37.464947) (xy 58.928911 -37.44694) (xy 58.983754 -37.43681) (xy 59.039488 -37.434773)
			(xy 59.094925 -37.440873) (xy 59.148882 -37.454979) (xy 59.200211 -37.476791) (xy 59.247817 -37.505845)
			(xy 59.290685 -37.54152) (xy 59.327902 -37.583057) (xy 59.358675 -37.62957) (xy 59.382347 -37.680067)
			(xy 59.398415 -37.733474) (xy 59.406535 -37.78865) (xy 59.407044 -37.816536) (xy 59.406535 -37.844422)
			(xy 59.398415 -37.899598) (xy 59.382347 -37.953005) (xy 59.358675 -38.003502) (xy 59.327902 -38.050015)
			(xy 59.290685 -38.091552) (xy 59.247817 -38.127227) (xy 59.200211 -38.156281) (xy 59.148882 -38.178093)
			(xy 59.094925 -38.192199) (xy 59.039488 -38.198299) (xy 58.983754 -38.196262) (xy 58.928911 -38.186132)
			(xy 58.876127 -38.168125) (xy 58.826527 -38.142624) (xy 58.781169 -38.110173) (xy 58.74102 -38.071464)
			(xy 58.706934 -38.027321) (xy 58.679638 -37.978686) (xy 58.659715 -37.926595) (xy 58.647589 -37.872158)
			(xy 58.643518 -37.816536) (xy 58.099706 -37.816536) (xy 57.875424 -38.040818) (xy 57.866155 -38.050669)
			(xy 57.85271 -38.074128) (xy 57.845898 -38.100295) (xy 57.846195 -38.127332) (xy 57.853582 -38.153342)
			(xy 57.86754 -38.1765) (xy 57.88709 -38.195179) (xy 57.910858 -38.208069) (xy 57.923938 -38.211506)
			(xy 57.951409 -38.218568) (xy 58.004043 -38.239705) (xy 58.052968 -38.268399) (xy 58.097108 -38.304018)
			(xy 58.13549 -38.345778) (xy 58.167269 -38.392758) (xy 58.191744 -38.443925) (xy 58.208377 -38.498151)
			(xy 58.216801 -38.554241) (xy 58.217308 -38.5826) (xy 58.216822 -38.609851) (xy 58.209066 -38.663799)
			(xy 58.193711 -38.716094) (xy 58.171069 -38.765671) (xy 58.141603 -38.811521) (xy 58.105912 -38.852712)
			(xy 58.064721 -38.888403) (xy 58.018871 -38.917869) (xy 57.969294 -38.940511) (xy 57.916999 -38.955866)
			(xy 57.863051 -38.963622) (xy 57.8358 -38.964108) (xy 57.816295 -38.963872) (xy 57.777485 -38.959922)
			(xy 57.75833 -38.956234) (xy 57.74285 -38.953631) (xy 57.711647 -38.956906) (xy 57.682905 -38.969483)
			(xy 57.659326 -38.99018) (xy 57.643129 -39.01705) (xy 57.63895 -39.03218) (xy 57.635131 -39.047503)
			(xy 57.624948 -39.077397) (xy 57.61863 -39.09187) (xy 57.614058 -39.101776) (xy 57.614058 -39.70909)
			(xy 57.615074 -39.713662) (xy 57.617845 -39.729133) (xy 57.620773 -39.760429) (xy 57.620916 -39.776146)
			(xy 57.620755 -39.791862) (xy 57.617832 -39.823157) (xy 57.615074 -39.83863) (xy 57.614058 -39.843202)
			(xy 57.614058 -40.508936) (xy 57.615074 -40.513508) (xy 57.617842 -40.528979) (xy 57.620766 -40.560275)
			(xy 57.620916 -40.575992) (xy 57.620753 -40.591708) (xy 57.619792 -40.601979) (xy 57.76011 -40.601979)
			(xy 57.76011 -40.550005) (xy 57.76824 -40.49867) (xy 57.784301 -40.44924) (xy 57.807897 -40.40293)
			(xy 57.838447 -40.360882) (xy 57.875198 -40.324131) (xy 57.917246 -40.293581) (xy 57.963556 -40.269985)
			(xy 58.012986 -40.253924) (xy 58.064321 -40.245794) (xy 58.116295 -40.245794) (xy 58.16763 -40.253924)
			(xy 58.21706 -40.269985) (xy 58.26337 -40.293581) (xy 58.305418 -40.324131) (xy 58.342169 -40.360882)
			(xy 58.372719 -40.40293) (xy 58.396315 -40.44924) (xy 58.412376 -40.49867) (xy 58.420506 -40.550005)
			(xy 58.421016 -40.575992) (xy 58.420506 -40.601979) (xy 58.412376 -40.653314) (xy 58.396315 -40.702744)
			(xy 58.372719 -40.749054) (xy 58.342169 -40.791102) (xy 58.305418 -40.827853) (xy 58.26337 -40.858403)
			(xy 58.21706 -40.881999) (xy 58.16763 -40.89806) (xy 58.116295 -40.90619) (xy 58.064321 -40.90619)
			(xy 58.012986 -40.89806) (xy 57.963556 -40.881999) (xy 57.917246 -40.858403) (xy 57.875198 -40.827853)
			(xy 57.838447 -40.791102) (xy 57.807897 -40.749054) (xy 57.784301 -40.702744) (xy 57.76824 -40.653314)
			(xy 57.76011 -40.601979) (xy 57.619792 -40.601979) (xy 57.617826 -40.623002) (xy 57.615074 -40.638476)
			(xy 57.614058 -40.643048) (xy 57.614058 -41.309036) (xy 57.615074 -41.313608) (xy 57.617842 -41.329079)
			(xy 57.620766 -41.360375) (xy 57.620916 -41.376092) (xy 57.620735 -41.392068) (xy 57.619774 -41.402079)
			(xy 57.76011 -41.402079) (xy 57.76011 -41.350105) (xy 57.76824 -41.29877) (xy 57.784301 -41.24934)
			(xy 57.807897 -41.20303) (xy 57.838447 -41.160982) (xy 57.875198 -41.124231) (xy 57.917246 -41.093681)
			(xy 57.963556 -41.070085) (xy 58.012986 -41.054024) (xy 58.064321 -41.045894) (xy 58.116295 -41.045894)
			(xy 58.16763 -41.054024) (xy 58.21706 -41.070085) (xy 58.26337 -41.093681) (xy 58.305418 -41.124231)
			(xy 58.342169 -41.160982) (xy 58.372719 -41.20303) (xy 58.396315 -41.24934) (xy 58.412376 -41.29877)
			(xy 58.420506 -41.350105) (xy 58.421016 -41.376092) (xy 58.420506 -41.402079) (xy 58.412376 -41.453414)
			(xy 58.396315 -41.502844) (xy 58.372719 -41.549154) (xy 58.342169 -41.591202) (xy 58.305418 -41.627953)
			(xy 58.26337 -41.658503) (xy 58.21706 -41.682099) (xy 58.16763 -41.69816) (xy 58.116295 -41.70629)
			(xy 58.064321 -41.70629) (xy 58.012986 -41.69816) (xy 57.963556 -41.682099) (xy 57.917246 -41.658503)
			(xy 57.875198 -41.627953) (xy 57.838447 -41.591202) (xy 57.807897 -41.549154) (xy 57.784301 -41.502844)
			(xy 57.76824 -41.453414) (xy 57.76011 -41.402079) (xy 57.619774 -41.402079) (xy 57.617681 -41.423873)
			(xy 57.61482 -41.439592) (xy 57.613804 -41.444418) (xy 57.613804 -42.107612) (xy 57.61482 -42.112438)
			(xy 57.617695 -42.128155) (xy 57.620753 -42.159961) (xy 57.620916 -42.175938) (xy 57.620738 -42.191914)
			(xy 57.619778 -42.201925) (xy 57.76011 -42.201925) (xy 57.76011 -42.149951) (xy 57.76824 -42.098616)
			(xy 57.784301 -42.049186) (xy 57.807897 -42.002876) (xy 57.838447 -41.960828) (xy 57.875198 -41.924077)
			(xy 57.917246 -41.893527) (xy 57.963556 -41.869931) (xy 58.012986 -41.85387) (xy 58.064321 -41.84574)
			(xy 58.116295 -41.84574) (xy 58.16763 -41.85387) (xy 58.21706 -41.869931) (xy 58.26337 -41.893527)
			(xy 58.305418 -41.924077) (xy 58.342169 -41.960828) (xy 58.372719 -42.002876) (xy 58.396315 -42.049186)
			(xy 58.412376 -42.098616) (xy 58.420506 -42.149951) (xy 58.421016 -42.175938) (xy 58.420506 -42.201925)
			(xy 58.412376 -42.25326) (xy 58.396315 -42.30269) (xy 58.372719 -42.349) (xy 58.342169 -42.391048)
			(xy 58.305418 -42.427799) (xy 58.26337 -42.458349) (xy 58.21706 -42.481945) (xy 58.16763 -42.498006)
			(xy 58.116295 -42.506136) (xy 58.064321 -42.506136) (xy 58.012986 -42.498006) (xy 57.963556 -42.481945)
			(xy 57.917246 -42.458349) (xy 57.875198 -42.427799) (xy 57.838447 -42.391048) (xy 57.807897 -42.349)
			(xy 57.784301 -42.30269) (xy 57.76824 -42.25326) (xy 57.76011 -42.201925) (xy 57.619778 -42.201925)
			(xy 57.617689 -42.223721) (xy 57.61482 -42.239438) (xy 57.613804 -42.244264) (xy 57.613804 -42.907712)
			(xy 57.61482 -42.912538) (xy 57.617695 -42.928255) (xy 57.620753 -42.960061) (xy 57.620916 -42.976038)
			(xy 57.620738 -42.992014) (xy 57.619778 -43.002025) (xy 57.76011 -43.002025) (xy 57.76011 -42.950051)
			(xy 57.76824 -42.898716) (xy 57.784301 -42.849286) (xy 57.807897 -42.802976) (xy 57.838447 -42.760928)
			(xy 57.875198 -42.724177) (xy 57.917246 -42.693627) (xy 57.963556 -42.670031) (xy 58.012986 -42.65397)
			(xy 58.064321 -42.64584) (xy 58.116295 -42.64584) (xy 58.16763 -42.65397) (xy 58.21706 -42.670031)
			(xy 58.26337 -42.693627) (xy 58.305418 -42.724177) (xy 58.342169 -42.760928) (xy 58.372719 -42.802976)
			(xy 58.396315 -42.849286) (xy 58.412376 -42.898716) (xy 58.420506 -42.950051) (xy 58.421016 -42.976038)
			(xy 58.420506 -43.002025) (xy 58.412376 -43.05336) (xy 58.396315 -43.10279) (xy 58.372719 -43.1491)
			(xy 58.342169 -43.191148) (xy 58.305418 -43.227899) (xy 58.26337 -43.258449) (xy 58.21706 -43.282045)
			(xy 58.16763 -43.298106) (xy 58.116295 -43.306236) (xy 58.064321 -43.306236) (xy 58.012986 -43.298106)
			(xy 57.963556 -43.282045) (xy 57.917246 -43.258449) (xy 57.875198 -43.227899) (xy 57.838447 -43.191148)
			(xy 57.807897 -43.1491) (xy 57.784301 -43.10279) (xy 57.76824 -43.05336) (xy 57.76011 -43.002025)
			(xy 57.619778 -43.002025) (xy 57.617689 -43.023821) (xy 57.61482 -43.039538) (xy 57.613804 -43.044364)
			(xy 57.613804 -45.307758) (xy 57.61482 -45.312584) (xy 57.617693 -45.328301) (xy 57.620746 -45.360107)
			(xy 57.620916 -45.376084) (xy 57.620735 -45.39206) (xy 57.617682 -45.423865) (xy 57.61482 -45.439584)
			(xy 57.613804 -45.44441) (xy 57.613804 -45.553884) (xy 57.686956 -45.62729) (xy 58.369962 -45.62729)
		)
		(stroke
			(width 0)
			(type solid)
		)
		(fill yes)
		(layer "In2.Cu")
		(net "P3V3_BMC_USB2AV33")
	)
	(gr_poly
		(pts
			(xy 43.466258 -51.453542) (xy 43.867324 -51.453542) (xy 44.20362 -51.1175) (xy 44.20362 -51.113182)
			(xy 44.192778 -51.090239) (xy 44.17742 -51.041878) (xy 44.169614 -50.99174) (xy 44.169076 -50.96637)
			(xy 44.169586 -50.940383) (xy 44.177716 -50.889048) (xy 44.193777 -50.839618) (xy 44.217373 -50.793308)
			(xy 44.247923 -50.75126) (xy 44.284674 -50.714509) (xy 44.326722 -50.683959) (xy 44.373032 -50.660363)
			(xy 44.422462 -50.644302) (xy 44.473797 -50.636172) (xy 44.525771 -50.636172) (xy 44.577106 -50.644302)
			(xy 44.626536 -50.660363) (xy 44.672846 -50.683959) (xy 44.714894 -50.714509) (xy 44.751645 -50.75126)
			(xy 44.782195 -50.793308) (xy 44.805791 -50.839618) (xy 44.821852 -50.889048) (xy 44.829982 -50.940383)
			(xy 44.830492 -50.96637) (xy 44.830114 -50.989952) (xy 44.82977 -50.992357) (xy 44.969686 -50.992357)
			(xy 44.969686 -50.940383) (xy 44.977816 -50.889048) (xy 44.993877 -50.839618) (xy 45.017473 -50.793308)
			(xy 45.048023 -50.75126) (xy 45.084774 -50.714509) (xy 45.126822 -50.683959) (xy 45.173132 -50.660363)
			(xy 45.222562 -50.644302) (xy 45.273897 -50.636172) (xy 45.325871 -50.636172) (xy 45.377206 -50.644302)
			(xy 45.426636 -50.660363) (xy 45.472946 -50.683959) (xy 45.514994 -50.714509) (xy 45.551745 -50.75126)
			(xy 45.582295 -50.793308) (xy 45.605891 -50.839618) (xy 45.621952 -50.889048) (xy 45.630082 -50.940383)
			(xy 45.630592 -50.96637) (xy 45.630082 -50.992357) (xy 45.769532 -50.992357) (xy 45.769532 -50.940383)
			(xy 45.777662 -50.889048) (xy 45.793723 -50.839618) (xy 45.817319 -50.793308) (xy 45.847869 -50.75126)
			(xy 45.88462 -50.714509) (xy 45.926668 -50.683959) (xy 45.972978 -50.660363) (xy 46.022408 -50.644302)
			(xy 46.073743 -50.636172) (xy 46.125717 -50.636172) (xy 46.177052 -50.644302) (xy 46.226482 -50.660363)
			(xy 46.272792 -50.683959) (xy 46.31484 -50.714509) (xy 46.351591 -50.75126) (xy 46.382141 -50.793308)
			(xy 46.405737 -50.839618) (xy 46.421798 -50.889048) (xy 46.429928 -50.940383) (xy 46.430438 -50.96637)
			(xy 46.429928 -50.992357) (xy 46.421798 -51.043692) (xy 46.405737 -51.093122) (xy 46.382141 -51.139432)
			(xy 46.351591 -51.18148) (xy 46.31484 -51.218231) (xy 46.272792 -51.248781) (xy 46.226482 -51.272377)
			(xy 46.177052 -51.288438) (xy 46.125717 -51.296568) (xy 46.073743 -51.296568) (xy 46.022408 -51.288438)
			(xy 45.972978 -51.272377) (xy 45.926668 -51.248781) (xy 45.88462 -51.218231) (xy 45.847869 -51.18148)
			(xy 45.817319 -51.139432) (xy 45.793723 -51.093122) (xy 45.777662 -51.043692) (xy 45.769532 -50.992357)
			(xy 45.630082 -50.992357) (xy 45.621952 -51.043692) (xy 45.605891 -51.093122) (xy 45.582295 -51.139432)
			(xy 45.551745 -51.18148) (xy 45.514994 -51.218231) (xy 45.472946 -51.248781) (xy 45.426636 -51.272377)
			(xy 45.377206 -51.288438) (xy 45.325871 -51.296568) (xy 45.273897 -51.296568) (xy 45.222562 -51.288438)
			(xy 45.173132 -51.272377) (xy 45.126822 -51.248781) (xy 45.084774 -51.218231) (xy 45.048023 -51.18148)
			(xy 45.017473 -51.139432) (xy 44.993877 -51.093122) (xy 44.977816 -51.043692) (xy 44.969686 -50.992357)
			(xy 44.82977 -50.992357) (xy 44.823442 -51.036642) (xy 44.810187 -51.081904) (xy 44.800774 -51.10353)
			(xy 44.795948 -51.11369) (xy 44.795948 -51.240182) (xy 44.795667 -51.261297) (xy 44.789801 -51.303116)
			(xy 44.784264 -51.323494) (xy 44.780898 -51.336533) (xy 44.78039 -51.363449) (xy 44.786937 -51.389561)
			(xy 44.800083 -51.413054) (xy 44.818914 -51.432292) (xy 44.84212 -51.445937) (xy 44.868087 -51.45304)
			(xy 44.881546 -51.453542) (xy 44.925742 -51.453542) (xy 44.999656 -51.527456) (xy 45.006992 -51.534097)
			(xy 45.025239 -51.541703) (xy 45.045007 -51.541851) (xy 45.063365 -51.534519) (xy 45.070776 -51.527964)
			(xy 45.089372 -51.510772) (xy 45.130819 -51.48167) (xy 45.176219 -51.45923) (xy 45.22451 -51.443976)
			(xy 45.274562 -51.436266) (xy 45.299884 -51.435762) (xy 45.325873 -51.43627) (xy 45.377211 -51.444399)
			(xy 45.426646 -51.460458) (xy 45.47296 -51.484052) (xy 45.515012 -51.514601) (xy 45.551769 -51.551353)
			(xy 45.582323 -51.593401) (xy 45.605924 -51.639712) (xy 45.621991 -51.689144) (xy 45.630126 -51.740481)
			(xy 45.630592 -51.76647) (xy 45.630112 -51.791793) (xy 45.63001 -51.792457) (xy 45.769532 -51.792457)
			(xy 45.769532 -51.740483) (xy 45.777662 -51.689148) (xy 45.793723 -51.639718) (xy 45.817319 -51.593408)
			(xy 45.847869 -51.55136) (xy 45.88462 -51.514609) (xy 45.926668 -51.484059) (xy 45.972978 -51.460463)
			(xy 46.022408 -51.444402) (xy 46.073743 -51.436272) (xy 46.125717 -51.436272) (xy 46.177052 -51.444402)
			(xy 46.226482 -51.460463) (xy 46.272792 -51.484059) (xy 46.31484 -51.514609) (xy 46.351591 -51.55136)
			(xy 46.382141 -51.593408) (xy 46.405737 -51.639718) (xy 46.421798 -51.689148) (xy 46.429928 -51.740483)
			(xy 46.430438 -51.76647) (xy 46.429928 -51.792457) (xy 46.569632 -51.792457) (xy 46.569632 -51.740483)
			(xy 46.577762 -51.689148) (xy 46.593823 -51.639718) (xy 46.617419 -51.593408) (xy 46.647969 -51.55136)
			(xy 46.68472 -51.514609) (xy 46.726768 -51.484059) (xy 46.773078 -51.460463) (xy 46.822508 -51.444402)
			(xy 46.873843 -51.436272) (xy 46.925817 -51.436272) (xy 46.977152 -51.444402) (xy 47.026582 -51.460463)
			(xy 47.072892 -51.484059) (xy 47.11494 -51.514609) (xy 47.151691 -51.55136) (xy 47.182241 -51.593408)
			(xy 47.205837 -51.639718) (xy 47.221898 -51.689148) (xy 47.230028 -51.740483) (xy 47.230538 -51.76647)
			(xy 47.230028 -51.792457) (xy 47.221898 -51.843792) (xy 47.205837 -51.893222) (xy 47.182241 -51.939532)
			(xy 47.151691 -51.98158) (xy 47.11494 -52.018331) (xy 47.072892 -52.048881) (xy 47.026582 -52.072477)
			(xy 46.977152 -52.088538) (xy 46.925817 -52.096668) (xy 46.873843 -52.096668) (xy 46.822508 -52.088538)
			(xy 46.773078 -52.072477) (xy 46.726768 -52.048881) (xy 46.68472 -52.018331) (xy 46.647969 -51.98158)
			(xy 46.617419 -51.939532) (xy 46.593823 -51.893222) (xy 46.577762 -51.843792) (xy 46.569632 -51.792457)
			(xy 46.429928 -51.792457) (xy 46.421798 -51.843792) (xy 46.405737 -51.893222) (xy 46.382141 -51.939532)
			(xy 46.351591 -51.98158) (xy 46.31484 -52.018331) (xy 46.272792 -52.048881) (xy 46.226482 -52.072477)
			(xy 46.177052 -52.088538) (xy 46.125717 -52.096668) (xy 46.073743 -52.096668) (xy 46.022408 -52.088538)
			(xy 45.972978 -52.072477) (xy 45.926668 -52.048881) (xy 45.88462 -52.018331) (xy 45.847869 -51.98158)
			(xy 45.817319 -51.939532) (xy 45.793723 -51.893222) (xy 45.777662 -51.843792) (xy 45.769532 -51.792457)
			(xy 45.63001 -51.792457) (xy 45.622396 -51.841848) (xy 45.60714 -51.890142) (xy 45.584701 -51.935546)
			(xy 45.555603 -51.976999) (xy 45.53839 -51.995578) (xy 45.53186 -52.00301) (xy 45.524523 -52.021363)
			(xy 45.524658 -52.041127) (xy 45.532246 -52.059377) (xy 45.538898 -52.066698) (xy 45.799502 -52.327302)
			(xy 45.806793 -52.334001) (xy 45.825008 -52.341712) (xy 45.844786 -52.341911) (xy 45.863152 -52.334568)
			(xy 45.870622 -52.328064) (xy 45.889217 -52.310868) (xy 45.930662 -52.28176) (xy 45.976062 -52.259313)
			(xy 46.024353 -52.244051) (xy 46.074407 -52.236332) (xy 46.09973 -52.235862) (xy 46.124393 -52.236313)
			(xy 46.173172 -52.243633) (xy 46.220322 -52.25812) (xy 46.264796 -52.279453) (xy 46.305606 -52.307159)
			(xy 46.341845 -52.340621) (xy 46.372709 -52.379097) (xy 46.38548 -52.4002) (xy 46.61408 -52.4002)
			(xy 46.627899 -52.377515) (xy 46.661618 -52.336476) (xy 46.701464 -52.301355) (xy 46.746411 -52.273055)
			(xy 46.795305 -52.252305) (xy 46.846886 -52.239637) (xy 46.89983 -52.235378) (xy 46.952774 -52.239637)
			(xy 47.004355 -52.252305) (xy 47.053249 -52.273055) (xy 47.098196 -52.301355) (xy 47.138042 -52.336476)
			(xy 47.171761 -52.377515) (xy 47.18558 -52.4002) (xy 47.6758 -52.4002) (xy 47.9044 -52.1716) (xy 48.497236 -52.1716)
			(xy 48.852836 -51.816) (xy 48.852836 -51.317906) (xy 48.852401 -51.303959) (xy 48.844851 -51.277106)
			(xy 48.830311 -51.253301) (xy 48.80987 -51.234321) (xy 48.785053 -51.221585) (xy 48.757715 -51.216044)
			(xy 48.729897 -51.218111) (xy 48.703679 -51.227633) (xy 48.692054 -51.235356) (xy 48.670897 -51.249896)
			(xy 48.625034 -51.272953) (xy 48.576157 -51.288643) (xy 48.525443 -51.296589) (xy 48.499776 -51.297078)
			(xy 48.473789 -51.296593) (xy 48.422455 -51.288459) (xy 48.373026 -51.272394) (xy 48.326718 -51.248794)
			(xy 48.284672 -51.218241) (xy 48.247924 -51.181487) (xy 48.217377 -51.139436) (xy 48.193785 -51.093125)
			(xy 48.177729 -51.043693) (xy 48.169603 -50.992357) (xy 48.169068 -50.96637) (xy 48.169517 -50.941518)
			(xy 48.17696 -50.892374) (xy 48.191672 -50.844896) (xy 48.213324 -50.800155) (xy 48.241427 -50.759158)
			(xy 48.275349 -50.722828) (xy 48.294544 -50.707036) (xy 48.305473 -50.697776) (xy 48.322123 -50.674484)
			(xy 48.331657 -50.647486) (xy 48.333325 -50.618903) (xy 48.326997 -50.590979) (xy 48.313169 -50.565908)
			(xy 48.303434 -50.555398) (xy 48.065436 -50.3174) (xy 47.994062 -50.3174) (xy 47.981771 -50.340243)
			(xy 47.951178 -50.38213) (xy 47.914428 -50.418734) (xy 47.872419 -50.44916) (xy 47.82618 -50.472663)
			(xy 47.776841 -50.488668) (xy 47.725611 -50.496784) (xy 47.699676 -50.497232) (xy 47.674052 -50.496748)
			(xy 47.623419 -50.488837) (xy 47.574613 -50.473209) (xy 47.528803 -50.450237) (xy 47.507652 -50.435764)
			(xy 47.4962 -50.428158) (xy 47.470377 -50.418761) (xy 47.442982 -50.416593) (xy 47.416002 -50.421812)
			(xy 47.391392 -50.434039) (xy 47.370936 -50.452389) (xy 47.363126 -50.463704) (xy 47.346814 -50.488408)
			(xy 47.309687 -50.53452) (xy 47.267826 -50.576382) (xy 47.221714 -50.613509) (xy 47.19701 -50.62982)
			(xy 47.185662 -50.637595) (xy 47.167274 -50.65804) (xy 47.155025 -50.682658) (xy 47.149809 -50.709656)
			(xy 47.152006 -50.737066) (xy 47.161455 -50.762889) (xy 47.16907 -50.774346) (xy 47.183558 -50.795487)
			(xy 47.206525 -50.841302) (xy 47.22215 -50.890111) (xy 47.23006 -50.940746) (xy 47.230538 -50.96637)
			(xy 47.230028 -50.992357) (xy 47.369478 -50.992357) (xy 47.369478 -50.940383) (xy 47.377608 -50.889048)
			(xy 47.393669 -50.839618) (xy 47.417265 -50.793308) (xy 47.447815 -50.75126) (xy 47.484566 -50.714509)
			(xy 47.526614 -50.683959) (xy 47.572924 -50.660363) (xy 47.622354 -50.644302) (xy 47.673689 -50.636172)
			(xy 47.725663 -50.636172) (xy 47.776998 -50.644302) (xy 47.826428 -50.660363) (xy 47.872738 -50.683959)
			(xy 47.914786 -50.714509) (xy 47.951537 -50.75126) (xy 47.982087 -50.793308) (xy 48.005683 -50.839618)
			(xy 48.021744 -50.889048) (xy 48.029874 -50.940383) (xy 48.030384 -50.96637) (xy 48.029874 -50.992357)
			(xy 48.021744 -51.043692) (xy 48.005683 -51.093122) (xy 47.982087 -51.139432) (xy 47.951537 -51.18148)
			(xy 47.914786 -51.218231) (xy 47.872738 -51.248781) (xy 47.826428 -51.272377) (xy 47.776998 -51.288438)
			(xy 47.725663 -51.296568) (xy 47.673689 -51.296568) (xy 47.622354 -51.288438) (xy 47.572924 -51.272377)
			(xy 47.526614 -51.248781) (xy 47.484566 -51.218231) (xy 47.447815 -51.18148) (xy 47.417265 -51.139432)
			(xy 47.393669 -51.093122) (xy 47.377608 -51.043692) (xy 47.369478 -50.992357) (xy 47.230028 -50.992357)
			(xy 47.221898 -51.043692) (xy 47.205837 -51.093122) (xy 47.182241 -51.139432) (xy 47.151691 -51.18148)
			(xy 47.11494 -51.218231) (xy 47.072892 -51.248781) (xy 47.026582 -51.272377) (xy 46.977152 -51.288438)
			(xy 46.925817 -51.296568) (xy 46.873843 -51.296568) (xy 46.822508 -51.288438) (xy 46.773078 -51.272377)
			(xy 46.726768 -51.248781) (xy 46.68472 -51.218231) (xy 46.647969 -51.18148) (xy 46.617419 -51.139432)
			(xy 46.593823 -51.093122) (xy 46.577762 -51.043692) (xy 46.569632 -50.992357) (xy 46.569122 -50.96637)
			(xy 46.569606 -50.940746) (xy 46.577516 -50.890113) (xy 46.593144 -50.841306) (xy 46.616114 -50.795495)
			(xy 46.63059 -50.774346) (xy 46.638198 -50.762895) (xy 46.647598 -50.737074) (xy 46.649766 -50.709679)
			(xy 46.644545 -50.6827) (xy 46.632312 -50.658093) (xy 46.613956 -50.637643) (xy 46.60265 -50.62982)
			(xy 46.577939 -50.613479) (xy 46.531818 -50.576289) (xy 46.489956 -50.534364) (xy 46.452836 -50.488187)
			(xy 46.436534 -50.46345) (xy 46.428739 -50.45213) (xy 46.408277 -50.433794) (xy 46.383667 -50.42158)
			(xy 46.35669 -50.416371) (xy 46.329302 -50.418545) (xy 46.303485 -50.427944) (xy 46.292008 -50.43551)
			(xy 46.270851 -50.450051) (xy 46.224988 -50.473112) (xy 46.176112 -50.488807) (xy 46.125397 -50.496761)
			(xy 46.09973 -50.497232) (xy 46.073737 -50.496751) (xy 46.022391 -50.488623) (xy 45.972949 -50.472562)
			(xy 45.926629 -50.448964) (xy 45.88457 -50.41841) (xy 45.847809 -50.381653) (xy 45.817251 -50.339597)
			(xy 45.793649 -50.293278) (xy 45.777584 -50.243838) (xy 45.769451 -50.192493) (xy 45.769451 -50.140507)
			(xy 45.777584 -50.089162) (xy 45.793649 -50.039722) (xy 45.817251 -49.993403) (xy 45.847809 -49.951347)
			(xy 45.88457 -49.91459) (xy 45.926629 -49.884036) (xy 45.972949 -49.860438) (xy 46.022391 -49.844377)
			(xy 46.073737 -49.836249) (xy 46.09973 -49.835816) (xy 46.130772 -49.836546) (xy 46.191756 -49.848184)
			(xy 46.220888 -49.85893) (xy 46.230735 -49.862319) (xy 46.251531 -49.861727) (xy 46.270388 -49.852941)
			(xy 46.28422 -49.837402) (xy 46.290761 -49.817653) (xy 46.288939 -49.796928) (xy 46.279052 -49.778624)
			(xy 46.27118 -49.771808) (xy 46.257577 -49.760729) (xy 46.231651 -49.737087) (xy 46.219364 -49.724564)
			(xy 45.010832 -49.724564) (xy 44.979953 -49.724165) (xy 44.91858 -49.717283) (xy 44.858363 -49.70357)
			(xy 44.800063 -49.683197) (xy 44.744411 -49.656421) (xy 44.69211 -49.623579) (xy 44.643817 -49.585085)
			(xy 44.621704 -49.563528) (xy 44.384976 -49.3268) (xy 43.643042 -49.3268) (xy 43.621745 -49.345891)
			(xy 43.574509 -49.378135) (xy 43.522992 -49.402974) (xy 43.468347 -49.419854) (xy 43.411796 -49.428397)
			(xy 43.3832 -49.428908) (xy 43.356432 -49.428436) (xy 43.303425 -49.420915) (xy 43.251989 -49.406064)
			(xy 43.203132 -49.384172) (xy 43.157813 -49.35567) (xy 43.137074 -49.338738) (xy 43.12285 -49.3268)
			(xy 43.018456 -49.3268) (xy 42.202608 -50.142648) (xy 42.18046 -50.164165) (xy 42.132165 -50.202647)
			(xy 42.079866 -50.235481) (xy 42.024221 -50.262255) (xy 41.965928 -50.282632) (xy 41.905721 -50.296356)
			(xy 41.844356 -50.303255) (xy 41.81348 -50.303684) (xy 41.656 -50.303684) (xy 41.656 -50.96637) (xy 43.290236 -50.96637)
			(xy 43.290708 -50.941001) (xy 43.297917 -50.890777) (xy 43.312186 -50.842085) (xy 43.333224 -50.795914)
			(xy 43.360605 -50.753197) (xy 43.37685 -50.733706) (xy 43.386019 -50.722442) (xy 43.398078 -50.696029)
			(xy 43.402208 -50.667289) (xy 43.398072 -50.638549) (xy 43.386007 -50.612139) (xy 43.37685 -50.600864)
			(xy 43.360606 -50.581371) (xy 43.333214 -50.538659) (xy 43.312168 -50.492489) (xy 43.297895 -50.443796)
			(xy 43.290686 -50.39357) (xy 43.290236 -50.3682) (xy 43.290734 -50.341551) (xy 43.298677 -50.288847)
			(xy 43.314387 -50.237917) (xy 43.337513 -50.189896) (xy 43.367537 -50.145859) (xy 43.403789 -50.106788)
			(xy 43.44546 -50.073557) (xy 43.491618 -50.046908) (xy 43.541232 -50.027436) (xy 43.593194 -50.015576)
			(xy 43.646344 -50.011593) (xy 43.699494 -50.015576) (xy 43.751456 -50.027436) (xy 43.80107 -50.046908)
			(xy 43.847228 -50.073557) (xy 43.888899 -50.106788) (xy 43.925151 -50.145859) (xy 43.955175 -50.189896)
			(xy 43.956434 -50.192511) (xy 44.169586 -50.192511) (xy 44.169586 -50.140537) (xy 44.177716 -50.089202)
			(xy 44.193777 -50.039772) (xy 44.217373 -49.993462) (xy 44.247923 -49.951414) (xy 44.284674 -49.914663)
			(xy 44.326722 -49.884113) (xy 44.373032 -49.860517) (xy 44.422462 -49.844456) (xy 44.473797 -49.836326)
			(xy 44.525771 -49.836326) (xy 44.577106 -49.844456) (xy 44.626536 -49.860517) (xy 44.672846 -49.884113)
			(xy 44.714894 -49.914663) (xy 44.751645 -49.951414) (xy 44.782195 -49.993462) (xy 44.805791 -50.039772)
			(xy 44.821852 -50.089202) (xy 44.829982 -50.140537) (xy 44.830492 -50.166524) (xy 44.829982 -50.192511)
			(xy 44.969686 -50.192511) (xy 44.969686 -50.140537) (xy 44.977816 -50.089202) (xy 44.993877 -50.039772)
			(xy 45.017473 -49.993462) (xy 45.048023 -49.951414) (xy 45.084774 -49.914663) (xy 45.126822 -49.884113)
			(xy 45.173132 -49.860517) (xy 45.222562 -49.844456) (xy 45.273897 -49.836326) (xy 45.325871 -49.836326)
			(xy 45.377206 -49.844456) (xy 45.426636 -49.860517) (xy 45.472946 -49.884113) (xy 45.514994 -49.914663)
			(xy 45.551745 -49.951414) (xy 45.582295 -49.993462) (xy 45.605891 -50.039772) (xy 45.621952 -50.089202)
			(xy 45.630082 -50.140537) (xy 45.630592 -50.166524) (xy 45.630082 -50.192511) (xy 45.621952 -50.243846)
			(xy 45.605891 -50.293276) (xy 45.582295 -50.339586) (xy 45.551745 -50.381634) (xy 45.514994 -50.418385)
			(xy 45.472946 -50.448935) (xy 45.426636 -50.472531) (xy 45.377206 -50.488592) (xy 45.325871 -50.496722)
			(xy 45.273897 -50.496722) (xy 45.222562 -50.488592) (xy 45.173132 -50.472531) (xy 45.126822 -50.448935)
			(xy 45.084774 -50.418385) (xy 45.048023 -50.381634) (xy 45.017473 -50.339586) (xy 44.993877 -50.293276)
			(xy 44.977816 -50.243846) (xy 44.969686 -50.192511) (xy 44.829982 -50.192511) (xy 44.821852 -50.243846)
			(xy 44.805791 -50.293276) (xy 44.782195 -50.339586) (xy 44.751645 -50.381634) (xy 44.714894 -50.418385)
			(xy 44.672846 -50.448935) (xy 44.626536 -50.472531) (xy 44.577106 -50.488592) (xy 44.525771 -50.496722)
			(xy 44.473797 -50.496722) (xy 44.422462 -50.488592) (xy 44.373032 -50.472531) (xy 44.326722 -50.448935)
			(xy 44.284674 -50.418385) (xy 44.247923 -50.381634) (xy 44.217373 -50.339586) (xy 44.193777 -50.293276)
			(xy 44.177716 -50.243846) (xy 44.169586 -50.192511) (xy 43.956434 -50.192511) (xy 43.978301 -50.237917)
			(xy 43.994011 -50.288847) (xy 44.001954 -50.341551) (xy 44.002452 -50.3682) (xy 44.002024 -50.393571)
			(xy 43.994804 -50.443797) (xy 43.980526 -50.492489) (xy 43.959478 -50.53866) (xy 43.932087 -50.581374)
			(xy 43.915838 -50.600864) (xy 43.906787 -50.612197) (xy 43.894804 -50.638593) (xy 43.890698 -50.667289)
			(xy 43.894798 -50.695985) (xy 43.906775 -50.722384) (xy 43.915838 -50.733706) (xy 43.932066 -50.753212)
			(xy 43.959461 -50.79592) (xy 43.98051 -50.842087) (xy 43.994786 -50.890777) (xy 44.002 -50.941) (xy 44.002452 -50.96637)
			(xy 44.001954 -50.993019) (xy 43.994011 -51.045723) (xy 43.978301 -51.096653) (xy 43.955175 -51.144674)
			(xy 43.925151 -51.188711) (xy 43.888899 -51.227782) (xy 43.847228 -51.261013) (xy 43.80107 -51.287662)
			(xy 43.751456 -51.307134) (xy 43.699494 -51.318994) (xy 43.646344 -51.322978) (xy 43.593194 -51.318994)
			(xy 43.541232 -51.307134) (xy 43.491618 -51.287662) (xy 43.44546 -51.261013) (xy 43.403789 -51.227782)
			(xy 43.367537 -51.188711) (xy 43.337513 -51.144674) (xy 43.314387 -51.096653) (xy 43.298677 -51.045723)
			(xy 43.290734 -50.993019) (xy 43.290236 -50.96637) (xy 41.656 -50.96637) (xy 41.656 -52.324) (xy 41.873932 -52.541932)
			(xy 42.377868 -52.541932)
		)
		(stroke
			(width 0)
			(type solid)
		)
		(fill yes)
		(layer "In2.Cu")
		(net "P1V2_P1V0_I3C_VDDL2")
	)
	(gr_poly
		(pts
			(xy 69.44741 -64.28232) (xy 69.44741 -63.491872) (xy 67.720464 -61.764926) (xy 66.437764 -61.764926)
			(xy 65.378838 -60.706) (xy 64.7192 -60.706) (xy 64.110362 -60.097416) (xy 63.690246 -60.097416) (xy 63.677038 -60.096908)
			(xy 63.666128 -60.096986) (xy 63.645947 -60.105216) (xy 63.630992 -60.121072) (xy 63.623954 -60.141699)
			(xy 63.6261 -60.163389) (xy 63.631064 -60.173108) (xy 63.645888 -60.200284) (xy 63.666954 -60.258486)
			(xy 63.677657 -60.319451) (xy 63.678308 -60.3504) (xy 63.67781 -60.377049) (xy 63.669867 -60.429753)
			(xy 63.654157 -60.480683) (xy 63.631031 -60.528704) (xy 63.601007 -60.572741) (xy 63.564755 -60.611812)
			(xy 63.523084 -60.645043) (xy 63.476926 -60.671692) (xy 63.427312 -60.691164) (xy 63.37535 -60.703024)
			(xy 63.3222 -60.707008) (xy 63.26905 -60.703024) (xy 63.217088 -60.691164) (xy 63.167474 -60.671692)
			(xy 63.121316 -60.645043) (xy 63.079645 -60.611812) (xy 63.043393 -60.572741) (xy 63.013369 -60.528704)
			(xy 62.990243 -60.480683) (xy 62.974533 -60.429753) (xy 62.96659 -60.377049) (xy 62.966092 -60.3504)
			(xy 62.966553 -60.324159) (xy 62.974243 -60.272244) (xy 62.989472 -60.222021) (xy 63.011909 -60.174577)
			(xy 63.041068 -60.130942) (xy 63.076317 -60.09206) (xy 63.116893 -60.058774) (xy 63.161915 -60.031806)
			(xy 63.210409 -60.011741) (xy 63.261324 -59.999012) (xy 63.287402 -59.99607) (xy 63.302313 -59.994026)
			(xy 63.330069 -59.98243) (xy 63.35325 -59.96326) (xy 63.36985 -59.938174) (xy 63.378432 -59.909344)
			(xy 63.378255 -59.879263) (xy 63.37427 -59.864752) (xy 63.367271 -59.840783) (xy 63.359751 -59.79142)
			(xy 63.359284 -59.766454) (xy 63.359863 -59.737606) (xy 63.369858 -59.680783) (xy 63.389573 -59.626559)
			(xy 63.418406 -59.576585) (xy 63.4365 -59.55411) (xy 63.445724 -59.542187) (xy 63.457424 -59.51442)
			(xy 63.460531 -59.48445) (xy 63.454774 -59.454875) (xy 63.440654 -59.428258) (xy 63.430404 -59.417204)
			(xy 63.239396 -59.226196) (xy 63.228359 -59.215907) (xy 63.201748 -59.201716) (xy 63.17215 -59.19593)
			(xy 63.142154 -59.199054) (xy 63.114384 -59.210816) (xy 63.10249 -59.2201) (xy 63.079967 -59.238121)
			(xy 63.029987 -59.266905) (xy 62.975781 -59.286612) (xy 62.918984 -59.296646) (xy 62.890146 -59.297316)
			(xy 62.0903 -59.297316) (xy 62.064296 -59.296806) (xy 62.01293 -59.28867) (xy 61.963468 -59.272599)
			(xy 61.91713 -59.248988) (xy 61.875055 -59.218419) (xy 61.838281 -59.181645) (xy 61.807712 -59.13957)
			(xy 61.784101 -59.093232) (xy 61.76803 -59.04377) (xy 61.759894 -58.992404) (xy 61.759894 -58.940396)
			(xy 61.76803 -58.88903) (xy 61.784101 -58.839568) (xy 61.807712 -58.79323) (xy 61.838281 -58.751155)
			(xy 61.875055 -58.714381) (xy 61.91713 -58.683812) (xy 61.963468 -58.660201) (xy 62.01293 -58.64413)
			(xy 62.064296 -58.635994) (xy 62.0903 -58.635392) (xy 62.403482 -58.635392) (xy 62.418454 -58.634864)
			(xy 62.44711 -58.626179) (xy 62.472012 -58.609553) (xy 62.491018 -58.586415) (xy 62.502492 -58.558757)
			(xy 62.505445 -58.52896) (xy 62.499625 -58.499588) (xy 62.485531 -58.473169) (xy 62.475364 -58.462164)
			(xy 62.37351 -58.36031) (xy 62.337442 -58.396632) (xy 62.336934 -58.396886) (xy 62.318117 -58.415514)
			(xy 62.275652 -58.447137) (xy 62.228693 -58.471593) (xy 62.178438 -58.488257) (xy 62.126171 -58.496705)
			(xy 62.099698 -58.497216) (xy 62.073711 -58.496706) (xy 62.022376 -58.488576) (xy 61.972945 -58.472514)
			(xy 61.926635 -58.448919) (xy 61.884587 -58.418369) (xy 61.847835 -58.381618) (xy 61.817284 -58.33957)
			(xy 61.793688 -58.29326) (xy 61.777626 -58.24383) (xy 61.769494 -58.192495) (xy 61.76899 -58.166508)
			(xy 61.769511 -58.140035) (xy 61.777948 -58.087766) (xy 61.794608 -58.037509) (xy 61.819064 -57.99055)
			(xy 61.850691 -57.948089) (xy 61.86932 -57.929272) (xy 61.869574 -57.928764) (xy 61.905896 -57.892696)
			(xy 61.848492 -57.835292) (xy 61.848492 -57.175908) (xy 60.698888 -56.02605) (xy 60.664598 -56.047386)
			(xy 60.644863 -56.05918) (xy 60.602827 -56.077797) (xy 60.558618 -56.090412) (xy 60.513087 -56.09678)
			(xy 60.4901 -56.09717) (xy 60.464112 -56.096687) (xy 60.412775 -56.088555) (xy 60.363343 -56.072493)
			(xy 60.317033 -56.048894) (xy 60.274985 -56.018341) (xy 60.238234 -55.981586) (xy 60.207686 -55.939535)
			(xy 60.184093 -55.893221) (xy 60.168036 -55.843788) (xy 60.15991 -55.79245) (xy 60.159392 -55.766462)
			(xy 60.159789 -55.743476) (xy 60.166162 -55.697948) (xy 60.178779 -55.653741) (xy 60.197398 -55.611708)
			(xy 60.209176 -55.591964) (xy 60.230512 -55.557674) (xy 58.3311 -53.658262) (xy 58.3311 -53.249068)
			(xy 58.149998 -53.067966) (xy 57.534302 -53.067966) (xy 57.378854 -53.223414) (xy 57.378854 -54.192503)
			(xy 57.769508 -54.192503) (xy 57.769508 -54.140529) (xy 57.777638 -54.089194) (xy 57.793699 -54.039764)
			(xy 57.817295 -53.993454) (xy 57.847845 -53.951406) (xy 57.884596 -53.914655) (xy 57.926644 -53.884105)
			(xy 57.972954 -53.860509) (xy 58.022384 -53.844448) (xy 58.073719 -53.836318) (xy 58.125693 -53.836318)
			(xy 58.177028 -53.844448) (xy 58.226458 -53.860509) (xy 58.272768 -53.884105) (xy 58.314816 -53.914655)
			(xy 58.351567 -53.951406) (xy 58.382117 -53.993454) (xy 58.405713 -54.039764) (xy 58.421774 -54.089194)
			(xy 58.429904 -54.140529) (xy 58.430414 -54.166516) (xy 58.429904 -54.192503) (xy 58.421774 -54.243838)
			(xy 58.405713 -54.293268) (xy 58.382117 -54.339578) (xy 58.351567 -54.381626) (xy 58.314816 -54.418377)
			(xy 58.272768 -54.448927) (xy 58.226458 -54.472523) (xy 58.177028 -54.488584) (xy 58.125693 -54.496714)
			(xy 58.073719 -54.496714) (xy 58.022384 -54.488584) (xy 57.972954 -54.472523) (xy 57.926644 -54.448927)
			(xy 57.884596 -54.418377) (xy 57.847845 -54.381626) (xy 57.817295 -54.339578) (xy 57.793699 -54.293268)
			(xy 57.777638 -54.243838) (xy 57.769508 -54.192503) (xy 57.378854 -54.192503) (xy 57.378854 -55.016654)
			(xy 57.473596 -55.111396) (xy 57.854342 -54.73065) (xy 57.873997 -54.711733) (xy 57.918111 -54.679645)
			(xy 57.966697 -54.654845) (xy 58.018562 -54.637944) (xy 58.072432 -54.629358) (xy 58.099706 -54.628796)
			(xy 58.126992 -54.629304) (xy 58.180892 -54.637842) (xy 58.232793 -54.654706) (xy 58.281416 -54.679483)
			(xy 58.325565 -54.711561) (xy 58.364152 -54.75015) (xy 58.396228 -54.794301) (xy 58.421001 -54.842926)
			(xy 58.437863 -54.894827) (xy 58.446398 -54.948728) (xy 58.446924 -54.976014) (xy 58.446399 -55.003292)
			(xy 58.437827 -55.05717) (xy 58.420928 -55.109043) (xy 58.396117 -55.157632) (xy 58.364008 -55.201738)
			(xy 58.34507 -55.221378) (xy 58.241946 -55.324502) (xy 58.231446 -55.335774) (xy 58.217158 -55.363049)
			(xy 58.211622 -55.393338) (xy 58.215338 -55.423904) (xy 58.22797 -55.451984) (xy 58.248378 -55.475041)
			(xy 58.26125 -55.483506) (xy 58.28182 -55.49641) (xy 58.319286 -55.5273) (xy 58.351827 -55.56334)
			(xy 58.378745 -55.603754) (xy 58.399459 -55.647673) (xy 58.413522 -55.694149) (xy 58.420634 -55.742183)
			(xy 58.421016 -55.766462) (xy 58.420622 -55.789731) (xy 58.418871 -55.802101) (xy 58.569608 -55.802101)
			(xy 58.569608 -55.750127) (xy 58.577738 -55.698792) (xy 58.593799 -55.649362) (xy 58.617395 -55.603052)
			(xy 58.647945 -55.561004) (xy 58.684696 -55.524253) (xy 58.726744 -55.493703) (xy 58.773054 -55.470107)
			(xy 58.822484 -55.454046) (xy 58.873819 -55.445916) (xy 58.925793 -55.445916) (xy 58.977128 -55.454046)
			(xy 59.026558 -55.470107) (xy 59.072868 -55.493703) (xy 59.114916 -55.524253) (xy 59.151667 -55.561004)
			(xy 59.182217 -55.603052) (xy 59.205813 -55.649362) (xy 59.221874 -55.698792) (xy 59.230004 -55.750127)
			(xy 59.230514 -55.776114) (xy 59.230193 -55.792449) (xy 59.360056 -55.792449) (xy 59.360056 -55.740475)
			(xy 59.368186 -55.68914) (xy 59.384247 -55.63971) (xy 59.407843 -55.5934) (xy 59.438393 -55.551352)
			(xy 59.475144 -55.514601) (xy 59.517192 -55.484051) (xy 59.563502 -55.460455) (xy 59.612932 -55.444394)
			(xy 59.664267 -55.436264) (xy 59.716241 -55.436264) (xy 59.767576 -55.444394) (xy 59.817006 -55.460455)
			(xy 59.863316 -55.484051) (xy 59.905364 -55.514601) (xy 59.942115 -55.551352) (xy 59.972665 -55.5934)
			(xy 59.996261 -55.63971) (xy 60.012322 -55.68914) (xy 60.020452 -55.740475) (xy 60.020962 -55.766462)
			(xy 60.020452 -55.792449) (xy 60.012322 -55.843784) (xy 59.996261 -55.893214) (xy 59.972665 -55.939524)
			(xy 59.942115 -55.981572) (xy 59.905364 -56.018323) (xy 59.863316 -56.048873) (xy 59.817006 -56.072469)
			(xy 59.767576 -56.08853) (xy 59.716241 -56.09666) (xy 59.664267 -56.09666) (xy 59.612932 -56.08853)
			(xy 59.563502 -56.072469) (xy 59.517192 -56.048873) (xy 59.475144 -56.018323) (xy 59.438393 -55.981572)
			(xy 59.407843 -55.939524) (xy 59.384247 -55.893214) (xy 59.368186 -55.843784) (xy 59.360056 -55.792449)
			(xy 59.230193 -55.792449) (xy 59.230004 -55.802101) (xy 59.221874 -55.853436) (xy 59.205813 -55.902866)
			(xy 59.182217 -55.949176) (xy 59.151667 -55.991224) (xy 59.114916 -56.027975) (xy 59.072868 -56.058525)
			(xy 59.026558 -56.082121) (xy 58.977128 -56.098182) (xy 58.925793 -56.106312) (xy 58.873819 -56.106312)
			(xy 58.822484 -56.098182) (xy 58.773054 -56.082121) (xy 58.726744 -56.058525) (xy 58.684696 -56.027975)
			(xy 58.647945 -55.991224) (xy 58.617395 -55.949176) (xy 58.593799 -55.902866) (xy 58.577738 -55.853436)
			(xy 58.569608 -55.802101) (xy 58.418871 -55.802101) (xy 58.414099 -55.835809) (xy 58.401177 -55.880517)
			(xy 58.382111 -55.92297) (xy 58.357279 -55.962328) (xy 58.34253 -55.98033) (xy 58.685938 -56.323738)
			(xy 58.703942 -56.308992) (xy 58.743304 -56.284169) (xy 58.785757 -56.265106) (xy 58.830462 -56.252179)
			(xy 58.876538 -56.245645) (xy 58.899806 -56.245252) (xy 58.925794 -56.245762) (xy 58.97713 -56.253893)
			(xy 59.026562 -56.269954) (xy 59.072874 -56.29355) (xy 59.114925 -56.324099) (xy 59.151679 -56.360849)
			(xy 59.182233 -56.402897) (xy 59.205833 -56.449206) (xy 59.221899 -56.498637) (xy 59.230035 -56.549972)
			(xy 59.230514 -56.57596) (xy 59.22998 -56.601947) (xy 59.369454 -56.601947) (xy 59.369454 -56.549973)
			(xy 59.377584 -56.498638) (xy 59.393645 -56.449208) (xy 59.417241 -56.402898) (xy 59.447791 -56.36085)
			(xy 59.484542 -56.324099) (xy 59.52659 -56.293549) (xy 59.5729 -56.269953) (xy 59.62233 -56.253892)
			(xy 59.673665 -56.245762) (xy 59.725639 -56.245762) (xy 59.776974 -56.253892) (xy 59.826404 -56.269953)
			(xy 59.872714 -56.293549) (xy 59.914762 -56.324099) (xy 59.951513 -56.36085) (xy 59.982063 -56.402898)
			(xy 60.005659 -56.449208) (xy 60.02172 -56.498638) (xy 60.02985 -56.549973) (xy 60.03036 -56.57596)
			(xy 60.030034 -56.592549) (xy 60.159902 -56.592549) (xy 60.159902 -56.540575) (xy 60.168032 -56.48924)
			(xy 60.184093 -56.43981) (xy 60.207689 -56.3935) (xy 60.238239 -56.351452) (xy 60.27499 -56.314701)
			(xy 60.317038 -56.284151) (xy 60.363348 -56.260555) (xy 60.412778 -56.244494) (xy 60.464113 -56.236364)
			(xy 60.516087 -56.236364) (xy 60.567422 -56.244494) (xy 60.616852 -56.260555) (xy 60.663162 -56.284151)
			(xy 60.70521 -56.314701) (xy 60.741961 -56.351452) (xy 60.772511 -56.3935) (xy 60.796107 -56.43981)
			(xy 60.812168 -56.48924) (xy 60.820298 -56.540575) (xy 60.820808 -56.566562) (xy 60.820298 -56.592549)
			(xy 60.812168 -56.643884) (xy 60.796107 -56.693314) (xy 60.772511 -56.739624) (xy 60.741961 -56.781672)
			(xy 60.70521 -56.818423) (xy 60.663162 -56.848973) (xy 60.616852 -56.872569) (xy 60.567422 -56.88863)
			(xy 60.516087 -56.89676) (xy 60.464113 -56.89676) (xy 60.412778 -56.88863) (xy 60.363348 -56.872569)
			(xy 60.317038 -56.848973) (xy 60.27499 -56.818423) (xy 60.238239 -56.781672) (xy 60.207689 -56.739624)
			(xy 60.184093 -56.693314) (xy 60.168032 -56.643884) (xy 60.159902 -56.592549) (xy 60.030034 -56.592549)
			(xy 60.02985 -56.601947) (xy 60.02172 -56.653282) (xy 60.005659 -56.702712) (xy 59.982063 -56.749022)
			(xy 59.951513 -56.79107) (xy 59.914762 -56.827821) (xy 59.872714 -56.858371) (xy 59.826404 -56.881967)
			(xy 59.776974 -56.898028) (xy 59.725639 -56.906158) (xy 59.673665 -56.906158) (xy 59.62233 -56.898028)
			(xy 59.5729 -56.881967) (xy 59.52659 -56.858371) (xy 59.484542 -56.827821) (xy 59.447791 -56.79107)
			(xy 59.417241 -56.749022) (xy 59.393645 -56.702712) (xy 59.377584 -56.653282) (xy 59.369454 -56.601947)
			(xy 59.22998 -56.601947) (xy 59.229945 -56.603671) (xy 59.220694 -56.658316) (xy 59.20246 -56.710654)
			(xy 59.18962 -56.735218) (xy 59.207749 -56.745612) (xy 59.241149 -56.770726) (xy 59.256168 -56.785256)
			(xy 59.51601 -57.045098) (xy 59.524544 -57.053855) (xy 59.540309 -57.07255) (xy 59.547506 -57.082436)
			(xy 59.571152 -57.070763) (xy 59.621226 -57.05424) (xy 59.673287 -57.045868) (xy 59.699652 -57.045352)
			(xy 59.725645 -57.045832) (xy 59.776992 -57.053957) (xy 59.826435 -57.070014) (xy 59.872758 -57.093609)
			(xy 59.914819 -57.124159) (xy 59.951583 -57.160914) (xy 59.982145 -57.202967) (xy 60.005752 -57.249283)
			(xy 60.021823 -57.298723) (xy 60.029962 -57.350067) (xy 60.03036 -57.37606) (xy 60.029991 -57.392395)
			(xy 60.169554 -57.392395) (xy 60.169554 -57.340421) (xy 60.177684 -57.289086) (xy 60.193745 -57.239656)
			(xy 60.217341 -57.193346) (xy 60.247891 -57.151298) (xy 60.284642 -57.114547) (xy 60.32669 -57.083997)
			(xy 60.373 -57.060401) (xy 60.42243 -57.04434) (xy 60.473765 -57.03621) (xy 60.525739 -57.03621)
			(xy 60.577074 -57.04434) (xy 60.626504 -57.060401) (xy 60.672814 -57.083997) (xy 60.714862 -57.114547)
			(xy 60.751613 -57.151298) (xy 60.782163 -57.193346) (xy 60.805759 -57.239656) (xy 60.82182 -57.289086)
			(xy 60.82995 -57.340421) (xy 60.83046 -57.366408) (xy 60.82995 -57.392395) (xy 60.82182 -57.44373)
			(xy 60.805759 -57.49316) (xy 60.782163 -57.53947) (xy 60.751613 -57.581518) (xy 60.714862 -57.618269)
			(xy 60.672814 -57.648819) (xy 60.626504 -57.672415) (xy 60.577074 -57.688476) (xy 60.525739 -57.696606)
			(xy 60.473765 -57.696606) (xy 60.42243 -57.688476) (xy 60.373 -57.672415) (xy 60.32669 -57.648819)
			(xy 60.284642 -57.618269) (xy 60.247891 -57.581518) (xy 60.217341 -57.53947) (xy 60.193745 -57.49316)
			(xy 60.177684 -57.44373) (xy 60.169554 -57.392395) (xy 60.029991 -57.392395) (xy 60.029673 -57.406481)
			(xy 60.01856 -57.466299) (xy 60.008262 -57.494932) (xy 59.996324 -57.525666) (xy 60.426092 -57.95518)
			(xy 60.442123 -57.971864) (xy 60.469324 -58.00929) (xy 60.49037 -58.050493) (xy 60.504747 -58.094469)
			(xy 60.508896 -58.117232) (xy 60.510674 -58.128154) (xy 60.512456 -58.139948) (xy 60.514362 -58.163725)
			(xy 60.51439 -58.166508) (xy 60.959492 -58.166508) (xy 60.959492 -57.366662) (xy 60.960011 -57.340669)
			(xy 60.968145 -57.289322) (xy 60.984205 -57.239879) (xy 61.007797 -57.193554) (xy 61.038342 -57.151487)
			(xy 61.075087 -57.114712) (xy 61.11713 -57.084135) (xy 61.163436 -57.060505) (xy 61.212867 -57.044406)
			(xy 61.264207 -57.036232) (xy 61.2902 -57.0357) (xy 61.316745 -57.036233) (xy 61.369152 -57.044715)
			(xy 61.419531 -57.06146) (xy 61.466588 -57.086039) (xy 61.509114 -57.117821) (xy 61.527944 -57.136538)
			(xy 61.547001 -57.155389) (xy 61.579339 -57.198137) (xy 61.604362 -57.24554) (xy 61.621413 -57.296357)
			(xy 61.630046 -57.349259) (xy 61.63056 -57.37606) (xy 61.630268 -57.394574) (xy 61.626065 -57.431363)
			(xy 61.622178 -57.449466) (xy 61.620908 -57.455054) (xy 61.620908 -58.166508) (xy 61.620398 -58.192495)
			(xy 61.612268 -58.24383) (xy 61.596207 -58.29326) (xy 61.572611 -58.33957) (xy 61.542061 -58.381618)
			(xy 61.50531 -58.418369) (xy 61.463262 -58.448919) (xy 61.416952 -58.472515) (xy 61.367522 -58.488576)
			(xy 61.316187 -58.496706) (xy 61.264213 -58.496706) (xy 61.212878 -58.488576) (xy 61.163448 -58.472515)
			(xy 61.117138 -58.448919) (xy 61.07509 -58.418369) (xy 61.038339 -58.381618) (xy 61.007789 -58.33957)
			(xy 60.984193 -58.29326) (xy 60.968132 -58.24383) (xy 60.960002 -58.192495) (xy 60.959492 -58.166508)
			(xy 60.51439 -58.166508) (xy 60.514484 -58.175652) (xy 60.514484 -58.992341) (xy 60.960002 -58.992341)
			(xy 60.960002 -58.940367) (xy 60.968132 -58.889032) (xy 60.984193 -58.839602) (xy 61.007789 -58.793292)
			(xy 61.038339 -58.751244) (xy 61.07509 -58.714493) (xy 61.117138 -58.683943) (xy 61.163448 -58.660347)
			(xy 61.212878 -58.644286) (xy 61.264213 -58.636156) (xy 61.316187 -58.636156) (xy 61.367522 -58.644286)
			(xy 61.416952 -58.660347) (xy 61.463262 -58.683943) (xy 61.50531 -58.714493) (xy 61.542061 -58.751244)
			(xy 61.572611 -58.793292) (xy 61.596207 -58.839602) (xy 61.612268 -58.889032) (xy 61.620398 -58.940367)
			(xy 61.620908 -58.966354) (xy 61.620398 -58.992341) (xy 61.612268 -59.043676) (xy 61.596207 -59.093106)
			(xy 61.572611 -59.139416) (xy 61.542061 -59.181464) (xy 61.50531 -59.218215) (xy 61.463262 -59.248765)
			(xy 61.416952 -59.272361) (xy 61.367522 -59.288422) (xy 61.316187 -59.296552) (xy 61.264213 -59.296552)
			(xy 61.212878 -59.288422) (xy 61.163448 -59.272361) (xy 61.117138 -59.248765) (xy 61.07509 -59.218215)
			(xy 61.038339 -59.181464) (xy 61.007789 -59.139416) (xy 60.984193 -59.093106) (xy 60.968132 -59.043676)
			(xy 60.960002 -58.992341) (xy 60.514484 -58.992341) (xy 60.514484 -59.142884) (xy 61.390276 -60.018676)
			(xy 61.55944 -60.018676) (xy 61.574662 -60.018103) (xy 61.603751 -60.009119) (xy 61.6289 -59.991962)
			(xy 61.647876 -59.968155) (xy 61.658992 -59.939813) (xy 61.661263 -59.909453) (xy 61.6585 -59.89447)
			(xy 61.654696 -59.876486) (xy 61.650626 -59.839952) (xy 61.650372 -59.821572) (xy 61.650882 -59.795585)
			(xy 61.659012 -59.74425) (xy 61.675073 -59.69482) (xy 61.698669 -59.64851) (xy 61.729219 -59.606462)
			(xy 61.76597 -59.569711) (xy 61.808018 -59.539161) (xy 61.854328 -59.515565) (xy 61.903758 -59.499504)
			(xy 61.955093 -59.491374) (xy 62.007067 -59.491374) (xy 62.058402 -59.499504) (xy 62.107832 -59.515565)
			(xy 62.154142 -59.539161) (xy 62.19619 -59.569711) (xy 62.232941 -59.606462) (xy 62.263491 -59.64851)
			(xy 62.287087 -59.69482) (xy 62.303148 -59.74425) (xy 62.311278 -59.795585) (xy 62.311788 -59.821572)
			(xy 62.311333 -59.846243) (xy 62.304001 -59.895036) (xy 62.289497 -59.942197) (xy 62.268142 -59.986677)
			(xy 62.240412 -60.027489) (xy 62.206922 -60.063723) (xy 62.168417 -60.094577) (xy 62.125753 -60.119362)
			(xy 62.103 -60.128912) (xy 62.089114 -60.135037) (xy 62.065459 -60.154026) (xy 62.048415 -60.179119)
			(xy 62.039481 -60.208107) (xy 62.039443 -60.238441) (xy 62.04331 -60.253118) (xy 62.050034 -60.276616)
			(xy 62.057298 -60.324948) (xy 62.057788 -60.349384) (xy 62.057228 -60.376798) (xy 62.048149 -60.430871)
			(xy 62.030286 -60.482709) (xy 62.004128 -60.530896) (xy 61.987684 -60.552838) (xy 61.959998 -60.588398)
			(xy 62.704218 -61.332618) (xy 62.969902 -61.4426) (xy 64.393572 -61.4426) (xy 65.39992 -62.448948)
			(xy 65.582292 -62.524386) (xy 65.598548 -62.520322) (xy 65.621414 -62.514964) (xy 65.668029 -62.509231)
			(xy 65.691512 -62.508892) (xy 65.718763 -62.509379) (xy 65.772709 -62.517137) (xy 65.825002 -62.532493)
			(xy 65.874578 -62.555135) (xy 65.920427 -62.584601) (xy 65.961616 -62.620293) (xy 65.997306 -62.661483)
			(xy 66.026771 -62.707332) (xy 66.049412 -62.756909) (xy 66.064766 -62.809203) (xy 66.072522 -62.863149)
			(xy 66.07302 -62.8904) (xy 66.072598 -62.916771) (xy 66.065367 -62.969015) (xy 66.050989 -63.019759)
			(xy 66.040762 -63.04407) (xy 66.026792 -63.07582) (xy 67.376548 -64.425576) (xy 69.304154 -64.425576)
		)
		(stroke
			(width 0)
			(type solid)
		)
		(fill yes)
		(layer "In2.Cu")
		(net "P1V8_STBY_RC_VCC18A")
	)
	(gr_poly
		(pts
			(xy 43.933618 -55.544466) (xy 43.947121 -55.544045) (xy 43.973181 -55.536963) (xy 43.996475 -55.523299)
			(xy 44.015373 -55.504009) (xy 44.028556 -55.480439) (xy 44.035101 -55.454239) (xy 44.034552 -55.427239)
			(xy 44.031154 -55.414164) (xy 44.024871 -55.391438) (xy 44.018112 -55.344775) (xy 44.017692 -55.3212)
			(xy 44.018202 -55.295213) (xy 44.026332 -55.243878) (xy 44.042393 -55.194448) (xy 44.065989 -55.148138)
			(xy 44.096539 -55.10609) (xy 44.13329 -55.069339) (xy 44.175338 -55.038789) (xy 44.221648 -55.015193)
			(xy 44.271078 -54.999132) (xy 44.322413 -54.991002) (xy 44.374387 -54.991002) (xy 44.425722 -54.999132)
			(xy 44.475152 -55.015193) (xy 44.521462 -55.038789) (xy 44.56351 -55.069339) (xy 44.600261 -55.10609)
			(xy 44.630811 -55.148138) (xy 44.654407 -55.194448) (xy 44.670468 -55.243878) (xy 44.678598 -55.295213)
			(xy 44.679108 -55.3212) (xy 44.678651 -55.344772) (xy 44.671892 -55.39143) (xy 44.665646 -55.414164)
			(xy 44.662228 -55.427242) (xy 44.661654 -55.454256) (xy 44.668187 -55.480475) (xy 44.681371 -55.504061)
			(xy 44.700281 -55.523361) (xy 44.723592 -55.537024) (xy 44.749671 -55.544093) (xy 44.763182 -55.544466)
			(xy 44.820332 -55.544466) (xy 44.987464 -55.377334) (xy 45.013912 -55.35172) (xy 45.07245 -55.307064)
			(xy 45.136418 -55.27061) (xy 45.204675 -55.243008) (xy 45.240194 -55.233316) (xy 45.25391 -55.22976)
			(xy 45.431456 -55.052214) (xy 45.667676 -55.052214) (xy 45.683289 -55.051638) (xy 45.713055 -55.042201)
			(xy 45.738589 -55.024227) (xy 45.757516 -54.99939) (xy 45.768073 -54.970002) (xy 45.769276 -54.954424)
			(xy 45.770656 -54.929069) (xy 45.780224 -54.879203) (xy 45.797303 -54.831386) (xy 45.821491 -54.786741)
			(xy 45.852219 -54.746319) (xy 45.888766 -54.711069) (xy 45.930271 -54.68182) (xy 45.97576 -54.659259)
			(xy 46.024163 -54.643918) (xy 46.074342 -54.636156) (xy 46.125118 -54.636156) (xy 46.175297 -54.643918)
			(xy 46.2237 -54.659259) (xy 46.269189 -54.68182) (xy 46.310694 -54.711069) (xy 46.347241 -54.746319)
			(xy 46.377969 -54.786741) (xy 46.402157 -54.831386) (xy 46.419236 -54.879203) (xy 46.428804 -54.929069)
			(xy 46.430184 -54.954424) (xy 46.431325 -54.970021) (xy 46.441857 -54.99945) (xy 46.460789 -55.024321)
			(xy 46.486352 -55.042308) (xy 46.516155 -55.051728) (xy 46.531784 -55.052214) (xy 48.732186 -55.052214)
			(xy 49.0728 -54.7116) (xy 49.0728 -53.898038) (xy 49.0728 -53.2638) (xy 48.98771 -53.17871) (xy 48.980519 -53.172191)
			(xy 48.96266 -53.164628) (xy 48.94327 -53.164219) (xy 48.925108 -53.171022) (xy 48.917606 -53.177186)
			(xy 48.901112 -53.191775) (xy 48.864618 -53.216417) (xy 48.824878 -53.235386) (xy 48.782769 -53.248264)
			(xy 48.739217 -53.254767) (xy 48.7172 -53.255164) (xy 48.229774 -53.255164) (xy 48.013366 -53.471826)
			(xy 48.009556 -53.481986) (xy 48.000351 -53.505348) (xy 47.975904 -53.549205) (xy 47.945108 -53.588862)
			(xy 47.90867 -53.623407) (xy 47.867429 -53.652047) (xy 47.822331 -53.674122) (xy 47.774415 -53.689126)
			(xy 47.724781 -53.696713) (xy 47.699676 -53.697124) (xy 47.67369 -53.696613) (xy 47.622357 -53.688479)
			(xy 47.572929 -53.672416) (xy 47.526621 -53.648819) (xy 47.484575 -53.61827) (xy 47.447825 -53.581519)
			(xy 47.417276 -53.539472) (xy 47.393681 -53.493164) (xy 47.377619 -53.443735) (xy 47.369487 -53.392402)
			(xy 47.368968 -53.366416) (xy 47.369379 -53.342877) (xy 47.376058 -53.296276) (xy 47.389298 -53.251099)
			(xy 47.398686 -53.22951) (xy 47.404206 -53.216067) (xy 47.408252 -53.187306) (xy 47.40404 -53.158568)
			(xy 47.39191 -53.132177) (xy 47.372843 -53.110266) (xy 47.34838 -53.094608) (xy 47.320499 -53.086468)
			(xy 47.305976 -53.086) (xy 47.29353 -53.086) (xy 47.27899 -53.08642) (xy 47.251066 -53.094528) (xy 47.226562 -53.11018)
			(xy 47.207464 -53.132107) (xy 47.195324 -53.158528) (xy 47.191127 -53.187301) (xy 47.195212 -53.216089)
			(xy 47.20082 -53.22951) (xy 47.210182 -53.251108) (xy 47.223399 -53.296287) (xy 47.230096 -53.34288)
			(xy 47.230538 -53.366416) (xy 47.230028 -53.392403) (xy 47.221898 -53.443738) (xy 47.205837 -53.493168)
			(xy 47.182241 -53.539478) (xy 47.151691 -53.581526) (xy 47.11494 -53.618277) (xy 47.072892 -53.648827)
			(xy 47.026582 -53.672423) (xy 46.977152 -53.688484) (xy 46.925817 -53.696614) (xy 46.873843 -53.696614)
			(xy 46.822508 -53.688484) (xy 46.773078 -53.672423) (xy 46.726768 -53.648827) (xy 46.68472 -53.618277)
			(xy 46.647969 -53.581526) (xy 46.617419 -53.539478) (xy 46.593823 -53.493168) (xy 46.577762 -53.443738)
			(xy 46.569632 -53.392403) (xy 46.569122 -53.366416) (xy 46.569533 -53.342877) (xy 46.576213 -53.296277)
			(xy 46.589455 -53.251101) (xy 46.59884 -53.22951) (xy 46.604361 -53.21607) (xy 46.60841 -53.187311)
			(xy 46.604198 -53.158575) (xy 46.592067 -53.132188) (xy 46.572998 -53.110283) (xy 46.548533 -53.094633)
			(xy 46.520652 -53.086503) (xy 46.50613 -53.086) (xy 46.1264 -53.086) (xy 45.74794 -52.70754) (xy 45.73819 -52.698353)
			(xy 45.714985 -52.684983) (xy 45.689101 -52.678114) (xy 45.66232 -52.678217) (xy 45.636489 -52.685286)
			(xy 45.613388 -52.698834) (xy 45.594608 -52.717926) (xy 45.587666 -52.729384) (xy 45.57498 -52.750876)
			(xy 45.544155 -52.790124) (xy 45.507785 -52.824298) (xy 45.466696 -52.852622) (xy 45.421819 -52.874455)
			(xy 45.374172 -52.8893) (xy 45.324837 -52.896822) (xy 45.299884 -52.897278) (xy 45.273896 -52.896794)
			(xy 45.222562 -52.88866) (xy 45.173131 -52.872596) (xy 45.126822 -52.848997) (xy 45.084775 -52.818444)
			(xy 45.048026 -52.78169) (xy 45.017479 -52.739638) (xy 44.993886 -52.693326) (xy 44.977829 -52.643894)
			(xy 44.969703 -52.592558) (xy 44.969176 -52.56657) (xy 44.969409 -52.549163) (xy 44.973096 -52.514546)
			(xy 44.976542 -52.497482) (xy 44.979139 -52.482581) (xy 44.976485 -52.452465) (xy 44.965138 -52.424444)
			(xy 44.946092 -52.400966) (xy 44.921011 -52.384085) (xy 44.892091 -52.375279) (xy 44.876974 -52.3748)
			(xy 44.803568 -52.3748) (xy 44.803568 -52.435252) (xy 44.807124 -52.444396) (xy 44.818003 -52.473762)
			(xy 44.829763 -52.535262) (xy 44.830492 -52.56657) (xy 44.830011 -52.59256) (xy 44.821883 -52.643902)
			(xy 44.805824 -52.693339) (xy 44.782227 -52.739655) (xy 44.751675 -52.78171) (xy 44.71492 -52.818466)
			(xy 44.672867 -52.84902) (xy 44.626552 -52.872618) (xy 44.577115 -52.88868) (xy 44.525774 -52.89681)
			(xy 44.499784 -52.897278) (xy 44.476946 -52.896893) (xy 44.431703 -52.89061) (xy 44.387755 -52.878165)
			(xy 44.366688 -52.869338) (xy 44.354063 -52.864254) (xy 44.327152 -52.860267) (xy 44.300144 -52.863539)
			(xy 44.274963 -52.873838) (xy 44.253403 -52.890431) (xy 44.236999 -52.912135) (xy 44.226919 -52.937404)
			(xy 44.224956 -52.950872) (xy 44.22394 -52.957984) (xy 44.2226 -52.971404) (xy 44.226213 -52.998121)
			(xy 44.236693 -53.022961) (xy 44.253309 -53.044192) (xy 44.274904 -53.060334) (xy 44.29997 -53.07026)
			(xy 44.326761 -53.07328) (xy 44.353408 -53.069181) (xy 44.365926 -53.064156) (xy 44.387094 -53.055196)
			(xy 44.431286 -53.042544) (xy 44.476801 -53.03612) (xy 44.499784 -53.035708) (xy 44.525772 -53.03619)
			(xy 44.577109 -53.044318) (xy 44.626541 -53.060377) (xy 44.672854 -53.083972) (xy 44.714904 -53.11452)
			(xy 44.751659 -53.151271) (xy 44.782212 -53.193319) (xy 44.80581 -53.239629) (xy 44.821874 -53.28906)
			(xy 44.830008 -53.340396) (xy 44.83001 -53.392372) (xy 44.830005 -53.392403) (xy 44.969686 -53.392403)
			(xy 44.969686 -53.340429) (xy 44.977816 -53.289094) (xy 44.993877 -53.239664) (xy 45.017473 -53.193354)
			(xy 45.048023 -53.151306) (xy 45.084774 -53.114555) (xy 45.126822 -53.084005) (xy 45.173132 -53.060409)
			(xy 45.222562 -53.044348) (xy 45.273897 -53.036218) (xy 45.325871 -53.036218) (xy 45.377206 -53.044348)
			(xy 45.426636 -53.060409) (xy 45.472946 -53.084005) (xy 45.514994 -53.114555) (xy 45.551745 -53.151306)
			(xy 45.582295 -53.193354) (xy 45.605891 -53.239664) (xy 45.621952 -53.289094) (xy 45.630082 -53.340429)
			(xy 45.630592 -53.366416) (xy 45.630082 -53.392403) (xy 45.621952 -53.443738) (xy 45.605891 -53.493168)
			(xy 45.582295 -53.539478) (xy 45.551745 -53.581526) (xy 45.514994 -53.618277) (xy 45.472946 -53.648827)
			(xy 45.426636 -53.672423) (xy 45.377206 -53.688484) (xy 45.325871 -53.696614) (xy 45.273897 -53.696614)
			(xy 45.222562 -53.688484) (xy 45.173132 -53.672423) (xy 45.126822 -53.648827) (xy 45.084774 -53.618277)
			(xy 45.048023 -53.581526) (xy 45.017473 -53.539478) (xy 44.993877 -53.493168) (xy 44.977816 -53.443738)
			(xy 44.969686 -53.392403) (xy 44.830005 -53.392403) (xy 44.821882 -53.443709) (xy 44.805823 -53.493141)
			(xy 44.782228 -53.539454) (xy 44.75168 -53.581504) (xy 44.714929 -53.618259) (xy 44.672881 -53.648812)
			(xy 44.626571 -53.67241) (xy 44.57714 -53.688474) (xy 44.525804 -53.696608) (xy 44.473828 -53.69661)
			(xy 44.422491 -53.688482) (xy 44.373059 -53.672423) (xy 44.326746 -53.648828) (xy 44.284696 -53.61828)
			(xy 44.247941 -53.581529) (xy 44.217388 -53.539481) (xy 44.19379 -53.493171) (xy 44.177726 -53.44374)
			(xy 44.169592 -53.392404) (xy 44.169076 -53.366416) (xy 44.169838 -53.34381) (xy 44.17034 -53.330347)
			(xy 44.16508 -53.303935) (xy 44.153093 -53.279818) (xy 44.135216 -53.259677) (xy 44.112692 -53.244914)
			(xy 44.08709 -53.236557) (xy 44.060193 -53.235188) (xy 44.033876 -53.240903) (xy 44.021756 -53.246782)
			(xy 43.994404 -53.260299) (xy 43.936473 -53.279425) (xy 43.876238 -53.289098) (xy 43.845734 -53.289708)
			(xy 43.816974 -53.289188) (xy 43.760104 -53.280558) (xy 43.705175 -53.263488) (xy 43.653431 -53.238366)
			(xy 43.606044 -53.20576) (xy 43.564089 -53.16641) (xy 43.528518 -53.121208) (xy 43.500135 -53.071178)
			(xy 43.479584 -53.017454) (xy 43.467332 -52.961253) (xy 43.464988 -52.932584) (xy 43.463568 -52.918067)
			(xy 43.45353 -52.890693) (xy 43.436168 -52.867269) (xy 43.412898 -52.849701) (xy 43.385613 -52.839422)
			(xy 43.356536 -52.837267) (xy 43.328034 -52.843412) (xy 43.302428 -52.857357) (xy 43.29176 -52.867306)
			(xy 43.11142 -53.047646) (xy 43.094641 -53.063794) (xy 43.056953 -53.091143) (xy 43.015448 -53.112257)
			(xy 42.971152 -53.126617) (xy 42.925153 -53.133868) (xy 42.90187 -53.13426) (xy 42.736008 -53.13426)
			(xy 42.721772 -53.134746) (xy 42.694409 -53.142621) (xy 42.670278 -53.157736) (xy 42.651251 -53.178918)
			(xy 42.638801 -53.204526) (xy 42.633894 -53.232573) (xy 42.634916 -53.246782) (xy 42.635965 -53.256973)
			(xy 42.637108 -53.277431) (xy 42.637202 -53.287676) (xy 42.636789 -53.313015) (xy 42.630083 -53.363248)
			(xy 42.616784 -53.41215) (xy 42.597129 -53.458861) (xy 42.571462 -53.502559) (xy 42.540235 -53.542474)
			(xy 42.522394 -53.560472) (xy 42.511969 -53.571435) (xy 42.497484 -53.597976) (xy 42.491404 -53.627595)
			(xy 42.494261 -53.657696) (xy 42.505805 -53.685642) (xy 42.515028 -53.697632) (xy 42.530324 -53.716855)
			(xy 42.556045 -53.75871) (xy 42.575771 -53.803701) (xy 42.589129 -53.850975) (xy 42.595865 -53.899637)
			(xy 42.596308 -53.9242) (xy 42.59581 -53.950849) (xy 42.587867 -54.003553) (xy 42.572157 -54.054483)
			(xy 42.549031 -54.102504) (xy 42.519007 -54.146541) (xy 42.482755 -54.185612) (xy 42.441084 -54.218843)
			(xy 42.394926 -54.245492) (xy 42.345312 -54.264964) (xy 42.29335 -54.276824) (xy 42.2402 -54.280808)
			(xy 42.18705 -54.276824) (xy 42.135088 -54.264964) (xy 42.085474 -54.245492) (xy 42.039316 -54.218843)
			(xy 41.997645 -54.185612) (xy 41.961393 -54.146541) (xy 41.931369 -54.102504) (xy 41.908243 -54.054483)
			(xy 41.892533 -54.003553) (xy 41.88459 -53.950849) (xy 41.884092 -53.9242) (xy 41.884565 -53.89791)
			(xy 41.892305 -53.845904) (xy 41.907616 -53.795604) (xy 41.930165 -53.748105) (xy 41.959461 -53.704443)
			(xy 41.976802 -53.684678) (xy 41.986565 -53.673116) (xy 41.999459 -53.645759) (xy 42.003771 -53.615823)
			(xy 41.999121 -53.585938) (xy 41.985919 -53.558728) (xy 41.97604 -53.547264) (xy 41.957009 -53.525962)
			(xy 41.924837 -53.478763) (xy 41.900056 -53.427299) (xy 41.883217 -53.372717) (xy 41.874697 -53.316236)
			(xy 41.874186 -53.287676) (xy 41.874274 -53.277431) (xy 41.875419 -53.256973) (xy 41.876472 -53.246782)
			(xy 41.877538 -53.232565) (xy 41.872669 -53.204487) (xy 41.860228 -53.178849) (xy 41.841186 -53.157649)
			(xy 41.817025 -53.142537) (xy 41.789629 -53.134693) (xy 41.77538 -53.13426) (xy 41.731946 -53.13426)
			(xy 41.705828 -53.133724) (xy 41.654394 -53.124612) (xy 41.605347 -53.106643) (xy 41.560199 -53.080372)
			(xy 41.539922 -53.063902) (xy 41.525698 -53.05171) (xy 41.48709 -53.05171) (xy 41.361868 -52.926488)
			(xy 41.060878 -52.926488) (xy 40.843454 -53.143912) (xy 40.843454 -54.5338) (xy 42.899582 -54.5338)
			(xy 42.903653 -54.478178) (xy 42.915779 -54.423741) (xy 42.935702 -54.37165) (xy 42.962998 -54.323015)
			(xy 42.997084 -54.278872) (xy 43.037233 -54.240163) (xy 43.082591 -54.207712) (xy 43.132191 -54.182211)
			(xy 43.184975 -54.164204) (xy 43.239818 -54.154074) (xy 43.295552 -54.152037) (xy 43.350989 -54.158137)
			(xy 43.404946 -54.172243) (xy 43.452623 -54.192503) (xy 44.169586 -54.192503) (xy 44.169586 -54.140529)
			(xy 44.177716 -54.089194) (xy 44.193777 -54.039764) (xy 44.217373 -53.993454) (xy 44.247923 -53.951406)
			(xy 44.284674 -53.914655) (xy 44.326722 -53.884105) (xy 44.373032 -53.860509) (xy 44.422462 -53.844448)
			(xy 44.473797 -53.836318) (xy 44.525771 -53.836318) (xy 44.577106 -53.844448) (xy 44.626536 -53.860509)
			(xy 44.672846 -53.884105) (xy 44.714894 -53.914655) (xy 44.751645 -53.951406) (xy 44.782195 -53.993454)
			(xy 44.805791 -54.039764) (xy 44.821852 -54.089194) (xy 44.829982 -54.140529) (xy 44.830492 -54.166516)
			(xy 44.829982 -54.192503) (xy 44.969686 -54.192503) (xy 44.969686 -54.140529) (xy 44.977816 -54.089194)
			(xy 44.993877 -54.039764) (xy 45.017473 -53.993454) (xy 45.048023 -53.951406) (xy 45.084774 -53.914655)
			(xy 45.126822 -53.884105) (xy 45.173132 -53.860509) (xy 45.222562 -53.844448) (xy 45.273897 -53.836318)
			(xy 45.325871 -53.836318) (xy 45.377206 -53.844448) (xy 45.426636 -53.860509) (xy 45.472946 -53.884105)
			(xy 45.514994 -53.914655) (xy 45.551745 -53.951406) (xy 45.582295 -53.993454) (xy 45.605891 -54.039764)
			(xy 45.621952 -54.089194) (xy 45.630082 -54.140529) (xy 45.630592 -54.166516) (xy 45.630082 -54.192503)
			(xy 46.569632 -54.192503) (xy 46.569632 -54.140529) (xy 46.577762 -54.089194) (xy 46.593823 -54.039764)
			(xy 46.617419 -53.993454) (xy 46.647969 -53.951406) (xy 46.68472 -53.914655) (xy 46.726768 -53.884105)
			(xy 46.773078 -53.860509) (xy 46.822508 -53.844448) (xy 46.873843 -53.836318) (xy 46.925817 -53.836318)
			(xy 46.977152 -53.844448) (xy 47.026582 -53.860509) (xy 47.072892 -53.884105) (xy 47.11494 -53.914655)
			(xy 47.151691 -53.951406) (xy 47.182241 -53.993454) (xy 47.205837 -54.039764) (xy 47.221898 -54.089194)
			(xy 47.230028 -54.140529) (xy 47.230538 -54.166516) (xy 47.230028 -54.192503) (xy 47.369478 -54.192503)
			(xy 47.369478 -54.140529) (xy 47.377608 -54.089194) (xy 47.393669 -54.039764) (xy 47.417265 -53.993454)
			(xy 47.447815 -53.951406) (xy 47.484566 -53.914655) (xy 47.526614 -53.884105) (xy 47.572924 -53.860509)
			(xy 47.622354 -53.844448) (xy 47.673689 -53.836318) (xy 47.725663 -53.836318) (xy 47.776998 -53.844448)
			(xy 47.826428 -53.860509) (xy 47.872738 -53.884105) (xy 47.914786 -53.914655) (xy 47.951537 -53.951406)
			(xy 47.982087 -53.993454) (xy 48.005683 -54.039764) (xy 48.021744 -54.089194) (xy 48.029874 -54.140529)
			(xy 48.030384 -54.166516) (xy 48.029874 -54.192503) (xy 48.169578 -54.192503) (xy 48.169578 -54.140529)
			(xy 48.177708 -54.089194) (xy 48.193769 -54.039764) (xy 48.217365 -53.993454) (xy 48.247915 -53.951406)
			(xy 48.284666 -53.914655) (xy 48.326714 -53.884105) (xy 48.373024 -53.860509) (xy 48.422454 -53.844448)
			(xy 48.473789 -53.836318) (xy 48.525763 -53.836318) (xy 48.577098 -53.844448) (xy 48.626528 -53.860509)
			(xy 48.672838 -53.884105) (xy 48.714886 -53.914655) (xy 48.751637 -53.951406) (xy 48.782187 -53.993454)
			(xy 48.805783 -54.039764) (xy 48.821844 -54.089194) (xy 48.829974 -54.140529) (xy 48.830484 -54.166516)
			(xy 48.829974 -54.192503) (xy 48.821844 -54.243838) (xy 48.805783 -54.293268) (xy 48.782187 -54.339578)
			(xy 48.751637 -54.381626) (xy 48.714886 -54.418377) (xy 48.672838 -54.448927) (xy 48.626528 -54.472523)
			(xy 48.577098 -54.488584) (xy 48.525763 -54.496714) (xy 48.473789 -54.496714) (xy 48.422454 -54.488584)
			(xy 48.373024 -54.472523) (xy 48.326714 -54.448927) (xy 48.284666 -54.418377) (xy 48.247915 -54.381626)
			(xy 48.217365 -54.339578) (xy 48.193769 -54.293268) (xy 48.177708 -54.243838) (xy 48.169578 -54.192503)
			(xy 48.029874 -54.192503) (xy 48.021744 -54.243838) (xy 48.005683 -54.293268) (xy 47.982087 -54.339578)
			(xy 47.951537 -54.381626) (xy 47.914786 -54.418377) (xy 47.872738 -54.448927) (xy 47.826428 -54.472523)
			(xy 47.776998 -54.488584) (xy 47.725663 -54.496714) (xy 47.673689 -54.496714) (xy 47.622354 -54.488584)
			(xy 47.572924 -54.472523) (xy 47.526614 -54.448927) (xy 47.484566 -54.418377) (xy 47.447815 -54.381626)
			(xy 47.417265 -54.339578) (xy 47.393669 -54.293268) (xy 47.377608 -54.243838) (xy 47.369478 -54.192503)
			(xy 47.230028 -54.192503) (xy 47.221898 -54.243838) (xy 47.205837 -54.293268) (xy 47.182241 -54.339578)
			(xy 47.151691 -54.381626) (xy 47.11494 -54.418377) (xy 47.072892 -54.448927) (xy 47.026582 -54.472523)
			(xy 46.977152 -54.488584) (xy 46.925817 -54.496714) (xy 46.873843 -54.496714) (xy 46.822508 -54.488584)
			(xy 46.773078 -54.472523) (xy 46.726768 -54.448927) (xy 46.68472 -54.418377) (xy 46.647969 -54.381626)
			(xy 46.617419 -54.339578) (xy 46.593823 -54.293268) (xy 46.577762 -54.243838) (xy 46.569632 -54.192503)
			(xy 45.630082 -54.192503) (xy 45.621952 -54.243838) (xy 45.605891 -54.293268) (xy 45.582295 -54.339578)
			(xy 45.551745 -54.381626) (xy 45.514994 -54.418377) (xy 45.472946 -54.448927) (xy 45.426636 -54.472523)
			(xy 45.377206 -54.488584) (xy 45.325871 -54.496714) (xy 45.273897 -54.496714) (xy 45.222562 -54.488584)
			(xy 45.173132 -54.472523) (xy 45.126822 -54.448927) (xy 45.084774 -54.418377) (xy 45.048023 -54.381626)
			(xy 45.017473 -54.339578) (xy 44.993877 -54.293268) (xy 44.977816 -54.243838) (xy 44.969686 -54.192503)
			(xy 44.829982 -54.192503) (xy 44.821852 -54.243838) (xy 44.805791 -54.293268) (xy 44.782195 -54.339578)
			(xy 44.751645 -54.381626) (xy 44.714894 -54.418377) (xy 44.672846 -54.448927) (xy 44.626536 -54.472523)
			(xy 44.577106 -54.488584) (xy 44.525771 -54.496714) (xy 44.473797 -54.496714) (xy 44.422462 -54.488584)
			(xy 44.373032 -54.472523) (xy 44.326722 -54.448927) (xy 44.284674 -54.418377) (xy 44.247923 -54.381626)
			(xy 44.217373 -54.339578) (xy 44.193777 -54.293268) (xy 44.177716 -54.243838) (xy 44.169586 -54.192503)
			(xy 43.452623 -54.192503) (xy 43.456275 -54.194055) (xy 43.503881 -54.223109) (xy 43.546749 -54.258784)
			(xy 43.583966 -54.300321) (xy 43.614739 -54.346834) (xy 43.638411 -54.397331) (xy 43.654479 -54.450738)
			(xy 43.662599 -54.505914) (xy 43.663108 -54.5338) (xy 43.662599 -54.561686) (xy 43.654479 -54.616862)
			(xy 43.638411 -54.670269) (xy 43.614739 -54.720766) (xy 43.583966 -54.767279) (xy 43.546749 -54.808816)
			(xy 43.503881 -54.844491) (xy 43.456275 -54.873545) (xy 43.404946 -54.895357) (xy 43.350989 -54.909463)
			(xy 43.295552 -54.915563) (xy 43.239818 -54.913526) (xy 43.184975 -54.903396) (xy 43.132191 -54.885389)
			(xy 43.082591 -54.859888) (xy 43.037233 -54.827437) (xy 42.997084 -54.788728) (xy 42.962998 -54.744585)
			(xy 42.935702 -54.69595) (xy 42.915779 -54.643859) (xy 42.903653 -54.589422) (xy 42.899582 -54.5338)
			(xy 40.843454 -54.5338) (xy 40.843454 -54.899052) (xy 40.996616 -55.052214) (xy 41.727374 -55.052214)
			(xy 42.168826 -55.493666) (xy 42.197274 -55.4863) (xy 42.232059 -55.477578) (xy 42.30315 -55.468153)
			(xy 42.339006 -55.467504) (xy 42.758868 -55.467504) (xy 42.795669 -55.468104) (xy 42.868612 -55.477941)
			(xy 42.939592 -55.497416) (xy 43.00734 -55.526183) (xy 43.039284 -55.544466)
		)
		(stroke
			(width 0)
			(type solid)
		)
		(fill yes)
		(layer "In2.Cu")
		(net "P1V2_P1V0_I3C_VDDL1")
	)
	(gr_poly
		(pts
			(xy 50.56759 -43.342814) (xy 50.56759 -39.56685) (xy 46.980602 -35.979862) (xy 46.959917 -35.99653)
			(xy 46.914809 -36.024585) (xy 46.866247 -36.046115) (xy 46.815168 -36.060704) (xy 46.76256 -36.068069)
			(xy 46.736 -36.068508) (xy 46.708749 -36.068022) (xy 46.654801 -36.060266) (xy 46.602506 -36.044911)
			(xy 46.552929 -36.022269) (xy 46.507079 -35.992803) (xy 46.465888 -35.957112) (xy 46.430197 -35.915921)
			(xy 46.400731 -35.870071) (xy 46.378089 -35.820494) (xy 46.362734 -35.768199) (xy 46.354978 -35.714251)
			(xy 46.354492 -35.687) (xy 46.355055 -35.65697) (xy 46.364475 -35.597653) (xy 46.383083 -35.540548)
			(xy 46.410417 -35.487069) (xy 46.427644 -35.462464) (xy 45.973238 -35.007804) (xy 41.442132 -35.007804)
			(xy 41.41885 -35.007389) (xy 41.372854 -35.00014) (xy 41.32856 -34.985783) (xy 41.287056 -34.964673)
			(xy 41.249367 -34.93733) (xy 41.232582 -34.92119) (xy 40.833548 -34.521902) (xy 40.823157 -34.512176)
			(xy 40.798269 -34.498393) (xy 40.770542 -34.492022) (xy 40.742135 -34.493561) (xy 40.715258 -34.50289)
			(xy 40.692006 -34.519282) (xy 40.682672 -34.53003) (xy 40.664442 -34.551722) (xy 40.622668 -34.590003)
			(xy 40.575695 -34.621688) (xy 40.524554 -34.646081) (xy 40.470369 -34.662648) (xy 40.41433 -34.671023)
			(xy 40.386 -34.671508) (xy 40.358749 -34.671022) (xy 40.304801 -34.663266) (xy 40.252506 -34.647911)
			(xy 40.202929 -34.625269) (xy 40.157079 -34.595803) (xy 40.115888 -34.560112) (xy 40.080197 -34.518921)
			(xy 40.050731 -34.473071) (xy 40.028089 -34.423494) (xy 40.012734 -34.371199) (xy 40.004978 -34.317251)
			(xy 40.004492 -34.29) (xy 40.004895 -34.265151) (xy 40.011342 -34.215874) (xy 40.024116 -34.167846)
			(xy 40.033194 -34.144712) (xy 40.038169 -34.131344) (xy 40.041291 -34.103004) (xy 40.036458 -34.074905)
			(xy 40.024046 -34.049237) (xy 40.005022 -34.028) (xy 39.980869 -34.012848) (xy 39.95347 -34.004963)
			(xy 39.939214 -34.004504) (xy 38.093396 -34.004504) (xy 37.543232 -34.554668) (xy 37.543232 -34.8234)
			(xy 38.747192 -34.8234) (xy 38.747678 -34.796149) (xy 38.755434 -34.742201) (xy 38.770789 -34.689906)
			(xy 38.793431 -34.640329) (xy 38.822897 -34.594479) (xy 38.858588 -34.553288) (xy 38.899779 -34.517597)
			(xy 38.945629 -34.488131) (xy 38.995206 -34.465489) (xy 39.047501 -34.450134) (xy 39.101449 -34.442378)
			(xy 39.155951 -34.442378) (xy 39.209899 -34.450134) (xy 39.262194 -34.465489) (xy 39.311771 -34.488131)
			(xy 39.357621 -34.517597) (xy 39.398812 -34.553288) (xy 39.434503 -34.594479) (xy 39.463969 -34.640329)
			(xy 39.486611 -34.689906) (xy 39.501966 -34.742201) (xy 39.509722 -34.796149) (xy 39.510208 -34.8234)
			(xy 39.509772 -34.849844) (xy 39.502512 -34.902231) (xy 39.49573 -34.927794) (xy 39.492547 -34.940571)
			(xy 39.492033 -34.966885) (xy 39.498277 -34.992454) (xy 39.510863 -35.015569) (xy 39.52895 -35.034689)
			(xy 39.551332 -35.048537) (xy 39.563802 -35.052762) (xy 39.589523 -35.061103) (xy 39.638493 -35.084027)
			(xy 39.683738 -35.113633) (xy 39.724352 -35.149328) (xy 39.759521 -35.190398) (xy 39.788542 -35.23602)
			(xy 39.810833 -35.285282) (xy 39.825948 -35.337196) (xy 39.833585 -35.390725) (xy 39.834058 -35.41776)
			(xy 39.833572 -35.445011) (xy 39.825816 -35.498959) (xy 39.810461 -35.551254) (xy 39.787819 -35.600831)
			(xy 39.758353 -35.646681) (xy 39.723418 -35.687) (xy 44.321982 -35.687) (xy 44.326053 -35.631378)
			(xy 44.338179 -35.576941) (xy 44.358102 -35.52485) (xy 44.385398 -35.476215) (xy 44.419484 -35.432072)
			(xy 44.459633 -35.393363) (xy 44.504991 -35.360912) (xy 44.554591 -35.335411) (xy 44.607375 -35.317404)
			(xy 44.662218 -35.307274) (xy 44.717952 -35.305237) (xy 44.773389 -35.311337) (xy 44.827346 -35.325443)
			(xy 44.878675 -35.347255) (xy 44.926281 -35.376309) (xy 44.969149 -35.411984) (xy 45.006366 -35.453521)
			(xy 45.037139 -35.500034) (xy 45.060811 -35.550531) (xy 45.076879 -35.603938) (xy 45.084999 -35.659114)
			(xy 45.085508 -35.687) (xy 45.084999 -35.714886) (xy 45.076879 -35.770062) (xy 45.060811 -35.823469)
			(xy 45.037139 -35.873966) (xy 45.006366 -35.920479) (xy 44.969149 -35.962016) (xy 44.926281 -35.997691)
			(xy 44.878675 -36.026745) (xy 44.827346 -36.048557) (xy 44.773389 -36.062663) (xy 44.717952 -36.068763)
			(xy 44.662218 -36.066726) (xy 44.607375 -36.056596) (xy 44.554591 -36.038589) (xy 44.504991 -36.013088)
			(xy 44.459633 -35.980637) (xy 44.419484 -35.941928) (xy 44.385398 -35.897785) (xy 44.358102 -35.84915)
			(xy 44.338179 -35.797059) (xy 44.326053 -35.742622) (xy 44.321982 -35.687) (xy 39.723418 -35.687)
			(xy 39.722662 -35.687872) (xy 39.681471 -35.723563) (xy 39.635621 -35.753029) (xy 39.586044 -35.775671)
			(xy 39.533749 -35.791026) (xy 39.479801 -35.798782) (xy 39.425299 -35.798782) (xy 39.371351 -35.791026)
			(xy 39.319056 -35.775671) (xy 39.269479 -35.753029) (xy 39.223629 -35.723563) (xy 39.182438 -35.687872)
			(xy 39.146747 -35.646681) (xy 39.117281 -35.600831) (xy 39.094639 -35.551254) (xy 39.079284 -35.498959)
			(xy 39.071528 -35.445011) (xy 39.071042 -35.41776) (xy 39.071471 -35.391316) (xy 39.078736 -35.338929)
			(xy 39.08552 -35.313366) (xy 39.088713 -35.300592) (xy 39.089217 -35.274279) (xy 39.082967 -35.248713)
			(xy 39.07038 -35.225599) (xy 39.052294 -35.206479) (xy 39.029917 -35.192626) (xy 39.017448 -35.188398)
			(xy 38.991736 -35.180034) (xy 38.942769 -35.157109) (xy 38.897527 -35.127504) (xy 38.856916 -35.091811)
			(xy 38.821748 -35.050744) (xy 38.792726 -35.005126) (xy 38.770432 -34.955868) (xy 38.755312 -34.903958)
			(xy 38.747669 -34.850434) (xy 38.747192 -34.8234) (xy 37.543232 -34.8234) (xy 37.543232 -36.262818)
			(xy 37.747194 -36.46678) (xy 39.347902 -36.46678) (xy 39.74338 -36.862258) (xy 43.475148 -36.862258)
			(xy 43.497809 -36.844791) (xy 43.547329 -36.816133) (xy 43.600572 -36.795191) (xy 43.656346 -36.782435)
			(xy 43.7134 -36.77815) (xy 43.770454 -36.782435) (xy 43.826228 -36.795191) (xy 43.879471 -36.816133)
			(xy 43.928991 -36.844791) (xy 43.951652 -36.862258) (xy 44.474638 -36.862258) (xy 46.45025 -38.83787)
			(xy 46.460056 -38.847056) (xy 46.483374 -38.860392) (xy 46.509361 -38.86719) (xy 46.536222 -38.86698)
			(xy 46.5621 -38.859777) (xy 46.585206 -38.846078) (xy 46.603944 -38.826831) (xy 46.610778 -38.815264)
			(xy 46.623399 -38.793527) (xy 46.654192 -38.753802) (xy 46.690643 -38.719196) (xy 46.731912 -38.690507)
			(xy 46.777049 -38.668396) (xy 46.825013 -38.653373) (xy 46.874699 -38.645784) (xy 46.89983 -38.645338)
			(xy 46.925816 -38.645823) (xy 46.977149 -38.653959) (xy 47.026576 -38.670024) (xy 47.072882 -38.693624)
			(xy 47.114926 -38.724178) (xy 47.151672 -38.760932) (xy 47.182216 -38.802983) (xy 47.205805 -38.849294)
			(xy 47.221859 -38.898725) (xy 47.229983 -38.950059) (xy 47.230538 -38.976046) (xy 47.230068 -39.001175)
			(xy 47.229937 -39.002033) (xy 47.369478 -39.002033) (xy 47.369478 -38.950059) (xy 47.377608 -38.898724)
			(xy 47.393669 -38.849294) (xy 47.417265 -38.802984) (xy 47.447815 -38.760936) (xy 47.484566 -38.724185)
			(xy 47.526614 -38.693635) (xy 47.572924 -38.670039) (xy 47.622354 -38.653978) (xy 47.673689 -38.645848)
			(xy 47.725663 -38.645848) (xy 47.776998 -38.653978) (xy 47.826428 -38.670039) (xy 47.872738 -38.693635)
			(xy 47.914786 -38.724185) (xy 47.951537 -38.760936) (xy 47.982087 -38.802984) (xy 48.000369 -38.838865)
			(xy 48.51399 -38.838865) (xy 48.51399 -38.785567) (xy 48.521933 -38.732863) (xy 48.537643 -38.681933)
			(xy 48.560769 -38.633912) (xy 48.590793 -38.589875) (xy 48.627045 -38.550804) (xy 48.668716 -38.517573)
			(xy 48.714874 -38.490924) (xy 48.764488 -38.471452) (xy 48.81645 -38.459592) (xy 48.8696 -38.455609)
			(xy 48.92275 -38.459592) (xy 48.974712 -38.471452) (xy 49.024326 -38.490924) (xy 49.070484 -38.517573)
			(xy 49.112155 -38.550804) (xy 49.148407 -38.589875) (xy 49.178431 -38.633912) (xy 49.201557 -38.681933)
			(xy 49.217267 -38.732863) (xy 49.22521 -38.785567) (xy 49.225708 -38.812216) (xy 49.22521 -38.838865)
			(xy 49.217267 -38.891569) (xy 49.201557 -38.942499) (xy 49.178431 -38.99052) (xy 49.148407 -39.034557)
			(xy 49.112155 -39.073628) (xy 49.070484 -39.106859) (xy 49.024326 -39.133508) (xy 48.974712 -39.15298)
			(xy 48.92275 -39.16484) (xy 48.8696 -39.168824) (xy 48.81645 -39.16484) (xy 48.764488 -39.15298)
			(xy 48.714874 -39.133508) (xy 48.668716 -39.106859) (xy 48.627045 -39.073628) (xy 48.590793 -39.034557)
			(xy 48.560769 -38.99052) (xy 48.537643 -38.942499) (xy 48.521933 -38.891569) (xy 48.51399 -38.838865)
			(xy 48.000369 -38.838865) (xy 48.005683 -38.849294) (xy 48.021744 -38.898724) (xy 48.029874 -38.950059)
			(xy 48.030384 -38.976046) (xy 48.029874 -39.002033) (xy 48.021744 -39.053368) (xy 48.005683 -39.102798)
			(xy 47.982087 -39.149108) (xy 47.951537 -39.191156) (xy 47.914786 -39.227907) (xy 47.872738 -39.258457)
			(xy 47.826428 -39.282053) (xy 47.776998 -39.298114) (xy 47.725663 -39.306244) (xy 47.673689 -39.306244)
			(xy 47.622354 -39.298114) (xy 47.572924 -39.282053) (xy 47.526614 -39.258457) (xy 47.484566 -39.227907)
			(xy 47.447815 -39.191156) (xy 47.417265 -39.149108) (xy 47.393669 -39.102798) (xy 47.377608 -39.053368)
			(xy 47.369478 -39.002033) (xy 47.229937 -39.002033) (xy 47.222462 -39.050853) (xy 47.207432 -39.09881)
			(xy 47.185323 -39.143943) (xy 47.156645 -39.185214) (xy 47.122055 -39.221675) (xy 47.082351 -39.252486)
			(xy 47.060612 -39.265098) (xy 47.049047 -39.271963) (xy 47.029737 -39.290668) (xy 47.015987 -39.313771)
			(xy 47.008755 -39.339664) (xy 47.008544 -39.366548) (xy 47.015368 -39.392552) (xy 47.028753 -39.415868)
			(xy 47.038006 -39.425626) (xy 47.250096 -39.637716) (xy 47.259876 -39.646926) (xy 47.283156 -39.660313)
			(xy 47.309125 -39.667157) (xy 47.335979 -39.666984) (xy 47.361857 -39.659805) (xy 47.384963 -39.646119)
			(xy 47.403694 -39.626875) (xy 47.410624 -39.615364) (xy 47.423246 -39.593629) (xy 47.45404 -39.553909)
			(xy 47.490492 -39.519308) (xy 47.531762 -39.490625) (xy 47.576899 -39.46852) (xy 47.624862 -39.453503)
			(xy 47.674546 -39.445921) (xy 47.699676 -39.445438) (xy 47.725665 -39.445919) (xy 47.777004 -39.454048)
			(xy 47.826439 -39.470109) (xy 47.872752 -39.493706) (xy 47.914803 -39.524258) (xy 47.951556 -39.561014)
			(xy 47.982106 -39.603067) (xy 48.0057 -39.649382) (xy 48.021757 -39.698817) (xy 48.029882 -39.750157)
			(xy 48.030384 -39.776146) (xy 48.029913 -39.801274) (xy 48.029781 -39.802133) (xy 49.769524 -39.802133)
			(xy 49.769524 -39.750159) (xy 49.777654 -39.698824) (xy 49.793715 -39.649394) (xy 49.817311 -39.603084)
			(xy 49.847861 -39.561036) (xy 49.884612 -39.524285) (xy 49.92666 -39.493735) (xy 49.97297 -39.470139)
			(xy 50.0224 -39.454078) (xy 50.073735 -39.445948) (xy 50.125709 -39.445948) (xy 50.177044 -39.454078)
			(xy 50.226474 -39.470139) (xy 50.272784 -39.493735) (xy 50.314832 -39.524285) (xy 50.351583 -39.561036)
			(xy 50.382133 -39.603084) (xy 50.405729 -39.649394) (xy 50.42179 -39.698824) (xy 50.42992 -39.750159)
			(xy 50.43043 -39.776146) (xy 50.42992 -39.802133) (xy 50.42179 -39.853468) (xy 50.405729 -39.902898)
			(xy 50.382133 -39.949208) (xy 50.351583 -39.991256) (xy 50.314832 -40.028007) (xy 50.272784 -40.058557)
			(xy 50.226474 -40.082153) (xy 50.177044 -40.098214) (xy 50.125709 -40.106344) (xy 50.073735 -40.106344)
			(xy 50.0224 -40.098214) (xy 49.97297 -40.082153) (xy 49.92666 -40.058557) (xy 49.884612 -40.028007)
			(xy 49.847861 -39.991256) (xy 49.817311 -39.949208) (xy 49.793715 -39.902898) (xy 49.777654 -39.853468)
			(xy 49.769524 -39.802133) (xy 48.029781 -39.802133) (xy 48.022307 -39.85095) (xy 48.007275 -39.898906)
			(xy 47.985165 -39.944036) (xy 47.956484 -39.985304) (xy 47.921892 -40.02176) (xy 47.882185 -40.052565)
			(xy 47.860458 -40.065198) (xy 47.848948 -40.072107) (xy 47.829751 -40.090861) (xy 47.816104 -40.113969)
			(xy 47.808947 -40.139834) (xy 47.808775 -40.16667) (xy 47.8156 -40.192625) (xy 47.828951 -40.215905)
			(xy 47.838106 -40.225726) (xy 48.050196 -40.437816) (xy 48.060004 -40.446992) (xy 48.083318 -40.46031)
			(xy 48.109297 -40.467094) (xy 48.136146 -40.466877) (xy 48.162011 -40.459672) (xy 48.185106 -40.445978)
			(xy 48.203837 -40.426741) (xy 48.210724 -40.41521) (xy 48.223349 -40.393478) (xy 48.254145 -40.353764)
			(xy 48.290599 -40.319168) (xy 48.331869 -40.29049) (xy 48.377005 -40.268389) (xy 48.424966 -40.253375)
			(xy 48.474648 -40.245794) (xy 48.499776 -40.245284) (xy 48.525767 -40.245765) (xy 48.577109 -40.253894)
			(xy 48.626547 -40.269954) (xy 48.672864 -40.29355) (xy 48.714919 -40.324102) (xy 48.751678 -40.360856)
			(xy 48.782233 -40.402909) (xy 48.805834 -40.449223) (xy 48.821899 -40.49866) (xy 48.830032 -40.550001)
			(xy 48.830484 -40.575992) (xy 48.83001 -40.601118) (xy 48.829878 -40.601979) (xy 48.969678 -40.601979)
			(xy 48.969678 -40.550005) (xy 48.977808 -40.49867) (xy 48.993869 -40.44924) (xy 49.017465 -40.40293)
			(xy 49.048015 -40.360882) (xy 49.084766 -40.324131) (xy 49.126814 -40.293581) (xy 49.173124 -40.269985)
			(xy 49.222554 -40.253924) (xy 49.273889 -40.245794) (xy 49.325863 -40.245794) (xy 49.377198 -40.253924)
			(xy 49.426628 -40.269985) (xy 49.472938 -40.293581) (xy 49.514986 -40.324131) (xy 49.551737 -40.360882)
			(xy 49.582287 -40.40293) (xy 49.605883 -40.44924) (xy 49.621944 -40.49867) (xy 49.630074 -40.550005)
			(xy 49.630584 -40.575992) (xy 49.630074 -40.601979) (xy 49.769524 -40.601979) (xy 49.769524 -40.550005)
			(xy 49.777654 -40.49867) (xy 49.793715 -40.44924) (xy 49.817311 -40.40293) (xy 49.847861 -40.360882)
			(xy 49.884612 -40.324131) (xy 49.92666 -40.293581) (xy 49.97297 -40.269985) (xy 50.0224 -40.253924)
			(xy 50.073735 -40.245794) (xy 50.125709 -40.245794) (xy 50.177044 -40.253924) (xy 50.226474 -40.269985)
			(xy 50.272784 -40.293581) (xy 50.314832 -40.324131) (xy 50.351583 -40.360882) (xy 50.382133 -40.40293)
			(xy 50.405729 -40.44924) (xy 50.42179 -40.49867) (xy 50.42992 -40.550005) (xy 50.43043 -40.575992)
			(xy 50.42992 -40.601979) (xy 50.42179 -40.653314) (xy 50.405729 -40.702744) (xy 50.382133 -40.749054)
			(xy 50.351583 -40.791102) (xy 50.314832 -40.827853) (xy 50.272784 -40.858403) (xy 50.226474 -40.881999)
			(xy 50.177044 -40.89806) (xy 50.125709 -40.90619) (xy 50.073735 -40.90619) (xy 50.0224 -40.89806)
			(xy 49.97297 -40.881999) (xy 49.92666 -40.858403) (xy 49.884612 -40.827853) (xy 49.847861 -40.791102)
			(xy 49.817311 -40.749054) (xy 49.793715 -40.702744) (xy 49.777654 -40.653314) (xy 49.769524 -40.601979)
			(xy 49.630074 -40.601979) (xy 49.621944 -40.653314) (xy 49.605883 -40.702744) (xy 49.582287 -40.749054)
			(xy 49.551737 -40.791102) (xy 49.514986 -40.827853) (xy 49.472938 -40.858403) (xy 49.426628 -40.881999)
			(xy 49.377198 -40.89806) (xy 49.325863 -40.90619) (xy 49.273889 -40.90619) (xy 49.222554 -40.89806)
			(xy 49.173124 -40.881999) (xy 49.126814 -40.858403) (xy 49.084766 -40.827853) (xy 49.048015 -40.791102)
			(xy 49.017465 -40.749054) (xy 48.993869 -40.702744) (xy 48.977808 -40.653314) (xy 48.969678 -40.601979)
			(xy 48.829878 -40.601979) (xy 48.822397 -40.65079) (xy 48.807361 -40.69874) (xy 48.785247 -40.743865)
			(xy 48.756564 -40.785128) (xy 48.721971 -40.821578) (xy 48.682264 -40.852379) (xy 48.660558 -40.865044)
			(xy 48.648995 -40.871906) (xy 48.629686 -40.890607) (xy 48.615941 -40.913706) (xy 48.608715 -40.939597)
			(xy 48.608511 -40.966476) (xy 48.615345 -40.992472) (xy 48.628739 -41.015777) (xy 48.637952 -41.025572)
			(xy 48.850296 -41.237916) (xy 48.860104 -41.247092) (xy 48.883418 -41.26041) (xy 48.909397 -41.267194)
			(xy 48.936246 -41.266977) (xy 48.962111 -41.259772) (xy 48.985206 -41.246078) (xy 49.003937 -41.226841)
			(xy 49.010824 -41.21531) (xy 49.023449 -41.193578) (xy 49.054245 -41.153864) (xy 49.090699 -41.119268)
			(xy 49.131969 -41.09059) (xy 49.177105 -41.068489) (xy 49.225066 -41.053475) (xy 49.274748 -41.045894)
			(xy 49.299876 -41.045384) (xy 49.325867 -41.045865) (xy 49.37721 -41.053994) (xy 49.426649 -41.070054)
			(xy 49.472966 -41.093651) (xy 49.515022 -41.124204) (xy 49.55178 -41.16096) (xy 49.582336 -41.203013)
			(xy 49.605936 -41.249329) (xy 49.622001 -41.298767) (xy 49.630133 -41.350109) (xy 49.630133 -41.402079)
			(xy 49.769524 -41.402079) (xy 49.769524 -41.350105) (xy 49.777654 -41.29877) (xy 49.793715 -41.24934)
			(xy 49.817311 -41.20303) (xy 49.847861 -41.160982) (xy 49.884612 -41.124231) (xy 49.92666 -41.093681)
			(xy 49.97297 -41.070085) (xy 50.0224 -41.054024) (xy 50.073735 -41.045894) (xy 50.125709 -41.045894)
			(xy 50.177044 -41.054024) (xy 50.226474 -41.070085) (xy 50.272784 -41.093681) (xy 50.314832 -41.124231)
			(xy 50.351583 -41.160982) (xy 50.382133 -41.20303) (xy 50.405729 -41.24934) (xy 50.42179 -41.29877)
			(xy 50.42992 -41.350105) (xy 50.43043 -41.376092) (xy 50.42992 -41.402079) (xy 50.42179 -41.453414)
			(xy 50.405729 -41.502844) (xy 50.382133 -41.549154) (xy 50.351583 -41.591202) (xy 50.314832 -41.627953)
			(xy 50.272784 -41.658503) (xy 50.226474 -41.682099) (xy 50.177044 -41.69816) (xy 50.125709 -41.70629)
			(xy 50.073735 -41.70629) (xy 50.0224 -41.69816) (xy 49.97297 -41.682099) (xy 49.92666 -41.658503)
			(xy 49.884612 -41.627953) (xy 49.847861 -41.591202) (xy 49.817311 -41.549154) (xy 49.793715 -41.502844)
			(xy 49.777654 -41.453414) (xy 49.769524 -41.402079) (xy 49.630133 -41.402079) (xy 49.630133 -41.402091)
			(xy 49.622001 -41.453433) (xy 49.605936 -41.502871) (xy 49.582336 -41.549187) (xy 49.55178 -41.59124)
			(xy 49.515022 -41.627996) (xy 49.472966 -41.658549) (xy 49.426649 -41.682146) (xy 49.37721 -41.698206)
			(xy 49.325867 -41.706335) (xy 49.299876 -41.7068) (xy 49.270884 -41.706193) (xy 49.213784 -41.696097)
			(xy 49.186338 -41.686734) (xy 49.173062 -41.682355) (xy 49.145196 -41.680248) (xy 49.117803 -41.685772)
			(xy 49.092931 -41.698513) (xy 49.072443 -41.717517) (xy 49.057872 -41.741363) (xy 49.050308 -41.768265)
			(xy 49.04994 -41.782238) (xy 49.04994 -41.850564) (xy 49.050415 -41.861394) (xy 49.059296 -41.881145)
			(xy 49.075535 -41.895473) (xy 49.096239 -41.901826) (xy 49.11772 -41.899072) (xy 49.127156 -41.893744)
			(xy 49.146739 -41.88222) (xy 49.188392 -41.864063) (xy 49.232139 -41.851782) (xy 49.277156 -41.84561)
			(xy 49.299876 -41.84523) (xy 49.325864 -41.845711) (xy 49.377199 -41.853839) (xy 49.426631 -41.869897)
			(xy 49.472942 -41.893491) (xy 49.514992 -41.924039) (xy 49.551746 -41.960789) (xy 49.582297 -42.002837)
			(xy 49.605894 -42.049147) (xy 49.621956 -42.098578) (xy 49.630087 -42.149913) (xy 49.630087 -42.201887)
			(xy 49.630081 -42.201925) (xy 49.769524 -42.201925) (xy 49.769524 -42.149951) (xy 49.777654 -42.098616)
			(xy 49.793715 -42.049186) (xy 49.817311 -42.002876) (xy 49.847861 -41.960828) (xy 49.884612 -41.924077)
			(xy 49.92666 -41.893527) (xy 49.97297 -41.869931) (xy 50.0224 -41.85387) (xy 50.073735 -41.84574)
			(xy 50.125709 -41.84574) (xy 50.177044 -41.85387) (xy 50.226474 -41.869931) (xy 50.272784 -41.893527)
			(xy 50.314832 -41.924077) (xy 50.351583 -41.960828) (xy 50.382133 -42.002876) (xy 50.405729 -42.049186)
			(xy 50.42179 -42.098616) (xy 50.42992 -42.149951) (xy 50.43043 -42.175938) (xy 50.42992 -42.201925)
			(xy 50.42179 -42.25326) (xy 50.405729 -42.30269) (xy 50.382133 -42.349) (xy 50.351583 -42.391048)
			(xy 50.314832 -42.427799) (xy 50.272784 -42.458349) (xy 50.226474 -42.481945) (xy 50.177044 -42.498006)
			(xy 50.125709 -42.506136) (xy 50.073735 -42.506136) (xy 50.0224 -42.498006) (xy 49.97297 -42.481945)
			(xy 49.92666 -42.458349) (xy 49.884612 -42.427799) (xy 49.847861 -42.391048) (xy 49.817311 -42.349)
			(xy 49.793715 -42.30269) (xy 49.777654 -42.25326) (xy 49.769524 -42.201925) (xy 49.630081 -42.201925)
			(xy 49.621956 -42.253222) (xy 49.605894 -42.302653) (xy 49.582297 -42.348963) (xy 49.551746 -42.391011)
			(xy 49.514992 -42.427761) (xy 49.472942 -42.458309) (xy 49.426631 -42.481903) (xy 49.377199 -42.497961)
			(xy 49.325864 -42.506089) (xy 49.299876 -42.506646) (xy 49.270884 -42.506039) (xy 49.213784 -42.495941)
			(xy 49.186338 -42.48658) (xy 49.173064 -42.4822) (xy 49.145202 -42.480091) (xy 49.117811 -42.485615)
			(xy 49.092943 -42.498357) (xy 49.072461 -42.517363) (xy 49.057898 -42.54121) (xy 49.050346 -42.568113)
			(xy 49.04994 -42.582084) (xy 49.04994 -43.193716) (xy 49.311814 -43.45559) (xy 50.454814 -43.45559)
		)
		(stroke
			(width 0)
			(type solid)
		)
		(fill yes)
		(layer "In2.Cu")
		(net "P3V3_P1V8_I2C_I3C")
	)
	(gr_poly
		(pts
			(xy 83.988656 -85.185504) (xy 83.988656 -80.482186) (xy 83.989091 -80.458893) (xy 83.996384 -80.412882)
			(xy 84.010789 -80.36858) (xy 84.03195 -80.327078) (xy 84.059347 -80.2894) (xy 84.075524 -80.272636)
			(xy 85.138514 -79.209646) (xy 85.138514 -74.02322) (xy 85.679534 -73.4822) (xy 85.679534 -72.401938)
			(xy 85.679004 -72.386528) (xy 85.669825 -72.357108) (xy 85.652289 -72.331763) (xy 85.627994 -72.312801)
			(xy 85.59915 -72.301946) (xy 85.568381 -72.300187) (xy 85.553296 -72.303386) (xy 85.530617 -72.308706)
			(xy 85.484386 -72.314432) (xy 85.461094 -72.314816) (xy 85.433842 -72.31433) (xy 85.379894 -72.306572)
			(xy 85.327599 -72.291216) (xy 85.278022 -72.268574) (xy 85.232171 -72.239107) (xy 85.190981 -72.203415)
			(xy 85.155289 -72.162224) (xy 85.125823 -72.116373) (xy 85.103181 -72.066795) (xy 85.087826 -72.0145)
			(xy 85.08007 -71.960552) (xy 85.08007 -71.906048) (xy 85.087826 -71.8521) (xy 85.103181 -71.799805)
			(xy 85.125823 -71.750227) (xy 85.155289 -71.704376) (xy 85.190981 -71.663185) (xy 85.232171 -71.627493)
			(xy 85.278022 -71.598026) (xy 85.327599 -71.575384) (xy 85.379894 -71.560028) (xy 85.433842 -71.55227)
			(xy 85.461094 -71.5518) (xy 85.484386 -71.552177) (xy 85.530618 -71.557904) (xy 85.553296 -71.56323)
			(xy 85.56837 -71.566443) (xy 85.599125 -71.56466) (xy 85.62795 -71.553792) (xy 85.652228 -71.534828)
			(xy 85.66975 -71.50949) (xy 85.678924 -71.480081) (xy 85.679534 -71.464678) (xy 85.679534 -68.711064)
			(xy 85.230208 -68.261738) (xy 76.391008 -68.261738) (xy 75.629008 -69.023992) (xy 75.629008 -70.578218)
			(xy 75.629466 -70.592316) (xy 75.637182 -70.619436) (xy 75.65202 -70.643412) (xy 75.67285 -70.662416)
			(xy 75.698083 -70.674999) (xy 75.725795 -70.680201) (xy 75.753873 -70.677627) (xy 75.767184 -70.67296)
			(xy 75.789284 -70.664749) (xy 75.834999 -70.653218) (xy 75.881787 -70.647406) (xy 75.90536 -70.647052)
			(xy 75.932618 -70.647512) (xy 75.986579 -70.655265) (xy 76.038887 -70.67062) (xy 76.088477 -70.693262)
			(xy 76.13434 -70.722732) (xy 76.175542 -70.75843) (xy 76.211244 -70.799628) (xy 76.240719 -70.845488)
			(xy 76.263366 -70.895076) (xy 76.278726 -70.947382) (xy 76.286485 -71.001342) (xy 76.286485 -71.055858)
			(xy 76.278726 -71.109818) (xy 76.263366 -71.162124) (xy 76.240719 -71.211712) (xy 76.211244 -71.257572)
			(xy 76.175542 -71.29877) (xy 76.13434 -71.334468) (xy 76.088477 -71.363938) (xy 76.038887 -71.38658)
			(xy 75.986579 -71.401935) (xy 75.932618 -71.409688) (xy 75.90536 -71.410068) (xy 75.881786 -71.40972)
			(xy 75.834996 -71.403915) (xy 75.789279 -71.392387) (xy 75.767184 -71.38416) (xy 75.753866 -71.37951)
			(xy 75.725787 -71.37694) (xy 75.698074 -71.382142) (xy 75.672838 -71.394721) (xy 75.652001 -71.413718)
			(xy 75.63715 -71.437688) (xy 75.629417 -71.464804) (xy 75.629008 -71.478902) (xy 75.629008 -71.751698)
			(xy 76.549758 -71.751698) (xy 76.55016 -71.725368) (xy 76.557397 -71.673208) (xy 76.571748 -71.622541)
			(xy 76.592937 -71.574332) (xy 76.620563 -71.529501) (xy 76.654099 -71.4889) (xy 76.673202 -71.470774)
			(xy 76.683286 -71.460982) (xy 76.698038 -71.437066) (xy 76.705703 -71.410031) (xy 76.705697 -71.38193)
			(xy 76.698023 -71.354898) (xy 76.683261 -71.330988) (xy 76.673202 -71.321168) (xy 76.654117 -71.303028)
			(xy 76.620601 -71.262419) (xy 76.592988 -71.217587) (xy 76.571804 -71.169383) (xy 76.557452 -71.118723)
			(xy 76.550204 -71.066571) (xy 76.549758 -71.040244) (xy 76.550244 -71.012993) (xy 76.558 -70.959045)
			(xy 76.573355 -70.90675) (xy 76.595997 -70.857173) (xy 76.625463 -70.811323) (xy 76.661154 -70.770132)
			(xy 76.702345 -70.734441) (xy 76.748195 -70.704975) (xy 76.797772 -70.682333) (xy 76.850067 -70.666978)
			(xy 76.904015 -70.659222) (xy 76.958517 -70.659222) (xy 77.012465 -70.666978) (xy 77.06476 -70.682333)
			(xy 77.114337 -70.704975) (xy 77.160187 -70.734441) (xy 77.201378 -70.770132) (xy 77.237069 -70.811323)
			(xy 77.266535 -70.857173) (xy 77.267318 -70.858888) (xy 82.71713 -70.858888) (xy 82.721201 -70.803266)
			(xy 82.733327 -70.748829) (xy 82.75325 -70.696738) (xy 82.780546 -70.648103) (xy 82.814632 -70.60396)
			(xy 82.854781 -70.565251) (xy 82.900139 -70.5328) (xy 82.949739 -70.507299) (xy 83.002523 -70.489292)
			(xy 83.057366 -70.479162) (xy 83.1131 -70.477125) (xy 83.168537 -70.483225) (xy 83.222494 -70.497331)
			(xy 83.273823 -70.519143) (xy 83.321429 -70.548197) (xy 83.364297 -70.583872) (xy 83.401514 -70.625409)
			(xy 83.432287 -70.671922) (xy 83.455959 -70.722419) (xy 83.472027 -70.775826) (xy 83.480147 -70.831002)
			(xy 83.480656 -70.858888) (xy 83.480147 -70.886774) (xy 83.472027 -70.94195) (xy 83.455959 -70.995357)
			(xy 83.432287 -71.045854) (xy 83.401514 -71.092367) (xy 83.364297 -71.133904) (xy 83.321429 -71.169579)
			(xy 83.273823 -71.198633) (xy 83.222494 -71.220445) (xy 83.168537 -71.234551) (xy 83.1131 -71.240651)
			(xy 83.057366 -71.238614) (xy 83.002523 -71.228484) (xy 82.949739 -71.210477) (xy 82.900139 -71.184976)
			(xy 82.854781 -71.152525) (xy 82.814632 -71.113816) (xy 82.780546 -71.069673) (xy 82.75325 -71.021038)
			(xy 82.733327 -70.968947) (xy 82.721201 -70.91451) (xy 82.71713 -70.858888) (xy 77.267318 -70.858888)
			(xy 77.289177 -70.90675) (xy 77.304532 -70.959045) (xy 77.312288 -71.012993) (xy 77.312774 -71.040244)
			(xy 77.312323 -71.066572) (xy 77.305094 -71.11873) (xy 77.290752 -71.169395) (xy 77.269572 -71.217604)
			(xy 77.241955 -71.262437) (xy 77.208428 -71.30304) (xy 77.18933 -71.321168) (xy 77.179359 -71.331044)
			(xy 77.164701 -71.354959) (xy 77.157083 -71.381955) (xy 77.157078 -71.410006) (xy 77.164685 -71.437005)
			(xy 77.179334 -71.460926) (xy 77.18933 -71.470774) (xy 77.208442 -71.488887) (xy 77.241955 -71.529502)
			(xy 77.269563 -71.57434) (xy 77.290742 -71.62255) (xy 77.305089 -71.673214) (xy 77.312331 -71.72537)
			(xy 77.312774 -71.751698) (xy 77.312288 -71.778949) (xy 77.304532 -71.832897) (xy 77.289177 -71.885192)
			(xy 77.266535 -71.934769) (xy 77.237069 -71.980619) (xy 77.201378 -72.02181) (xy 77.160187 -72.057501)
			(xy 77.114337 -72.086967) (xy 77.06476 -72.109609) (xy 77.012465 -72.124964) (xy 76.958517 -72.13272)
			(xy 76.904015 -72.13272) (xy 76.850067 -72.124964) (xy 76.797772 -72.109609) (xy 76.748195 -72.086967)
			(xy 76.702345 -72.057501) (xy 76.661154 -72.02181) (xy 76.625463 -71.980619) (xy 76.595997 -71.934769)
			(xy 76.573355 -71.885192) (xy 76.558 -71.832897) (xy 76.550244 -71.778949) (xy 76.549758 -71.751698)
			(xy 75.629008 -71.751698) (xy 75.629008 -72.6948) (xy 76.529182 -72.6948) (xy 76.533253 -72.639178)
			(xy 76.545379 -72.584741) (xy 76.565302 -72.53265) (xy 76.592598 -72.484015) (xy 76.626684 -72.439872)
			(xy 76.666833 -72.401163) (xy 76.712191 -72.368712) (xy 76.761791 -72.343211) (xy 76.814575 -72.325204)
			(xy 76.869418 -72.315074) (xy 76.925152 -72.313037) (xy 76.980589 -72.319137) (xy 77.034546 -72.333243)
			(xy 77.085875 -72.355055) (xy 77.133481 -72.384109) (xy 77.176349 -72.419784) (xy 77.186076 -72.43064)
			(xy 78.782672 -72.43064) (xy 78.783104 -72.403139) (xy 78.791017 -72.348708) (xy 78.806658 -72.295975)
			(xy 78.829703 -72.246032) (xy 78.859673 -72.199912) (xy 78.895951 -72.158569) (xy 78.937785 -72.122857)
			(xy 78.984309 -72.093517) (xy 79.00924 -72.081898) (xy 79.021793 -72.075849) (xy 79.043239 -72.058073)
			(xy 79.059091 -72.035167) (xy 79.068169 -72.008832) (xy 79.0698 -71.981025) (xy 79.063862 -71.953809)
			(xy 79.050797 -71.929207) (xy 79.041498 -71.91883) (xy 79.021785 -71.897381) (xy 78.988377 -71.84966)
			(xy 78.962603 -71.79742) (xy 78.945061 -71.741872) (xy 78.936157 -71.684304) (xy 78.93558 -71.655178)
			(xy 78.936066 -71.627927) (xy 78.943822 -71.573979) (xy 78.959177 -71.521684) (xy 78.981819 -71.472107)
			(xy 79.011285 -71.426257) (xy 79.046976 -71.385066) (xy 79.088167 -71.349375) (xy 79.134017 -71.319909)
			(xy 79.183594 -71.297267) (xy 79.235889 -71.281912) (xy 79.289837 -71.274156) (xy 79.344339 -71.274156)
			(xy 79.398287 -71.281912) (xy 79.450582 -71.297267) (xy 79.500159 -71.319909) (xy 79.546009 -71.349375)
			(xy 79.5872 -71.385066) (xy 79.622891 -71.426257) (xy 79.652357 -71.472107) (xy 79.674999 -71.521684)
			(xy 79.690354 -71.573979) (xy 79.69811 -71.627927) (xy 79.698596 -71.655178) (xy 79.698055 -71.682675)
			(xy 79.690155 -71.737099) (xy 79.674528 -71.789827) (xy 79.651499 -71.839768) (xy 79.621543 -71.885888)
			(xy 79.585281 -71.927234) (xy 79.543462 -71.962949) (xy 79.496952 -71.992296) (xy 79.472028 -72.00392)
			(xy 79.45946 -72.009939) (xy 79.438016 -72.027723) (xy 79.422169 -72.050635) (xy 79.413094 -72.076974)
			(xy 79.411465 -72.104785) (xy 79.417405 -72.132004) (xy 79.43047 -72.156609) (xy 79.43977 -72.166988)
			(xy 79.459503 -72.18842) (xy 79.492906 -72.236146) (xy 79.518675 -72.288391) (xy 79.536213 -72.343943)
			(xy 79.545112 -72.401513) (xy 79.545688 -72.43064) (xy 79.545202 -72.457891) (xy 79.537446 -72.511839)
			(xy 79.522091 -72.564134) (xy 79.499449 -72.613711) (xy 79.469983 -72.659561) (xy 79.434292 -72.700752)
			(xy 79.393101 -72.736443) (xy 79.347251 -72.765909) (xy 79.297674 -72.788551) (xy 79.245379 -72.803906)
			(xy 79.191431 -72.811662) (xy 79.136929 -72.811662) (xy 79.082981 -72.803906) (xy 79.030686 -72.788551)
			(xy 78.981109 -72.765909) (xy 78.935259 -72.736443) (xy 78.894068 -72.700752) (xy 78.858377 -72.659561)
			(xy 78.828911 -72.613711) (xy 78.806269 -72.564134) (xy 78.790914 -72.511839) (xy 78.783158 -72.457891)
			(xy 78.782672 -72.43064) (xy 77.186076 -72.43064) (xy 77.213566 -72.461321) (xy 77.244339 -72.507834)
			(xy 77.268011 -72.558331) (xy 77.284079 -72.611738) (xy 77.292199 -72.666914) (xy 77.292708 -72.6948)
			(xy 77.292199 -72.722686) (xy 77.284079 -72.777862) (xy 77.268011 -72.831269) (xy 77.244339 -72.881766)
			(xy 77.213566 -72.928279) (xy 77.176349 -72.969816) (xy 77.133481 -73.005491) (xy 77.085875 -73.034545)
			(xy 77.034546 -73.056357) (xy 76.980589 -73.070463) (xy 76.925152 -73.076563) (xy 76.869418 -73.074526)
			(xy 76.814575 -73.064396) (xy 76.761791 -73.046389) (xy 76.712191 -73.020888) (xy 76.666833 -72.988437)
			(xy 76.626684 -72.949728) (xy 76.592598 -72.905585) (xy 76.565302 -72.85695) (xy 76.545379 -72.804859)
			(xy 76.533253 -72.750422) (xy 76.529182 -72.6948) (xy 75.629008 -72.6948) (xy 75.629008 -74.876406)
			(xy 78.281782 -74.876406) (xy 78.285853 -74.820784) (xy 78.297979 -74.766347) (xy 78.317902 -74.714256)
			(xy 78.345198 -74.665621) (xy 78.379284 -74.621478) (xy 78.419433 -74.582769) (xy 78.464791 -74.550318)
			(xy 78.514391 -74.524817) (xy 78.567175 -74.50681) (xy 78.622018 -74.49668) (xy 78.677752 -74.494643)
			(xy 78.733189 -74.500743) (xy 78.787146 -74.514849) (xy 78.838475 -74.536661) (xy 78.886081 -74.565715)
			(xy 78.928949 -74.60139) (xy 78.966166 -74.642927) (xy 78.996939 -74.68944) (xy 79.020611 -74.739937)
			(xy 79.036679 -74.793344) (xy 79.044799 -74.84852) (xy 79.045308 -74.876406) (xy 79.044799 -74.904292)
			(xy 79.036679 -74.959468) (xy 79.020611 -75.012875) (xy 78.996939 -75.063372) (xy 78.966166 -75.109885)
			(xy 78.928949 -75.151422) (xy 78.886081 -75.187097) (xy 78.838475 -75.216151) (xy 78.787146 -75.237963)
			(xy 78.733189 -75.252069) (xy 78.677752 -75.258169) (xy 78.622018 -75.256132) (xy 78.567175 -75.246002)
			(xy 78.514391 -75.227995) (xy 78.464791 -75.202494) (xy 78.419433 -75.170043) (xy 78.379284 -75.131334)
			(xy 78.345198 -75.087191) (xy 78.317902 -75.038556) (xy 78.297979 -74.986465) (xy 78.285853 -74.932028)
			(xy 78.281782 -74.876406) (xy 75.629008 -74.876406) (xy 75.629008 -76.581) (xy 77.468982 -76.581)
			(xy 77.473053 -76.525378) (xy 77.485179 -76.470941) (xy 77.505102 -76.41885) (xy 77.532398 -76.370215)
			(xy 77.566484 -76.326072) (xy 77.606633 -76.287363) (xy 77.651991 -76.254912) (xy 77.701591 -76.229411)
			(xy 77.754375 -76.211404) (xy 77.809218 -76.201274) (xy 77.864952 -76.199237) (xy 77.920389 -76.205337)
			(xy 77.974346 -76.219443) (xy 78.025675 -76.241255) (xy 78.073281 -76.270309) (xy 78.116149 -76.305984)
			(xy 78.153366 -76.347521) (xy 78.184139 -76.394034) (xy 78.207811 -76.444531) (xy 78.223879 -76.497938)
			(xy 78.231999 -76.553114) (xy 78.232508 -76.581) (xy 78.231999 -76.608886) (xy 78.223879 -76.664062)
			(xy 78.207811 -76.717469) (xy 78.184139 -76.767966) (xy 78.153366 -76.814479) (xy 78.116149 -76.856016)
			(xy 78.073281 -76.891691) (xy 78.025675 -76.920745) (xy 77.974346 -76.942557) (xy 77.920389 -76.956663)
			(xy 77.864952 -76.962763) (xy 77.809218 -76.960726) (xy 77.754375 -76.950596) (xy 77.701591 -76.932589)
			(xy 77.651991 -76.907088) (xy 77.606633 -76.874637) (xy 77.566484 -76.835928) (xy 77.532398 -76.791785)
			(xy 77.505102 -76.74315) (xy 77.485179 -76.691059) (xy 77.473053 -76.636622) (xy 77.468982 -76.581)
			(xy 75.629008 -76.581) (xy 75.629008 -76.77785) (xy 76.7842 -77.933042) (xy 76.805028 -77.933296)
			(xy 76.833997 -77.933876) (xy 76.891417 -77.941629) (xy 76.947342 -77.95678) (xy 77.000825 -77.97907)
			(xy 77.050956 -78.008121) (xy 77.096887 -78.043442) (xy 77.117702 -78.063598) (xy 77.276452 -78.222348)
			(xy 77.293724 -78.240128) (xy 77.302903 -78.249826) (xy 77.32523 -78.264456) (xy 77.350591 -78.272782)
			(xy 77.377246 -78.274232) (xy 77.403361 -78.268705) (xy 77.427142 -78.256581) (xy 77.446956 -78.238694)
			(xy 77.454506 -78.227682) (xy 77.469685 -78.205163) (xy 77.5054 -78.164252) (xy 77.546554 -78.128818)
			(xy 77.592314 -78.099575) (xy 77.641758 -78.077113) (xy 77.693886 -78.061886) (xy 77.747647 -78.054203)
			(xy 77.7748 -78.053692) (xy 77.802051 -78.054178) (xy 77.855999 -78.061934) (xy 77.908294 -78.077289)
			(xy 77.957871 -78.099931) (xy 78.003721 -78.129397) (xy 78.044912 -78.165088) (xy 78.080603 -78.206279)
			(xy 78.110069 -78.252129) (xy 78.132711 -78.301706) (xy 78.148066 -78.354001) (xy 78.155822 -78.407949)
			(xy 78.155822 -78.462451) (xy 78.148066 -78.516399) (xy 78.132711 -78.568694) (xy 78.110069 -78.618271)
			(xy 78.080603 -78.664121) (xy 78.044912 -78.705312) (xy 78.003721 -78.741003) (xy 77.957871 -78.770469)
			(xy 77.908294 -78.793111) (xy 77.855999 -78.808466) (xy 77.802051 -78.816222) (xy 77.7748 -78.816708)
			(xy 77.746276 -78.816178) (xy 77.689863 -78.80769) (xy 77.63534 -78.790902) (xy 77.583922 -78.766189)
			(xy 77.536754 -78.7341) (xy 77.515466 -78.715108) (xy 77.505414 -78.706311) (xy 77.481805 -78.693834)
			(xy 77.455765 -78.687917) (xy 77.429082 -78.688968) (xy 77.403588 -78.696914) (xy 77.381034 -78.71121)
			(xy 77.362967 -78.730874) (xy 77.356462 -78.74254) (xy 77.341995 -78.769197) (xy 77.306922 -78.81868)
			(xy 77.265448 -78.862936) (xy 77.218345 -78.901144) (xy 77.166485 -78.932595) (xy 77.110831 -78.956705)
			(xy 77.052417 -78.973027) (xy 76.992326 -78.981257) (xy 76.962 -78.981808) (xy 76.932872 -78.981338)
			(xy 76.875117 -78.9737) (xy 76.818856 -78.958581) (xy 76.765052 -78.93624) (xy 76.714629 -78.907061)
			(xy 76.668451 -78.871544) (xy 76.647548 -78.851252) (xy 76.6191 -78.823058) (xy 76.598272 -78.822804)
			(xy 76.569303 -78.822224) (xy 76.511883 -78.814471) (xy 76.455958 -78.79932) (xy 76.402475 -78.77703)
			(xy 76.352344 -78.747979) (xy 76.306413 -78.712658) (xy 76.285598 -78.692502) (xy 75.07605 -77.483208)
			(xy 75.065073 -77.472977) (xy 75.038627 -77.458833) (xy 75.009212 -77.452979) (xy 74.979365 -77.455921)
			(xy 74.951659 -77.467405) (xy 74.928483 -77.486441) (xy 74.911835 -77.511387) (xy 74.90315 -77.540094)
			(xy 74.902568 -77.55509) (xy 74.902568 -79.538068) (xy 75.08875 -79.72425) (xy 75.104894 -79.74103)
			(xy 75.132233 -79.778721) (xy 75.153337 -79.820226) (xy 75.167686 -79.864522) (xy 75.174926 -79.910518)
			(xy 75.175364 -79.9338) (xy 75.175364 -82.010504) (xy 75.525122 -82.360262) (xy 75.536806 -82.363818)
			(xy 75.561673 -82.372096) (xy 75.609044 -82.394518) (xy 75.652901 -82.423213) (xy 75.692418 -82.45764)
			(xy 75.726851 -82.497151) (xy 75.755553 -82.541003) (xy 75.777982 -82.588371) (xy 75.786234 -82.613246)
			(xy 75.78979 -82.62493) (xy 76.631292 -83.466432) (xy 82.17027 -83.466432) (xy 82.17076 -83.437692)
			(xy 82.179392 -83.380863) (xy 82.196451 -83.325973) (xy 82.221549 -83.274262) (xy 82.254121 -83.2269)
			(xy 82.273394 -83.205574) (xy 82.283432 -83.194014) (xy 82.296775 -83.166477) (xy 82.301364 -83.136224)
			(xy 82.296789 -83.105968) (xy 82.283459 -83.078425) (xy 82.273394 -83.06689) (xy 82.254148 -83.045541)
			(xy 82.221576 -82.998186) (xy 82.196478 -82.94648) (xy 82.179422 -82.891594) (xy 82.170794 -82.83477)
			(xy 82.17027 -82.806032) (xy 82.170738 -82.778662) (xy 82.178553 -82.724482) (xy 82.19404 -82.671978)
			(xy 82.216882 -82.622231) (xy 82.246608 -82.576265) (xy 82.26425 -82.555334) (xy 82.273452 -82.543982)
			(xy 82.285627 -82.517432) (xy 82.289804 -82.488524) (xy 82.285641 -82.459614) (xy 82.273478 -82.433059)
			(xy 82.26425 -82.42173) (xy 82.246619 -82.400791) (xy 82.216904 -82.354821) (xy 82.194066 -82.305075)
			(xy 82.178573 -82.252576) (xy 82.170744 -82.198401) (xy 82.17027 -82.171032) (xy 82.170785 -82.143781)
			(xy 82.178537 -82.089833) (xy 82.193888 -82.037537) (xy 82.216525 -81.987959) (xy 82.245988 -81.942107)
			(xy 82.281676 -81.900914) (xy 82.322863 -81.86522) (xy 82.368711 -81.835751) (xy 82.418287 -81.813107)
			(xy 82.47058 -81.797749) (xy 82.524527 -81.789989) (xy 82.551778 -81.789524) (xy 82.577177 -81.789941)
			(xy 82.627525 -81.796679) (xy 82.676534 -81.810041) (xy 82.723336 -81.829788) (xy 82.767103 -81.855572)
			(xy 82.807061 -81.886937) (xy 82.825082 -81.90484) (xy 82.834695 -81.91413) (xy 82.85771 -81.927718)
			(xy 82.883461 -81.934872) (xy 82.910186 -81.935104) (xy 82.936058 -81.928396) (xy 82.959304 -81.915208)
			(xy 82.9691 -81.90611) (xy 82.990647 -81.885673) (xy 83.038895 -81.851053) (xy 83.091926 -81.82433)
			(xy 83.148458 -81.806148) (xy 83.207124 -81.796947) (xy 83.236816 -81.796382) (xy 83.264067 -81.796863)
			(xy 83.318015 -81.804621) (xy 83.370309 -81.819978) (xy 83.419885 -81.84262) (xy 83.465735 -81.872087)
			(xy 83.506925 -81.907779) (xy 83.542616 -81.94897) (xy 83.572083 -81.99482) (xy 83.594724 -82.044397)
			(xy 83.61008 -82.096691) (xy 83.617838 -82.150639) (xy 83.618324 -82.17789) (xy 83.617871 -82.205261)
			(xy 83.610053 -82.259441) (xy 83.594562 -82.311945) (xy 83.571716 -82.361692) (xy 83.541988 -82.407658)
			(xy 83.524344 -82.428588) (xy 83.515121 -82.439924) (xy 83.50295 -82.46648) (xy 83.498778 -82.495392)
			(xy 83.502945 -82.524306) (xy 83.515113 -82.550863) (xy 83.524344 -82.562192) (xy 83.542 -82.58311)
			(xy 83.571708 -82.629088) (xy 83.59454 -82.678839) (xy 83.610027 -82.731342) (xy 83.617852 -82.78552)
			(xy 83.618324 -82.81289) (xy 83.617788 -82.841628) (xy 83.609167 -82.898455) (xy 83.59212 -82.953345)
			(xy 83.567031 -83.005057) (xy 83.534469 -83.05242) (xy 83.5152 -83.073748) (xy 83.505141 -83.085291)
			(xy 83.491801 -83.112834) (xy 83.487216 -83.143093) (xy 83.491797 -83.173352) (xy 83.505132 -83.200897)
			(xy 83.5152 -83.212432) (xy 83.534455 -83.233773) (xy 83.567026 -83.28113) (xy 83.592122 -83.332838)
			(xy 83.609176 -83.387726) (xy 83.617802 -83.444552) (xy 83.618324 -83.47329) (xy 83.617812 -83.50054)
			(xy 83.610058 -83.554486) (xy 83.594705 -83.606779) (xy 83.572066 -83.656355) (xy 83.542602 -83.702205)
			(xy 83.506913 -83.743395) (xy 83.465726 -83.779087) (xy 83.419878 -83.808553) (xy 83.370304 -83.831196)
			(xy 83.318012 -83.846552) (xy 83.264066 -83.854311) (xy 83.236816 -83.854798) (xy 83.211417 -83.854379)
			(xy 83.161069 -83.847639) (xy 83.112061 -83.834278) (xy 83.065259 -83.814531) (xy 83.021492 -83.788748)
			(xy 82.981533 -83.757385) (xy 82.963512 -83.739482) (xy 82.953905 -83.730185) (xy 82.930889 -83.716594)
			(xy 82.905136 -83.709439) (xy 82.878408 -83.709209) (xy 82.852536 -83.715919) (xy 82.829289 -83.729111)
			(xy 82.819494 -83.738212) (xy 82.797954 -83.758656) (xy 82.749703 -83.793273) (xy 82.696671 -83.819995)
			(xy 82.640138 -83.838176) (xy 82.58147 -83.847376) (xy 82.551778 -83.84794) (xy 82.524528 -83.847443)
			(xy 82.470582 -83.839684) (xy 82.418289 -83.824328) (xy 82.368714 -83.801686) (xy 82.322866 -83.772221)
			(xy 82.281676 -83.736531) (xy 82.245985 -83.695342) (xy 82.216518 -83.649495) (xy 82.193876 -83.59992)
			(xy 82.178518 -83.547628) (xy 82.170758 -83.493682) (xy 82.17027 -83.466432) (xy 76.631292 -83.466432)
			(xy 77.1779 -84.01304) (xy 77.1779 -84.716874) (xy 77.9018 -85.440774) (xy 83.733386 -85.440774)
		)
		(stroke
			(width 0)
			(type solid)
		)
		(fill yes)
		(layer "In2.Cu")
		(net "GND")
	)
	(gr_poly
		(pts
			(xy 74.032364 -63.982854) (xy 74.032364 -60.24245) (xy 73.822052 -60.032138) (xy 73.801732 -60.031884)
			(xy 73.77509 -60.0309) (xy 73.722451 -60.022457) (xy 73.671497 -60.006778) (xy 73.623217 -59.984167)
			(xy 73.57855 -59.955063) (xy 73.558146 -59.937904) (xy 73.546818 -59.928668) (xy 73.520261 -59.916492)
			(xy 73.491344 -59.912319) (xy 73.462427 -59.916492) (xy 73.43587 -59.928668) (xy 73.424542 -59.937904)
			(xy 73.40361 -59.955543) (xy 73.357642 -59.985261) (xy 73.307894 -60.008097) (xy 73.255391 -60.023579)
			(xy 73.201213 -60.031389) (xy 73.173844 -60.031884) (xy 73.14659 -60.031424) (xy 73.092635 -60.023672)
			(xy 73.040334 -60.008319) (xy 72.990749 -59.985679) (xy 72.944892 -59.956212) (xy 72.903697 -59.920518)
			(xy 72.868 -59.879324) (xy 72.838531 -59.833468) (xy 72.815888 -59.783885) (xy 72.800533 -59.731584)
			(xy 72.792778 -59.67763) (xy 72.792336 -59.650376) (xy 72.792841 -59.623134) (xy 72.800616 -59.569208)
			(xy 72.80783 -59.542934) (xy 72.811203 -59.529875) (xy 72.811709 -59.502918) (xy 72.805138 -59.476768)
			(xy 72.791949 -59.453252) (xy 72.773063 -59.43401) (xy 72.749797 -59.420384) (xy 72.723775 -59.413326)
			(xy 72.710294 -59.412886) (xy 72.170036 -59.412886) (xy 72.15481 -59.413417) (xy 72.125692 -59.422321)
			(xy 72.10049 -59.43941) (xy 72.081441 -59.463166) (xy 72.070239 -59.491479) (xy 72.067875 -59.521837)
			(xy 72.074562 -59.551543) (xy 72.081644 -59.565032) (xy 72.093637 -59.586745) (xy 72.112528 -59.63261)
			(xy 72.125319 -59.680536) (xy 72.131793 -59.729715) (xy 72.13219 -59.754516) (xy 72.131726 -59.781768)
			(xy 72.123967 -59.835716) (xy 72.108609 -59.888011) (xy 72.085965 -59.937588) (xy 72.056497 -59.983438)
			(xy 72.020803 -60.024627) (xy 71.97961 -60.060317) (xy 71.933758 -60.089782) (xy 71.884179 -60.112421)
			(xy 71.831883 -60.127774) (xy 71.777934 -60.135528) (xy 71.750682 -60.136024) (xy 71.723312 -60.135552)
			(xy 71.669135 -60.127726) (xy 71.616632 -60.112238) (xy 71.566882 -60.089405) (xy 71.520905 -60.059696)
			(xy 71.499984 -60.042044) (xy 71.488656 -60.032808) (xy 71.462099 -60.020632) (xy 71.433182 -60.016459)
			(xy 71.404265 -60.020632) (xy 71.377708 -60.032808) (xy 71.36638 -60.042044) (xy 71.345449 -60.059687)
			(xy 71.299484 -60.089415) (xy 71.249737 -60.112259) (xy 71.197233 -60.127749) (xy 71.143053 -60.135566)
			(xy 71.115682 -60.136024) (xy 71.088431 -60.135537) (xy 71.034485 -60.127778) (xy 70.982191 -60.112422)
			(xy 70.932615 -60.08978) (xy 70.886766 -60.060314) (xy 70.845576 -60.024622) (xy 70.809885 -59.983433)
			(xy 70.780419 -59.937583) (xy 70.757777 -59.888007) (xy 70.742421 -59.835714) (xy 70.734663 -59.781767)
			(xy 70.734174 -59.754516) (xy 70.734584 -59.729714) (xy 70.741041 -59.680532) (xy 70.753823 -59.632604)
			(xy 70.772714 -59.586738) (xy 70.78472 -59.565032) (xy 70.791801 -59.551544) (xy 70.79849 -59.521841)
			(xy 70.796128 -59.491486) (xy 70.784924 -59.463175) (xy 70.765875 -59.439424) (xy 70.740671 -59.422342)
			(xy 70.711553 -59.413446) (xy 70.696328 -59.412886) (xy 68.861178 -59.412886) (xy 68.520564 -59.7535)
			(xy 67.871848 -59.7535) (xy 65.696592 -57.578244) (xy 65.686242 -57.568534) (xy 65.661456 -57.554735)
			(xy 65.633832 -57.548279) (xy 65.605497 -57.549662) (xy 65.578633 -57.558777) (xy 65.555308 -57.574924)
			(xy 65.54597 -57.58561) (xy 65.530192 -57.60421) (xy 65.494097 -57.637013) (xy 65.45357 -57.664151)
			(xy 65.409493 -57.685034) (xy 65.362825 -57.699208) (xy 65.314579 -57.706365) (xy 65.290192 -57.706768)
			(xy 65.264204 -57.706284) (xy 65.212869 -57.698152) (xy 65.163438 -57.682088) (xy 65.117129 -57.658489)
			(xy 65.075082 -57.627936) (xy 65.038332 -57.591182) (xy 65.007785 -57.54913) (xy 64.984193 -57.502817)
			(xy 64.968137 -57.453384) (xy 64.960012 -57.402048) (xy 64.959484 -57.37606) (xy 64.959922 -57.351675)
			(xy 64.96709 -57.303436) (xy 64.981265 -57.256772) (xy 65.002139 -57.212696) (xy 65.02926 -57.172163)
			(xy 65.062039 -57.136053) (xy 65.080642 -57.120282) (xy 65.091345 -57.11095) (xy 65.107547 -57.087646)
			(xy 65.116692 -57.060776) (xy 65.118071 -57.032426) (xy 65.111576 -57.004796) (xy 65.097712 -56.980029)
			(xy 65.088008 -56.96966) (xy 64.985392 -56.867044) (xy 64.628522 -56.867044) (xy 64.619124 -56.871108)
			(xy 64.598639 -56.87941) (xy 64.556004 -56.891077) (xy 64.512193 -56.896942) (xy 64.490092 -56.89727)
			(xy 64.467994 -56.896899) (xy 64.424191 -56.891018) (xy 64.381556 -56.879376) (xy 64.36106 -56.871108)
			(xy 64.351662 -56.867044) (xy 63.961264 -56.867044) (xy 63.90894 -56.81472) (xy 63.890722 -56.830201)
			(xy 63.850671 -56.856303) (xy 63.807282 -56.876372) (xy 63.761457 -56.88999) (xy 63.714149 -56.896874)
			(xy 63.690246 -56.89727) (xy 63.664255 -56.89679) (xy 63.612914 -56.888665) (xy 63.563475 -56.872606)
			(xy 63.517158 -56.84901) (xy 63.475104 -56.818458) (xy 63.438347 -56.781702) (xy 63.407794 -56.739648)
			(xy 63.384197 -56.693332) (xy 63.368137 -56.643894) (xy 63.36001 -56.592553) (xy 63.359538 -56.566562)
			(xy 63.359961 -56.542661) (xy 63.366844 -56.495357) (xy 63.38046 -56.449535) (xy 63.400527 -56.406149)
			(xy 63.426627 -56.3661) (xy 63.442088 -56.347868) (xy 62.745366 -55.651146) (xy 62.732666 -55.647336)
			(xy 62.697158 -55.636779) (xy 62.628312 -55.609419) (xy 62.562597 -55.575216) (xy 62.500692 -55.534521)
			(xy 62.443235 -55.487755) (xy 62.41669 -55.461916) (xy 62.416436 -55.461916) (xy 62.324996 -55.370222)
			(xy 62.324742 -55.370222) (xy 62.304255 -55.349084) (xy 62.268163 -55.302578) (xy 62.238168 -55.251924)
			(xy 62.214743 -55.197918) (xy 62.198254 -55.141407) (xy 62.19317 -55.112412) (xy 62.19063 -55.09641)
			(xy 61.510672 -54.416452) (xy 61.475874 -54.440074) (xy 61.455226 -54.453565) (xy 61.410771 -54.474928)
			(xy 61.363633 -54.48944) (xy 61.314861 -54.496778) (xy 61.2902 -54.497224) (xy 61.264212 -54.496714)
			(xy 61.212877 -54.488584) (xy 61.163445 -54.472523) (xy 61.117135 -54.448928) (xy 61.075085 -54.418378)
			(xy 61.038332 -54.381627) (xy 61.007781 -54.339579) (xy 60.984183 -54.293269) (xy 60.96812 -54.243839)
			(xy 60.959987 -54.192504) (xy 60.959492 -54.166516) (xy 60.959645 -54.152024) (xy 60.962186 -54.123153)
			(xy 60.964572 -54.108858) (xy 60.96584 -54.099085) (xy 60.961714 -54.079834) (xy 60.950634 -54.063559)
			(xy 60.934236 -54.052663) (xy 60.924694 -54.050184) (xy 60.896338 -54.043771) (xy 60.841841 -54.023527)
			(xy 60.791036 -53.995269) (xy 60.745093 -53.959648) (xy 60.705068 -53.917484) (xy 60.671886 -53.86975)
			(xy 60.646308 -53.817544) (xy 60.628926 -53.762069) (xy 60.620138 -53.704602) (xy 60.61964 -53.675534)
			(xy 60.61964 -53.52542) (xy 60.367672 -53.273452) (xy 60.174632 -53.273452) (xy 60.164327 -53.273432)
			(xy 60.143741 -53.272416) (xy 60.133484 -53.27142) (xy 60.119394 -53.270349) (xy 60.091552 -53.275105)
			(xy 60.066079 -53.287308) (xy 60.044923 -53.306023) (xy 60.029705 -53.329818) (xy 60.021589 -53.356873)
			(xy 60.020962 -53.370988) (xy 60.020113 -53.396738) (xy 60.011418 -53.447518) (xy 59.994954 -53.496335)
			(xy 59.971118 -53.542008) (xy 59.940488 -53.583432) (xy 59.903805 -53.619605) (xy 59.861955 -53.649652)
			(xy 59.815953 -53.672845) (xy 59.76691 -53.688623) (xy 59.716013 -53.696606) (xy 59.690254 -53.697124)
			(xy 59.664269 -53.696611) (xy 59.612939 -53.688475) (xy 59.563513 -53.67241) (xy 59.517209 -53.648812)
			(xy 59.475166 -53.618262) (xy 59.438419 -53.581511) (xy 59.407872 -53.539465) (xy 59.384278 -53.493159)
			(xy 59.368218 -53.443732) (xy 59.360087 -53.392401) (xy 59.359546 -53.366416) (xy 59.360119 -53.338682)
			(xy 59.369388 -53.283994) (xy 59.387653 -53.231619) (xy 59.414402 -53.183026) (xy 59.431174 -53.16093)
			(xy 59.43968 -53.149469) (xy 59.45057 -53.1231) (xy 59.453738 -53.094748) (xy 59.448936 -53.066626)
			(xy 59.43654 -53.040931) (xy 59.417517 -53.019671) (xy 59.393353 -53.004504) (xy 59.365937 -52.996617)
			(xy 59.351672 -52.996084) (xy 58.718704 -52.996084) (xy 58.597292 -53.117496) (xy 58.597292 -53.530754)
			(xy 60.502038 -55.4355) (xy 60.520326 -55.437024) (xy 60.545698 -55.439826) (xy 60.595208 -55.452241)
			(xy 60.642225 -55.472111) (xy 60.685632 -55.498967) (xy 60.7244 -55.532171) (xy 60.757609 -55.570934)
			(xy 60.78447 -55.614338) (xy 60.804346 -55.661352) (xy 60.816767 -55.710861) (xy 60.819538 -55.736236)
			(xy 60.821062 -55.754524) (xy 62.248796 -57.182004) (xy 62.248796 -57.392395) (xy 62.5696 -57.392395)
			(xy 62.5696 -57.340421) (xy 62.57773 -57.289086) (xy 62.593791 -57.239656) (xy 62.617387 -57.193346)
			(xy 62.647937 -57.151298) (xy 62.684688 -57.114547) (xy 62.726736 -57.083997) (xy 62.773046 -57.060401)
			(xy 62.822476 -57.04434) (xy 62.873811 -57.03621) (xy 62.925785 -57.03621) (xy 62.97712 -57.04434)
			(xy 63.02655 -57.060401) (xy 63.07286 -57.083997) (xy 63.114908 -57.114547) (xy 63.151659 -57.151298)
			(xy 63.182209 -57.193346) (xy 63.205805 -57.239656) (xy 63.221866 -57.289086) (xy 63.229996 -57.340421)
			(xy 63.230506 -57.366408) (xy 63.229996 -57.392395) (xy 63.360048 -57.392395) (xy 63.360048 -57.340421)
			(xy 63.368178 -57.289086) (xy 63.384239 -57.239656) (xy 63.407835 -57.193346) (xy 63.438385 -57.151298)
			(xy 63.475136 -57.114547) (xy 63.517184 -57.083997) (xy 63.563494 -57.060401) (xy 63.612924 -57.04434)
			(xy 63.664259 -57.03621) (xy 63.716233 -57.03621) (xy 63.767568 -57.04434) (xy 63.816998 -57.060401)
			(xy 63.863308 -57.083997) (xy 63.905356 -57.114547) (xy 63.942107 -57.151298) (xy 63.972657 -57.193346)
			(xy 63.996253 -57.239656) (xy 64.012314 -57.289086) (xy 64.020444 -57.340421) (xy 64.020954 -57.366408)
			(xy 64.020444 -57.392395) (xy 64.012314 -57.44373) (xy 63.996253 -57.49316) (xy 63.972657 -57.53947)
			(xy 63.942107 -57.581518) (xy 63.905356 -57.618269) (xy 63.863308 -57.648819) (xy 63.816998 -57.672415)
			(xy 63.767568 -57.688476) (xy 63.716233 -57.696606) (xy 63.664259 -57.696606) (xy 63.612924 -57.688476)
			(xy 63.563494 -57.672415) (xy 63.517184 -57.648819) (xy 63.475136 -57.618269) (xy 63.438385 -57.581518)
			(xy 63.407835 -57.53947) (xy 63.384239 -57.49316) (xy 63.368178 -57.44373) (xy 63.360048 -57.392395)
			(xy 63.229996 -57.392395) (xy 63.221866 -57.44373) (xy 63.205805 -57.49316) (xy 63.182209 -57.53947)
			(xy 63.151659 -57.581518) (xy 63.114908 -57.618269) (xy 63.07286 -57.648819) (xy 63.02655 -57.672415)
			(xy 62.97712 -57.688476) (xy 62.925785 -57.696606) (xy 62.873811 -57.696606) (xy 62.822476 -57.688476)
			(xy 62.773046 -57.672415) (xy 62.726736 -57.648819) (xy 62.684688 -57.618269) (xy 62.647937 -57.581518)
			(xy 62.617387 -57.53947) (xy 62.593791 -57.49316) (xy 62.57773 -57.44373) (xy 62.5696 -57.392395)
			(xy 62.248796 -57.392395) (xy 62.248796 -57.87136) (xy 62.2722 -57.883769) (xy 62.315068 -57.914885)
			(xy 62.352426 -57.952438) (xy 62.383321 -57.995466) (xy 62.395608 -58.018934) (xy 62.399418 -58.026554)
			(xy 62.56542 -58.192491) (xy 63.359983 -58.192491) (xy 63.359983 -58.140509) (xy 63.368116 -58.089167)
			(xy 63.38418 -58.03973) (xy 63.407782 -57.993415) (xy 63.438338 -57.951362) (xy 63.475097 -57.914608)
			(xy 63.517154 -57.884058) (xy 63.563473 -57.860463) (xy 63.612912 -57.844405) (xy 63.664255 -57.83628)
			(xy 63.690246 -57.8358) (xy 64.490092 -57.8358) (xy 64.516082 -57.836267) (xy 64.567423 -57.844397)
			(xy 64.61686 -57.860459) (xy 64.663175 -57.884057) (xy 64.705229 -57.91461) (xy 64.741985 -57.951365)
			(xy 64.772539 -57.993418) (xy 64.796138 -58.039733) (xy 64.812201 -58.089169) (xy 64.820333 -58.14051)
			(xy 64.820333 -58.19249) (xy 64.812201 -58.243831) (xy 64.796138 -58.293267) (xy 64.772539 -58.339582)
			(xy 64.741985 -58.381635) (xy 64.705229 -58.41839) (xy 64.663175 -58.448943) (xy 64.61686 -58.472541)
			(xy 64.567423 -58.488603) (xy 64.516082 -58.496733) (xy 64.490092 -58.497216) (xy 63.690246 -58.497216)
			(xy 63.664255 -58.49672) (xy 63.612912 -58.488595) (xy 63.563473 -58.472537) (xy 63.517154 -58.448942)
			(xy 63.475097 -58.418392) (xy 63.438338 -58.381638) (xy 63.407782 -58.339585) (xy 63.38418 -58.29327)
			(xy 63.368116 -58.243833) (xy 63.359983 -58.192491) (xy 62.56542 -58.192491) (xy 63.04915 -58.676032)
			(xy 63.054992 -58.679334) (xy 63.079969 -58.694387) (xy 63.124667 -58.731833) (xy 63.162113 -58.776531)
			(xy 63.177166 -58.801508) (xy 63.180468 -58.80735) (xy 63.227204 -58.85434) (xy 63.237368 -58.863909)
			(xy 63.261691 -58.877587) (xy 63.28881 -58.884168) (xy 63.316697 -58.88316) (xy 63.34327 -58.874638)
			(xy 63.366542 -58.859239) (xy 63.384775 -58.838114) (xy 63.391034 -58.825638) (xy 63.40288 -58.801667)
			(xy 63.433128 -58.757578) (xy 63.470071 -58.718926) (xy 63.512749 -58.686718) (xy 63.560051 -58.661792)
			(xy 63.610745 -58.644797) (xy 63.663513 -58.636175) (xy 63.690246 -58.635646) (xy 63.716232 -58.636159)
			(xy 63.767564 -58.644295) (xy 63.816991 -58.660359) (xy 63.863298 -58.683957) (xy 63.905343 -58.714507)
			(xy 63.942093 -58.751257) (xy 63.972643 -58.793302) (xy 63.996241 -58.839609) (xy 64.012305 -58.889036)
			(xy 64.020441 -58.940368) (xy 64.020954 -58.966354) (xy 64.020519 -58.990781) (xy 64.020277 -58.99241)
			(xy 64.159602 -58.99241) (xy 64.159602 -58.94039) (xy 64.16774 -58.889009) (xy 64.183815 -58.839535)
			(xy 64.207431 -58.793184) (xy 64.238008 -58.751098) (xy 64.274792 -58.714313) (xy 64.316877 -58.683735)
			(xy 64.363227 -58.660118) (xy 64.412702 -58.644042) (xy 64.464082 -58.635903) (xy 64.490092 -58.635392)
			(xy 65.289938 -58.635392) (xy 65.318867 -58.636012) (xy 65.375844 -58.646065) (xy 65.430205 -58.665876)
			(xy 65.455546 -58.679842) (xy 65.478316 -58.693714) (xy 65.519596 -58.727448) (xy 65.554933 -58.767364)
			(xy 65.583415 -58.812429) (xy 65.604303 -58.861477) (xy 65.617057 -58.913239) (xy 65.621348 -58.966377)
			(xy 65.617065 -59.019515) (xy 65.604317 -59.071279) (xy 65.583436 -59.12033) (xy 65.554961 -59.165399)
			(xy 65.519629 -59.20532) (xy 65.478353 -59.23906) (xy 65.455546 -59.252866) (xy 65.430197 -59.26682)
			(xy 65.375842 -59.286646) (xy 65.318867 -59.296716) (xy 65.289938 -59.297316) (xy 64.490092 -59.297316)
			(xy 64.464082 -59.296897) (xy 64.412702 -59.288758) (xy 64.363227 -59.272682) (xy 64.316877 -59.249065)
			(xy 64.274792 -59.218487) (xy 64.238008 -59.181702) (xy 64.207431 -59.139616) (xy 64.183815 -59.093265)
			(xy 64.16774 -59.043791) (xy 64.159602 -58.99241) (xy 64.020277 -58.99241) (xy 64.013337 -59.039103)
			(xy 63.999124 -59.085842) (xy 63.978188 -59.129982) (xy 63.950986 -59.170561) (xy 63.918109 -59.206695)
			(xy 63.880273 -59.237599) (xy 63.838302 -59.2626) (xy 63.793109 -59.281152) (xy 63.769494 -59.28741)
			(xy 63.755524 -59.290966) (xy 63.709804 -59.336686) (xy 63.80861 -59.435492) (xy 64.490092 -59.435492)
			(xy 64.516094 -59.435976) (xy 64.567458 -59.444114) (xy 64.616916 -59.460191) (xy 64.663247 -59.48381)
			(xy 64.705311 -59.51439) (xy 64.74207 -59.551177) (xy 64.772619 -59.593263) (xy 64.796204 -59.639612)
			(xy 64.812244 -59.689081) (xy 64.820344 -59.740451) (xy 64.8208 -59.766454) (xy 64.820298 -59.792441)
			(xy 64.959994 -59.792441) (xy 64.959994 -59.740467) (xy 64.968124 -59.689132) (xy 64.984185 -59.639702)
			(xy 65.007781 -59.593392) (xy 65.038331 -59.551344) (xy 65.075082 -59.514593) (xy 65.11713 -59.484043)
			(xy 65.16344 -59.460447) (xy 65.21287 -59.444386) (xy 65.264205 -59.436256) (xy 65.316179 -59.436256)
			(xy 65.367514 -59.444386) (xy 65.416944 -59.460447) (xy 65.463254 -59.484043) (xy 65.505302 -59.514593)
			(xy 65.542053 -59.551344) (xy 65.572603 -59.593392) (xy 65.596199 -59.639702) (xy 65.61226 -59.689132)
			(xy 65.62039 -59.740467) (xy 65.6209 -59.766454) (xy 65.62039 -59.792441) (xy 65.61226 -59.843776)
			(xy 65.596199 -59.893206) (xy 65.572603 -59.939516) (xy 65.542053 -59.981564) (xy 65.505302 -60.018315)
			(xy 65.463254 -60.048865) (xy 65.416944 -60.072461) (xy 65.367514 -60.088522) (xy 65.316179 -60.096652)
			(xy 65.264205 -60.096652) (xy 65.21287 -60.088522) (xy 65.16344 -60.072461) (xy 65.11713 -60.048865)
			(xy 65.075082 -60.018315) (xy 65.038331 -59.981564) (xy 65.007781 -59.939516) (xy 64.984185 -59.893206)
			(xy 64.968124 -59.843776) (xy 64.959994 -59.792441) (xy 64.820298 -59.792441) (xy 64.820284 -59.793176)
			(xy 64.811686 -59.845925) (xy 64.794722 -59.896606) (xy 64.769834 -59.943902) (xy 64.737669 -59.986584)
			(xy 64.699062 -60.023541) (xy 64.655017 -60.053814) (xy 64.631062 -60.065666) (xy 64.618625 -60.071987)
			(xy 64.597529 -60.090227) (xy 64.582148 -60.113491) (xy 64.573629 -60.140046) (xy 64.572604 -60.167915)
			(xy 64.579151 -60.195024) (xy 64.592782 -60.219354) (xy 64.60236 -60.229496) (xy 64.774064 -60.4012)
			(xy 65.467738 -60.4012) (xy 66.559938 -61.4934) (xy 72.261982 -61.4934) (xy 72.266053 -61.437778)
			(xy 72.278179 -61.383341) (xy 72.298102 -61.33125) (xy 72.325398 -61.282615) (xy 72.359484 -61.238472)
			(xy 72.399633 -61.199763) (xy 72.444991 -61.167312) (xy 72.494591 -61.141811) (xy 72.547375 -61.123804)
			(xy 72.602218 -61.113674) (xy 72.657952 -61.111637) (xy 72.713389 -61.117737) (xy 72.767346 -61.131843)
			(xy 72.818675 -61.153655) (xy 72.866281 -61.182709) (xy 72.909149 -61.218384) (xy 72.946366 -61.259921)
			(xy 72.977139 -61.306434) (xy 73.000811 -61.356931) (xy 73.016879 -61.410338) (xy 73.024999 -61.465514)
			(xy 73.025508 -61.4934) (xy 73.024999 -61.521286) (xy 73.016879 -61.576462) (xy 73.000811 -61.629869)
			(xy 72.977139 -61.680366) (xy 72.946366 -61.726879) (xy 72.909149 -61.768416) (xy 72.866281 -61.804091)
			(xy 72.818675 -61.833145) (xy 72.767346 -61.854957) (xy 72.713389 -61.869063) (xy 72.657952 -61.875163)
			(xy 72.602218 -61.873126) (xy 72.547375 -61.862996) (xy 72.494591 -61.844989) (xy 72.444991 -61.819488)
			(xy 72.399633 -61.787037) (xy 72.359484 -61.748328) (xy 72.325398 -61.704185) (xy 72.298102 -61.65555)
			(xy 72.278179 -61.603459) (xy 72.266053 -61.549022) (xy 72.261982 -61.4934) (xy 66.559938 -61.4934)
			(xy 66.57721 -61.510672) (xy 67.825874 -61.510672) (xy 67.84213 -61.526928) (xy 67.978274 -61.526928)
			(xy 69.760592 -63.309246) (xy 69.760592 -63.875752) (xy 71.748366 -63.875752) (xy 71.748366 -63.821248)
			(xy 71.756122 -63.767299) (xy 71.771478 -63.715003) (xy 71.794119 -63.665424) (xy 71.823586 -63.619573)
			(xy 71.859278 -63.578381) (xy 71.90047 -63.542689) (xy 71.946321 -63.513221) (xy 71.995899 -63.490579)
			(xy 72.048195 -63.475223) (xy 72.102144 -63.467466) (xy 72.129396 -63.46698) (xy 72.156354 -63.467459)
			(xy 72.209732 -63.47505) (xy 72.261511 -63.49008) (xy 72.310657 -63.51225) (xy 72.356193 -63.541118)
			(xy 72.39721 -63.57611) (xy 72.4154 -63.596012) (xy 72.425137 -63.606348) (xy 72.449087 -63.621588)
			(xy 72.476302 -63.62966) (xy 72.504688 -63.629941) (xy 72.532058 -63.622411) (xy 72.556305 -63.607649)
			(xy 72.566276 -63.597536) (xy 72.584381 -63.578417) (xy 72.624999 -63.544906) (xy 72.669839 -63.5173)
			(xy 72.71805 -63.496122) (xy 72.768715 -63.481776) (xy 72.820872 -63.474534) (xy 72.8472 -63.474092)
			(xy 72.874451 -63.474578) (xy 72.928399 -63.482334) (xy 72.980694 -63.497689) (xy 73.030271 -63.520331)
			(xy 73.076121 -63.549797) (xy 73.117312 -63.585488) (xy 73.153003 -63.626679) (xy 73.182469 -63.672529)
			(xy 73.205111 -63.722106) (xy 73.220466 -63.774401) (xy 73.228222 -63.828349) (xy 73.228222 -63.882851)
			(xy 73.220466 -63.936799) (xy 73.205111 -63.989094) (xy 73.182469 -64.038671) (xy 73.153003 -64.084521)
			(xy 73.117312 -64.125712) (xy 73.076121 -64.161403) (xy 73.030271 -64.190869) (xy 72.980694 -64.213511)
			(xy 72.928399 -64.228866) (xy 72.874451 -64.236622) (xy 72.8472 -64.237108) (xy 72.820242 -64.236635)
			(xy 72.766863 -64.229044) (xy 72.715084 -64.214013) (xy 72.665938 -64.191842) (xy 72.620402 -64.162972)
			(xy 72.579385 -64.127978) (xy 72.561196 -64.108076) (xy 72.551462 -64.097737) (xy 72.527511 -64.082499)
			(xy 72.500295 -64.074429) (xy 72.471909 -64.074148) (xy 72.444539 -64.081678) (xy 72.420291 -64.09644)
			(xy 72.41032 -64.106552) (xy 72.392165 -64.125622) (xy 72.351559 -64.159138) (xy 72.306729 -64.186751)
			(xy 72.258528 -64.207937) (xy 72.207871 -64.222293) (xy 72.155722 -64.229547) (xy 72.129396 -64.229996)
			(xy 72.102144 -64.229534) (xy 72.048195 -64.221777) (xy 71.995899 -64.206421) (xy 71.946321 -64.183779)
			(xy 71.90047 -64.154311) (xy 71.859278 -64.118619) (xy 71.823586 -64.077427) (xy 71.794119 -64.031576)
			(xy 71.771478 -63.981997) (xy 71.756122 -63.929701) (xy 71.748366 -63.875752) (xy 69.760592 -63.875752)
			(xy 69.760592 -64.123824) (xy 69.990462 -64.353948) (xy 73.66127 -64.353948)
		)
		(stroke
			(width 0)
			(type solid)
		)
		(fill yes)
		(layer "In2.Cu")
		(net "P1V8_STBY_PE_VCC18A")
	)
	(gr_poly
		(pts
			(xy 59.49315 -47.386494) (xy 59.502914 -47.376052) (xy 59.516731 -47.35104) (xy 59.52307 -47.323177)
			(xy 59.521433 -47.294649) (xy 59.511949 -47.267694) (xy 59.495361 -47.244426) (xy 59.484514 -47.23511)
			(xy 59.465367 -47.219324) (xy 59.431568 -47.182991) (xy 59.403574 -47.142017) (xy 59.382013 -47.097323)
			(xy 59.367368 -47.04991) (xy 59.359968 -47.000842) (xy 59.359546 -46.97603) (xy 59.360053 -46.95004)
			(xy 59.36818 -46.898699) (xy 59.384238 -46.849262) (xy 59.407831 -46.802945) (xy 59.43838 -46.760889)
			(xy 59.475131 -46.724129) (xy 59.51718 -46.693571) (xy 59.563491 -46.669967) (xy 59.612925 -46.653898)
			(xy 59.664264 -46.645759) (xy 59.690254 -46.645322) (xy 59.714533 -46.645753) (xy 59.762568 -46.652857)
			(xy 59.809049 -46.666906) (xy 59.852977 -46.687598) (xy 59.89341 -46.714488) (xy 59.911742 -46.730412)
			(xy 59.923392 -46.74012) (xy 59.950897 -46.752856) (xy 59.980928 -46.756962) (xy 60.010841 -46.752077)
			(xy 60.038006 -46.738631) (xy 60.04941 -46.728634) (xy 60.069073 -46.7107) (xy 60.112456 -46.679877)
			(xy 60.159689 -46.655358) (xy 60.209863 -46.637615) (xy 60.235846 -46.63186) (xy 60.250832 -46.628812)
			(xy 60.57011 -46.309534) (xy 60.57011 -43.407584) (xy 60.569522 -43.392118) (xy 60.560195 -43.36262)
			(xy 60.542488 -43.337252) (xy 60.518016 -43.318327) (xy 60.48901 -43.30757) (xy 60.47359 -43.306238)
			(xy 60.448493 -43.304506) (xy 60.399213 -43.294401) (xy 60.352032 -43.27695) (xy 60.308038 -43.252555)
			(xy 60.268245 -43.22178) (xy 60.233571 -43.185334) (xy 60.204816 -43.144058) (xy 60.182643 -43.098903)
			(xy 60.167563 -43.050912) (xy 60.159925 -43.00119) (xy 60.159392 -42.976038) (xy 60.159872 -42.950047)
			(xy 60.167999 -42.898704) (xy 60.184058 -42.849264) (xy 60.207653 -42.802946) (xy 60.238205 -42.760889)
			(xy 60.27496 -42.72413) (xy 60.317013 -42.693573) (xy 60.363329 -42.669972) (xy 60.412767 -42.653908)
			(xy 60.464109 -42.645775) (xy 60.4901 -42.64533) (xy 60.515246 -42.646346) (xy 60.525767 -42.646667)
			(xy 60.545643 -42.639808) (xy 60.561106 -42.625561) (xy 60.569568 -42.606312) (xy 60.57011 -42.5958)
			(xy 60.57011 -42.556176) (xy 60.569598 -42.545655) (xy 60.561161 -42.52638) (xy 60.545682 -42.512129)
			(xy 60.525777 -42.505311) (xy 60.515246 -42.50563) (xy 60.4901 -42.506646) (xy 60.46411 -42.506136)
			(xy 60.412769 -42.498005) (xy 60.363333 -42.481942) (xy 60.317018 -42.458343) (xy 60.274965 -42.42779)
			(xy 60.23821 -42.391035) (xy 60.207657 -42.348982) (xy 60.184058 -42.302667) (xy 60.167995 -42.253231)
			(xy 60.159864 -42.20189) (xy 60.159864 -42.14991) (xy 60.167995 -42.098569) (xy 60.184058 -42.049133)
			(xy 60.207657 -42.002818) (xy 60.23821 -41.960765) (xy 60.274965 -41.92401) (xy 60.317018 -41.893457)
			(xy 60.363333 -41.869858) (xy 60.412769 -41.853795) (xy 60.46411 -41.845664) (xy 60.4901 -41.84523)
			(xy 60.515246 -41.846246) (xy 60.525767 -41.846567) (xy 60.545643 -41.839708) (xy 60.561106 -41.825461)
			(xy 60.569568 -41.806212) (xy 60.57011 -41.7957) (xy 60.57011 -41.75633) (xy 60.56959 -41.745816)
			(xy 60.561145 -41.726558) (xy 60.545669 -41.712321) (xy 60.525774 -41.705511) (xy 60.515246 -41.705784)
			(xy 60.4901 -41.7068) (xy 60.464113 -41.70629) (xy 60.41278 -41.69816) (xy 60.363351 -41.6821) (xy 60.317042 -41.658504)
			(xy 60.274995 -41.627955) (xy 60.238245 -41.591205) (xy 60.207696 -41.549158) (xy 60.1841 -41.502849)
			(xy 60.16804 -41.45342) (xy 60.15991 -41.402087) (xy 60.15991 -41.350113) (xy 60.16804 -41.29878)
			(xy 60.1841 -41.249351) (xy 60.207696 -41.203042) (xy 60.238245 -41.160995) (xy 60.274995 -41.124245)
			(xy 60.317042 -41.093696) (xy 60.363351 -41.0701) (xy 60.41278 -41.05404) (xy 60.464113 -41.04591)
			(xy 60.4901 -41.045384) (xy 60.515246 -41.0464) (xy 60.525771 -41.046721) (xy 60.545656 -41.039863)
			(xy 60.561132 -41.025619) (xy 60.569611 -41.00637) (xy 60.57011 -40.995854) (xy 60.57011 -40.95623)
			(xy 60.56959 -40.945716) (xy 60.561145 -40.926458) (xy 60.545669 -40.912221) (xy 60.525774 -40.905411)
			(xy 60.515246 -40.905684) (xy 60.4901 -40.9067) (xy 60.464113 -40.90619) (xy 60.41278 -40.89806)
			(xy 60.363351 -40.882) (xy 60.317042 -40.858404) (xy 60.274995 -40.827855) (xy 60.238245 -40.791105)
			(xy 60.207696 -40.749058) (xy 60.1841 -40.702749) (xy 60.16804 -40.65332) (xy 60.15991 -40.601987)
			(xy 60.15991 -40.550013) (xy 60.16804 -40.49868) (xy 60.1841 -40.449251) (xy 60.207696 -40.402942)
			(xy 60.238245 -40.360895) (xy 60.274995 -40.324145) (xy 60.317042 -40.293596) (xy 60.363351 -40.27)
			(xy 60.41278 -40.25394) (xy 60.464113 -40.24581) (xy 60.4901 -40.245284) (xy 60.515246 -40.2463)
			(xy 60.525771 -40.246621) (xy 60.545656 -40.239763) (xy 60.561132 -40.225519) (xy 60.569611 -40.20627)
			(xy 60.57011 -40.195754) (xy 60.57011 -40.156384) (xy 60.5696 -40.145862) (xy 60.561164 -40.126584)
			(xy 60.545684 -40.11233) (xy 60.525777 -40.105511) (xy 60.515246 -40.105838) (xy 60.4901 -40.106854)
			(xy 60.464109 -40.106344) (xy 60.412768 -40.098213) (xy 60.36333 -40.082149) (xy 60.317014 -40.05855)
			(xy 60.27496 -40.027996) (xy 60.238204 -39.99124) (xy 60.20765 -39.949186) (xy 60.184051 -39.90287)
			(xy 60.167987 -39.853432) (xy 60.159856 -39.802091) (xy 60.159856 -39.750109) (xy 60.167987 -39.698768)
			(xy 60.184051 -39.64933) (xy 60.20765 -39.603014) (xy 60.238204 -39.56096) (xy 60.27496 -39.524204)
			(xy 60.317014 -39.49365) (xy 60.36333 -39.470051) (xy 60.412768 -39.453987) (xy 60.464109 -39.445856)
			(xy 60.4901 -39.445438) (xy 60.514457 -39.44587) (xy 60.562644 -39.453013) (xy 60.609263 -39.467145)
			(xy 60.653306 -39.487959) (xy 60.693821 -39.515006) (xy 60.729933 -39.547702) (xy 60.76086 -39.585339)
			(xy 60.785934 -39.627104) (xy 60.804613 -39.672094) (xy 60.810902 -39.695628) (xy 60.814551 -39.708572)
			(xy 60.827638 -39.732055) (xy 60.846407 -39.751303) (xy 60.869554 -39.764977) (xy 60.89547 -39.772127)
			(xy 60.922353 -39.772257) (xy 60.948337 -39.765357) (xy 60.971615 -39.751908) (xy 60.981336 -39.742618)
			(xy 62.087252 -38.636702) (xy 62.578996 -38.636702) (xy 63.333376 -37.882322) (xy 68.353432 -37.882322)
			(xy 68.845055 -38.373847) (xy 70.895512 -38.373847) (xy 70.895512 -38.319353) (xy 70.903267 -38.265413)
			(xy 70.918619 -38.213126) (xy 70.941255 -38.163556) (xy 70.970716 -38.117711) (xy 71.0064 -38.076526)
			(xy 71.047582 -38.040837) (xy 71.093424 -38.011373) (xy 71.142992 -37.988731) (xy 71.195278 -37.973375)
			(xy 71.249217 -37.965615) (xy 71.276464 -37.965126) (xy 71.30538 -37.96566) (xy 71.362551 -37.974385)
			(xy 71.41775 -37.991639) (xy 71.469712 -38.017027) (xy 71.517247 -38.049969) (xy 71.559264 -38.089707)
			(xy 71.577454 -38.112192) (xy 71.587351 -38.123997) (xy 71.612675 -38.141516) (xy 71.642068 -38.150692)
			(xy 71.67286 -38.150692) (xy 71.702253 -38.141516) (xy 71.727577 -38.123997) (xy 71.737474 -38.112192)
			(xy 71.755678 -38.089719) (xy 71.797695 -38.049984) (xy 71.845227 -38.017044) (xy 71.897186 -37.991654)
			(xy 71.952381 -37.974395) (xy 72.009549 -37.965663) (xy 72.038464 -37.965126) (xy 72.065721 -37.965518)
			(xy 72.119681 -37.973272) (xy 72.171988 -37.988626) (xy 72.221577 -38.011269) (xy 72.267438 -38.040738)
			(xy 72.308639 -38.076435) (xy 72.34434 -38.117633) (xy 72.373814 -38.163492) (xy 72.396461 -38.213079)
			(xy 72.41182 -38.265384) (xy 72.419579 -38.319343) (xy 72.419579 -38.373857) (xy 72.41182 -38.427816)
			(xy 72.396461 -38.480121) (xy 72.373814 -38.529708) (xy 72.34434 -38.575567) (xy 72.308639 -38.616765)
			(xy 72.267438 -38.652462) (xy 72.221577 -38.681931) (xy 72.171988 -38.704574) (xy 72.119681 -38.719928)
			(xy 72.065721 -38.727682) (xy 72.038464 -38.728142) (xy 72.009548 -38.727599) (xy 71.952377 -38.718879)
			(xy 71.897177 -38.701627) (xy 71.845215 -38.67624) (xy 71.797681 -38.643299) (xy 71.755664 -38.60356)
			(xy 71.737474 -38.581076) (xy 71.727577 -38.569271) (xy 71.702253 -38.551752) (xy 71.67286 -38.542576)
			(xy 71.642068 -38.542576) (xy 71.612675 -38.551752) (xy 71.587351 -38.569271) (xy 71.577454 -38.581076)
			(xy 71.559226 -38.603529) (xy 71.517215 -38.643267) (xy 71.469688 -38.67621) (xy 71.417734 -38.701604)
			(xy 71.362542 -38.718867) (xy 71.305378 -38.727603) (xy 71.276464 -38.728142) (xy 71.249217 -38.727585)
			(xy 71.195278 -38.719825) (xy 71.142992 -38.704469) (xy 71.093424 -38.681827) (xy 71.047582 -38.652363)
			(xy 71.0064 -38.616674) (xy 70.970716 -38.575489) (xy 70.941255 -38.529644) (xy 70.918619 -38.480074)
			(xy 70.903267 -38.427787) (xy 70.895512 -38.373847) (xy 68.845055 -38.373847) (xy 69.628004 -39.15664)
			(xy 72.958706 -39.15664) (xy 73.0504 -39.0652) (xy 73.0504 -37.49929) (xy 72.118728 -36.567618) (xy 68.809616 -36.567618)
			(xy 68.795934 -36.568049) (xy 68.76955 -36.575303) (xy 68.746049 -36.589319) (xy 68.727127 -36.609085)
			(xy 68.714149 -36.633175) (xy 68.708053 -36.65985) (xy 68.70827 -36.673536) (xy 68.708524 -36.6903)
			(xy 68.708038 -36.717551) (xy 68.700282 -36.771499) (xy 68.684927 -36.823794) (xy 68.662285 -36.873371)
			(xy 68.632819 -36.919221) (xy 68.597128 -36.960412) (xy 68.555937 -36.996103) (xy 68.510087 -37.025569)
			(xy 68.46051 -37.048211) (xy 68.408215 -37.063566) (xy 68.354267 -37.071322) (xy 68.299765 -37.071322)
			(xy 68.245817 -37.063566) (xy 68.193522 -37.048211) (xy 68.143945 -37.025569) (xy 68.098095 -36.996103)
			(xy 68.056904 -36.960412) (xy 68.021213 -36.919221) (xy 67.991747 -36.873371) (xy 67.969105 -36.823794)
			(xy 67.95375 -36.771499) (xy 67.945994 -36.717551) (xy 67.945508 -36.6903) (xy 67.945762 -36.673536)
			(xy 67.945892 -36.659861) (xy 67.939751 -36.633221) (xy 67.926769 -36.609162) (xy 67.907876 -36.589404)
			(xy 67.884421 -36.575359) (xy 67.858084 -36.568032) (xy 67.844416 -36.567618) (xy 63.169546 -36.567618)
			(xy 63.16726 -36.569904) (xy 62.631828 -36.569904) (xy 62.016132 -37.1856) (xy 65.276982 -37.1856)
			(xy 65.281053 -37.129978) (xy 65.293179 -37.075541) (xy 65.313102 -37.02345) (xy 65.340398 -36.974815)
			(xy 65.374484 -36.930672) (xy 65.414633 -36.891963) (xy 65.459991 -36.859512) (xy 65.509591 -36.834011)
			(xy 65.562375 -36.816004) (xy 65.617218 -36.805874) (xy 65.672952 -36.803837) (xy 65.728389 -36.809937)
			(xy 65.782346 -36.824043) (xy 65.833675 -36.845855) (xy 65.881281 -36.874909) (xy 65.924149 -36.910584)
			(xy 65.961366 -36.952121) (xy 65.992139 -36.998634) (xy 66.015811 -37.049131) (xy 66.031879 -37.102538)
			(xy 66.039999 -37.157714) (xy 66.040508 -37.1856) (xy 66.039999 -37.213486) (xy 66.031879 -37.268662)
			(xy 66.015811 -37.322069) (xy 65.992139 -37.372566) (xy 65.961366 -37.419079) (xy 65.924149 -37.460616)
			(xy 65.881281 -37.496291) (xy 65.833675 -37.525345) (xy 65.782346 -37.547157) (xy 65.728389 -37.561263)
			(xy 65.672952 -37.567363) (xy 65.617218 -37.565326) (xy 65.562375 -37.555196) (xy 65.509591 -37.537189)
			(xy 65.459991 -37.511688) (xy 65.414633 -37.479237) (xy 65.374484 -37.440528) (xy 65.340398 -37.396385)
			(xy 65.313102 -37.34775) (xy 65.293179 -37.295659) (xy 65.281053 -37.241222) (xy 65.276982 -37.1856)
			(xy 62.016132 -37.1856) (xy 59.990228 -39.211504) (xy 59.923426 -39.211504) (xy 59.908948 -39.224204)
			(xy 59.890729 -39.23968) (xy 59.850676 -39.265772) (xy 59.807286 -39.28583) (xy 59.761461 -39.299437)
			(xy 59.714155 -39.306308) (xy 59.690254 -39.306754) (xy 59.667645 -39.306381) (xy 59.62285 -39.300209)
			(xy 59.579314 -39.287987) (xy 59.558428 -39.279322) (xy 59.526678 -39.265606) (xy 59.179714 -39.61257)
			(xy 59.19343 -39.64432) (xy 59.202107 -39.665201) (xy 59.214318 -39.70874) (xy 59.220477 -39.753537)
			(xy 59.220862 -39.776146) (xy 59.220361 -39.802133) (xy 59.360056 -39.802133) (xy 59.360056 -39.750159)
			(xy 59.368186 -39.698824) (xy 59.384247 -39.649394) (xy 59.407843 -39.603084) (xy 59.438393 -39.561036)
			(xy 59.475144 -39.524285) (xy 59.517192 -39.493735) (xy 59.563502 -39.470139) (xy 59.612932 -39.454078)
			(xy 59.664267 -39.445948) (xy 59.716241 -39.445948) (xy 59.767576 -39.454078) (xy 59.817006 -39.470139)
			(xy 59.863316 -39.493735) (xy 59.905364 -39.524285) (xy 59.942115 -39.561036) (xy 59.972665 -39.603084)
			(xy 59.996261 -39.649394) (xy 60.012322 -39.698824) (xy 60.020452 -39.750159) (xy 60.020962 -39.776146)
			(xy 60.020452 -39.802133) (xy 60.012322 -39.853468) (xy 59.996261 -39.902898) (xy 59.972665 -39.949208)
			(xy 59.942115 -39.991256) (xy 59.905364 -40.028007) (xy 59.863316 -40.058557) (xy 59.817006 -40.082153)
			(xy 59.767576 -40.098214) (xy 59.716241 -40.106344) (xy 59.664267 -40.106344) (xy 59.612932 -40.098214)
			(xy 59.563502 -40.082153) (xy 59.517192 -40.058557) (xy 59.475144 -40.028007) (xy 59.438393 -39.991256)
			(xy 59.407843 -39.949208) (xy 59.384247 -39.902898) (xy 59.368186 -39.853468) (xy 59.360056 -39.802133)
			(xy 59.220361 -39.802133) (xy 59.220347 -39.802838) (xy 59.211759 -39.855526) (xy 59.194813 -39.906149)
			(xy 59.16995 -39.953389) (xy 59.154314 -39.975028) (xy 59.154314 -40.36949) (xy 59.17102 -40.39175)
			(xy 59.197584 -40.440654) (xy 59.215704 -40.493275) (xy 59.224883 -40.548165) (xy 59.225434 -40.575992)
			(xy 59.224116 -40.601979) (xy 59.360056 -40.601979) (xy 59.360056 -40.550005) (xy 59.368186 -40.49867)
			(xy 59.384247 -40.44924) (xy 59.407843 -40.40293) (xy 59.438393 -40.360882) (xy 59.475144 -40.324131)
			(xy 59.517192 -40.293581) (xy 59.563502 -40.269985) (xy 59.612932 -40.253924) (xy 59.664267 -40.245794)
			(xy 59.716241 -40.245794) (xy 59.767576 -40.253924) (xy 59.817006 -40.269985) (xy 59.863316 -40.293581)
			(xy 59.905364 -40.324131) (xy 59.942115 -40.360882) (xy 59.972665 -40.40293) (xy 59.996261 -40.44924)
			(xy 60.012322 -40.49867) (xy 60.020452 -40.550005) (xy 60.020962 -40.575992) (xy 60.020452 -40.601979)
			(xy 60.012322 -40.653314) (xy 59.996261 -40.702744) (xy 59.972665 -40.749054) (xy 59.942115 -40.791102)
			(xy 59.905364 -40.827853) (xy 59.863316 -40.858403) (xy 59.817006 -40.881999) (xy 59.767576 -40.89806)
			(xy 59.716241 -40.90619) (xy 59.664267 -40.90619) (xy 59.612932 -40.89806) (xy 59.563502 -40.881999)
			(xy 59.517192 -40.858403) (xy 59.475144 -40.827853) (xy 59.438393 -40.791102) (xy 59.407843 -40.749054)
			(xy 59.384247 -40.702744) (xy 59.368186 -40.653314) (xy 59.360056 -40.601979) (xy 59.224116 -40.601979)
			(xy 59.223656 -40.611044) (xy 59.221482 -40.634774) (xy 59.210829 -40.681218) (xy 59.193213 -40.725492)
			(xy 59.169048 -40.76656) (xy 59.154314 -40.785288) (xy 59.154314 -41.172892) (xy 59.161511 -41.183569)
			(xy 59.174477 -41.205819) (xy 59.180222 -41.217342) (xy 59.192998 -41.241832) (xy 59.211105 -41.294012)
			(xy 59.220287 -41.348476) (xy 59.220862 -41.376092) (xy 59.220365 -41.402079) (xy 59.360056 -41.402079)
			(xy 59.360056 -41.350105) (xy 59.368186 -41.29877) (xy 59.384247 -41.24934) (xy 59.407843 -41.20303)
			(xy 59.438393 -41.160982) (xy 59.475144 -41.124231) (xy 59.517192 -41.093681) (xy 59.563502 -41.070085)
			(xy 59.612932 -41.054024) (xy 59.664267 -41.045894) (xy 59.716241 -41.045894) (xy 59.767576 -41.054024)
			(xy 59.817006 -41.070085) (xy 59.863316 -41.093681) (xy 59.905364 -41.124231) (xy 59.942115 -41.160982)
			(xy 59.972665 -41.20303) (xy 59.996261 -41.24934) (xy 60.012322 -41.29877) (xy 60.020452 -41.350105)
			(xy 60.020962 -41.376092) (xy 60.020452 -41.402079) (xy 60.012322 -41.453414) (xy 59.996261 -41.502844)
			(xy 59.972665 -41.549154) (xy 59.942115 -41.591202) (xy 59.905364 -41.627953) (xy 59.863316 -41.658503)
			(xy 59.817006 -41.682099) (xy 59.767576 -41.69816) (xy 59.716241 -41.70629) (xy 59.664267 -41.70629)
			(xy 59.612932 -41.69816) (xy 59.563502 -41.682099) (xy 59.517192 -41.658503) (xy 59.475144 -41.627953)
			(xy 59.438393 -41.591202) (xy 59.407843 -41.549154) (xy 59.384247 -41.502844) (xy 59.368186 -41.453414)
			(xy 59.360056 -41.402079) (xy 59.220365 -41.402079) (xy 59.220351 -41.402785) (xy 59.211771 -41.455477)
			(xy 59.194832 -41.506105) (xy 59.169974 -41.553351) (xy 59.154314 -41.574974) (xy 59.154314 -41.977056)
			(xy 59.169967 -41.998682) (xy 59.194819 -42.045926) (xy 59.211753 -42.096551) (xy 59.220329 -42.149239)
			(xy 59.220324 -42.201925) (xy 59.360056 -42.201925) (xy 59.360056 -42.149951) (xy 59.368186 -42.098616)
			(xy 59.384247 -42.049186) (xy 59.407843 -42.002876) (xy 59.438393 -41.960828) (xy 59.475144 -41.924077)
			(xy 59.517192 -41.893527) (xy 59.563502 -41.869931) (xy 59.612932 -41.85387) (xy 59.664267 -41.84574)
			(xy 59.716241 -41.84574) (xy 59.767576 -41.85387) (xy 59.817006 -41.869931) (xy 59.863316 -41.893527)
			(xy 59.905364 -41.924077) (xy 59.942115 -41.960828) (xy 59.972665 -42.002876) (xy 59.996261 -42.049186)
			(xy 60.012322 -42.098616) (xy 60.020452 -42.149951) (xy 60.020962 -42.175938) (xy 60.020452 -42.201925)
			(xy 60.012322 -42.25326) (xy 59.996261 -42.30269) (xy 59.972665 -42.349) (xy 59.942115 -42.391048)
			(xy 59.905364 -42.427799) (xy 59.863316 -42.458349) (xy 59.817006 -42.481945) (xy 59.767576 -42.498006)
			(xy 59.716241 -42.506136) (xy 59.664267 -42.506136) (xy 59.612932 -42.498006) (xy 59.563502 -42.481945)
			(xy 59.517192 -42.458349) (xy 59.475144 -42.427799) (xy 59.438393 -42.391048) (xy 59.407843 -42.349)
			(xy 59.384247 -42.30269) (xy 59.368186 -42.25326) (xy 59.360056 -42.201925) (xy 59.220324 -42.201925)
			(xy 59.220324 -42.202621) (xy 59.211738 -42.255308) (xy 59.194795 -42.30593) (xy 59.169934 -42.35317)
			(xy 59.154314 -42.37482) (xy 59.154314 -42.777156) (xy 59.169967 -42.798782) (xy 59.194819 -42.846026)
			(xy 59.211753 -42.896651) (xy 59.220329 -42.949339) (xy 59.220324 -43.002025) (xy 59.360056 -43.002025)
			(xy 59.360056 -42.950051) (xy 59.368186 -42.898716) (xy 59.384247 -42.849286) (xy 59.407843 -42.802976)
			(xy 59.438393 -42.760928) (xy 59.475144 -42.724177) (xy 59.517192 -42.693627) (xy 59.563502 -42.670031)
			(xy 59.612932 -42.65397) (xy 59.664267 -42.64584) (xy 59.716241 -42.64584) (xy 59.767576 -42.65397)
			(xy 59.817006 -42.670031) (xy 59.863316 -42.693627) (xy 59.905364 -42.724177) (xy 59.942115 -42.760928)
			(xy 59.972665 -42.802976) (xy 59.996261 -42.849286) (xy 60.012322 -42.898716) (xy 60.020452 -42.950051)
			(xy 60.020962 -42.976038) (xy 60.020452 -43.002025) (xy 60.012322 -43.05336) (xy 59.996261 -43.10279)
			(xy 59.972665 -43.1491) (xy 59.942115 -43.191148) (xy 59.905364 -43.227899) (xy 59.863316 -43.258449)
			(xy 59.817006 -43.282045) (xy 59.767576 -43.298106) (xy 59.716241 -43.306236) (xy 59.664267 -43.306236)
			(xy 59.612932 -43.298106) (xy 59.563502 -43.282045) (xy 59.517192 -43.258449) (xy 59.475144 -43.227899)
			(xy 59.438393 -43.191148) (xy 59.407843 -43.1491) (xy 59.384247 -43.10279) (xy 59.368186 -43.05336)
			(xy 59.360056 -43.002025) (xy 59.220324 -43.002025) (xy 59.220324 -43.002721) (xy 59.211738 -43.055408)
			(xy 59.194795 -43.10603) (xy 59.169934 -43.15327) (xy 59.154314 -43.17492) (xy 59.154314 -44.601971)
			(xy 59.360056 -44.601971) (xy 59.360056 -44.549997) (xy 59.368186 -44.498662) (xy 59.384247 -44.449232)
			(xy 59.407843 -44.402922) (xy 59.438393 -44.360874) (xy 59.475144 -44.324123) (xy 59.517192 -44.293573)
			(xy 59.563502 -44.269977) (xy 59.612932 -44.253916) (xy 59.664267 -44.245786) (xy 59.716241 -44.245786)
			(xy 59.767576 -44.253916) (xy 59.817006 -44.269977) (xy 59.863316 -44.293573) (xy 59.905364 -44.324123)
			(xy 59.942115 -44.360874) (xy 59.972665 -44.402922) (xy 59.996261 -44.449232) (xy 60.012322 -44.498662)
			(xy 60.020452 -44.549997) (xy 60.020962 -44.575984) (xy 60.020452 -44.601971) (xy 60.012322 -44.653306)
			(xy 59.996261 -44.702736) (xy 59.972665 -44.749046) (xy 59.942115 -44.791094) (xy 59.905364 -44.827845)
			(xy 59.863316 -44.858395) (xy 59.817006 -44.881991) (xy 59.767576 -44.898052) (xy 59.716241 -44.906182)
			(xy 59.664267 -44.906182) (xy 59.612932 -44.898052) (xy 59.563502 -44.881991) (xy 59.517192 -44.858395)
			(xy 59.475144 -44.827845) (xy 59.438393 -44.791094) (xy 59.407843 -44.749046) (xy 59.384247 -44.702736)
			(xy 59.368186 -44.653306) (xy 59.360056 -44.601971) (xy 59.154314 -44.601971) (xy 59.154314 -45.177202)
			(xy 59.169971 -45.198827) (xy 59.194831 -45.246072) (xy 59.211774 -45.296699) (xy 59.220358 -45.349391)
			(xy 59.220862 -45.376084) (xy 59.220407 -45.401052) (xy 59.220252 -45.402071) (xy 59.360056 -45.402071)
			(xy 59.360056 -45.350097) (xy 59.368186 -45.298762) (xy 59.384247 -45.249332) (xy 59.407843 -45.203022)
			(xy 59.438393 -45.160974) (xy 59.475144 -45.124223) (xy 59.517192 -45.093673) (xy 59.563502 -45.070077)
			(xy 59.612932 -45.054016) (xy 59.664267 -45.045886) (xy 59.716241 -45.045886) (xy 59.767576 -45.054016)
			(xy 59.817006 -45.070077) (xy 59.863316 -45.093673) (xy 59.905364 -45.124223) (xy 59.942115 -45.160974)
			(xy 59.972665 -45.203022) (xy 59.996261 -45.249332) (xy 60.012322 -45.298762) (xy 60.020452 -45.350097)
			(xy 60.020962 -45.376084) (xy 60.020452 -45.402071) (xy 60.012322 -45.453406) (xy 59.996261 -45.502836)
			(xy 59.972665 -45.549146) (xy 59.942115 -45.591194) (xy 59.905364 -45.627945) (xy 59.863316 -45.658495)
			(xy 59.817006 -45.682091) (xy 59.767576 -45.698152) (xy 59.716241 -45.706282) (xy 59.664267 -45.706282)
			(xy 59.612932 -45.698152) (xy 59.563502 -45.682091) (xy 59.517192 -45.658495) (xy 59.475144 -45.627945)
			(xy 59.438393 -45.591194) (xy 59.407843 -45.549146) (xy 59.384247 -45.502836) (xy 59.368186 -45.453406)
			(xy 59.360056 -45.402071) (xy 59.220252 -45.402071) (xy 59.212903 -45.45042) (xy 59.198064 -45.4981)
			(xy 59.176225 -45.543007) (xy 59.147885 -45.584121) (xy 59.113686 -45.620507) (xy 59.074406 -45.65134)
			(xy 59.030937 -45.675917) (xy 59.007756 -45.685202) (xy 58.997596 -45.689012) (xy 58.861452 -45.825156)
			(xy 58.858912 -45.825156) (xy 58.798968 -45.8851) (xy 57.88152 -45.8851) (xy 57.733692 -46.032928)
			(xy 57.733692 -47.487586) (xy 57.845706 -47.5996) (xy 59.280044 -47.5996)
		)
		(stroke
			(width 0)
			(type solid)
		)
		(fill yes)
		(layer "In2.Cu")
		(net "P1V8_BMC_USB2AV18")
	)
	(gr_poly
		(pts
			(xy 43.669458 -60.417202) (xy 43.74769 -60.417202) (xy 43.754548 -60.410344) (xy 48.32096 -60.410344)
			(xy 48.334988 -60.409892) (xy 48.361985 -60.402251) (xy 48.385889 -60.387562) (xy 48.404901 -60.366929)
			(xy 48.417591 -60.341906) (xy 48.423004 -60.314377) (xy 48.420731 -60.286412) (xy 48.410944 -60.260117)
			(xy 48.403002 -60.248546) (xy 48.386748 -60.225513) (xy 48.360953 -60.17539) (xy 48.34338 -60.121828)
			(xy 48.334467 -60.066165) (xy 48.333914 -60.03798) (xy 48.334412 -60.011331) (xy 48.342355 -59.958627)
			(xy 48.358065 -59.907697) (xy 48.381191 -59.859676) (xy 48.411215 -59.815639) (xy 48.447467 -59.776568)
			(xy 48.489138 -59.743337) (xy 48.535296 -59.716688) (xy 48.58491 -59.697216) (xy 48.636872 -59.685356)
			(xy 48.690022 -59.681373) (xy 48.743172 -59.685356) (xy 48.795134 -59.697216) (xy 48.844748 -59.716688)
			(xy 48.890906 -59.743337) (xy 48.932577 -59.776568) (xy 48.968829 -59.815639) (xy 48.998853 -59.859676)
			(xy 49.021979 -59.907697) (xy 49.037689 -59.958627) (xy 49.045632 -60.011331) (xy 49.04613 -60.03798)
			(xy 49.045627 -60.065038) (xy 49.037441 -60.11853) (xy 49.021253 -60.170167) (xy 48.997438 -60.21876)
			(xy 48.966543 -60.263189) (xy 48.92928 -60.302431) (xy 48.908208 -60.319412) (xy 48.88865 -60.334652)
			(xy 48.88865 -60.410344) (xy 49.000156 -60.410344) (xy 49.386236 -60.024518) (xy 49.386236 -59.398408)
			(xy 49.385654 -59.38277) (xy 49.376184 -59.352963) (xy 49.358156 -59.327405) (xy 49.333252 -59.308484)
			(xy 49.303798 -59.297965) (xy 49.288192 -59.296808) (xy 49.262829 -59.295445) (xy 49.212943 -59.285904)
			(xy 49.165102 -59.268847) (xy 49.120433 -59.244674) (xy 49.079986 -59.213953) (xy 49.044713 -59.177408)
			(xy 49.015445 -59.135899) (xy 48.992869 -59.090402) (xy 48.977516 -59.041987) (xy 48.969749 -58.991794)
			(xy 48.969749 -58.941003) (xy 48.977517 -58.89081) (xy 48.99287 -58.842395) (xy 49.015446 -58.796898)
			(xy 49.044715 -58.755389) (xy 49.079988 -58.718845) (xy 49.120435 -58.688125) (xy 49.165105 -58.663952)
			(xy 49.212946 -58.646895) (xy 49.262832 -58.637355) (xy 49.288192 -58.6359) (xy 49.303812 -58.63479)
			(xy 49.3333 -58.624297) (xy 49.358228 -58.605372) (xy 49.37626 -58.57979) (xy 49.385703 -58.54995)
			(xy 49.386236 -58.5343) (xy 49.386236 -57.798462) (xy 49.385662 -57.782819) (xy 49.376201 -57.752997)
			(xy 49.358175 -57.727426) (xy 49.333268 -57.708493) (xy 49.303805 -57.697967) (xy 49.288192 -57.696862)
			(xy 49.262822 -57.695499) (xy 49.212922 -57.685959) (xy 49.165068 -57.668901) (xy 49.120384 -57.644726)
			(xy 49.079923 -57.614003) (xy 49.044634 -57.577455) (xy 49.01535 -57.535941) (xy 48.992757 -57.490437)
			(xy 48.977387 -57.442014) (xy 48.969603 -57.39181) (xy 48.969168 -57.366408) (xy 48.969676 -57.349898)
			(xy 48.969951 -57.336113) (xy 48.963995 -57.309205) (xy 48.951052 -57.284873) (xy 48.932067 -57.264895)
			(xy 48.908427 -57.250728) (xy 48.881857 -57.243408) (xy 48.868076 -57.242964) (xy 48.079914 -57.242964)
			(xy 48.075088 -57.242964) (xy 48.063736 -57.243415) (xy 48.043102 -57.252853) (xy 48.028498 -57.270218)
			(xy 48.022735 -57.292164) (xy 48.024288 -57.303416) (xy 48.027135 -57.319008) (xy 48.030184 -57.350559)
			(xy 48.030384 -57.366408) (xy 48.029874 -57.392395) (xy 48.021744 -57.44373) (xy 48.005683 -57.49316)
			(xy 47.982087 -57.53947) (xy 47.951537 -57.581518) (xy 47.914786 -57.618269) (xy 47.872738 -57.648819)
			(xy 47.826428 -57.672415) (xy 47.776998 -57.688476) (xy 47.725663 -57.696606) (xy 47.673689 -57.696606)
			(xy 47.622354 -57.688476) (xy 47.572924 -57.672415) (xy 47.526614 -57.648819) (xy 47.484566 -57.618269)
			(xy 47.447815 -57.581518) (xy 47.417265 -57.53947) (xy 47.393669 -57.49316) (xy 47.377608 -57.44373)
			(xy 47.369478 -57.392395) (xy 47.368968 -57.366408) (xy 47.369602 -57.336061) (xy 47.380592 -57.276372)
			(xy 47.390812 -57.24779) (xy 47.394207 -57.237475) (xy 47.392889 -57.21582) (xy 47.382754 -57.196638)
			(xy 47.365607 -57.183347) (xy 47.344504 -57.178313) (xy 47.323205 -57.182435) (xy 47.314104 -57.188354)
			(xy 47.299135 -57.19862) (xy 47.267169 -57.215818) (xy 47.25035 -57.222644) (xy 47.241876 -57.226397)
			(xy 47.22817 -57.23885) (xy 47.219805 -57.255372) (xy 47.217881 -57.27379) (xy 47.21987 -57.282842)
			(xy 47.22487 -57.303371) (xy 47.230223 -57.345282) (xy 47.230538 -57.366408) (xy 47.230028 -57.392395)
			(xy 47.221898 -57.44373) (xy 47.205837 -57.49316) (xy 47.182241 -57.53947) (xy 47.151691 -57.581518)
			(xy 47.11494 -57.618269) (xy 47.072892 -57.648819) (xy 47.026582 -57.672415) (xy 46.977152 -57.688476)
			(xy 46.925817 -57.696606) (xy 46.873843 -57.696606) (xy 46.822508 -57.688476) (xy 46.773078 -57.672415)
			(xy 46.726768 -57.648819) (xy 46.68472 -57.618269) (xy 46.647969 -57.581518) (xy 46.617419 -57.53947)
			(xy 46.593823 -57.49316) (xy 46.577762 -57.44373) (xy 46.569632 -57.392395) (xy 46.569122 -57.366408)
			(xy 46.569321 -57.350559) (xy 46.572372 -57.319009) (xy 46.575218 -57.303416) (xy 46.57598 -57.298844)
			(xy 46.57598 -57.242964) (xy 46.42358 -57.242964) (xy 46.42358 -57.298844) (xy 46.424342 -57.303416)
			(xy 46.427188 -57.319008) (xy 46.430237 -57.350559) (xy 46.430438 -57.366408) (xy 46.429928 -57.392395)
			(xy 46.421798 -57.44373) (xy 46.405737 -57.49316) (xy 46.382141 -57.53947) (xy 46.351591 -57.581518)
			(xy 46.31484 -57.618269) (xy 46.272792 -57.648819) (xy 46.226482 -57.672415) (xy 46.177052 -57.688476)
			(xy 46.125717 -57.696606) (xy 46.073743 -57.696606) (xy 46.022408 -57.688476) (xy 45.972978 -57.672415)
			(xy 45.926668 -57.648819) (xy 45.88462 -57.618269) (xy 45.847869 -57.581518) (xy 45.817319 -57.53947)
			(xy 45.793723 -57.49316) (xy 45.777662 -57.44373) (xy 45.769532 -57.392395) (xy 45.769022 -57.366408)
			(xy 45.769221 -57.350559) (xy 45.772272 -57.319009) (xy 45.775118 -57.303416) (xy 45.77588 -57.298844)
			(xy 45.77588 -57.242964) (xy 45.623734 -57.242964) (xy 45.623734 -57.298844) (xy 45.624496 -57.303416)
			(xy 45.627343 -57.319008) (xy 45.630392 -57.350559) (xy 45.630592 -57.366408) (xy 45.630108 -57.392396)
			(xy 45.621976 -57.443733) (xy 45.605913 -57.493165) (xy 45.582314 -57.539476) (xy 45.551762 -57.581526)
			(xy 45.515007 -57.618277) (xy 45.472956 -57.648827) (xy 45.426643 -57.672422) (xy 45.37721 -57.688482)
			(xy 45.325872 -57.69661) (xy 45.299884 -57.697116) (xy 45.274131 -57.696623) (xy 45.223249 -57.688633)
			(xy 45.174221 -57.672849) (xy 45.128235 -57.649654) (xy 45.086401 -57.619607) (xy 45.067728 -57.601866)
			(xy 45.05798 -57.592865) (xy 45.034925 -57.579751) (xy 45.009271 -57.573018) (xy 44.982749 -57.57312)
			(xy 44.957147 -57.580051) (xy 44.934195 -57.593342) (xy 44.924472 -57.602374) (xy 44.73575 -57.791096)
			(xy 44.726666 -57.800778) (xy 44.713363 -57.823741) (xy 44.706428 -57.849358) (xy 44.70633 -57.875896)
			(xy 44.713076 -57.901563) (xy 44.726209 -57.924624) (xy 44.735242 -57.934352) (xy 44.752984 -57.953026)
			(xy 44.783043 -57.994853) (xy 44.806244 -58.040839) (xy 44.822025 -58.089869) (xy 44.830004 -58.140754)
			(xy 44.830492 -58.166508) (xy 44.829982 -58.192495) (xy 44.969686 -58.192495) (xy 44.969686 -58.140521)
			(xy 44.977816 -58.089186) (xy 44.993877 -58.039756) (xy 45.017473 -57.993446) (xy 45.048023 -57.951398)
			(xy 45.084774 -57.914647) (xy 45.126822 -57.884097) (xy 45.173132 -57.860501) (xy 45.222562 -57.84444)
			(xy 45.273897 -57.83631) (xy 45.325871 -57.83631) (xy 45.377206 -57.84444) (xy 45.426636 -57.860501)
			(xy 45.472946 -57.884097) (xy 45.514994 -57.914647) (xy 45.551745 -57.951398) (xy 45.582295 -57.993446)
			(xy 45.605891 -58.039756) (xy 45.621952 -58.089186) (xy 45.630082 -58.140521) (xy 45.630592 -58.166508)
			(xy 45.630082 -58.192495) (xy 45.769532 -58.192495) (xy 45.769532 -58.140521) (xy 45.777662 -58.089186)
			(xy 45.793723 -58.039756) (xy 45.817319 -57.993446) (xy 45.847869 -57.951398) (xy 45.88462 -57.914647)
			(xy 45.926668 -57.884097) (xy 45.972978 -57.860501) (xy 46.022408 -57.84444) (xy 46.073743 -57.83631)
			(xy 46.125717 -57.83631) (xy 46.177052 -57.84444) (xy 46.226482 -57.860501) (xy 46.272792 -57.884097)
			(xy 46.31484 -57.914647) (xy 46.351591 -57.951398) (xy 46.382141 -57.993446) (xy 46.405737 -58.039756)
			(xy 46.421798 -58.089186) (xy 46.429928 -58.140521) (xy 46.430438 -58.166508) (xy 46.429928 -58.192495)
			(xy 46.569632 -58.192495) (xy 46.569632 -58.140521) (xy 46.577762 -58.089186) (xy 46.593823 -58.039756)
			(xy 46.617419 -57.993446) (xy 46.647969 -57.951398) (xy 46.68472 -57.914647) (xy 46.726768 -57.884097)
			(xy 46.773078 -57.860501) (xy 46.822508 -57.84444) (xy 46.873843 -57.83631) (xy 46.925817 -57.83631)
			(xy 46.977152 -57.84444) (xy 47.026582 -57.860501) (xy 47.072892 -57.884097) (xy 47.11494 -57.914647)
			(xy 47.151691 -57.951398) (xy 47.182241 -57.993446) (xy 47.205837 -58.039756) (xy 47.221898 -58.089186)
			(xy 47.230028 -58.140521) (xy 47.230538 -58.166508) (xy 47.230028 -58.192495) (xy 47.369478 -58.192495)
			(xy 47.369478 -58.140521) (xy 47.377608 -58.089186) (xy 47.393669 -58.039756) (xy 47.417265 -57.993446)
			(xy 47.447815 -57.951398) (xy 47.484566 -57.914647) (xy 47.526614 -57.884097) (xy 47.572924 -57.860501)
			(xy 47.622354 -57.84444) (xy 47.673689 -57.83631) (xy 47.725663 -57.83631) (xy 47.776998 -57.84444)
			(xy 47.826428 -57.860501) (xy 47.872738 -57.884097) (xy 47.914786 -57.914647) (xy 47.951537 -57.951398)
			(xy 47.982087 -57.993446) (xy 48.005683 -58.039756) (xy 48.021744 -58.089186) (xy 48.029874 -58.140521)
			(xy 48.030384 -58.166508) (xy 48.029874 -58.192495) (xy 48.021744 -58.24383) (xy 48.005683 -58.29326)
			(xy 47.982087 -58.33957) (xy 47.951537 -58.381618) (xy 47.914786 -58.418369) (xy 47.872738 -58.448919)
			(xy 47.826428 -58.472515) (xy 47.776998 -58.488576) (xy 47.725663 -58.496706) (xy 47.673689 -58.496706)
			(xy 47.622354 -58.488576) (xy 47.572924 -58.472515) (xy 47.526614 -58.448919) (xy 47.484566 -58.418369)
			(xy 47.447815 -58.381618) (xy 47.417265 -58.33957) (xy 47.393669 -58.29326) (xy 47.377608 -58.24383)
			(xy 47.369478 -58.192495) (xy 47.230028 -58.192495) (xy 47.221898 -58.24383) (xy 47.205837 -58.29326)
			(xy 47.182241 -58.33957) (xy 47.151691 -58.381618) (xy 47.11494 -58.418369) (xy 47.072892 -58.448919)
			(xy 47.026582 -58.472515) (xy 46.977152 -58.488576) (xy 46.925817 -58.496706) (xy 46.873843 -58.496706)
			(xy 46.822508 -58.488576) (xy 46.773078 -58.472515) (xy 46.726768 -58.448919) (xy 46.68472 -58.418369)
			(xy 46.647969 -58.381618) (xy 46.617419 -58.33957) (xy 46.593823 -58.29326) (xy 46.577762 -58.24383)
			(xy 46.569632 -58.192495) (xy 46.429928 -58.192495) (xy 46.421798 -58.24383) (xy 46.405737 -58.29326)
			(xy 46.382141 -58.33957) (xy 46.351591 -58.381618) (xy 46.31484 -58.418369) (xy 46.272792 -58.448919)
			(xy 46.226482 -58.472515) (xy 46.177052 -58.488576) (xy 46.125717 -58.496706) (xy 46.073743 -58.496706)
			(xy 46.022408 -58.488576) (xy 45.972978 -58.472515) (xy 45.926668 -58.448919) (xy 45.88462 -58.418369)
			(xy 45.847869 -58.381618) (xy 45.817319 -58.33957) (xy 45.793723 -58.29326) (xy 45.777662 -58.24383)
			(xy 45.769532 -58.192495) (xy 45.630082 -58.192495) (xy 45.621952 -58.24383) (xy 45.605891 -58.29326)
			(xy 45.582295 -58.33957) (xy 45.551745 -58.381618) (xy 45.514994 -58.418369) (xy 45.472946 -58.448919)
			(xy 45.426636 -58.472515) (xy 45.377206 -58.488576) (xy 45.325871 -58.496706) (xy 45.273897 -58.496706)
			(xy 45.222562 -58.488576) (xy 45.173132 -58.472515) (xy 45.126822 -58.448919) (xy 45.084774 -58.418369)
			(xy 45.048023 -58.381618) (xy 45.017473 -58.33957) (xy 44.993877 -58.29326) (xy 44.977816 -58.24383)
			(xy 44.969686 -58.192495) (xy 44.829982 -58.192495) (xy 44.821852 -58.24383) (xy 44.805791 -58.29326)
			(xy 44.782195 -58.33957) (xy 44.751645 -58.381618) (xy 44.714894 -58.418369) (xy 44.672846 -58.448919)
			(xy 44.626536 -58.472515) (xy 44.577106 -58.488576) (xy 44.525771 -58.496706) (xy 44.473797 -58.496706)
			(xy 44.422462 -58.488576) (xy 44.373032 -58.472515) (xy 44.326722 -58.448919) (xy 44.284674 -58.418369)
			(xy 44.247923 -58.381618) (xy 44.217373 -58.33957) (xy 44.193777 -58.29326) (xy 44.177716 -58.24383)
			(xy 44.169586 -58.192495) (xy 44.169076 -58.166508) (xy 44.170092 -58.140092) (xy 44.170779 -58.126089)
			(xy 44.165356 -58.098592) (xy 44.152657 -58.073608) (xy 44.13364 -58.053021) (xy 44.10974 -58.038384)
			(xy 44.08276 -58.030801) (xy 44.068746 -58.030364) (xy 42.820082 -58.030364) (xy 41.96715 -58.88355)
			(xy 41.95037 -58.899694) (xy 41.912679 -58.927033) (xy 41.871174 -58.948137) (xy 41.826878 -58.962486)
			(xy 41.780882 -58.969726) (xy 41.7576 -58.970164) (xy 41.3258 -58.970164) (xy 41.304351 -58.969818)
			(xy 41.261893 -58.963693) (xy 41.241218 -58.957972) (xy 41.231593 -58.955591) (xy 41.211881 -58.957542)
			(xy 41.194375 -58.966811) (xy 41.18168 -58.982016) (xy 41.178402 -58.992341) (xy 46.569632 -58.992341)
			(xy 46.569632 -58.940367) (xy 46.577762 -58.889032) (xy 46.593823 -58.839602) (xy 46.617419 -58.793292)
			(xy 46.647969 -58.751244) (xy 46.68472 -58.714493) (xy 46.726768 -58.683943) (xy 46.773078 -58.660347)
			(xy 46.822508 -58.644286) (xy 46.873843 -58.636156) (xy 46.925817 -58.636156) (xy 46.977152 -58.644286)
			(xy 47.026582 -58.660347) (xy 47.072892 -58.683943) (xy 47.11494 -58.714493) (xy 47.151691 -58.751244)
			(xy 47.182241 -58.793292) (xy 47.205837 -58.839602) (xy 47.221898 -58.889032) (xy 47.230028 -58.940367)
			(xy 47.230538 -58.966354) (xy 47.230028 -58.992341) (xy 47.221898 -59.043676) (xy 47.205837 -59.093106)
			(xy 47.182241 -59.139416) (xy 47.151691 -59.181464) (xy 47.11494 -59.218215) (xy 47.072892 -59.248765)
			(xy 47.026582 -59.272361) (xy 46.977152 -59.288422) (xy 46.925817 -59.296552) (xy 46.873843 -59.296552)
			(xy 46.822508 -59.288422) (xy 46.773078 -59.272361) (xy 46.726768 -59.248765) (xy 46.68472 -59.218215)
			(xy 46.647969 -59.181464) (xy 46.617419 -59.139416) (xy 46.593823 -59.093106) (xy 46.577762 -59.043676)
			(xy 46.569632 -58.992341) (xy 41.178402 -58.992341) (xy 41.175686 -59.000896) (xy 41.177286 -59.02064)
			(xy 41.18624 -59.038308) (xy 41.193466 -59.045094) (xy 41.213922 -59.063299) (xy 41.249919 -59.104562)
			(xy 41.27965 -59.150547) (xy 41.302503 -59.200309) (xy 41.318009 -59.252826) (xy 41.32585 -59.307021)
			(xy 41.326308 -59.3344) (xy 41.325822 -59.361651) (xy 41.318066 -59.415599) (xy 41.302711 -59.467894)
			(xy 41.280069 -59.517471) (xy 41.250603 -59.563321) (xy 41.214912 -59.604512) (xy 41.173721 -59.640203)
			(xy 41.127871 -59.669669) (xy 41.078294 -59.692311) (xy 41.025999 -59.707666) (xy 40.972051 -59.715422)
			(xy 40.917549 -59.715422) (xy 40.863601 -59.707666) (xy 40.811306 -59.692311) (xy 40.761729 -59.669669)
			(xy 40.715879 -59.640203) (xy 40.674688 -59.604512) (xy 40.638997 -59.563321) (xy 40.609531 -59.517471)
			(xy 40.586889 -59.467894) (xy 40.571534 -59.415599) (xy 40.563778 -59.361651) (xy 40.563778 -59.307149)
			(xy 40.571534 -59.253201) (xy 40.586889 -59.200906) (xy 40.609531 -59.151329) (xy 40.638997 -59.105479)
			(xy 40.674688 -59.064288) (xy 40.715879 -59.028597) (xy 40.761729 -58.999131) (xy 40.811306 -58.976489)
			(xy 40.863601 -58.961134) (xy 40.917549 -58.953378) (xy 40.9448 -58.952892) (xy 40.976916 -58.953533)
			(xy 41.040246 -58.964262) (xy 41.070784 -58.974228) (xy 41.080284 -58.977069) (xy 41.100068 -58.976053)
			(xy 41.117984 -58.967603) (xy 41.131352 -58.952983) (xy 41.138168 -58.934384) (xy 41.137413 -58.914589)
			(xy 41.1292 -58.896562) (xy 41.122346 -58.889392) (xy 41.11625 -58.88355) (xy 40.86225 -58.62955)
			(xy 40.846106 -58.61277) (xy 40.818767 -58.575079) (xy 40.797663 -58.533574) (xy 40.783314 -58.489278)
			(xy 40.776074 -58.443282) (xy 40.775636 -58.42) (xy 40.775636 -58.174636) (xy 40.55237 -57.95137)
			(xy 37.74567 -57.95137) (xy 37.44722 -58.24982) (xy 36.707318 -58.24982) (xy 36.693532 -58.250275)
			(xy 36.666965 -58.257651) (xy 36.643342 -58.27187) (xy 36.624387 -58.291892) (xy 36.611483 -58.316259)
			(xy 36.605573 -58.34319) (xy 36.607088 -58.37072) (xy 36.611052 -58.383932) (xy 36.620226 -58.412274)
			(xy 36.633094 -58.470441) (xy 36.639591 -58.529659) (xy 36.640008 -58.559446) (xy 36.63954 -58.591452)
			(xy 36.632107 -58.655031) (xy 36.617345 -58.717318) (xy 36.595455 -58.777471) (xy 36.566732 -58.834678)
			(xy 36.531564 -58.888164) (xy 36.490428 -58.937209) (xy 36.443877 -58.981148) (xy 36.392543 -59.019388)
			(xy 36.337117 -59.051412) (xy 36.278349 -59.076789) (xy 36.217034 -59.095174) (xy 36.185602 -59.101228)
			(xy 36.153679 -59.119394) (xy 36.086046 -59.148042) (xy 36.015207 -59.167454) (xy 35.942418 -59.177287)
			(xy 35.905694 -59.177936) (xy 35.715956 -59.177936) (xy 35.618928 -59.274964) (xy 35.59678 -59.296481)
			(xy 35.548485 -59.334964) (xy 35.496187 -59.367799) (xy 35.440541 -59.394574) (xy 35.382249 -59.414953)
			(xy 35.322041 -59.428679) (xy 35.260676 -59.435579) (xy 35.2298 -59.436) (xy 32.840676 -59.436) (xy 32.840676 -60.272676)
			(xy 33.02 -60.452) (xy 34.807144 -60.452) (xy 34.81578 -60.448698) (xy 34.840956 -60.439806) (xy 34.893479 -60.430228)
			(xy 34.920174 -60.429648) (xy 37.289232 -60.429648) (xy 37.98443 -59.73445) (xy 38.00121 -59.718305)
			(xy 38.0389 -59.690963) (xy 38.080405 -59.669856) (xy 38.124701 -59.655504) (xy 38.170698 -59.648261)
			(xy 38.19398 -59.647836) (xy 38.503098 -59.647836) (xy 38.50767 -59.601862) (xy 38.51092 -59.573937)
			(xy 38.524574 -59.519402) (xy 38.546085 -59.467462) (xy 38.574986 -59.419242) (xy 38.610651 -59.375786)
			(xy 38.652308 -59.338035) (xy 38.699055 -59.306807) (xy 38.749879 -59.282777) (xy 38.803679 -59.266468)
			(xy 38.859291 -59.258231) (xy 38.8874 -59.257692) (xy 38.916139 -59.258213) (xy 38.972967 -59.266835)
			(xy 39.027858 -59.283885) (xy 39.079571 -59.308977) (xy 39.126934 -59.341542) (xy 39.148258 -59.360816)
			(xy 39.158308 -59.369709) (xy 39.181965 -59.38236) (xy 39.208102 -59.388402) (xy 39.234911 -59.387418)
			(xy 39.260535 -59.379477) (xy 39.283201 -59.365127) (xy 39.29253 -59.355482) (xy 39.310653 -59.33642)
			(xy 39.351234 -59.302962) (xy 39.396031 -59.275401) (xy 39.444193 -59.254263) (xy 39.494804 -59.239949)
			(xy 39.546902 -59.23273) (xy 39.5732 -59.232292) (xy 39.600451 -59.232778) (xy 39.654399 -59.240534)
			(xy 39.706694 -59.255889) (xy 39.756271 -59.278531) (xy 39.802121 -59.307997) (xy 39.843312 -59.343688)
			(xy 39.879003 -59.384879) (xy 39.908469 -59.430729) (xy 39.931111 -59.480306) (xy 39.946466 -59.532601)
			(xy 39.954222 -59.586549) (xy 39.954222 -59.641051) (xy 39.946466 -59.694999) (xy 39.931111 -59.747294)
			(xy 39.908469 -59.796871) (xy 39.879003 -59.842721) (xy 39.843312 -59.883912) (xy 39.802121 -59.919603)
			(xy 39.756271 -59.949069) (xy 39.711754 -59.9694) (xy 41.654982 -59.9694) (xy 41.659053 -59.913778)
			(xy 41.671179 -59.859341) (xy 41.691102 -59.80725) (xy 41.718398 -59.758615) (xy 41.752484 -59.714472)
			(xy 41.792633 -59.675763) (xy 41.837991 -59.643312) (xy 41.887591 -59.617811) (xy 41.940375 -59.599804)
			(xy 41.995218 -59.589674) (xy 42.050952 -59.587637) (xy 42.106389 -59.593737) (xy 42.160346 -59.607843)
			(xy 42.178137 -59.615403) (xy 43.885868 -59.615403) (xy 43.885868 -59.563429) (xy 43.893998 -59.512094)
			(xy 43.910059 -59.462664) (xy 43.933655 -59.416354) (xy 43.964205 -59.374306) (xy 44.000956 -59.337555)
			(xy 44.043004 -59.307005) (xy 44.089314 -59.283409) (xy 44.138744 -59.267348) (xy 44.190079 -59.259218)
			(xy 44.242053 -59.259218) (xy 44.293388 -59.267348) (xy 44.342818 -59.283409) (xy 44.389128 -59.307005)
			(xy 44.431176 -59.337555) (xy 44.467927 -59.374306) (xy 44.498477 -59.416354) (xy 44.522073 -59.462664)
			(xy 44.538134 -59.512094) (xy 44.546264 -59.563429) (xy 44.546774 -59.589416) (xy 44.546264 -59.615403)
			(xy 44.538134 -59.666738) (xy 44.522073 -59.716168) (xy 44.498477 -59.762478) (xy 44.467927 -59.804526)
			(xy 44.431176 -59.841277) (xy 44.389128 -59.871827) (xy 44.342818 -59.895423) (xy 44.293388 -59.911484)
			(xy 44.242053 -59.919614) (xy 44.190079 -59.919614) (xy 44.138744 -59.911484) (xy 44.089314 -59.895423)
			(xy 44.043004 -59.871827) (xy 44.000956 -59.841277) (xy 43.964205 -59.804526) (xy 43.933655 -59.762478)
			(xy 43.910059 -59.716168) (xy 43.893998 -59.666738) (xy 43.885868 -59.615403) (xy 42.178137 -59.615403)
			(xy 42.211675 -59.629655) (xy 42.259281 -59.658709) (xy 42.302149 -59.694384) (xy 42.339366 -59.735921)
			(xy 42.370139 -59.782434) (xy 42.393811 -59.832931) (xy 42.409879 -59.886338) (xy 42.417999 -59.941514)
			(xy 42.418508 -59.9694) (xy 42.417999 -59.997286) (xy 42.409879 -60.052462) (xy 42.393811 -60.105869)
			(xy 42.370139 -60.156366) (xy 42.339366 -60.202879) (xy 42.302149 -60.244416) (xy 42.259281 -60.280091)
			(xy 42.211675 -60.309145) (xy 42.160346 -60.330957) (xy 42.106389 -60.345063) (xy 42.050952 -60.351163)
			(xy 41.995218 -60.349126) (xy 41.940375 -60.338996) (xy 41.887591 -60.320989) (xy 41.837991 -60.295488)
			(xy 41.792633 -60.263037) (xy 41.752484 -60.224328) (xy 41.718398 -60.180185) (xy 41.691102 -60.13155)
			(xy 41.671179 -60.079459) (xy 41.659053 -60.025022) (xy 41.654982 -59.9694) (xy 39.711754 -59.9694)
			(xy 39.706694 -59.971711) (xy 39.654399 -59.987066) (xy 39.600451 -59.994822) (xy 39.5732 -59.995308)
			(xy 39.544461 -59.994787) (xy 39.487633 -59.986165) (xy 39.432742 -59.969115) (xy 39.381029 -59.944023)
			(xy 39.333666 -59.911458) (xy 39.312342 -59.892184) (xy 39.302292 -59.883291) (xy 39.278635 -59.87064)
			(xy 39.252498 -59.864598) (xy 39.225689 -59.865582) (xy 39.200065 -59.873523) (xy 39.177399 -59.887873)
			(xy 39.16807 -59.897518) (xy 39.155748 -59.9106) (xy 39.129034 -59.934644) (xy 39.11473 -59.945524)
			(xy 39.103312 -59.954589) (xy 39.085765 -59.977858) (xy 39.07549 -60.00513) (xy 39.073321 -60.034192)
			(xy 39.079433 -60.062688) (xy 39.093331 -60.088304) (xy 39.1033 -60.09894) (xy 39.12235 -60.11799)
			(xy 39.138498 -60.134769) (xy 39.165845 -60.172458) (xy 39.186957 -60.213962) (xy 39.201315 -60.258259)
			(xy 39.208565 -60.304257) (xy 39.208964 -60.32754) (xy 39.208964 -60.452) (xy 39.806118 -60.452)
			(xy 39.932102 -60.577984) (xy 39.951406 -60.579254) (xy 39.980254 -60.581509) (xy 40.036834 -60.593629)
			(xy 40.090936 -60.61415) (xy 40.141321 -60.642601) (xy 40.186835 -60.67833) (xy 40.226435 -60.72052)
			(xy 40.259214 -60.768203) (xy 40.28442 -60.820287) (xy 40.301477 -60.875579) (xy 40.306244 -60.90412)
			(xy 40.308784 -60.920884) (xy 40.876982 -61.489082) (xy 42.597578 -61.489082)
		)
		(stroke
			(width 0)
			(type solid)
		)
		(fill yes)
		(layer "In2.Cu")
		(net "P12V_SENSOR")
	)
	(gr_poly
		(pts
			(xy 52.987956 -54.280308) (xy 52.980336 -54.25186) (xy 52.975086 -54.230917) (xy 52.969479 -54.188105)
			(xy 52.96916 -54.166516) (xy 52.969668 -54.140527) (xy 52.977797 -54.089189) (xy 52.993856 -54.039754)
			(xy 53.01745 -53.99344) (xy 53.047999 -53.951387) (xy 53.08475 -53.914631) (xy 53.126799 -53.884075)
			(xy 53.17311 -53.860474) (xy 53.222542 -53.844408) (xy 53.273879 -53.836272) (xy 53.299868 -53.835808)
			(xy 53.31044 -53.835916) (xy 53.331538 -53.837314) (xy 53.342032 -53.838602) (xy 53.345334 -53.838856)
			(xy 53.399436 -53.838856) (xy 53.399436 -53.694076) (xy 53.345334 -53.694076) (xy 53.342032 -53.69433)
			(xy 53.331538 -53.695619) (xy 53.31044 -53.697016) (xy 53.299868 -53.697124) (xy 53.273881 -53.696612)
			(xy 53.222548 -53.688477) (xy 53.173119 -53.672413) (xy 53.126812 -53.648814) (xy 53.084766 -53.618262)
			(xy 53.048017 -53.581509) (xy 53.017469 -53.539461) (xy 52.993875 -53.493151) (xy 52.977815 -53.443721)
			(xy 52.969685 -53.392387) (xy 52.969685 -53.340413) (xy 52.977815 -53.289079) (xy 52.993875 -53.239649)
			(xy 53.017469 -53.193339) (xy 53.048017 -53.151291) (xy 53.084766 -53.114538) (xy 53.126812 -53.083986)
			(xy 53.173119 -53.060388) (xy 53.222548 -53.044323) (xy 53.273881 -53.036188) (xy 53.299868 -53.035708)
			(xy 53.31044 -53.035816) (xy 53.331538 -53.037214) (xy 53.342032 -53.038502) (xy 53.345334 -53.038756)
			(xy 53.399436 -53.038756) (xy 53.399436 -52.89423) (xy 53.345334 -52.89423) (xy 53.342032 -52.894484)
			(xy 53.331538 -52.895773) (xy 53.31044 -52.897171) (xy 53.299868 -52.897278) (xy 53.273883 -52.896766)
			(xy 53.222554 -52.888631) (xy 53.17313 -52.872567) (xy 53.126827 -52.848969) (xy 53.084786 -52.818418)
			(xy 53.048041 -52.781667) (xy 53.017498 -52.73962) (xy 52.993909 -52.693313) (xy 52.977854 -52.643885)
			(xy 52.969729 -52.592555) (xy 52.96916 -52.56657) (xy 52.969666 -52.54066) (xy 52.977752 -52.489473)
			(xy 52.993723 -52.440175) (xy 53.017187 -52.39397) (xy 53.04757 -52.351991) (xy 53.084129 -52.315263)
			(xy 53.125968 -52.284687) (xy 53.172063 -52.26101) (xy 53.221288 -52.244812) (xy 53.272436 -52.236489)
			(xy 53.298344 -52.235862) (xy 53.311613 -52.235362) (xy 53.337221 -52.228376) (xy 53.36016 -52.215019)
			(xy 53.378875 -52.196196) (xy 53.3921 -52.173182) (xy 53.398939 -52.147534) (xy 53.399436 -52.134262)
			(xy 53.399436 -51.398678) (xy 53.399005 -51.385402) (xy 53.39215 -51.359749) (xy 53.378912 -51.336732)
			(xy 53.360184 -51.317908) (xy 53.337235 -51.304551) (xy 53.311618 -51.297565) (xy 53.298344 -51.297078)
			(xy 53.272438 -51.296453) (xy 53.221293 -51.288129) (xy 53.172072 -51.27193) (xy 53.12598 -51.248252)
			(xy 53.084146 -51.217675) (xy 53.047593 -51.180946) (xy 53.017217 -51.138966) (xy 52.99376 -51.092761)
			(xy 52.977797 -51.043463) (xy 52.969719 -50.992279) (xy 52.96916 -50.96637) (xy 52.969672 -50.940383)
			(xy 52.977806 -50.889051) (xy 52.993869 -50.839622) (xy 53.017466 -50.793314) (xy 53.048016 -50.751268)
			(xy 53.084766 -50.714517) (xy 53.126813 -50.683967) (xy 53.17312 -50.66037) (xy 53.222549 -50.644306)
			(xy 53.273881 -50.636172) (xy 53.299868 -50.635662) (xy 53.31044 -50.63577) (xy 53.331538 -50.637168)
			(xy 53.342032 -50.638456) (xy 53.345334 -50.63871) (xy 53.399436 -50.63871) (xy 53.399436 -50.494184)
			(xy 53.345334 -50.494184) (xy 53.342032 -50.494438) (xy 53.331538 -50.495727) (xy 53.31044 -50.497124)
			(xy 53.299868 -50.497232) (xy 53.273882 -50.49672) (xy 53.22255 -50.488586) (xy 53.173122 -50.472522)
			(xy 53.126815 -50.448925) (xy 53.084769 -50.418375) (xy 53.04802 -50.381625) (xy 53.017471 -50.339578)
			(xy 52.993875 -50.293271) (xy 52.977812 -50.243842) (xy 52.969679 -50.19251) (xy 52.96916 -50.166524)
			(xy 52.969662 -50.140611) (xy 52.977742 -50.089418) (xy 52.993708 -50.040112) (xy 53.017169 -49.9939)
			(xy 53.047551 -49.951913) (xy 53.08411 -49.915179) (xy 53.125951 -49.884597) (xy 53.172051 -49.860915)
			(xy 53.22128 -49.844714) (xy 53.272433 -49.836389) (xy 53.298344 -49.835816) (xy 53.311616 -49.835316)
			(xy 53.33723 -49.828331) (xy 53.360175 -49.814976) (xy 53.378899 -49.796154) (xy 53.392135 -49.77314)
			(xy 53.398987 -49.74749) (xy 53.399436 -49.734216) (xy 53.399436 -47.408338) (xy 53.399012 -47.395056)
			(xy 53.392168 -47.369391) (xy 53.378933 -47.34636) (xy 53.360204 -47.327523) (xy 53.33725 -47.314157)
			(xy 53.311623 -47.307166) (xy 53.298344 -47.306738) (xy 53.272436 -47.306113) (xy 53.221287 -47.29779)
			(xy 53.172063 -47.281592) (xy 53.125967 -47.257915) (xy 53.084127 -47.227338) (xy 53.047569 -47.190611)
			(xy 53.017186 -47.148631) (xy 52.993722 -47.102426) (xy 52.977751 -47.053127) (xy 52.969664 -47.001941)
			(xy 52.96916 -46.97603) (xy 52.969667 -46.95004) (xy 52.977794 -46.8987) (xy 52.993852 -46.849264)
			(xy 53.017446 -46.802948) (xy 53.047994 -46.760893) (xy 53.084746 -46.724135) (xy 53.126795 -46.693578)
			(xy 53.173106 -46.669976) (xy 53.22254 -46.653908) (xy 53.273878 -46.645772) (xy 53.299868 -46.645322)
			(xy 53.31044 -46.64543) (xy 53.331538 -46.646828) (xy 53.342032 -46.648116) (xy 53.345334 -46.64837)
			(xy 53.399436 -46.64837) (xy 53.399436 -46.50359) (xy 53.345334 -46.50359) (xy 53.342032 -46.503844)
			(xy 53.331538 -46.505133) (xy 53.31044 -46.50653) (xy 53.299868 -46.506638) (xy 53.273882 -46.506126)
			(xy 53.222549 -46.497992) (xy 53.173121 -46.481928) (xy 53.126814 -46.458331) (xy 53.084768 -46.427781)
			(xy 53.048017 -46.391031) (xy 53.017468 -46.348984) (xy 52.993871 -46.302677) (xy 52.977808 -46.253249)
			(xy 52.969674 -46.201916) (xy 52.96916 -46.17593) (xy 52.969661 -46.150016) (xy 52.977741 -46.098823)
			(xy 52.993706 -46.049516) (xy 53.017167 -46.003304) (xy 53.047549 -45.961316) (xy 53.084108 -45.924581)
			(xy 53.12595 -45.893998) (xy 53.172049 -45.870316) (xy 53.221279 -45.854114) (xy 53.272433 -45.845789)
			(xy 53.298344 -45.845222) (xy 53.311616 -45.844722) (xy 53.337231 -45.837738) (xy 53.360177 -45.824382)
			(xy 53.378902 -45.805561) (xy 53.392139 -45.782547) (xy 53.398992 -45.756897) (xy 53.399436 -45.743622)
			(xy 53.399436 -44.316904) (xy 51.302412 -44.316904) (xy 51.288278 -44.317364) (xy 51.261094 -44.325118)
			(xy 51.237081 -44.340035) (xy 51.218083 -44.360968) (xy 51.20556 -44.386311) (xy 51.200472 -44.414118)
			(xy 51.20321 -44.442254) (xy 51.207924 -44.455588) (xy 51.218483 -44.484559) (xy 51.229858 -44.545156)
			(xy 51.23053 -44.575984) (xy 51.23002 -44.601971) (xy 51.22189 -44.653306) (xy 51.205829 -44.702736)
			(xy 51.182233 -44.749046) (xy 51.151683 -44.791094) (xy 51.114932 -44.827845) (xy 51.072884 -44.858395)
			(xy 51.026574 -44.881991) (xy 50.977144 -44.898052) (xy 50.925809 -44.906182) (xy 50.873835 -44.906182)
			(xy 50.8225 -44.898052) (xy 50.77307 -44.881991) (xy 50.72676 -44.858395) (xy 50.684712 -44.827845)
			(xy 50.647961 -44.791094) (xy 50.617411 -44.749046) (xy 50.593815 -44.702736) (xy 50.577754 -44.653306)
			(xy 50.569624 -44.601971) (xy 50.569114 -44.575984) (xy 50.569774 -44.545155) (xy 50.581153 -44.484557)
			(xy 50.59172 -44.455588) (xy 50.596449 -44.442263) (xy 50.599158 -44.414129) (xy 50.594053 -44.386329)
			(xy 50.581526 -44.360992) (xy 50.562536 -44.340058) (xy 50.538536 -44.32513) (xy 50.511364 -44.317349)
			(xy 50.497232 -44.316904) (xy 50.419254 -44.316904) (xy 50.408309 -44.317478) (xy 50.388432 -44.326662)
			(xy 50.37416 -44.343268) (xy 50.368068 -44.364299) (xy 50.371254 -44.385962) (xy 50.376836 -44.39539)
			(xy 50.389534 -44.415632) (xy 50.409594 -44.458998) (xy 50.423191 -44.504805) (xy 50.430041 -44.552093)
			(xy 50.43043 -44.575984) (xy 50.42992 -44.601971) (xy 50.42179 -44.653306) (xy 50.405729 -44.702736)
			(xy 50.382133 -44.749046) (xy 50.351583 -44.791094) (xy 50.314832 -44.827845) (xy 50.272784 -44.858395)
			(xy 50.226474 -44.881991) (xy 50.177044 -44.898052) (xy 50.125709 -44.906182) (xy 50.073735 -44.906182)
			(xy 50.0224 -44.898052) (xy 49.97297 -44.881991) (xy 49.92666 -44.858395) (xy 49.884612 -44.827845)
			(xy 49.847861 -44.791094) (xy 49.817311 -44.749046) (xy 49.793715 -44.702736) (xy 49.777654 -44.653306)
			(xy 49.769524 -44.601971) (xy 49.769014 -44.575984) (xy 49.76944 -44.552097) (xy 49.776317 -44.50482)
			(xy 49.789912 -44.45902) (xy 49.809943 -44.415648) (xy 49.822608 -44.39539) (xy 49.828134 -44.385925)
			(xy 49.831354 -44.364269) (xy 49.825281 -44.343233) (xy 49.811015 -44.326625) (xy 49.791135 -44.31745)
			(xy 49.78019 -44.316904) (xy 49.717198 -44.316904) (xy 49.344072 -44.69003) (xy 49.344072 -45.402071)
			(xy 49.769524 -45.402071) (xy 49.769524 -45.350097) (xy 49.777654 -45.298762) (xy 49.793715 -45.249332)
			(xy 49.817311 -45.203022) (xy 49.847861 -45.160974) (xy 49.884612 -45.124223) (xy 49.92666 -45.093673)
			(xy 49.97297 -45.070077) (xy 50.0224 -45.054016) (xy 50.073735 -45.045886) (xy 50.125709 -45.045886)
			(xy 50.177044 -45.054016) (xy 50.226474 -45.070077) (xy 50.272784 -45.093673) (xy 50.314832 -45.124223)
			(xy 50.351583 -45.160974) (xy 50.382133 -45.203022) (xy 50.405729 -45.249332) (xy 50.42179 -45.298762)
			(xy 50.42992 -45.350097) (xy 50.43043 -45.376084) (xy 50.42992 -45.402071) (xy 52.16957 -45.402071)
			(xy 52.16957 -45.350097) (xy 52.1777 -45.298762) (xy 52.193761 -45.249332) (xy 52.217357 -45.203022)
			(xy 52.247907 -45.160974) (xy 52.284658 -45.124223) (xy 52.326706 -45.093673) (xy 52.373016 -45.070077)
			(xy 52.422446 -45.054016) (xy 52.473781 -45.045886) (xy 52.525755 -45.045886) (xy 52.57709 -45.054016)
			(xy 52.62652 -45.070077) (xy 52.67283 -45.093673) (xy 52.714878 -45.124223) (xy 52.751629 -45.160974)
			(xy 52.782179 -45.203022) (xy 52.805775 -45.249332) (xy 52.821836 -45.298762) (xy 52.829966 -45.350097)
			(xy 52.830476 -45.376084) (xy 52.829966 -45.402071) (xy 52.821836 -45.453406) (xy 52.805775 -45.502836)
			(xy 52.782179 -45.549146) (xy 52.751629 -45.591194) (xy 52.714878 -45.627945) (xy 52.67283 -45.658495)
			(xy 52.62652 -45.682091) (xy 52.57709 -45.698152) (xy 52.525755 -45.706282) (xy 52.473781 -45.706282)
			(xy 52.422446 -45.698152) (xy 52.373016 -45.682091) (xy 52.326706 -45.658495) (xy 52.284658 -45.627945)
			(xy 52.247907 -45.591194) (xy 52.217357 -45.549146) (xy 52.193761 -45.502836) (xy 52.1777 -45.453406)
			(xy 52.16957 -45.402071) (xy 50.42992 -45.402071) (xy 50.42179 -45.453406) (xy 50.405729 -45.502836)
			(xy 50.382133 -45.549146) (xy 50.351583 -45.591194) (xy 50.314832 -45.627945) (xy 50.272784 -45.658495)
			(xy 50.226474 -45.682091) (xy 50.177044 -45.698152) (xy 50.125709 -45.706282) (xy 50.073735 -45.706282)
			(xy 50.0224 -45.698152) (xy 49.97297 -45.682091) (xy 49.92666 -45.658495) (xy 49.884612 -45.627945)
			(xy 49.847861 -45.591194) (xy 49.817311 -45.549146) (xy 49.793715 -45.502836) (xy 49.777654 -45.453406)
			(xy 49.769524 -45.402071) (xy 49.344072 -45.402071) (xy 49.344072 -46.201917) (xy 52.16957 -46.201917)
			(xy 52.16957 -46.149943) (xy 52.1777 -46.098608) (xy 52.193761 -46.049178) (xy 52.217357 -46.002868)
			(xy 52.247907 -45.96082) (xy 52.284658 -45.924069) (xy 52.326706 -45.893519) (xy 52.373016 -45.869923)
			(xy 52.422446 -45.853862) (xy 52.473781 -45.845732) (xy 52.525755 -45.845732) (xy 52.57709 -45.853862)
			(xy 52.62652 -45.869923) (xy 52.67283 -45.893519) (xy 52.714878 -45.924069) (xy 52.751629 -45.96082)
			(xy 52.782179 -46.002868) (xy 52.805775 -46.049178) (xy 52.821836 -46.098608) (xy 52.829966 -46.149943)
			(xy 52.830476 -46.17593) (xy 52.829966 -46.201917) (xy 52.821836 -46.253252) (xy 52.805775 -46.302682)
			(xy 52.782179 -46.348992) (xy 52.751629 -46.39104) (xy 52.714878 -46.427791) (xy 52.67283 -46.458341)
			(xy 52.62652 -46.481937) (xy 52.57709 -46.497998) (xy 52.525755 -46.506128) (xy 52.473781 -46.506128)
			(xy 52.422446 -46.497998) (xy 52.373016 -46.481937) (xy 52.326706 -46.458341) (xy 52.284658 -46.427791)
			(xy 52.247907 -46.39104) (xy 52.217357 -46.348992) (xy 52.193761 -46.302682) (xy 52.1777 -46.253252)
			(xy 52.16957 -46.201917) (xy 49.344072 -46.201917) (xy 49.344072 -47.002017) (xy 49.769524 -47.002017)
			(xy 49.769524 -46.950043) (xy 49.777654 -46.898708) (xy 49.793715 -46.849278) (xy 49.817311 -46.802968)
			(xy 49.847861 -46.76092) (xy 49.884612 -46.724169) (xy 49.92666 -46.693619) (xy 49.97297 -46.670023)
			(xy 50.0224 -46.653962) (xy 50.073735 -46.645832) (xy 50.125709 -46.645832) (xy 50.177044 -46.653962)
			(xy 50.226474 -46.670023) (xy 50.272784 -46.693619) (xy 50.314832 -46.724169) (xy 50.351583 -46.76092)
			(xy 50.382133 -46.802968) (xy 50.405729 -46.849278) (xy 50.42179 -46.898708) (xy 50.42992 -46.950043)
			(xy 50.43043 -46.97603) (xy 50.42992 -47.002017) (xy 50.42179 -47.053352) (xy 50.405729 -47.102782)
			(xy 50.382133 -47.149092) (xy 50.351583 -47.19114) (xy 50.314832 -47.227891) (xy 50.272784 -47.258441)
			(xy 50.226474 -47.282037) (xy 50.177044 -47.298098) (xy 50.125709 -47.306228) (xy 50.073735 -47.306228)
			(xy 50.0224 -47.298098) (xy 49.97297 -47.282037) (xy 49.92666 -47.258441) (xy 49.884612 -47.227891)
			(xy 49.847861 -47.19114) (xy 49.817311 -47.149092) (xy 49.793715 -47.102782) (xy 49.777654 -47.053352)
			(xy 49.769524 -47.002017) (xy 49.344072 -47.002017) (xy 49.344072 -48.239934) (xy 49.361715 -48.260515)
			(xy 49.389964 -48.306775) (xy 49.409336 -48.357398) (xy 49.419186 -48.410698) (xy 49.419764 -48.4378)
			(xy 49.419764 -48.601963) (xy 49.769524 -48.601963) (xy 49.769524 -48.549989) (xy 49.777654 -48.498654)
			(xy 49.793715 -48.449224) (xy 49.817311 -48.402914) (xy 49.847861 -48.360866) (xy 49.884612 -48.324115)
			(xy 49.92666 -48.293565) (xy 49.97297 -48.269969) (xy 50.0224 -48.253908) (xy 50.073735 -48.245778)
			(xy 50.125709 -48.245778) (xy 50.177044 -48.253908) (xy 50.226474 -48.269969) (xy 50.272784 -48.293565)
			(xy 50.314832 -48.324115) (xy 50.351583 -48.360866) (xy 50.382133 -48.402914) (xy 50.405729 -48.449224)
			(xy 50.42179 -48.498654) (xy 50.42992 -48.549989) (xy 50.43043 -48.575976) (xy 50.42992 -48.601963)
			(xy 50.569624 -48.601963) (xy 50.569624 -48.549989) (xy 50.577754 -48.498654) (xy 50.593815 -48.449224)
			(xy 50.617411 -48.402914) (xy 50.647961 -48.360866) (xy 50.684712 -48.324115) (xy 50.72676 -48.293565)
			(xy 50.77307 -48.269969) (xy 50.8225 -48.253908) (xy 50.873835 -48.245778) (xy 50.925809 -48.245778)
			(xy 50.977144 -48.253908) (xy 51.026574 -48.269969) (xy 51.072884 -48.293565) (xy 51.114932 -48.324115)
			(xy 51.151683 -48.360866) (xy 51.182233 -48.402914) (xy 51.205829 -48.449224) (xy 51.22189 -48.498654)
			(xy 51.23002 -48.549989) (xy 51.23053 -48.575976) (xy 51.23002 -48.601963) (xy 51.36947 -48.601963)
			(xy 51.36947 -48.549989) (xy 51.3776 -48.498654) (xy 51.393661 -48.449224) (xy 51.417257 -48.402914)
			(xy 51.447807 -48.360866) (xy 51.484558 -48.324115) (xy 51.526606 -48.293565) (xy 51.572916 -48.269969)
			(xy 51.622346 -48.253908) (xy 51.673681 -48.245778) (xy 51.725655 -48.245778) (xy 51.77699 -48.253908)
			(xy 51.82642 -48.269969) (xy 51.87273 -48.293565) (xy 51.914778 -48.324115) (xy 51.951529 -48.360866)
			(xy 51.982079 -48.402914) (xy 52.005675 -48.449224) (xy 52.021736 -48.498654) (xy 52.029866 -48.549989)
			(xy 52.030376 -48.575976) (xy 52.029866 -48.601963) (xy 52.16957 -48.601963) (xy 52.16957 -48.549989)
			(xy 52.1777 -48.498654) (xy 52.193761 -48.449224) (xy 52.217357 -48.402914) (xy 52.247907 -48.360866)
			(xy 52.284658 -48.324115) (xy 52.326706 -48.293565) (xy 52.373016 -48.269969) (xy 52.422446 -48.253908)
			(xy 52.473781 -48.245778) (xy 52.525755 -48.245778) (xy 52.57709 -48.253908) (xy 52.62652 -48.269969)
			(xy 52.67283 -48.293565) (xy 52.714878 -48.324115) (xy 52.751629 -48.360866) (xy 52.782179 -48.402914)
			(xy 52.805775 -48.449224) (xy 52.821836 -48.498654) (xy 52.829966 -48.549989) (xy 52.830476 -48.575976)
			(xy 52.829966 -48.601963) (xy 52.821836 -48.653298) (xy 52.805775 -48.702728) (xy 52.782179 -48.749038)
			(xy 52.751629 -48.791086) (xy 52.714878 -48.827837) (xy 52.67283 -48.858387) (xy 52.62652 -48.881983)
			(xy 52.57709 -48.898044) (xy 52.525755 -48.906174) (xy 52.473781 -48.906174) (xy 52.422446 -48.898044)
			(xy 52.373016 -48.881983) (xy 52.326706 -48.858387) (xy 52.284658 -48.827837) (xy 52.247907 -48.791086)
			(xy 52.217357 -48.749038) (xy 52.193761 -48.702728) (xy 52.1777 -48.653298) (xy 52.16957 -48.601963)
			(xy 52.029866 -48.601963) (xy 52.021736 -48.653298) (xy 52.005675 -48.702728) (xy 51.982079 -48.749038)
			(xy 51.951529 -48.791086) (xy 51.914778 -48.827837) (xy 51.87273 -48.858387) (xy 51.82642 -48.881983)
			(xy 51.77699 -48.898044) (xy 51.725655 -48.906174) (xy 51.673681 -48.906174) (xy 51.622346 -48.898044)
			(xy 51.572916 -48.881983) (xy 51.526606 -48.858387) (xy 51.484558 -48.827837) (xy 51.447807 -48.791086)
			(xy 51.417257 -48.749038) (xy 51.393661 -48.702728) (xy 51.3776 -48.653298) (xy 51.36947 -48.601963)
			(xy 51.23002 -48.601963) (xy 51.22189 -48.653298) (xy 51.205829 -48.702728) (xy 51.182233 -48.749038)
			(xy 51.151683 -48.791086) (xy 51.114932 -48.827837) (xy 51.072884 -48.858387) (xy 51.026574 -48.881983)
			(xy 50.977144 -48.898044) (xy 50.925809 -48.906174) (xy 50.873835 -48.906174) (xy 50.8225 -48.898044)
			(xy 50.77307 -48.881983) (xy 50.72676 -48.858387) (xy 50.684712 -48.827837) (xy 50.647961 -48.791086)
			(xy 50.617411 -48.749038) (xy 50.593815 -48.702728) (xy 50.577754 -48.653298) (xy 50.569624 -48.601963)
			(xy 50.42992 -48.601963) (xy 50.42179 -48.653298) (xy 50.405729 -48.702728) (xy 50.382133 -48.749038)
			(xy 50.351583 -48.791086) (xy 50.314832 -48.827837) (xy 50.272784 -48.858387) (xy 50.226474 -48.881983)
			(xy 50.177044 -48.898044) (xy 50.125709 -48.906174) (xy 50.073735 -48.906174) (xy 50.0224 -48.898044)
			(xy 49.97297 -48.881983) (xy 49.92666 -48.858387) (xy 49.884612 -48.827837) (xy 49.847861 -48.791086)
			(xy 49.817311 -48.749038) (xy 49.793715 -48.702728) (xy 49.777654 -48.653298) (xy 49.769524 -48.601963)
			(xy 49.419764 -48.601963) (xy 49.419764 -49.187608) (xy 49.740058 -49.507648) (xy 49.740058 -49.53508)
			(xy 49.856136 -49.651158) (xy 49.872527 -49.668226) (xy 49.900219 -49.706597) (xy 49.921463 -49.74888)
			(xy 49.929034 -49.7713) (xy 49.933919 -49.785089) (xy 49.950308 -49.809308) (xy 49.972883 -49.827895)
			(xy 49.999797 -49.83933) (xy 50.028847 -49.842676) (xy 50.043334 -49.840642) (xy 50.05732 -49.83837)
			(xy 50.085553 -49.835956) (xy 50.099722 -49.835816) (xy 50.125706 -49.836327) (xy 50.177034 -49.84446)
			(xy 50.226458 -49.860522) (xy 50.272761 -49.884117) (xy 50.314803 -49.914665) (xy 50.351549 -49.951413)
			(xy 50.382095 -49.993457) (xy 50.405687 -50.039762) (xy 50.421745 -50.089187) (xy 50.429875 -50.140516)
			(xy 50.429875 -50.192484) (xy 50.429871 -50.192511) (xy 51.36947 -50.192511) (xy 51.36947 -50.140537)
			(xy 51.3776 -50.089202) (xy 51.393661 -50.039772) (xy 51.417257 -49.993462) (xy 51.447807 -49.951414)
			(xy 51.484558 -49.914663) (xy 51.526606 -49.884113) (xy 51.572916 -49.860517) (xy 51.622346 -49.844456)
			(xy 51.673681 -49.836326) (xy 51.725655 -49.836326) (xy 51.77699 -49.844456) (xy 51.82642 -49.860517)
			(xy 51.87273 -49.884113) (xy 51.914778 -49.914663) (xy 51.951529 -49.951414) (xy 51.982079 -49.993462)
			(xy 52.005675 -50.039772) (xy 52.021736 -50.089202) (xy 52.029866 -50.140537) (xy 52.030376 -50.166524)
			(xy 52.029866 -50.192511) (xy 52.021736 -50.243846) (xy 52.005675 -50.293276) (xy 51.982079 -50.339586)
			(xy 51.951529 -50.381634) (xy 51.914778 -50.418385) (xy 51.87273 -50.448935) (xy 51.82642 -50.472531)
			(xy 51.77699 -50.488592) (xy 51.725655 -50.496722) (xy 51.673681 -50.496722) (xy 51.622346 -50.488592)
			(xy 51.572916 -50.472531) (xy 51.526606 -50.448935) (xy 51.484558 -50.418385) (xy 51.447807 -50.381634)
			(xy 51.417257 -50.339586) (xy 51.393661 -50.293276) (xy 51.3776 -50.243846) (xy 51.36947 -50.192511)
			(xy 50.429871 -50.192511) (xy 50.421745 -50.243813) (xy 50.405687 -50.293238) (xy 50.382095 -50.339543)
			(xy 50.351549 -50.381587) (xy 50.314803 -50.418335) (xy 50.272761 -50.448883) (xy 50.226458 -50.472478)
			(xy 50.177034 -50.48854) (xy 50.125706 -50.496673) (xy 50.099722 -50.497232) (xy 50.08915 -50.497123)
			(xy 50.068052 -50.495725) (xy 50.057558 -50.494438) (xy 50.043199 -50.493095) (xy 50.01472 -50.497555)
			(xy 49.988622 -50.509797) (xy 49.966985 -50.528844) (xy 49.951533 -50.553179) (xy 49.943497 -50.580862)
			(xy 49.943004 -50.595276) (xy 49.943004 -50.650648) (xy 50.000916 -50.650648) (xy 50.007774 -50.648616)
			(xy 50.030273 -50.642541) (xy 50.07642 -50.636046) (xy 50.099722 -50.635662) (xy 50.12571 -50.636173)
			(xy 50.177047 -50.644307) (xy 50.226479 -50.660372) (xy 50.27279 -50.683971) (xy 50.314839 -50.714524)
			(xy 50.351591 -50.751278) (xy 50.382141 -50.793329) (xy 50.405737 -50.839641) (xy 50.421798 -50.889075)
			(xy 50.429928 -50.940412) (xy 50.429928 -50.992357) (xy 51.36947 -50.992357) (xy 51.36947 -50.940383)
			(xy 51.3776 -50.889048) (xy 51.393661 -50.839618) (xy 51.417257 -50.793308) (xy 51.447807 -50.75126)
			(xy 51.484558 -50.714509) (xy 51.526606 -50.683959) (xy 51.572916 -50.660363) (xy 51.622346 -50.644302)
			(xy 51.673681 -50.636172) (xy 51.725655 -50.636172) (xy 51.77699 -50.644302) (xy 51.82642 -50.660363)
			(xy 51.87273 -50.683959) (xy 51.914778 -50.714509) (xy 51.951529 -50.75126) (xy 51.982079 -50.793308)
			(xy 52.005675 -50.839618) (xy 52.021736 -50.889048) (xy 52.029866 -50.940383) (xy 52.030376 -50.96637)
			(xy 52.029866 -50.992357) (xy 52.021736 -51.043692) (xy 52.005675 -51.093122) (xy 51.982079 -51.139432)
			(xy 51.951529 -51.18148) (xy 51.914778 -51.218231) (xy 51.87273 -51.248781) (xy 51.82642 -51.272377)
			(xy 51.77699 -51.288438) (xy 51.725655 -51.296568) (xy 51.673681 -51.296568) (xy 51.622346 -51.288438)
			(xy 51.572916 -51.272377) (xy 51.526606 -51.248781) (xy 51.484558 -51.218231) (xy 51.447807 -51.18148)
			(xy 51.417257 -51.139432) (xy 51.393661 -51.093122) (xy 51.3776 -51.043692) (xy 51.36947 -50.992357)
			(xy 50.429928 -50.992357) (xy 50.429928 -50.992388) (xy 50.421798 -51.043725) (xy 50.405737 -51.093159)
			(xy 50.382141 -51.139471) (xy 50.351591 -51.181522) (xy 50.314839 -51.218276) (xy 50.27279 -51.248829)
			(xy 50.226479 -51.272428) (xy 50.177047 -51.288493) (xy 50.12571 -51.296627) (xy 50.099722 -51.297078)
			(xy 50.08915 -51.296969) (xy 50.068052 -51.295571) (xy 50.057558 -51.294284) (xy 50.043201 -51.292941)
			(xy 50.014726 -51.297401) (xy 49.988634 -51.309644) (xy 49.967004 -51.328692) (xy 49.951561 -51.353028)
			(xy 49.943537 -51.38071) (xy 49.943004 -51.395122) (xy 49.943004 -51.450748) (xy 50.000916 -51.450748)
			(xy 50.007774 -51.448716) (xy 50.030273 -51.442641) (xy 50.07642 -51.436146) (xy 50.099722 -51.435762)
			(xy 50.12571 -51.436273) (xy 50.177047 -51.444407) (xy 50.226479 -51.460472) (xy 50.27279 -51.484071)
			(xy 50.314839 -51.514624) (xy 50.351591 -51.551378) (xy 50.382141 -51.593429) (xy 50.405737 -51.639741)
			(xy 50.421798 -51.689175) (xy 50.429928 -51.740512) (xy 50.429928 -51.792488) (xy 50.421798 -51.843825)
			(xy 50.405737 -51.893259) (xy 50.382141 -51.939571) (xy 50.351591 -51.981622) (xy 50.314839 -52.018376)
			(xy 50.27279 -52.048929) (xy 50.226479 -52.072528) (xy 50.177047 -52.088593) (xy 50.12571 -52.096727)
			(xy 50.099722 -52.097178) (xy 50.08915 -52.097069) (xy 50.068052 -52.095671) (xy 50.057558 -52.094384)
			(xy 50.043201 -52.093041) (xy 50.014726 -52.097501) (xy 49.988634 -52.109744) (xy 49.967004 -52.128792)
			(xy 49.951561 -52.153128) (xy 49.943537 -52.18081) (xy 49.943004 -52.195222) (xy 49.943004 -52.592557)
			(xy 50.569624 -52.592557) (xy 50.569624 -52.540583) (xy 50.577754 -52.489248) (xy 50.593815 -52.439818)
			(xy 50.617411 -52.393508) (xy 50.647961 -52.35146) (xy 50.684712 -52.314709) (xy 50.72676 -52.284159)
			(xy 50.77307 -52.260563) (xy 50.8225 -52.244502) (xy 50.873835 -52.236372) (xy 50.925809 -52.236372)
			(xy 50.977144 -52.244502) (xy 51.026574 -52.260563) (xy 51.072884 -52.284159) (xy 51.114932 -52.314709)
			(xy 51.151683 -52.35146) (xy 51.182233 -52.393508) (xy 51.205829 -52.439818) (xy 51.22189 -52.489248)
			(xy 51.23002 -52.540583) (xy 51.23053 -52.56657) (xy 51.23002 -52.592557) (xy 51.36947 -52.592557)
			(xy 51.36947 -52.540583) (xy 51.3776 -52.489248) (xy 51.393661 -52.439818) (xy 51.417257 -52.393508)
			(xy 51.447807 -52.35146) (xy 51.484558 -52.314709) (xy 51.526606 -52.284159) (xy 51.572916 -52.260563)
			(xy 51.622346 -52.244502) (xy 51.673681 -52.236372) (xy 51.725655 -52.236372) (xy 51.77699 -52.244502)
			(xy 51.82642 -52.260563) (xy 51.87273 -52.284159) (xy 51.914778 -52.314709) (xy 51.951529 -52.35146)
			(xy 51.982079 -52.393508) (xy 52.005675 -52.439818) (xy 52.021736 -52.489248) (xy 52.029866 -52.540583)
			(xy 52.030376 -52.56657) (xy 52.029866 -52.592557) (xy 52.16957 -52.592557) (xy 52.16957 -52.540583)
			(xy 52.1777 -52.489248) (xy 52.193761 -52.439818) (xy 52.217357 -52.393508) (xy 52.247907 -52.35146)
			(xy 52.284658 -52.314709) (xy 52.326706 -52.284159) (xy 52.373016 -52.260563) (xy 52.422446 -52.244502)
			(xy 52.473781 -52.236372) (xy 52.525755 -52.236372) (xy 52.57709 -52.244502) (xy 52.62652 -52.260563)
			(xy 52.67283 -52.284159) (xy 52.714878 -52.314709) (xy 52.751629 -52.35146) (xy 52.782179 -52.393508)
			(xy 52.805775 -52.439818) (xy 52.821836 -52.489248) (xy 52.829966 -52.540583) (xy 52.830476 -52.56657)
			(xy 52.829966 -52.592557) (xy 52.821836 -52.643892) (xy 52.805775 -52.693322) (xy 52.782179 -52.739632)
			(xy 52.751629 -52.78168) (xy 52.714878 -52.818431) (xy 52.67283 -52.848981) (xy 52.62652 -52.872577)
			(xy 52.57709 -52.888638) (xy 52.525755 -52.896768) (xy 52.473781 -52.896768) (xy 52.422446 -52.888638)
			(xy 52.373016 -52.872577) (xy 52.326706 -52.848981) (xy 52.284658 -52.818431) (xy 52.247907 -52.78168)
			(xy 52.217357 -52.739632) (xy 52.193761 -52.693322) (xy 52.1777 -52.643892) (xy 52.16957 -52.592557)
			(xy 52.029866 -52.592557) (xy 52.021736 -52.643892) (xy 52.005675 -52.693322) (xy 51.982079 -52.739632)
			(xy 51.951529 -52.78168) (xy 51.914778 -52.818431) (xy 51.87273 -52.848981) (xy 51.82642 -52.872577)
			(xy 51.77699 -52.888638) (xy 51.725655 -52.896768) (xy 51.673681 -52.896768) (xy 51.622346 -52.888638)
			(xy 51.572916 -52.872577) (xy 51.526606 -52.848981) (xy 51.484558 -52.818431) (xy 51.447807 -52.78168)
			(xy 51.417257 -52.739632) (xy 51.393661 -52.693322) (xy 51.3776 -52.643892) (xy 51.36947 -52.592557)
			(xy 51.23002 -52.592557) (xy 51.22189 -52.643892) (xy 51.205829 -52.693322) (xy 51.182233 -52.739632)
			(xy 51.151683 -52.78168) (xy 51.114932 -52.818431) (xy 51.072884 -52.848981) (xy 51.026574 -52.872577)
			(xy 50.977144 -52.888638) (xy 50.925809 -52.896768) (xy 50.873835 -52.896768) (xy 50.8225 -52.888638)
			(xy 50.77307 -52.872577) (xy 50.72676 -52.848981) (xy 50.684712 -52.818431) (xy 50.647961 -52.78168)
			(xy 50.617411 -52.739632) (xy 50.593815 -52.693322) (xy 50.577754 -52.643892) (xy 50.569624 -52.592557)
			(xy 49.943004 -52.592557) (xy 49.943004 -53.392403) (xy 50.569624 -53.392403) (xy 50.569624 -53.340429)
			(xy 50.577754 -53.289094) (xy 50.593815 -53.239664) (xy 50.617411 -53.193354) (xy 50.647961 -53.151306)
			(xy 50.684712 -53.114555) (xy 50.72676 -53.084005) (xy 50.77307 -53.060409) (xy 50.8225 -53.044348)
			(xy 50.873835 -53.036218) (xy 50.925809 -53.036218) (xy 50.977144 -53.044348) (xy 51.026574 -53.060409)
			(xy 51.072884 -53.084005) (xy 51.114932 -53.114555) (xy 51.151683 -53.151306) (xy 51.182233 -53.193354)
			(xy 51.205829 -53.239664) (xy 51.22189 -53.289094) (xy 51.23002 -53.340429) (xy 51.23053 -53.366416)
			(xy 51.23002 -53.392403) (xy 51.36947 -53.392403) (xy 51.36947 -53.340429) (xy 51.3776 -53.289094)
			(xy 51.393661 -53.239664) (xy 51.417257 -53.193354) (xy 51.447807 -53.151306) (xy 51.484558 -53.114555)
			(xy 51.526606 -53.084005) (xy 51.572916 -53.060409) (xy 51.622346 -53.044348) (xy 51.673681 -53.036218)
			(xy 51.725655 -53.036218) (xy 51.77699 -53.044348) (xy 51.82642 -53.060409) (xy 51.87273 -53.084005)
			(xy 51.914778 -53.114555) (xy 51.951529 -53.151306) (xy 51.982079 -53.193354) (xy 52.005675 -53.239664)
			(xy 52.021736 -53.289094) (xy 52.029866 -53.340429) (xy 52.030376 -53.366416) (xy 52.029866 -53.392403)
			(xy 52.021736 -53.443738) (xy 52.005675 -53.493168) (xy 51.982079 -53.539478) (xy 51.951529 -53.581526)
			(xy 51.914778 -53.618277) (xy 51.87273 -53.648827) (xy 51.82642 -53.672423) (xy 51.77699 -53.688484)
			(xy 51.725655 -53.696614) (xy 51.673681 -53.696614) (xy 51.622346 -53.688484) (xy 51.572916 -53.672423)
			(xy 51.526606 -53.648827) (xy 51.484558 -53.618277) (xy 51.447807 -53.581526) (xy 51.417257 -53.539478)
			(xy 51.393661 -53.493168) (xy 51.3776 -53.443738) (xy 51.36947 -53.392403) (xy 51.23002 -53.392403)
			(xy 51.22189 -53.443738) (xy 51.205829 -53.493168) (xy 51.182233 -53.539478) (xy 51.151683 -53.581526)
			(xy 51.114932 -53.618277) (xy 51.072884 -53.648827) (xy 51.026574 -53.672423) (xy 50.977144 -53.688484)
			(xy 50.925809 -53.696614) (xy 50.873835 -53.696614) (xy 50.8225 -53.688484) (xy 50.77307 -53.672423)
			(xy 50.72676 -53.648827) (xy 50.684712 -53.618277) (xy 50.647961 -53.581526) (xy 50.617411 -53.539478)
			(xy 50.593815 -53.493168) (xy 50.577754 -53.443738) (xy 50.569624 -53.392403) (xy 49.943004 -53.392403)
			(xy 49.943004 -53.689758) (xy 50.765456 -54.51221) (xy 52.756054 -54.51221)
		)
		(stroke
			(width 0)
			(type solid)
		)
		(fill yes)
		(layer "In2.Cu")
		(net "P3V3_AUX")
	)
	(gr_poly
		(pts
			(xy 56.750966 -69.34835) (xy 56.750966 -66.94424) (xy 56.75049 -66.930047) (xy 56.742664 -66.90276)
			(xy 56.727634 -66.878678) (xy 56.706559 -66.85966) (xy 56.681066 -66.847174) (xy 56.653121 -66.842183)
			(xy 56.638952 -66.843148) (xy 56.629138 -66.844103) (xy 56.609443 -66.84512) (xy 56.599582 -66.84518)
			(xy 56.572334 -66.844693) (xy 56.518392 -66.836935) (xy 56.466103 -66.821579) (xy 56.416532 -66.798939)
			(xy 56.370687 -66.769474) (xy 56.329502 -66.733785) (xy 56.293815 -66.692598) (xy 56.264353 -66.646752)
			(xy 56.241715 -66.59718) (xy 56.226362 -66.544891) (xy 56.218606 -66.490948) (xy 56.218606 -66.436452)
			(xy 56.226362 -66.382509) (xy 56.241715 -66.33022) (xy 56.264353 -66.280648) (xy 56.293815 -66.234802)
			(xy 56.329502 -66.193615) (xy 56.370687 -66.157926) (xy 56.416532 -66.128461) (xy 56.466103 -66.105821)
			(xy 56.518392 -66.090465) (xy 56.572334 -66.082707) (xy 56.599582 -66.082164) (xy 56.609442 -66.082229)
			(xy 56.629137 -66.083247) (xy 56.638952 -66.084196) (xy 56.653128 -66.085189) (xy 56.681094 -66.080216)
			(xy 56.70661 -66.067735) (xy 56.727703 -66.04871) (xy 56.742742 -66.024613) (xy 56.750564 -65.997306)
			(xy 56.750966 -65.983104) (xy 56.750966 -65.090548) (xy 56.717184 -65.07861) (xy 56.69136 -65.068895)
			(xy 56.642594 -65.043089) (xy 56.598053 -65.010528) (xy 56.558667 -64.971891) (xy 56.525258 -64.927983)
			(xy 56.498521 -64.879721) (xy 56.479014 -64.828111) (xy 56.467145 -64.774229) (xy 56.463161 -64.7192)
			(xy 56.467145 -64.664171) (xy 56.479014 -64.610289) (xy 56.498521 -64.558679) (xy 56.525258 -64.510417)
			(xy 56.558667 -64.466509) (xy 56.598053 -64.427872) (xy 56.642594 -64.395311) (xy 56.69136 -64.369505)
			(xy 56.717184 -64.35979) (xy 56.750966 -64.347852) (xy 56.750966 -63.240666) (xy 56.55945 -63.04915)
			(xy 56.543306 -63.03237) (xy 56.515967 -62.994679) (xy 56.494863 -62.953174) (xy 56.480514 -62.908878)
			(xy 56.473274 -62.862882) (xy 56.472836 -62.8396) (xy 56.472836 -62.142878) (xy 56.472275 -62.127719)
			(xy 56.463366 -62.098739) (xy 56.446341 -62.073653) (xy 56.4227 -62.054671) (xy 56.394528 -62.043468)
			(xy 56.364308 -62.04103) (xy 56.334705 -62.047574) (xy 56.321198 -62.054486) (xy 56.299697 -62.066168)
			(xy 56.254339 -62.08453) (xy 56.207002 -62.096928) (xy 56.158467 -62.10316) (xy 56.134 -62.103508)
			(xy 56.106749 -62.103022) (xy 56.052801 -62.095266) (xy 56.000506 -62.079911) (xy 55.950929 -62.057269)
			(xy 55.905079 -62.027803) (xy 55.863888 -61.992112) (xy 55.828197 -61.950921) (xy 55.798731 -61.905071)
			(xy 55.776089 -61.855494) (xy 55.760734 -61.803199) (xy 55.752978 -61.749251) (xy 55.752978 -61.694749)
			(xy 55.760734 -61.640801) (xy 55.776089 -61.588506) (xy 55.798731 -61.538929) (xy 55.828197 -61.493079)
			(xy 55.863888 -61.451888) (xy 55.905079 -61.416197) (xy 55.950929 -61.386731) (xy 56.000506 -61.364089)
			(xy 56.052801 -61.348734) (xy 56.106749 -61.340978) (xy 56.134 -61.340492) (xy 56.162528 -61.341031)
			(xy 56.218947 -61.349538) (xy 56.273471 -61.36635) (xy 56.324886 -61.39109) (xy 56.372045 -61.423207)
			(xy 56.413897 -61.461986) (xy 56.449512 -61.506564) (xy 56.478093 -61.555945) (xy 56.499006 -61.609032)
			(xy 56.511784 -61.664639) (xy 56.514492 -61.693044) (xy 56.515762 -61.71184) (xy 56.565038 -61.760862)
			(xy 56.650636 -61.675518) (xy 56.650636 -59.800998) (xy 56.058562 -59.208924) (xy 56.047062 -59.198233)
			(xy 56.019187 -59.183817) (xy 55.98825 -59.178552) (xy 55.957176 -59.182936) (xy 55.928903 -59.196554)
			(xy 55.917084 -59.206892) (xy 55.898578 -59.223726) (xy 55.857438 -59.252188) (xy 55.812479 -59.274127)
			(xy 55.764728 -59.28904) (xy 55.715275 -59.296588) (xy 55.690262 -59.297062) (xy 55.664276 -59.296576)
			(xy 55.612945 -59.28844) (xy 55.563518 -59.272374) (xy 55.517214 -59.248773) (xy 55.475171 -59.218219)
			(xy 55.438426 -59.181465) (xy 55.407883 -59.139415) (xy 55.384294 -59.093104) (xy 55.368241 -59.043673)
			(xy 55.360117 -58.99234) (xy 55.359554 -58.966354) (xy 55.359813 -58.948037) (xy 55.363882 -58.91163)
			(xy 55.367682 -58.89371) (xy 55.369519 -58.882577) (xy 55.364495 -58.860608) (xy 55.350574 -58.842885)
			(xy 55.340758 -58.837322) (xy 55.319724 -58.826249) (xy 55.281184 -58.798427) (xy 55.26405 -58.78195)
			(xy 54.62905 -58.14695) (xy 54.612906 -58.13017) (xy 54.585567 -58.092479) (xy 54.564463 -58.050974)
			(xy 54.550114 -58.006678) (xy 54.542874 -57.960682) (xy 54.542436 -57.9374) (xy 54.542436 -57.692798)
			(xy 54.468268 -57.61863) (xy 54.456768 -57.607938) (xy 54.428893 -57.593519) (xy 54.397955 -57.588252)
			(xy 54.366879 -57.592635) (xy 54.338604 -57.606253) (xy 54.32679 -57.616598) (xy 54.308259 -57.633441)
			(xy 54.267069 -57.661913) (xy 54.222058 -57.683854) (xy 54.174255 -57.698761) (xy 54.124751 -57.706294)
			(xy 54.099714 -57.706768) (xy 54.073725 -57.706286) (xy 54.022387 -57.698156) (xy 53.972953 -57.682095)
			(xy 53.926641 -57.658497) (xy 53.884591 -57.627944) (xy 53.847839 -57.591189) (xy 53.817289 -57.549137)
			(xy 53.793695 -57.502823) (xy 53.777638 -57.453387) (xy 53.769512 -57.402049) (xy 53.769006 -57.37606)
			(xy 53.769372 -57.354462) (xy 53.775028 -57.311636) (xy 53.786212 -57.269911) (xy 53.794152 -57.249822)
			(xy 53.779565 -57.240571) (xy 53.752445 -57.21918) (xy 53.74005 -57.20715) (xy 53.619908 -57.087008)
			(xy 53.554884 -57.152032) (xy 53.577236 -57.186322) (xy 53.589854 -57.206524) (xy 53.609788 -57.249783)
			(xy 53.62331 -57.295454) (xy 53.630141 -57.342593) (xy 53.630576 -57.366408) (xy 53.630092 -57.392396)
			(xy 53.62196 -57.443732) (xy 53.605896 -57.493163) (xy 53.582298 -57.539473) (xy 53.551745 -57.581521)
			(xy 53.51499 -57.618271) (xy 53.472939 -57.648819) (xy 53.426626 -57.672412) (xy 53.377193 -57.688469)
			(xy 53.325856 -57.696595) (xy 53.299868 -57.697116) (xy 53.274766 -57.696648) (xy 53.225138 -57.689057)
			(xy 53.177228 -57.674055) (xy 53.132134 -57.651986) (xy 53.090893 -57.623356) (xy 53.054452 -57.588824)
			(xy 53.023646 -57.549181) (xy 52.999185 -57.505339) (xy 52.989988 -57.481978) (xy 52.986178 -57.471818)
			(xy 52.971954 -57.457594) (xy 52.961493 -57.447802) (xy 52.936423 -57.43395) (xy 52.908492 -57.427611)
			(xy 52.879899 -57.429285) (xy 52.852898 -57.43884) (xy 52.829616 -57.455523) (xy 52.811888 -57.478019)
			(xy 52.806092 -57.491122) (xy 52.796451 -57.513641) (xy 52.771499 -57.555792) (xy 52.740602 -57.593802)
			(xy 52.704436 -57.626838) (xy 52.663793 -57.654178) (xy 52.619561 -57.675223) (xy 52.572708 -57.689512)
			(xy 52.52426 -57.696733) (xy 52.499768 -57.697116) (xy 52.473782 -57.696604) (xy 52.42245 -57.688469)
			(xy 52.373023 -57.672405) (xy 52.326716 -57.648807) (xy 52.284672 -57.618256) (xy 52.247923 -57.581504)
			(xy 52.217376 -57.539456) (xy 52.193783 -57.493148) (xy 52.177723 -57.443719) (xy 52.169593 -57.392386)
			(xy 52.169593 -57.340414) (xy 52.177723 -57.289081) (xy 52.193783 -57.239652) (xy 52.217376 -57.193344)
			(xy 52.247923 -57.151296) (xy 52.284672 -57.114544) (xy 52.326716 -57.083993) (xy 52.373023 -57.060395)
			(xy 52.42245 -57.044331) (xy 52.473782 -57.036196) (xy 52.499768 -57.0357) (xy 52.526438 -57.036716)
			(xy 52.537801 -57.037011) (xy 52.559005 -57.02891) (xy 52.574657 -57.012469) (xy 52.581708 -56.990892)
			(xy 52.580794 -56.979566) (xy 52.578508 -56.946292) (xy 52.577862 -56.935907) (xy 52.56933 -56.916954)
			(xy 52.553965 -56.902956) (xy 52.534301 -56.896223) (xy 52.523898 -56.896508) (xy 52.499768 -56.89727)
			(xy 52.473362 -56.89675) (xy 52.421222 -56.888345) (xy 52.371082 -56.871755) (xy 52.32422 -56.847402)
			(xy 52.281827 -56.815906) (xy 52.244983 -56.778068) (xy 52.214625 -56.734852) (xy 52.202588 -56.711342)
			(xy 52.188618 -56.682894) (xy 52.010818 -56.682894) (xy 51.996848 -56.711342) (xy 51.984833 -56.734864)
			(xy 51.954473 -56.778082) (xy 51.917626 -56.815921) (xy 51.87523 -56.847418) (xy 51.828363 -56.87177)
			(xy 51.778219 -56.888357) (xy 51.726076 -56.896758) (xy 51.67326 -56.896758) (xy 51.621117 -56.888357)
			(xy 51.570973 -56.87177) (xy 51.524106 -56.847418) (xy 51.48171 -56.815921) (xy 51.444863 -56.778082)
			(xy 51.414503 -56.734864) (xy 51.402488 -56.711342) (xy 51.388518 -56.682894) (xy 51.210972 -56.682894)
			(xy 51.197002 -56.711342) (xy 51.184987 -56.734864) (xy 51.154627 -56.778082) (xy 51.11778 -56.815921)
			(xy 51.075384 -56.847418) (xy 51.028517 -56.87177) (xy 50.978373 -56.888357) (xy 50.92623 -56.896758)
			(xy 50.873414 -56.896758) (xy 50.821271 -56.888357) (xy 50.771127 -56.87177) (xy 50.72426 -56.847418)
			(xy 50.681864 -56.815921) (xy 50.645017 -56.778082) (xy 50.614657 -56.734864) (xy 50.602642 -56.711342)
			(xy 50.588672 -56.682894) (xy 50.410872 -56.682894) (xy 50.396902 -56.711342) (xy 50.384887 -56.734864)
			(xy 50.354527 -56.778083) (xy 50.31768 -56.815922) (xy 50.275283 -56.84742) (xy 50.228417 -56.871774)
			(xy 50.178274 -56.888364) (xy 50.12613 -56.896767) (xy 50.099722 -56.89727) (xy 50.069981 -56.896662)
			(xy 50.011456 -56.886048) (xy 49.98339 -56.876188) (xy 49.97306 -56.872816) (xy 49.951394 -56.874186)
			(xy 49.932221 -56.884369) (xy 49.918953 -56.901553) (xy 49.913953 -56.922678) (xy 49.918111 -56.943986)
			(xy 49.923954 -56.95315) (xy 49.934088 -56.96783) (xy 49.95115 -56.999159) (xy 49.95799 -57.015634)
			(xy 49.961738 -57.024024) (xy 49.974093 -57.037606) (xy 49.990444 -57.04596) (xy 50.00869 -57.048012)
			(xy 50.01768 -57.046114) (xy 50.037844 -57.041268) (xy 50.078986 -57.036046) (xy 50.099722 -57.0357)
			(xy 50.125707 -57.036211) (xy 50.177038 -57.044344) (xy 50.226464 -57.060407) (xy 50.27277 -57.084003)
			(xy 50.314814 -57.114553) (xy 50.351562 -57.151303) (xy 50.382108 -57.193349) (xy 50.405702 -57.239656)
			(xy 50.421761 -57.289083) (xy 50.429891 -57.340415) (xy 50.429891 -57.392385) (xy 50.429889 -57.392395)
			(xy 50.569624 -57.392395) (xy 50.569624 -57.340421) (xy 50.577754 -57.289086) (xy 50.593815 -57.239656)
			(xy 50.617411 -57.193346) (xy 50.647961 -57.151298) (xy 50.684712 -57.114547) (xy 50.72676 -57.083997)
			(xy 50.77307 -57.060401) (xy 50.8225 -57.04434) (xy 50.873835 -57.03621) (xy 50.925809 -57.03621)
			(xy 50.977144 -57.04434) (xy 51.026574 -57.060401) (xy 51.072884 -57.083997) (xy 51.114932 -57.114547)
			(xy 51.151683 -57.151298) (xy 51.182233 -57.193346) (xy 51.205829 -57.239656) (xy 51.22189 -57.289086)
			(xy 51.23002 -57.340421) (xy 51.23053 -57.366408) (xy 51.23002 -57.392395) (xy 51.36947 -57.392395)
			(xy 51.36947 -57.340421) (xy 51.3776 -57.289086) (xy 51.393661 -57.239656) (xy 51.417257 -57.193346)
			(xy 51.447807 -57.151298) (xy 51.484558 -57.114547) (xy 51.526606 -57.083997) (xy 51.572916 -57.060401)
			(xy 51.622346 -57.04434) (xy 51.673681 -57.03621) (xy 51.725655 -57.03621) (xy 51.77699 -57.04434)
			(xy 51.82642 -57.060401) (xy 51.87273 -57.083997) (xy 51.914778 -57.114547) (xy 51.951529 -57.151298)
			(xy 51.982079 -57.193346) (xy 52.005675 -57.239656) (xy 52.021736 -57.289086) (xy 52.029866 -57.340421)
			(xy 52.030376 -57.366408) (xy 52.029866 -57.392395) (xy 52.021736 -57.44373) (xy 52.005675 -57.49316)
			(xy 51.982079 -57.53947) (xy 51.951529 -57.581518) (xy 51.914778 -57.618269) (xy 51.87273 -57.648819)
			(xy 51.82642 -57.672415) (xy 51.77699 -57.688476) (xy 51.725655 -57.696606) (xy 51.673681 -57.696606)
			(xy 51.622346 -57.688476) (xy 51.572916 -57.672415) (xy 51.526606 -57.648819) (xy 51.484558 -57.618269)
			(xy 51.447807 -57.581518) (xy 51.417257 -57.53947) (xy 51.393661 -57.49316) (xy 51.3776 -57.44373)
			(xy 51.36947 -57.392395) (xy 51.23002 -57.392395) (xy 51.22189 -57.44373) (xy 51.205829 -57.49316)
			(xy 51.182233 -57.53947) (xy 51.151683 -57.581518) (xy 51.114932 -57.618269) (xy 51.072884 -57.648819)
			(xy 51.026574 -57.672415) (xy 50.977144 -57.688476) (xy 50.925809 -57.696606) (xy 50.873835 -57.696606)
			(xy 50.8225 -57.688476) (xy 50.77307 -57.672415) (xy 50.72676 -57.648819) (xy 50.684712 -57.618269)
			(xy 50.647961 -57.581518) (xy 50.617411 -57.53947) (xy 50.593815 -57.49316) (xy 50.577754 -57.44373)
			(xy 50.569624 -57.392395) (xy 50.429889 -57.392395) (xy 50.421761 -57.443717) (xy 50.405702 -57.493144)
			(xy 50.382108 -57.539451) (xy 50.351562 -57.581497) (xy 50.314814 -57.618247) (xy 50.27277 -57.648797)
			(xy 50.226464 -57.672393) (xy 50.177038 -57.688456) (xy 50.125707 -57.696589) (xy 50.099722 -57.697116)
			(xy 50.084736 -57.696862) (xy 50.071036 -57.696682) (xy 50.044331 -57.702755) (xy 50.020203 -57.715713)
			(xy 50.000391 -57.734622) (xy 49.986324 -57.758121) (xy 49.979014 -57.784515) (xy 49.978564 -57.798208)
			(xy 49.978564 -58.475372) (xy 50.5206 -58.475372) (xy 50.535646 -58.474845) (xy 50.564437 -58.466097)
			(xy 50.589426 -58.449332) (xy 50.608438 -58.426008) (xy 50.619821 -58.398153) (xy 50.622585 -58.36819)
			(xy 50.61649 -58.338722) (xy 50.609754 -58.325258) (xy 50.596979 -58.300768) (xy 50.578873 -58.248588)
			(xy 50.569692 -58.194124) (xy 50.569114 -58.166508) (xy 50.569624 -58.140521) (xy 50.577754 -58.089186)
			(xy 50.593815 -58.039756) (xy 50.617411 -57.993446) (xy 50.647961 -57.951398) (xy 50.684712 -57.914647)
			(xy 50.72676 -57.884097) (xy 50.77307 -57.860501) (xy 50.8225 -57.84444) (xy 50.873835 -57.83631)
			(xy 50.925809 -57.83631) (xy 50.977144 -57.84444) (xy 51.026574 -57.860501) (xy 51.072884 -57.884097)
			(xy 51.114932 -57.914647) (xy 51.151683 -57.951398) (xy 51.182233 -57.993446) (xy 51.205829 -58.039756)
			(xy 51.22189 -58.089186) (xy 51.23002 -58.140521) (xy 51.23053 -58.166508) (xy 51.229972 -58.194125)
			(xy 51.220784 -58.248589) (xy 51.202665 -58.300767) (xy 51.18989 -58.325258) (xy 51.183181 -58.338728)
			(xy 51.177131 -58.36819) (xy 51.179916 -58.398138) (xy 51.191297 -58.425979) (xy 51.210288 -58.449303)
			(xy 51.235244 -58.46609) (xy 51.264006 -58.474888) (xy 51.279044 -58.475372) (xy 51.320446 -58.475372)
			(xy 51.335487 -58.474838) (xy 51.364266 -58.466083) (xy 51.389242 -58.449317) (xy 51.408244 -58.425998)
			(xy 51.419621 -58.398151) (xy 51.422386 -58.368197) (xy 51.416296 -58.338739) (xy 51.4096 -58.325258)
			(xy 51.396823 -58.300769) (xy 51.378715 -58.248589) (xy 51.369533 -58.194124) (xy 51.36896 -58.166508)
			(xy 51.36947 -58.140521) (xy 51.3776 -58.089186) (xy 51.393661 -58.039756) (xy 51.417257 -57.993446)
			(xy 51.447807 -57.951398) (xy 51.484558 -57.914647) (xy 51.526606 -57.884097) (xy 51.572916 -57.860501)
			(xy 51.622346 -57.84444) (xy 51.673681 -57.83631) (xy 51.725655 -57.83631) (xy 51.77699 -57.84444)
			(xy 51.82642 -57.860501) (xy 51.87273 -57.884097) (xy 51.914778 -57.914647) (xy 51.951529 -57.951398)
			(xy 51.982079 -57.993446) (xy 52.005675 -58.039756) (xy 52.021736 -58.089186) (xy 52.029866 -58.140521)
			(xy 52.030376 -58.166508) (xy 52.029918 -58.191201) (xy 52.029723 -58.192495) (xy 52.16957 -58.192495)
			(xy 52.16957 -58.140521) (xy 52.1777 -58.089186) (xy 52.193761 -58.039756) (xy 52.217357 -57.993446)
			(xy 52.247907 -57.951398) (xy 52.284658 -57.914647) (xy 52.326706 -57.884097) (xy 52.373016 -57.860501)
			(xy 52.422446 -57.84444) (xy 52.473781 -57.83631) (xy 52.525755 -57.83631) (xy 52.57709 -57.84444)
			(xy 52.62652 -57.860501) (xy 52.67283 -57.884097) (xy 52.714878 -57.914647) (xy 52.751629 -57.951398)
			(xy 52.782179 -57.993446) (xy 52.805775 -58.039756) (xy 52.821836 -58.089186) (xy 52.829966 -58.140521)
			(xy 52.830476 -58.166508) (xy 52.829966 -58.192495) (xy 52.96967 -58.192495) (xy 52.96967 -58.140521)
			(xy 52.9778 -58.089186) (xy 52.993861 -58.039756) (xy 53.017457 -57.993446) (xy 53.048007 -57.951398)
			(xy 53.084758 -57.914647) (xy 53.126806 -57.884097) (xy 53.173116 -57.860501) (xy 53.222546 -57.84444)
			(xy 53.273881 -57.83631) (xy 53.325855 -57.83631) (xy 53.37719 -57.84444) (xy 53.42662 -57.860501)
			(xy 53.47293 -57.884097) (xy 53.514978 -57.914647) (xy 53.551729 -57.951398) (xy 53.582279 -57.993446)
			(xy 53.605875 -58.039756) (xy 53.621936 -58.089186) (xy 53.630066 -58.140521) (xy 53.630576 -58.166508)
			(xy 53.630066 -58.192495) (xy 53.769516 -58.192495) (xy 53.769516 -58.140521) (xy 53.777646 -58.089186)
			(xy 53.793707 -58.039756) (xy 53.817303 -57.993446) (xy 53.847853 -57.951398) (xy 53.884604 -57.914647)
			(xy 53.926652 -57.884097) (xy 53.972962 -57.860501) (xy 54.022392 -57.84444) (xy 54.073727 -57.83631)
			(xy 54.125701 -57.83631) (xy 54.177036 -57.84444) (xy 54.226466 -57.860501) (xy 54.272776 -57.884097)
			(xy 54.314824 -57.914647) (xy 54.351575 -57.951398) (xy 54.382125 -57.993446) (xy 54.405721 -58.039756)
			(xy 54.421782 -58.089186) (xy 54.429912 -58.140521) (xy 54.430422 -58.166508) (xy 54.429912 -58.192495)
			(xy 54.421782 -58.24383) (xy 54.405721 -58.29326) (xy 54.382125 -58.33957) (xy 54.351575 -58.381618)
			(xy 54.314824 -58.418369) (xy 54.272776 -58.448919) (xy 54.226466 -58.472515) (xy 54.177036 -58.488576)
			(xy 54.125701 -58.496706) (xy 54.073727 -58.496706) (xy 54.022392 -58.488576) (xy 53.972962 -58.472515)
			(xy 53.926652 -58.448919) (xy 53.884604 -58.418369) (xy 53.847853 -58.381618) (xy 53.817303 -58.33957)
			(xy 53.793707 -58.29326) (xy 53.777646 -58.24383) (xy 53.769516 -58.192495) (xy 53.630066 -58.192495)
			(xy 53.621936 -58.24383) (xy 53.605875 -58.29326) (xy 53.582279 -58.33957) (xy 53.551729 -58.381618)
			(xy 53.514978 -58.418369) (xy 53.47293 -58.448919) (xy 53.42662 -58.472515) (xy 53.37719 -58.488576)
			(xy 53.325855 -58.496706) (xy 53.273881 -58.496706) (xy 53.222546 -58.488576) (xy 53.173116 -58.472515)
			(xy 53.126806 -58.448919) (xy 53.084758 -58.418369) (xy 53.048007 -58.381618) (xy 53.017457 -58.33957)
			(xy 52.993861 -58.29326) (xy 52.9778 -58.24383) (xy 52.96967 -58.192495) (xy 52.829966 -58.192495)
			(xy 52.821836 -58.24383) (xy 52.805775 -58.29326) (xy 52.782179 -58.33957) (xy 52.751629 -58.381618)
			(xy 52.714878 -58.418369) (xy 52.67283 -58.448919) (xy 52.62652 -58.472515) (xy 52.57709 -58.488576)
			(xy 52.525755 -58.496706) (xy 52.473781 -58.496706) (xy 52.422446 -58.488576) (xy 52.373016 -58.472515)
			(xy 52.326706 -58.448919) (xy 52.284658 -58.418369) (xy 52.247907 -58.381618) (xy 52.217357 -58.33957)
			(xy 52.193761 -58.29326) (xy 52.1777 -58.24383) (xy 52.16957 -58.192495) (xy 52.029723 -58.192495)
			(xy 52.022576 -58.240038) (xy 52.008057 -58.287242) (xy 51.986684 -58.331763) (xy 51.95893 -58.372612)
			(xy 51.942492 -58.391044) (xy 51.936128 -58.398589) (xy 51.929168 -58.417039) (xy 51.929675 -58.436752)
			(xy 51.937574 -58.454821) (xy 51.9517 -58.46858) (xy 51.96997 -58.476001) (xy 51.97983 -58.476388)
			(xy 52.017422 -58.476388) (xy 52.267612 -58.726578) (xy 52.302918 -58.70067) (xy 52.32441 -58.685377)
			(xy 52.371233 -58.661095) (xy 52.421319 -58.64456) (xy 52.473395 -58.636191) (xy 52.499768 -58.635646)
			(xy 52.525758 -58.636153) (xy 52.577099 -58.644279) (xy 52.626537 -58.660337) (xy 52.672854 -58.68393)
			(xy 52.714911 -58.714479) (xy 52.75167 -58.75123) (xy 52.782229 -58.793279) (xy 52.805833 -58.839591)
			(xy 52.821902 -58.889025) (xy 52.830041 -58.940364) (xy 52.830476 -58.966354) (xy 52.829965 -58.992341)
			(xy 52.96967 -58.992341) (xy 52.96967 -58.940367) (xy 52.9778 -58.889032) (xy 52.993861 -58.839602)
			(xy 53.017457 -58.793292) (xy 53.048007 -58.751244) (xy 53.084758 -58.714493) (xy 53.126806 -58.683943)
			(xy 53.173116 -58.660347) (xy 53.222546 -58.644286) (xy 53.273881 -58.636156) (xy 53.325855 -58.636156)
			(xy 53.37719 -58.644286) (xy 53.42662 -58.660347) (xy 53.47293 -58.683943) (xy 53.514978 -58.714493)
			(xy 53.551729 -58.751244) (xy 53.582279 -58.793292) (xy 53.605875 -58.839602) (xy 53.621936 -58.889032)
			(xy 53.630066 -58.940367) (xy 53.630576 -58.966354) (xy 53.630066 -58.992341) (xy 53.769516 -58.992341)
			(xy 53.769516 -58.940367) (xy 53.777646 -58.889032) (xy 53.793707 -58.839602) (xy 53.817303 -58.793292)
			(xy 53.847853 -58.751244) (xy 53.884604 -58.714493) (xy 53.926652 -58.683943) (xy 53.972962 -58.660347)
			(xy 54.022392 -58.644286) (xy 54.073727 -58.636156) (xy 54.125701 -58.636156) (xy 54.177036 -58.644286)
			(xy 54.226466 -58.660347) (xy 54.272776 -58.683943) (xy 54.314824 -58.714493) (xy 54.351575 -58.751244)
			(xy 54.382125 -58.793292) (xy 54.405721 -58.839602) (xy 54.421782 -58.889032) (xy 54.429912 -58.940367)
			(xy 54.430422 -58.966354) (xy 54.429912 -58.992341) (xy 54.421782 -59.043676) (xy 54.405721 -59.093106)
			(xy 54.382125 -59.139416) (xy 54.351575 -59.181464) (xy 54.314824 -59.218215) (xy 54.272776 -59.248765)
			(xy 54.226466 -59.272361) (xy 54.177036 -59.288422) (xy 54.125701 -59.296552) (xy 54.073727 -59.296552)
			(xy 54.022392 -59.288422) (xy 53.972962 -59.272361) (xy 53.926652 -59.248765) (xy 53.884604 -59.218215)
			(xy 53.847853 -59.181464) (xy 53.817303 -59.139416) (xy 53.793707 -59.093106) (xy 53.777646 -59.043676)
			(xy 53.769516 -58.992341) (xy 53.630066 -58.992341) (xy 53.621936 -59.043676) (xy 53.605875 -59.093106)
			(xy 53.582279 -59.139416) (xy 53.551729 -59.181464) (xy 53.514978 -59.218215) (xy 53.47293 -59.248765)
			(xy 53.42662 -59.272361) (xy 53.37719 -59.288422) (xy 53.325855 -59.296552) (xy 53.273881 -59.296552)
			(xy 53.222546 -59.288422) (xy 53.173116 -59.272361) (xy 53.126806 -59.248765) (xy 53.084758 -59.218215)
			(xy 53.048007 -59.181464) (xy 53.017457 -59.139416) (xy 52.993861 -59.093106) (xy 52.9778 -59.043676)
			(xy 52.96967 -58.992341) (xy 52.829965 -58.992341) (xy 52.829957 -58.992726) (xy 52.821571 -59.0448)
			(xy 52.80502 -59.094881) (xy 52.780724 -59.141697) (xy 52.765452 -59.163204) (xy 52.739544 -59.19851)
			(xy 53.069744 -59.52871) (xy 53.104034 -59.508136) (xy 53.123498 -59.496754) (xy 53.164855 -59.478795)
			(xy 53.208272 -59.466633) (xy 53.25294 -59.460493) (xy 53.275484 -59.46013) (xy 53.301473 -59.460612)
			(xy 53.352811 -59.468741) (xy 53.402246 -59.484803) (xy 53.448558 -59.5084) (xy 53.490609 -59.538953)
			(xy 53.527361 -59.575708) (xy 53.557911 -59.617761) (xy 53.581506 -59.664075) (xy 53.597564 -59.71351)
			(xy 53.60569 -59.764849) (xy 53.606192 -59.790838) (xy 53.605789 -59.813379) (xy 53.599632 -59.858039)
			(xy 53.587477 -59.901452) (xy 53.569549 -59.942817) (xy 53.558186 -59.962288) (xy 53.537612 -59.996578)
			(xy 53.816483 -60.275449) (xy 55.54979 -60.275449) (xy 55.54979 -60.222151) (xy 55.557733 -60.169447)
			(xy 55.573443 -60.118517) (xy 55.596569 -60.070496) (xy 55.626593 -60.026459) (xy 55.662845 -59.987388)
			(xy 55.704516 -59.954157) (xy 55.750674 -59.927508) (xy 55.800288 -59.908036) (xy 55.85225 -59.896176)
			(xy 55.9054 -59.892193) (xy 55.95855 -59.896176) (xy 56.010512 -59.908036) (xy 56.060126 -59.927508)
			(xy 56.106284 -59.954157) (xy 56.147955 -59.987388) (xy 56.184207 -60.026459) (xy 56.214231 -60.070496)
			(xy 56.237357 -60.118517) (xy 56.253067 -60.169447) (xy 56.26101 -60.222151) (xy 56.261508 -60.2488)
			(xy 56.26101 -60.275449) (xy 56.253067 -60.328153) (xy 56.237357 -60.379083) (xy 56.214231 -60.427104)
			(xy 56.184207 -60.471141) (xy 56.147955 -60.510212) (xy 56.106284 -60.543443) (xy 56.060126 -60.570092)
			(xy 56.010512 -60.589564) (xy 55.95855 -60.601424) (xy 55.9054 -60.605408) (xy 55.85225 -60.601424)
			(xy 55.800288 -60.589564) (xy 55.750674 -60.570092) (xy 55.704516 -60.543443) (xy 55.662845 -60.510212)
			(xy 55.626593 -60.471141) (xy 55.596569 -60.427104) (xy 55.573443 -60.379083) (xy 55.557733 -60.328153)
			(xy 55.54979 -60.275449) (xy 53.816483 -60.275449) (xy 54.66588 -61.124846) (xy 54.66588 -61.618876)
			(xy 54.707028 -61.62675) (xy 54.73284 -61.632143) (xy 54.782772 -61.649094) (xy 54.829895 -61.672758)
			(xy 54.87331 -61.702686) (xy 54.91219 -61.738307) (xy 54.945794 -61.778943) (xy 54.973483 -61.823819)
			(xy 54.994729 -61.872081) (xy 55.009126 -61.922808) (xy 55.016401 -61.975035) (xy 55.016908 -62.0014)
			(xy 55.016328 -62.031668) (xy 55.006765 -62.091443) (xy 54.987881 -62.148957) (xy 54.960149 -62.202767)
			(xy 54.924266 -62.25152) (xy 54.903116 -62.27318) (xy 54.893834 -62.282906) (xy 54.880284 -62.306117)
			(xy 54.873266 -62.332061) (xy 54.873265 -62.358937) (xy 54.880283 -62.384881) (xy 54.893833 -62.408092)
			(xy 54.912974 -62.426959) (xy 54.924452 -62.433962) (xy 54.949291 -62.448585) (xy 54.994657 -62.484139)
			(xy 55.034159 -62.526112) (xy 55.0669 -62.573548) (xy 55.092134 -62.625369) (xy 55.109289 -62.680395)
			(xy 55.117973 -62.737375) (xy 55.118508 -62.766194) (xy 55.117985 -62.794966) (xy 55.109344 -62.851856)
			(xy 55.092257 -62.906804) (xy 55.067112 -62.958563) (xy 55.034478 -63.005958) (xy 54.995097 -63.047914)
			(xy 54.949862 -63.083481) (xy 54.899798 -63.11185) (xy 54.846041 -63.132379) (xy 54.789811 -63.144602)
			(xy 54.76113 -63.14694) (xy 54.745836 -63.148427) (xy 54.717135 -63.159364) (xy 54.692975 -63.178329)
			(xy 54.675534 -63.20361) (xy 54.666383 -63.23293) (xy 54.66588 -63.248286) (xy 54.66588 -63.858394)
			(xy 54.666375 -63.873827) (xy 54.675513 -63.903307) (xy 54.693046 -63.928707) (xy 54.717371 -63.947704)
			(xy 54.746262 -63.95856) (xy 54.761638 -63.959994) (xy 54.790434 -63.962173) (xy 54.846929 -63.974126)
			(xy 54.900974 -63.994465) (xy 54.951333 -64.022724) (xy 54.996852 -64.058257) (xy 55.03649 -64.100251)
			(xy 55.069339 -64.147743) (xy 55.094648 -64.199648) (xy 55.111836 -64.254776) (xy 55.120512 -64.311867)
			(xy 55.121048 -64.34074) (xy 55.120729 -64.362199) (xy 55.115891 -64.404844) (xy 55.111396 -64.42583)
			(xy 55.10849 -64.440795) (xy 55.11075 -64.471182) (xy 55.121877 -64.499549) (xy 55.140879 -64.523369)
			(xy 55.166064 -64.540521) (xy 55.180484 -64.545464) (xy 55.206041 -64.553901) (xy 55.254671 -64.576955)
			(xy 55.29958 -64.606613) (xy 55.339875 -64.642288) (xy 55.374758 -64.683271) (xy 55.403536 -64.728749)
			(xy 55.425639 -64.777819) (xy 55.440627 -64.829509) (xy 55.448203 -64.882791) (xy 55.448708 -64.9097)
			(xy 55.448222 -64.936951) (xy 55.440466 -64.990899) (xy 55.425111 -65.043194) (xy 55.402469 -65.092771)
			(xy 55.373003 -65.138621) (xy 55.337312 -65.179812) (xy 55.296121 -65.215503) (xy 55.250271 -65.244969)
			(xy 55.200694 -65.267611) (xy 55.148399 -65.282966) (xy 55.094451 -65.290722) (xy 55.0672 -65.291208)
			(xy 55.041653 -65.290799) (xy 54.991015 -65.283983) (xy 54.941738 -65.270472) (xy 54.894705 -65.250509)
			(xy 54.850755 -65.22445) (xy 54.830472 -65.208912) (xy 54.818998 -65.200453) (xy 54.79263 -65.189653)
			(xy 54.764304 -65.186562) (xy 54.736227 -65.19142) (xy 54.710586 -65.203849) (xy 54.689379 -65.22288)
			(xy 54.674258 -65.247031) (xy 54.666402 -65.274421) (xy 54.66588 -65.288668) (xy 54.66588 -66.18224)
			(xy 54.682682 -66.204677) (xy 54.710222 -66.253497) (xy 54.730326 -66.30582) (xy 54.742563 -66.36052)
			(xy 54.746669 -66.416422) (xy 54.742557 -66.472323) (xy 54.730313 -66.527022) (xy 54.710203 -66.579343)
			(xy 54.682657 -66.62816) (xy 54.66588 -66.650616) (xy 54.66588 -67.056) (xy 54.862982 -67.056) (xy 54.867053 -67.000378)
			(xy 54.879179 -66.945941) (xy 54.899102 -66.89385) (xy 54.926398 -66.845215) (xy 54.960484 -66.801072)
			(xy 55.000633 -66.762363) (xy 55.045991 -66.729912) (xy 55.095591 -66.704411) (xy 55.148375 -66.686404)
			(xy 55.203218 -66.676274) (xy 55.258952 -66.674237) (xy 55.314389 -66.680337) (xy 55.368346 -66.694443)
			(xy 55.419675 -66.716255) (xy 55.467281 -66.745309) (xy 55.510149 -66.780984) (xy 55.547366 -66.822521)
			(xy 55.578139 -66.869034) (xy 55.601811 -66.919531) (xy 55.617879 -66.972938) (xy 55.625999 -67.028114)
			(xy 55.626508 -67.056) (xy 55.625999 -67.083886) (xy 55.617879 -67.139062) (xy 55.601811 -67.192469)
			(xy 55.578139 -67.242966) (xy 55.547366 -67.289479) (xy 55.510149 -67.331016) (xy 55.467281 -67.366691)
			(xy 55.419675 -67.395745) (xy 55.368346 -67.417557) (xy 55.314389 -67.431663) (xy 55.258952 -67.437763)
			(xy 55.203218 -67.435726) (xy 55.148375 -67.425596) (xy 55.095591 -67.407589) (xy 55.045991 -67.382088)
			(xy 55.000633 -67.349637) (xy 54.960484 -67.310928) (xy 54.926398 -67.266785) (xy 54.899102 -67.21815)
			(xy 54.879179 -67.166059) (xy 54.867053 -67.111622) (xy 54.862982 -67.056) (xy 54.66588 -67.056)
			(xy 54.66588 -68.182236) (xy 55.122318 -68.182236) (xy 55.472838 -67.831462) (xy 55.474362 -67.81292)
			(xy 55.477159 -67.784603) (xy 55.490077 -67.729188) (xy 55.511081 -67.676306) (xy 55.539706 -67.627129)
			(xy 55.575316 -67.582749) (xy 55.617122 -67.544149) (xy 55.664196 -67.512186) (xy 55.715496 -67.487568)
			(xy 55.769882 -67.470841) (xy 55.82615 -67.462376) (xy 55.8546 -67.461892) (xy 55.881851 -67.462378)
			(xy 55.935799 -67.470134) (xy 55.988094 -67.485489) (xy 56.037671 -67.508131) (xy 56.083521 -67.537597)
			(xy 56.124712 -67.573288) (xy 56.160403 -67.614479) (xy 56.189869 -67.660329) (xy 56.212511 -67.709906)
			(xy 56.227866 -67.762201) (xy 56.235622 -67.816149) (xy 56.236108 -67.8434) (xy 56.235587 -67.87204)
			(xy 56.227011 -67.928676) (xy 56.210066 -67.983393) (xy 56.185134 -68.034964) (xy 56.152773 -68.082228)
			(xy 56.113712 -68.124125) (xy 56.068828 -68.159713) (xy 56.019128 -68.188193) (xy 55.96573 -68.208925)
			(xy 55.937912 -68.215764) (xy 55.923434 -68.218812) (xy 55.45455 -68.68795) (xy 55.43777 -68.704094)
			(xy 55.400079 -68.731433) (xy 55.358574 -68.752537) (xy 55.314278 -68.766886) (xy 55.268282 -68.774126)
			(xy 55.245 -68.774564) (xy 54.427882 -68.774564) (xy 54.073975 -69.12864) (xy 55.717946 -69.12864)
			(xy 55.722017 -69.073018) (xy 55.734143 -69.018581) (xy 55.754066 -68.96649) (xy 55.781362 -68.917855)
			(xy 55.815448 -68.873712) (xy 55.855597 -68.835003) (xy 55.900955 -68.802552) (xy 55.950555 -68.777051)
			(xy 56.003339 -68.759044) (xy 56.058182 -68.748914) (xy 56.113916 -68.746877) (xy 56.169353 -68.752977)
			(xy 56.22331 -68.767083) (xy 56.274639 -68.788895) (xy 56.322245 -68.817949) (xy 56.365113 -68.853624)
			(xy 56.40233 -68.895161) (xy 56.433103 -68.941674) (xy 56.456775 -68.992171) (xy 56.472843 -69.045578)
			(xy 56.480963 -69.100754) (xy 56.481472 -69.12864) (xy 56.480963 -69.156526) (xy 56.472843 -69.211702)
			(xy 56.456775 -69.265109) (xy 56.433103 -69.315606) (xy 56.40233 -69.362119) (xy 56.365113 -69.403656)
			(xy 56.322245 -69.439331) (xy 56.274639 -69.468385) (xy 56.22331 -69.490197) (xy 56.169353 -69.504303)
			(xy 56.113916 -69.510403) (xy 56.058182 -69.508366) (xy 56.003339 -69.498236) (xy 55.950555 -69.480229)
			(xy 55.900955 -69.454728) (xy 55.855597 -69.422277) (xy 55.815448 -69.383568) (xy 55.781362 -69.339425)
			(xy 55.754066 -69.29079) (xy 55.734143 -69.238699) (xy 55.722017 -69.184262) (xy 55.717946 -69.12864)
			(xy 54.073975 -69.12864) (xy 53.895244 -69.307456) (xy 53.895244 -69.511926) (xy 54.070758 -69.68744)
			(xy 56.411876 -69.68744)
		)
		(stroke
			(width 0)
			(type solid)
		)
		(fill yes)
		(layer "In2.Cu")
		(net "P2V5_SENSOR")
	)
	(gr_poly
		(pts
			(xy 7.3152 -80.256888) (xy 7.328818 -80.256414) (xy 7.355067 -80.249139) (xy 7.378462 -80.235187)
			(xy 7.397338 -80.215549) (xy 7.410354 -80.191622) (xy 7.416585 -80.165105) (xy 7.416546 -80.151478)
			(xy 7.416292 -80.137) (xy 7.416778 -80.109749) (xy 7.424534 -80.055801) (xy 7.439889 -80.003506)
			(xy 7.462531 -79.953929) (xy 7.491997 -79.908079) (xy 7.527688 -79.866888) (xy 7.568879 -79.831197)
			(xy 7.614729 -79.801731) (xy 7.664306 -79.779089) (xy 7.716601 -79.763734) (xy 7.770549 -79.755978)
			(xy 7.7978 -79.755492) (xy 7.826226 -79.756016) (xy 7.882448 -79.764453) (xy 7.936796 -79.781139)
			(xy 7.988066 -79.805706) (xy 8.035123 -79.83761) (xy 8.076924 -79.876143) (xy 8.112544 -79.920452)
			(xy 8.141195 -79.969557) (xy 8.162241 -80.02237) (xy 8.175216 -80.077722) (xy 8.178038 -80.106012)
			(xy 8.180258 -80.120655) (xy 8.191979 -80.14784) (xy 8.210999 -80.170527) (xy 8.235722 -80.186811)
			(xy 8.264075 -80.195329) (xy 8.278876 -80.195928) (xy 8.854694 -80.195928) (xy 9.014206 -80.036416)
			(xy 9.030975 -80.020245) (xy 9.068651 -79.992851) (xy 9.110152 -79.971693) (xy 9.154454 -79.957294)
			(xy 9.200464 -79.950009) (xy 9.223756 -79.949548) (xy 9.775698 -79.949548) (xy 9.94156 -79.783686)
			(xy 9.951282 -79.773301) (xy 9.965072 -79.748435) (xy 9.971475 -79.72073) (xy 9.969995 -79.692334)
			(xy 9.960745 -79.665446) (xy 9.944444 -79.642149) (xy 9.922352 -79.624246) (xy 9.896183 -79.613126)
			(xy 9.882124 -79.610966) (xy 9.853994 -79.607951) (xy 9.799 -79.594677) (xy 9.746569 -79.573429)
			(xy 9.697849 -79.544673) (xy 9.65391 -79.509038) (xy 9.615714 -79.467306) (xy 9.584098 -79.420391)
			(xy 9.559756 -79.369323) (xy 9.543221 -79.31522) (xy 9.534856 -79.259268) (xy 9.534398 -79.230982)
			(xy 9.534859 -79.203808) (xy 9.542536 -79.150005) (xy 9.557775 -79.097838) (xy 9.580266 -79.048363)
			(xy 9.609554 -79.002583) (xy 9.645046 -78.961425) (xy 9.665208 -78.9432) (xy 9.676521 -78.933489)
			(xy 9.693424 -78.908947) (xy 9.702511 -78.880566) (xy 9.703004 -78.850771) (xy 9.694861 -78.822105)
			(xy 9.678778 -78.797017) (xy 9.667748 -78.78699) (xy 9.64721 -78.768783) (xy 9.611061 -78.727485)
			(xy 9.581207 -78.68143) (xy 9.558263 -78.631571) (xy 9.542706 -78.578938) (xy 9.534854 -78.524618)
			(xy 9.534398 -78.497176) (xy 9.534884 -78.469925) (xy 9.54264 -78.415977) (xy 9.557995 -78.363682)
			(xy 9.580637 -78.314105) (xy 9.610103 -78.268255) (xy 9.645794 -78.227064) (xy 9.686985 -78.191373)
			(xy 9.732835 -78.161907) (xy 9.782412 -78.139265) (xy 9.834707 -78.12391) (xy 9.888655 -78.116154)
			(xy 9.943157 -78.116154) (xy 9.997105 -78.12391) (xy 10.0494 -78.139265) (xy 10.098977 -78.161907)
			(xy 10.144827 -78.191373) (xy 10.186018 -78.227064) (xy 10.221709 -78.268255) (xy 10.251175 -78.314105)
			(xy 10.273817 -78.363682) (xy 10.289172 -78.415977) (xy 10.296928 -78.469925) (xy 10.297414 -78.497176)
			(xy 10.296956 -78.524351) (xy 10.289284 -78.578157) (xy 10.274051 -78.630329) (xy 10.251563 -78.679809)
			(xy 10.222278 -78.725594) (xy 10.186789 -78.766757) (xy 10.166604 -78.784958) (xy 10.155702 -78.794312)
			(xy 10.139168 -78.817787) (xy 10.129832 -78.84494) (xy 10.128433 -78.87362) (xy 10.135082 -78.901553)
			(xy 10.149253 -78.926526) (xy 10.159238 -78.93685) (xy 10.170414 -78.946756) (xy 10.191448 -78.966285)
			(xy 10.227988 -79.010548) (xy 10.257479 -79.059788) (xy 10.279256 -79.112892) (xy 10.292827 -79.168661)
			(xy 10.29589 -79.1972) (xy 10.298103 -79.211246) (xy 10.309231 -79.237401) (xy 10.327131 -79.25948)
			(xy 10.35042 -79.275775) (xy 10.377296 -79.285026) (xy 10.40568 -79.286518) (xy 10.433378 -79.280135)
			(xy 10.458246 -79.26637) (xy 10.46861 -79.256636) (xy 11.049508 -78.675738) (xy 11.049508 -76.51496)
			(xy 11.049945 -76.491668) (xy 11.057243 -76.445661) (xy 11.071653 -76.401362) (xy 11.092819 -76.359866)
			(xy 11.12022 -76.322194) (xy 11.136376 -76.30541) (xy 11.654282 -75.787504) (xy 11.671051 -75.771332)
			(xy 11.708727 -75.743936) (xy 11.750228 -75.722776) (xy 11.79453 -75.708374) (xy 11.84054 -75.701086)
			(xy 11.863832 -75.700636) (xy 12.152376 -75.700636) (xy 12.152376 -74.610976) (xy 12.18311 -74.580496)
			(xy 12.18311 -70.742556) (xy 12.182551 -70.727714) (xy 12.17393 -70.699305) (xy 12.157513 -70.674569)
			(xy 12.134684 -70.65559) (xy 12.107366 -70.643966) (xy 12.07786 -70.640676) (xy 12.048653 -70.645999)
			(xy 12.022205 -70.659484) (xy 12.011152 -70.669404) (xy 11.989513 -70.690472) (xy 11.940817 -70.726192)
			(xy 11.887103 -70.753796) (xy 11.829712 -70.772595) (xy 11.770076 -70.78212) (xy 11.73988 -70.782688)
			(xy 11.712631 -70.7822) (xy 11.658688 -70.774442) (xy 11.606399 -70.759086) (xy 11.556827 -70.736445)
			(xy 11.510981 -70.70698) (xy 11.469796 -70.67129) (xy 11.434108 -70.630103) (xy 11.404646 -70.584256)
			(xy 11.382007 -70.534682) (xy 11.366654 -70.482392) (xy 11.358898 -70.428449) (xy 11.358898 -70.373951)
			(xy 11.366654 -70.320008) (xy 11.382007 -70.267718) (xy 11.404646 -70.218144) (xy 11.434108 -70.172297)
			(xy 11.469796 -70.13111) (xy 11.510981 -70.09542) (xy 11.556827 -70.065955) (xy 11.606399 -70.043314)
			(xy 11.658688 -70.027958) (xy 11.712631 -70.0202) (xy 11.73988 -70.019672) (xy 11.770076 -70.020245)
			(xy 11.829713 -70.029761) (xy 11.887105 -70.048558) (xy 11.940817 -70.076166) (xy 11.989506 -70.111895)
			(xy 12.011152 -70.132956) (xy 12.022225 -70.142867) (xy 12.048671 -70.156395) (xy 12.07789 -70.161747)
			(xy 12.107414 -70.158471) (xy 12.134749 -70.146844) (xy 12.157586 -70.127849) (xy 12.173997 -70.103089)
			(xy 12.182595 -70.074655) (xy 12.18311 -70.059804) (xy 12.18311 -68.09359) (xy 11.476228 -67.386708)
			(xy 11.476228 -59.406028) (xy 8.6106 -56.5404) (xy 8.6106 -53.1368) (xy 11.811 -49.9364) (xy 11.811 -48.387)
			(xy 13.659612 -46.538388) (xy 13.659612 -33.291272) (xy 13.539216 -33.170876) (xy 13.511276 -33.19272)
			(xy 13.490666 -33.209165) (xy 13.445779 -33.236825) (xy 13.397512 -33.258045) (xy 13.346784 -33.27242)
			(xy 13.294561 -33.279676) (xy 13.268198 -33.280096) (xy 13.237821 -33.279509) (xy 13.177834 -33.26989)
			(xy 13.120126 -33.250895) (xy 13.066154 -33.223002) (xy 13.041376 -33.20542) (xy 13.029264 -33.19752)
			(xy 13.001907 -33.18819) (xy 12.973031 -33.18691) (xy 12.944956 -33.193784) (xy 12.919938 -33.208259)
			(xy 12.899985 -33.229171) (xy 12.886701 -33.254842) (xy 12.883388 -33.26892) (xy 12.878883 -33.295694)
			(xy 12.863294 -33.347701) (xy 12.840495 -33.396975) (xy 12.810946 -33.442522) (xy 12.775243 -33.483425)
			(xy 12.734106 -33.518858) (xy 12.688364 -33.548106) (xy 12.638941 -33.570579) (xy 12.586833 -33.585826)
			(xy 12.53309 -33.593537) (xy 12.505944 -33.59404) (xy 12.478688 -33.59358) (xy 12.424731 -33.585828)
			(xy 12.372426 -33.570477) (xy 12.322838 -33.547837) (xy 12.276977 -33.518371) (xy 12.235776 -33.482677)
			(xy 12.200075 -33.441484) (xy 12.170599 -33.395629) (xy 12.14795 -33.346046) (xy 12.132588 -33.293744)
			(xy 12.124825 -33.239788) (xy 12.124436 -33.212532) (xy 12.124985 -33.183482) (xy 12.133802 -33.126054)
			(xy 12.15122 -33.070625) (xy 12.176839 -33.018477) (xy 12.210066 -32.970815) (xy 12.250133 -32.928739)
			(xy 12.272772 -32.910526) (xy 12.284328 -32.900541) (xy 12.301361 -32.875208) (xy 12.310151 -32.845974)
			(xy 12.309912 -32.815448) (xy 12.300667 -32.786354) (xy 12.28324 -32.76129) (xy 12.271502 -32.751522)
			(xy 12.249019 -32.733331) (xy 12.209282 -32.691314) (xy 12.176344 -32.643779) (xy 12.150959 -32.591817)
			(xy 12.133709 -32.536618) (xy 12.124989 -32.479448) (xy 12.124436 -32.450532) (xy 12.124828 -32.42664)
			(xy 12.130829 -32.379233) (xy 12.142693 -32.332944) (xy 12.151106 -32.310578) (xy 12.155048 -32.297385)
			(xy 12.156502 -32.269899) (xy 12.150558 -32.243024) (xy 12.137647 -32.218715) (xy 12.118709 -32.198742)
			(xy 12.095122 -32.184555) (xy 12.068602 -32.177189) (xy 12.05484 -32.17672) (xy 10.798048 -32.17672)
			(xy 10.784302 -32.177217) (xy 10.757826 -32.184635) (xy 10.734283 -32.198839) (xy 10.715375 -32.218802)
			(xy 10.702471 -32.243081) (xy 10.696501 -32.269921) (xy 10.697899 -32.297381) (xy 10.701782 -32.310578)
			(xy 10.710499 -32.33363) (xy 10.722607 -32.381405) (xy 10.725912 -32.405828) (xy 10.72642 -32.410654)
			(xy 10.727386 -32.420595) (xy 10.728403 -32.440544) (xy 10.728452 -32.450532) (xy 10.727905 -32.479583)
			(xy 10.719093 -32.537014) (xy 10.701678 -32.592446) (xy 10.676062 -32.644597) (xy 10.642837 -32.692263)
			(xy 10.60277 -32.734342) (xy 10.580116 -32.752538) (xy 10.568571 -32.762523) (xy 10.551558 -32.787851)
			(xy 10.542786 -32.817074) (xy 10.543036 -32.847584) (xy 10.552287 -32.876658) (xy 10.569713 -32.901703)
			(xy 10.581386 -32.911542) (xy 10.603872 -32.929731) (xy 10.643613 -32.971748) (xy 10.676557 -33.019282)
			(xy 10.701948 -33.071244) (xy 10.719203 -33.126443) (xy 10.727929 -33.183615) (xy 10.728452 -33.212532)
			(xy 10.727966 -33.239783) (xy 10.72021 -33.293731) (xy 10.704855 -33.346026) (xy 10.682213 -33.395603)
			(xy 10.652747 -33.441453) (xy 10.617056 -33.482644) (xy 10.575865 -33.518335) (xy 10.530015 -33.547801)
			(xy 10.480438 -33.570443) (xy 10.428143 -33.585798) (xy 10.374195 -33.593554) (xy 10.319693 -33.593554)
			(xy 10.265745 -33.585798) (xy 10.21345 -33.570443) (xy 10.163873 -33.547801) (xy 10.118023 -33.518335)
			(xy 10.076832 -33.482644) (xy 10.041141 -33.441453) (xy 10.011675 -33.395603) (xy 9.989033 -33.346026)
			(xy 9.973678 -33.293731) (xy 9.965922 -33.239783) (xy 9.965436 -33.212532) (xy 9.965985 -33.183482)
			(xy 9.974802 -33.126054) (xy 9.99222 -33.070625) (xy 10.017839 -33.018477) (xy 10.051066 -32.970815)
			(xy 10.091133 -32.928739) (xy 10.113772 -32.910526) (xy 10.125328 -32.900541) (xy 10.142361 -32.875208)
			(xy 10.151151 -32.845974) (xy 10.150912 -32.815448) (xy 10.141667 -32.786354) (xy 10.12424 -32.76129)
			(xy 10.112502 -32.751522) (xy 10.090019 -32.733331) (xy 10.050282 -32.691314) (xy 10.017344 -32.643779)
			(xy 9.991959 -32.591817) (xy 9.974709 -32.536618) (xy 9.965989 -32.479448) (xy 9.965436 -32.450532)
			(xy 9.965828 -32.42664) (xy 9.971829 -32.379233) (xy 9.983693 -32.332944) (xy 9.992106 -32.310578)
			(xy 9.996048 -32.297385) (xy 9.997502 -32.269899) (xy 9.991558 -32.243024) (xy 9.978647 -32.218715)
			(xy 9.959709 -32.198742) (xy 9.936122 -32.184555) (xy 9.909602 -32.177189) (xy 9.89584 -32.17672)
			(xy 8.639048 -32.17672) (xy 8.625302 -32.177217) (xy 8.598826 -32.184635) (xy 8.575283 -32.198839)
			(xy 8.556375 -32.218802) (xy 8.543471 -32.243081) (xy 8.537501 -32.269921) (xy 8.538899 -32.297381)
			(xy 8.542782 -32.310578) (xy 8.551499 -32.33363) (xy 8.563607 -32.381405) (xy 8.566912 -32.405828)
			(xy 8.56742 -32.410654) (xy 8.568386 -32.420595) (xy 8.569403 -32.440544) (xy 8.569452 -32.450532)
			(xy 8.568905 -32.479583) (xy 8.560093 -32.537014) (xy 8.542678 -32.592446) (xy 8.517062 -32.644597)
			(xy 8.483837 -32.692263) (xy 8.44377 -32.734342) (xy 8.421116 -32.752538) (xy 8.409571 -32.762523)
			(xy 8.392558 -32.787851) (xy 8.383786 -32.817074) (xy 8.384036 -32.847584) (xy 8.393287 -32.876658)
			(xy 8.410713 -32.901703) (xy 8.422386 -32.911542) (xy 8.444872 -32.929731) (xy 8.484613 -32.971748)
			(xy 8.517557 -33.019282) (xy 8.542948 -33.071244) (xy 8.560203 -33.126443) (xy 8.568929 -33.183615)
			(xy 8.569452 -33.212532) (xy 8.568966 -33.239783) (xy 8.56121 -33.293731) (xy 8.545855 -33.346026)
			(xy 8.523213 -33.395603) (xy 8.493747 -33.441453) (xy 8.458056 -33.482644) (xy 8.416865 -33.518335)
			(xy 8.371015 -33.547801) (xy 8.321438 -33.570443) (xy 8.269143 -33.585798) (xy 8.215195 -33.593554)
			(xy 8.160693 -33.593554) (xy 8.106745 -33.585798) (xy 8.05445 -33.570443) (xy 8.004873 -33.547801)
			(xy 7.959023 -33.518335) (xy 7.917832 -33.482644) (xy 7.882141 -33.441453) (xy 7.852675 -33.395603)
			(xy 7.830033 -33.346026) (xy 7.814678 -33.293731) (xy 7.806922 -33.239783) (xy 7.806436 -33.212532)
			(xy 7.806985 -33.183482) (xy 7.815802 -33.126054) (xy 7.83322 -33.070625) (xy 7.858839 -33.018477)
			(xy 7.892066 -32.970815) (xy 7.932133 -32.928739) (xy 7.954772 -32.910526) (xy 7.966328 -32.900541)
			(xy 7.983361 -32.875208) (xy 7.992151 -32.845974) (xy 7.991912 -32.815448) (xy 7.982667 -32.786354)
			(xy 7.96524 -32.76129) (xy 7.953502 -32.751522) (xy 7.931019 -32.733331) (xy 7.891282 -32.691314)
			(xy 7.858344 -32.643779) (xy 7.832959 -32.591817) (xy 7.815709 -32.536618) (xy 7.806989 -32.479448)
			(xy 7.806436 -32.450532) (xy 7.806828 -32.42664) (xy 7.812829 -32.379233) (xy 7.824693 -32.332944)
			(xy 7.833106 -32.310578) (xy 7.837048 -32.297385) (xy 7.838502 -32.269899) (xy 7.832558 -32.243024)
			(xy 7.819647 -32.218715) (xy 7.800709 -32.198742) (xy 7.777122 -32.184555) (xy 7.750602 -32.177189)
			(xy 7.73684 -32.17672) (xy 6.480048 -32.17672) (xy 6.466302 -32.177217) (xy 6.439826 -32.184635)
			(xy 6.416283 -32.198839) (xy 6.397375 -32.218802) (xy 6.384471 -32.243081) (xy 6.378501 -32.269921)
			(xy 6.379899 -32.297381) (xy 6.383782 -32.310578) (xy 6.392499 -32.33363) (xy 6.404607 -32.381405)
			(xy 6.407912 -32.405828) (xy 6.40842 -32.410654) (xy 6.409386 -32.420595) (xy 6.410403 -32.440544)
			(xy 6.410452 -32.450532) (xy 6.409905 -32.479583) (xy 6.401093 -32.537014) (xy 6.383678 -32.592446)
			(xy 6.358062 -32.644597) (xy 6.324837 -32.692263) (xy 6.28477 -32.734342) (xy 6.262116 -32.752538)
			(xy 6.250571 -32.762523) (xy 6.233558 -32.787851) (xy 6.224786 -32.817074) (xy 6.225036 -32.847584)
			(xy 6.234287 -32.876658) (xy 6.251713 -32.901703) (xy 6.263386 -32.911542) (xy 6.285872 -32.929731)
			(xy 6.325613 -32.971748) (xy 6.358557 -33.019282) (xy 6.383948 -33.071244) (xy 6.401203 -33.126443)
			(xy 6.409929 -33.183615) (xy 6.410452 -33.212532) (xy 6.409966 -33.239783) (xy 6.40221 -33.293731)
			(xy 6.386855 -33.346026) (xy 6.364213 -33.395603) (xy 6.334747 -33.441453) (xy 6.299056 -33.482644)
			(xy 6.257865 -33.518335) (xy 6.212015 -33.547801) (xy 6.162438 -33.570443) (xy 6.110143 -33.585798)
			(xy 6.056195 -33.593554) (xy 6.001693 -33.593554) (xy 5.947745 -33.585798) (xy 5.89545 -33.570443)
			(xy 5.845873 -33.547801) (xy 5.800023 -33.518335) (xy 5.758832 -33.482644) (xy 5.723141 -33.441453)
			(xy 5.693675 -33.395603) (xy 5.671033 -33.346026) (xy 5.655678 -33.293731) (xy 5.647922 -33.239783)
			(xy 5.647436 -33.212532) (xy 5.647985 -33.183482) (xy 5.656802 -33.126054) (xy 5.67422 -33.070625)
			(xy 5.699839 -33.018477) (xy 5.733066 -32.970815) (xy 5.773133 -32.928739) (xy 5.795772 -32.910526)
			(xy 5.807328 -32.900541) (xy 5.824361 -32.875208) (xy 5.833151 -32.845974) (xy 5.832912 -32.815448)
			(xy 5.823667 -32.786354) (xy 5.80624 -32.76129) (xy 5.794502 -32.751522) (xy 5.772019 -32.733331)
			(xy 5.732282 -32.691314) (xy 5.699344 -32.643779) (xy 5.673959 -32.591817) (xy 5.656709 -32.536618)
			(xy 5.647989 -32.479448) (xy 5.647436 -32.450532) (xy 5.647828 -32.42664) (xy 5.653829 -32.379233)
			(xy 5.665693 -32.332944) (xy 5.674106 -32.310578) (xy 5.678048 -32.297385) (xy 5.679502 -32.269899)
			(xy 5.673558 -32.243024) (xy 5.660647 -32.218715) (xy 5.641709 -32.198742) (xy 5.618122 -32.184555)
			(xy 5.591602 -32.177189) (xy 5.57784 -32.17672) (xy 5.176774 -32.17672) (xy 3.866134 -33.48736) (xy 3.866134 -47.60468)
			(xy 4.469382 -47.60468) (xy 4.473453 -47.549058) (xy 4.485579 -47.494621) (xy 4.505502 -47.44253)
			(xy 4.532798 -47.393895) (xy 4.566884 -47.349752) (xy 4.607033 -47.311043) (xy 4.652391 -47.278592)
			(xy 4.701991 -47.253091) (xy 4.754775 -47.235084) (xy 4.809618 -47.224954) (xy 4.865352 -47.222917)
			(xy 4.920789 -47.229017) (xy 4.974746 -47.243123) (xy 5.026075 -47.264935) (xy 5.073681 -47.293989)
			(xy 5.116549 -47.329664) (xy 5.153766 -47.371201) (xy 5.184539 -47.417714) (xy 5.208211 -47.468211)
			(xy 5.224279 -47.521618) (xy 5.232399 -47.576794) (xy 5.232908 -47.60468) (xy 5.232399 -47.632566)
			(xy 5.224279 -47.687742) (xy 5.208211 -47.741149) (xy 5.184539 -47.791646) (xy 5.153766 -47.838159)
			(xy 5.116549 -47.879696) (xy 5.073681 -47.915371) (xy 5.026075 -47.944425) (xy 4.974746 -47.966237)
			(xy 4.920789 -47.980343) (xy 4.865352 -47.986443) (xy 4.809618 -47.984406) (xy 4.754775 -47.974276)
			(xy 4.701991 -47.956269) (xy 4.652391 -47.930768) (xy 4.607033 -47.898317) (xy 4.566884 -47.859608)
			(xy 4.532798 -47.815465) (xy 4.505502 -47.76683) (xy 4.485579 -47.714739) (xy 4.473453 -47.660302)
			(xy 4.469382 -47.60468) (xy 3.866134 -47.60468) (xy 3.866134 -48.2346) (xy 4.196334 -48.5648) (xy 5.0038 -48.5648)
			(xy 5.8166 -49.3776) (xy 5.8166 -49.78146) (xy 9.627614 -49.78146) (xy 9.631685 -49.725838) (xy 9.643811 -49.671401)
			(xy 9.663734 -49.61931) (xy 9.69103 -49.570675) (xy 9.725116 -49.526532) (xy 9.765265 -49.487823)
			(xy 9.810623 -49.455372) (xy 9.860223 -49.429871) (xy 9.913007 -49.411864) (xy 9.96785 -49.401734)
			(xy 10.023584 -49.399697) (xy 10.079021 -49.405797) (xy 10.132978 -49.419903) (xy 10.184307 -49.441715)
			(xy 10.231913 -49.470769) (xy 10.274781 -49.506444) (xy 10.311998 -49.547981) (xy 10.342771 -49.594494)
			(xy 10.366443 -49.644991) (xy 10.382511 -49.698398) (xy 10.390631 -49.753574) (xy 10.39114 -49.78146)
			(xy 10.390631 -49.809346) (xy 10.382511 -49.864522) (xy 10.366443 -49.917929) (xy 10.342771 -49.968426)
			(xy 10.311998 -50.014939) (xy 10.274781 -50.056476) (xy 10.231913 -50.092151) (xy 10.184307 -50.121205)
			(xy 10.132978 -50.143017) (xy 10.079021 -50.157123) (xy 10.023584 -50.163223) (xy 9.96785 -50.161186)
			(xy 9.913007 -50.151056) (xy 9.860223 -50.133049) (xy 9.810623 -50.107548) (xy 9.765265 -50.075097)
			(xy 9.725116 -50.036388) (xy 9.69103 -49.992245) (xy 9.663734 -49.94361) (xy 9.643811 -49.891519)
			(xy 9.631685 -49.837082) (xy 9.627614 -49.78146) (xy 5.8166 -49.78146) (xy 5.8166 -56.1848) (xy 6.0706 -56.4388)
			(xy 6.0706 -58.2168) (xy 5.8166 -58.4708) (xy 4.120134 -58.4708) (xy 3.866134 -58.7248) (xy 3.866134 -61.2648)
			(xy 8.660892 -61.2648) (xy 8.661375 -61.235881) (xy 8.670107 -61.178707) (xy 8.687369 -61.123506)
			(xy 8.712767 -61.071544) (xy 8.745719 -61.024011) (xy 8.785468 -60.981997) (xy 8.807958 -60.96381)
			(xy 8.819766 -60.953914) (xy 8.837288 -60.928591) (xy 8.846467 -60.899197) (xy 8.846467 -60.868403)
			(xy 8.837288 -60.839009) (xy 8.819766 -60.813686) (xy 8.807958 -60.80379) (xy 8.785461 -60.785615)
			(xy 8.745729 -60.743591) (xy 8.712792 -60.696052) (xy 8.687407 -60.644088) (xy 8.670153 -60.588888)
			(xy 8.661426 -60.531717) (xy 8.660892 -60.5028) (xy 8.661378 -60.475549) (xy 8.669134 -60.421601)
			(xy 8.684489 -60.369306) (xy 8.707131 -60.319729) (xy 8.736597 -60.273879) (xy 8.772288 -60.232688)
			(xy 8.813479 -60.196997) (xy 8.859329 -60.167531) (xy 8.908906 -60.144889) (xy 8.961201 -60.129534)
			(xy 9.015149 -60.121778) (xy 9.069651 -60.121778) (xy 9.123599 -60.129534) (xy 9.175894 -60.144889)
			(xy 9.225471 -60.167531) (xy 9.271321 -60.196997) (xy 9.312512 -60.232688) (xy 9.348203 -60.273879)
			(xy 9.377669 -60.319729) (xy 9.400311 -60.369306) (xy 9.415666 -60.421601) (xy 9.423422 -60.475549)
			(xy 9.423908 -60.5028) (xy 9.423425 -60.531719) (xy 9.414693 -60.588893) (xy 9.397431 -60.644094)
			(xy 9.372033 -60.696056) (xy 9.339081 -60.743589) (xy 9.299332 -60.785603) (xy 9.276842 -60.80379)
			(xy 9.265034 -60.813686) (xy 9.247512 -60.839009) (xy 9.238333 -60.868403) (xy 9.238333 -60.899197)
			(xy 9.247512 -60.928591) (xy 9.265034 -60.953914) (xy 9.276842 -60.96381) (xy 9.299339 -60.981985)
			(xy 9.339071 -61.024009) (xy 9.372008 -61.071548) (xy 9.397393 -61.123512) (xy 9.414647 -61.178712)
			(xy 9.423374 -61.235883) (xy 9.423908 -61.2648) (xy 9.423422 -61.292051) (xy 9.415666 -61.345999)
			(xy 9.400311 -61.398294) (xy 9.377669 -61.447871) (xy 9.348203 -61.493721) (xy 9.312512 -61.534912)
			(xy 9.271321 -61.570603) (xy 9.225471 -61.600069) (xy 9.175894 -61.622711) (xy 9.123599 -61.638066)
			(xy 9.069651 -61.645822) (xy 9.015149 -61.645822) (xy 8.961201 -61.638066) (xy 8.908906 -61.622711)
			(xy 8.859329 -61.600069) (xy 8.813479 -61.570603) (xy 8.772288 -61.534912) (xy 8.736597 -61.493721)
			(xy 8.707131 -61.447871) (xy 8.684489 -61.398294) (xy 8.669134 -61.345999) (xy 8.661378 -61.292051)
			(xy 8.660892 -61.2648) (xy 3.866134 -61.2648) (xy 3.866134 -63.2206) (xy 10.057382 -63.2206) (xy 10.061453 -63.164978)
			(xy 10.073579 -63.110541) (xy 10.093502 -63.05845) (xy 10.120798 -63.009815) (xy 10.154884 -62.965672)
			(xy 10.195033 -62.926963) (xy 10.240391 -62.894512) (xy 10.289991 -62.869011) (xy 10.342775 -62.851004)
			(xy 10.397618 -62.840874) (xy 10.453352 -62.838837) (xy 10.508789 -62.844937) (xy 10.562746 -62.859043)
			(xy 10.614075 -62.880855) (xy 10.661681 -62.909909) (xy 10.704549 -62.945584) (xy 10.741766 -62.987121)
			(xy 10.772539 -63.033634) (xy 10.796211 -63.084131) (xy 10.812279 -63.137538) (xy 10.820399 -63.192714)
			(xy 10.820908 -63.2206) (xy 10.820399 -63.248486) (xy 10.812279 -63.303662) (xy 10.796211 -63.357069)
			(xy 10.772539 -63.407566) (xy 10.741766 -63.454079) (xy 10.704549 -63.495616) (xy 10.661681 -63.531291)
			(xy 10.614075 -63.560345) (xy 10.562746 -63.582157) (xy 10.508789 -63.596263) (xy 10.453352 -63.602363)
			(xy 10.397618 -63.600326) (xy 10.342775 -63.590196) (xy 10.289991 -63.572189) (xy 10.240391 -63.546688)
			(xy 10.195033 -63.514237) (xy 10.154884 -63.475528) (xy 10.120798 -63.431385) (xy 10.093502 -63.38275)
			(xy 10.073579 -63.330659) (xy 10.061453 -63.276222) (xy 10.057382 -63.2206) (xy 3.866134 -63.2206)
			(xy 3.866134 -63.733934) (xy 4.75996 -64.62776) (xy 4.75996 -65.726818) (xy 5.893052 -65.726818)
			(xy 5.897123 -65.671196) (xy 5.909249 -65.616759) (xy 5.929172 -65.564668) (xy 5.956468 -65.516033)
			(xy 5.990554 -65.47189) (xy 6.030703 -65.433181) (xy 6.076061 -65.40073) (xy 6.125661 -65.375229)
			(xy 6.178445 -65.357222) (xy 6.233288 -65.347092) (xy 6.289022 -65.345055) (xy 6.344459 -65.351155)
			(xy 6.398416 -65.365261) (xy 6.449745 -65.387073) (xy 6.497351 -65.416127) (xy 6.540219 -65.451802)
			(xy 6.577436 -65.493339) (xy 6.608209 -65.539852) (xy 6.631881 -65.590349) (xy 6.647949 -65.643756)
			(xy 6.656069 -65.698932) (xy 6.656578 -65.726818) (xy 6.656393 -65.736978) (xy 9.139172 -65.736978)
			(xy 9.143243 -65.681356) (xy 9.155369 -65.626919) (xy 9.175292 -65.574828) (xy 9.202588 -65.526193)
			(xy 9.236674 -65.48205) (xy 9.276823 -65.443341) (xy 9.322181 -65.41089) (xy 9.371781 -65.385389)
			(xy 9.424565 -65.367382) (xy 9.479408 -65.357252) (xy 9.535142 -65.355215) (xy 9.590579 -65.361315)
			(xy 9.644536 -65.375421) (xy 9.695865 -65.397233) (xy 9.743471 -65.426287) (xy 9.786339 -65.461962)
			(xy 9.823556 -65.503499) (xy 9.854329 -65.550012) (xy 9.878001 -65.600509) (xy 9.894069 -65.653916)
			(xy 9.902189 -65.709092) (xy 9.902698 -65.736978) (xy 9.902189 -65.764864) (xy 9.894069 -65.82004)
			(xy 9.878001 -65.873447) (xy 9.854329 -65.923944) (xy 9.823556 -65.970457) (xy 9.786339 -66.011994)
			(xy 9.743471 -66.047669) (xy 9.695865 -66.076723) (xy 9.644536 -66.098535) (xy 9.590579 -66.112641)
			(xy 9.535142 -66.118741) (xy 9.479408 -66.116704) (xy 9.424565 -66.106574) (xy 9.371781 -66.088567)
			(xy 9.322181 -66.063066) (xy 9.276823 -66.030615) (xy 9.236674 -65.991906) (xy 9.202588 -65.947763)
			(xy 9.175292 -65.899128) (xy 9.155369 -65.847037) (xy 9.143243 -65.7926) (xy 9.139172 -65.736978)
			(xy 6.656393 -65.736978) (xy 6.656069 -65.754704) (xy 6.647949 -65.80988) (xy 6.631881 -65.863287)
			(xy 6.608209 -65.913784) (xy 6.577436 -65.960297) (xy 6.540219 -66.001834) (xy 6.497351 -66.037509)
			(xy 6.449745 -66.066563) (xy 6.398416 -66.088375) (xy 6.344459 -66.102481) (xy 6.289022 -66.108581)
			(xy 6.233288 -66.106544) (xy 6.178445 -66.096414) (xy 6.125661 -66.078407) (xy 6.076061 -66.052906)
			(xy 6.030703 -66.020455) (xy 5.990554 -65.981746) (xy 5.956468 -65.937603) (xy 5.929172 -65.888968)
			(xy 5.909249 -65.836877) (xy 5.897123 -65.78244) (xy 5.893052 -65.726818) (xy 4.75996 -65.726818)
			(xy 4.75996 -65.931034) (xy 3.866134 -66.82486) (xy 3.866134 -76.11491) (xy 3.866642 -76.118466)
			(xy 3.868377 -76.131415) (xy 3.870283 -76.157473) (xy 3.870452 -76.170536) (xy 3.870452 -76.172314)
			(xy 3.870329 -76.185822) (xy 3.868419 -76.212771) (xy 3.866642 -76.226162) (xy 3.866134 -76.229718)
			(xy 3.866134 -76.975716) (xy 3.866642 -76.979272) (xy 3.868377 -76.992221) (xy 3.870283 -77.018279)
			(xy 3.870452 -77.031342) (xy 3.870452 -77.03312) (xy 3.870333 -77.046628) (xy 3.868429 -77.073578)
			(xy 3.866642 -77.086968) (xy 3.866134 -77.090524) (xy 3.866134 -77.375004) (xy 5.26669 -77.375004)
			(xy 5.267155 -77.348782) (xy 5.274351 -77.296833) (xy 5.288592 -77.246359) (xy 5.309612 -77.198311)
			(xy 5.337014 -77.153595) (xy 5.370281 -77.113052) (xy 5.408787 -77.077447) (xy 5.451807 -77.047451)
			(xy 5.47497 -77.035152) (xy 5.487246 -77.028409) (xy 5.507814 -77.009413) (xy 5.52245 -76.985545)
			(xy 5.530054 -76.958599) (xy 5.530054 -76.930601) (xy 5.522451 -76.903656) (xy 5.507815 -76.879788)
			(xy 5.487247 -76.860792) (xy 5.47497 -76.85405) (xy 5.451797 -76.841763) (xy 5.408762 -76.811779)
			(xy 5.370242 -76.77618) (xy 5.336965 -76.735637) (xy 5.309558 -76.690917) (xy 5.288539 -76.642862)
			(xy 5.274304 -76.59238) (xy 5.267123 -76.540423) (xy 5.26669 -76.514198) (xy 5.267176 -76.486947)
			(xy 5.274932 -76.432999) (xy 5.290287 -76.380704) (xy 5.312929 -76.331127) (xy 5.342395 -76.285277)
			(xy 5.378086 -76.244086) (xy 5.419277 -76.208395) (xy 5.465127 -76.178929) (xy 5.514704 -76.156287)
			(xy 5.566999 -76.140932) (xy 5.620947 -76.133176) (xy 5.675449 -76.133176) (xy 5.729397 -76.140932)
			(xy 5.781692 -76.156287) (xy 5.831269 -76.178929) (xy 5.877119 -76.208395) (xy 5.91831 -76.244086)
			(xy 5.954001 -76.285277) (xy 5.983467 -76.331127) (xy 6.006109 -76.380704) (xy 6.021464 -76.432999)
			(xy 6.02922 -76.486947) (xy 6.029706 -76.514198) (xy 6.029244 -76.54042) (xy 6.022049 -76.592369)
			(xy 6.007807 -76.642843) (xy 5.986786 -76.690891) (xy 5.959384 -76.735608) (xy 5.926116 -76.776151)
			(xy 5.88761 -76.811756) (xy 5.84459 -76.841752) (xy 5.821426 -76.85405) (xy 5.809187 -76.86082) (xy 5.788698 -76.879844)
			(xy 5.774124 -76.903705) (xy 5.766554 -76.930621) (xy 5.766555 -76.95858) (xy 5.774124 -76.985496)
			(xy 5.788698 -77.009357) (xy 5.809188 -77.028381) (xy 5.821426 -77.035152) (xy 5.844599 -77.04744)
			(xy 5.887634 -77.077423) (xy 5.926154 -77.113022) (xy 5.959432 -77.153564) (xy 5.986839 -77.198285)
			(xy 6.007858 -77.24634) (xy 6.022092 -77.296822) (xy 6.029273 -77.348779) (xy 6.029605 -77.368908)
			(xy 7.400544 -77.368908) (xy 7.401038 -77.342687) (xy 7.408231 -77.290741) (xy 7.422471 -77.240269)
			(xy 7.443487 -77.192222) (xy 7.470885 -77.147506) (xy 7.504147 -77.106962) (xy 7.542649 -77.071356)
			(xy 7.585663 -77.041357) (xy 7.608824 -77.029056) (xy 7.621101 -77.02231) (xy 7.641677 -77.003319)
			(xy 7.656321 -76.979451) (xy 7.663929 -76.952503) (xy 7.663929 -76.924502) (xy 7.656322 -76.897553)
			(xy 7.64168 -76.873685) (xy 7.621104 -76.854693) (xy 7.608824 -76.847954) (xy 7.585654 -76.835662)
			(xy 7.542618 -76.805679) (xy 7.504098 -76.770081) (xy 7.470821 -76.729539) (xy 7.443414 -76.684819)
			(xy 7.422394 -76.636765) (xy 7.408159 -76.586283) (xy 7.400977 -76.534327) (xy 7.400544 -76.508102)
			(xy 7.40103 -76.480851) (xy 7.408786 -76.426903) (xy 7.424141 -76.374608) (xy 7.446783 -76.325031)
			(xy 7.476249 -76.279181) (xy 7.51194 -76.23799) (xy 7.553131 -76.202299) (xy 7.598981 -76.172833)
			(xy 7.648558 -76.150191) (xy 7.700853 -76.134836) (xy 7.754801 -76.12708) (xy 7.809303 -76.12708)
			(xy 7.863251 -76.134836) (xy 7.915546 -76.150191) (xy 7.965123 -76.172833) (xy 8.010973 -76.202299)
			(xy 8.052164 -76.23799) (xy 8.087855 -76.279181) (xy 8.117321 -76.325031) (xy 8.139963 -76.374608)
			(xy 8.155318 -76.426903) (xy 8.163074 -76.480851) (xy 8.16356 -76.508102) (xy 8.163072 -76.534323)
			(xy 8.155877 -76.58627) (xy 8.141637 -76.636742) (xy 8.12062 -76.684788) (xy 8.093221 -76.729505)
			(xy 8.059958 -76.770048) (xy 8.021456 -76.805654) (xy 7.978441 -76.835653) (xy 7.95528 -76.847954)
			(xy 7.943032 -76.854714) (xy 7.922532 -76.873736) (xy 7.90795 -76.897599) (xy 7.900376 -76.924519)
			(xy 7.900377 -76.952485) (xy 7.907952 -76.979405) (xy 7.922535 -77.003268) (xy 7.943036 -77.022288)
			(xy 7.95528 -77.029056) (xy 7.978451 -77.041346) (xy 8.021486 -77.07133) (xy 8.060006 -77.106928)
			(xy 8.093284 -77.14747) (xy 8.120691 -77.19219) (xy 8.14171 -77.240245) (xy 8.154785 -77.286612)
			(xy 9.534398 -77.286612) (xy 9.534894 -77.257996) (xy 9.543435 -77.201406) (xy 9.560341 -77.146729)
			(xy 9.585234 -77.095195) (xy 9.617552 -77.047962) (xy 9.656569 -77.006092) (xy 9.67867 -76.987908)
			(xy 9.690366 -76.978038) (xy 9.707665 -76.952806) (xy 9.716718 -76.923583) (xy 9.716714 -76.892991)
			(xy 9.707653 -76.863771) (xy 9.690348 -76.838543) (xy 9.67867 -76.82865) (xy 9.656589 -76.810445)
			(xy 9.617585 -76.768571) (xy 9.585275 -76.721339) (xy 9.560384 -76.66981) (xy 9.54347 -76.615141)
			(xy 9.534914 -76.558559) (xy 9.534398 -76.529946) (xy 9.534884 -76.502695) (xy 9.54264 -76.448747)
			(xy 9.557995 -76.396452) (xy 9.580637 -76.346875) (xy 9.610103 -76.301025) (xy 9.645794 -76.259834)
			(xy 9.686985 -76.224143) (xy 9.732835 -76.194677) (xy 9.782412 -76.172035) (xy 9.834707 -76.15668)
			(xy 9.888655 -76.148924) (xy 9.943157 -76.148924) (xy 9.997105 -76.15668) (xy 10.0494 -76.172035)
			(xy 10.098977 -76.194677) (xy 10.144827 -76.224143) (xy 10.186018 -76.259834) (xy 10.221709 -76.301025)
			(xy 10.251175 -76.346875) (xy 10.273817 -76.396452) (xy 10.289172 -76.448747) (xy 10.296928 -76.502695)
			(xy 10.297414 -76.529946) (xy 10.296883 -76.55856) (xy 10.288349 -76.615149) (xy 10.271449 -76.669825)
			(xy 10.246563 -76.721359) (xy 10.214251 -76.768593) (xy 10.17524 -76.810464) (xy 10.153142 -76.82865)
			(xy 10.141588 -76.838638) (xy 10.124398 -76.863859) (xy 10.115402 -76.893026) (xy 10.115398 -76.923548)
			(xy 10.124386 -76.952717) (xy 10.14157 -76.977943) (xy 10.153142 -76.987908) (xy 10.175205 -77.006133)
			(xy 10.21421 -77.048004) (xy 10.246522 -77.095231) (xy 10.271416 -77.146756) (xy 10.288334 -77.201421)
			(xy 10.296895 -77.258) (xy 10.297414 -77.286612) (xy 10.296928 -77.313863) (xy 10.289172 -77.367811)
			(xy 10.273817 -77.420106) (xy 10.251175 -77.469683) (xy 10.221709 -77.515533) (xy 10.186018 -77.556724)
			(xy 10.144827 -77.592415) (xy 10.098977 -77.621881) (xy 10.0494 -77.644523) (xy 9.997105 -77.659878)
			(xy 9.943157 -77.667634) (xy 9.888655 -77.667634) (xy 9.834707 -77.659878) (xy 9.782412 -77.644523)
			(xy 9.732835 -77.621881) (xy 9.686985 -77.592415) (xy 9.645794 -77.556724) (xy 9.610103 -77.515533)
			(xy 9.580637 -77.469683) (xy 9.557995 -77.420106) (xy 9.54264 -77.367811) (xy 9.534884 -77.313863)
			(xy 9.534398 -77.286612) (xy 8.154785 -77.286612) (xy 8.155945 -77.290726) (xy 8.163127 -77.342683)
			(xy 8.16356 -77.368908) (xy 8.163074 -77.396159) (xy 8.155318 -77.450107) (xy 8.139963 -77.502402)
			(xy 8.117321 -77.551979) (xy 8.087855 -77.597829) (xy 8.052164 -77.63902) (xy 8.010973 -77.674711)
			(xy 7.965123 -77.704177) (xy 7.915546 -77.726819) (xy 7.863251 -77.742174) (xy 7.809303 -77.74993)
			(xy 7.754801 -77.74993) (xy 7.700853 -77.742174) (xy 7.648558 -77.726819) (xy 7.598981 -77.704177)
			(xy 7.553131 -77.674711) (xy 7.51194 -77.63902) (xy 7.476249 -77.597829) (xy 7.446783 -77.551979)
			(xy 7.424141 -77.502402) (xy 7.408786 -77.450107) (xy 7.40103 -77.396159) (xy 7.400544 -77.368908)
			(xy 6.029605 -77.368908) (xy 6.029706 -77.375004) (xy 6.02922 -77.402255) (xy 6.021464 -77.456203)
			(xy 6.006109 -77.508498) (xy 5.983467 -77.558075) (xy 5.954001 -77.603925) (xy 5.91831 -77.645116)
			(xy 5.877119 -77.680807) (xy 5.831269 -77.710273) (xy 5.781692 -77.732915) (xy 5.729397 -77.74827)
			(xy 5.675449 -77.756026) (xy 5.620947 -77.756026) (xy 5.566999 -77.74827) (xy 5.514704 -77.732915)
			(xy 5.465127 -77.710273) (xy 5.419277 -77.680807) (xy 5.378086 -77.645116) (xy 5.342395 -77.603925)
			(xy 5.312929 -77.558075) (xy 5.290287 -77.508498) (xy 5.274932 -77.456203) (xy 5.267176 -77.402255)
			(xy 5.26669 -77.375004) (xy 3.866134 -77.375004) (xy 3.866134 -77.907134) (xy 5.096002 -79.137002)
			(xy 5.105896 -79.146255) (xy 5.129435 -79.159646) (xy 5.155666 -79.166377) (xy 5.182744 -79.165974)
			(xy 5.208763 -79.158467) (xy 5.231893 -79.144382) (xy 5.250506 -79.124711) (xy 5.263292 -79.100838)
			(xy 5.26669 -79.087726) (xy 5.270754 -79.061056) (xy 5.275186 -79.034023) (xy 5.290776 -78.981509)
			(xy 5.313705 -78.931758) (xy 5.343502 -78.885791) (xy 5.379557 -78.84455) (xy 5.40004 -78.82636)
			(xy 5.40131 -78.825344) (xy 5.411802 -78.81535) (xy 5.427198 -78.790818) (xy 5.435094 -78.762953)
			(xy 5.434857 -78.733992) (xy 5.426506 -78.706259) (xy 5.410711 -78.681983) (xy 5.40004 -78.672182)
			(xy 5.379503 -78.653974) (xy 5.343356 -78.612676) (xy 5.313503 -78.566621) (xy 5.290561 -78.516762)
			(xy 5.275004 -78.464129) (xy 5.267155 -78.40981) (xy 5.26669 -78.382368) (xy 5.267176 -78.355117)
			(xy 5.274932 -78.301169) (xy 5.290287 -78.248874) (xy 5.312929 -78.199297) (xy 5.342395 -78.153447)
			(xy 5.378086 -78.112256) (xy 5.419277 -78.076565) (xy 5.465127 -78.047099) (xy 5.514704 -78.024457)
			(xy 5.566999 -78.009102) (xy 5.620947 -78.001346) (xy 5.675449 -78.001346) (xy 5.729397 -78.009102)
			(xy 5.781692 -78.024457) (xy 5.831269 -78.047099) (xy 5.877119 -78.076565) (xy 5.91831 -78.112256)
			(xy 5.954001 -78.153447) (xy 5.983467 -78.199297) (xy 6.006109 -78.248874) (xy 6.021464 -78.301169)
			(xy 6.02922 -78.355117) (xy 6.029706 -78.382368) (xy 6.029248 -78.409544) (xy 6.021578 -78.46335)
			(xy 6.006345 -78.515522) (xy 5.983858 -78.565002) (xy 5.954573 -78.610788) (xy 5.919083 -78.651952)
			(xy 5.898896 -78.67015) (xy 5.88759 -78.67986) (xy 5.8707 -78.704398) (xy 5.861625 -78.732771) (xy 5.861142 -78.762556)
			(xy 5.869291 -78.791209) (xy 5.885376 -78.816282) (xy 5.896356 -78.82636) (xy 5.916896 -78.844566)
			(xy 5.95305 -78.885863) (xy 5.98291 -78.931917) (xy 6.00586 -78.981775) (xy 6.021425 -79.034409)
			(xy 6.029283 -79.088731) (xy 6.029706 -79.116174) (xy 6.029212 -79.144131) (xy 6.021044 -79.199444)
			(xy 6.004895 -79.252974) (xy 5.981108 -79.303575) (xy 5.950195 -79.350165) (xy 5.912815 -79.391747)
			(xy 5.869769 -79.427431) (xy 5.821977 -79.456453) (xy 5.770464 -79.478192) (xy 5.716329 -79.492184)
			(xy 5.688584 -79.49565) (xy 5.674396 -79.497618) (xy 5.647864 -79.508381) (xy 5.625367 -79.526093)
			(xy 5.608679 -79.549359) (xy 5.599113 -79.576345) (xy 5.597422 -79.604927) (xy 5.603741 -79.632853)
			(xy 5.61757 -79.657924) (xy 5.62737 -79.66837) (xy 6.215888 -80.256888)
		)
		(stroke
			(width 0)
			(type solid)
		)
		(fill yes)
		(layer "In2.Cu")
		(net "GND")
	)
	(gr_poly
		(pts
			(xy 48.11268 -47.269908) (xy 48.127454 -47.26941) (xy 48.155765 -47.260953) (xy 48.180469 -47.244741)
			(xy 48.199494 -47.222134) (xy 48.211248 -47.195025) (xy 48.214745 -47.165685) (xy 48.209693 -47.136572)
			(xy 48.203612 -47.123096) (xy 48.19273 -47.100124) (xy 48.177356 -47.051674) (xy 48.169561 -47.001445)
			(xy 48.169068 -46.97603) (xy 48.169549 -46.950039) (xy 48.177676 -46.898695) (xy 48.193736 -46.849255)
			(xy 48.217331 -46.802936) (xy 48.247883 -46.760878) (xy 48.284637 -46.724118) (xy 48.32669 -46.69356)
			(xy 48.373005 -46.669956) (xy 48.422442 -46.653889) (xy 48.473785 -46.645753) (xy 48.499776 -46.645322)
			(xy 48.524438 -46.645783) (xy 48.573212 -46.653118) (xy 48.620357 -46.667615) (xy 48.664827 -46.688951)
			(xy 48.705635 -46.716655) (xy 48.741878 -46.75011) (xy 48.77275 -46.788577) (xy 48.797569 -46.831201)
			(xy 48.815782 -46.877038) (xy 48.826988 -46.925072) (xy 48.829468 -46.949614) (xy 48.831119 -46.964006)
			(xy 48.841417 -46.991067) (xy 48.858899 -47.014147) (xy 48.882159 -47.03139) (xy 48.909325 -47.041407)
			(xy 48.938211 -47.043394) (xy 48.966492 -47.037189) (xy 48.991894 -47.023293) (xy 49.002442 -47.013368)
			(xy 49.044606 -46.971204) (xy 49.044606 -43.588432) (xy 48.795432 -43.339258) (xy 48.795432 -43.268646)
			(xy 48.795011 -43.259028) (xy 48.78791 -43.241149) (xy 48.774725 -43.22714) (xy 48.75731 -43.218968)
			(xy 48.738109 -43.217782) (xy 48.71982 -43.223747) (xy 48.71212 -43.22953) (xy 48.689637 -43.247614)
			(xy 48.639665 -43.276448) (xy 48.585444 -43.296164) (xy 48.528623 -43.306163) (xy 48.499776 -43.306746)
			(xy 48.473787 -43.306235) (xy 48.42245 -43.2981) (xy 48.373017 -43.282035) (xy 48.326705 -43.258435)
			(xy 48.284655 -43.227882) (xy 48.247903 -43.191126) (xy 48.217352 -43.149074) (xy 48.193756 -43.102761)
			(xy 48.177694 -43.053327) (xy 48.169564 -43.001989) (xy 48.169564 -42.950011) (xy 48.177694 -42.898673)
			(xy 48.193756 -42.849239) (xy 48.217352 -42.802926) (xy 48.247903 -42.760874) (xy 48.284655 -42.724118)
			(xy 48.326705 -42.693565) (xy 48.373017 -42.669965) (xy 48.42245 -42.6539) (xy 48.473787 -42.645765)
			(xy 48.499776 -42.64533) (xy 48.525434 -42.645831) (xy 48.576129 -42.653803) (xy 48.624978 -42.669526)
			(xy 48.648112 -42.680636) (xy 48.661585 -42.686851) (xy 48.690787 -42.692019) (xy 48.720243 -42.688581)
			(xy 48.747472 -42.676829) (xy 48.770177 -42.657751) (xy 48.786447 -42.632956) (xy 48.79491 -42.604533)
			(xy 48.795432 -42.589704) (xy 48.795432 -42.562272) (xy 48.794962 -42.547437) (xy 48.786509 -42.518998)
			(xy 48.770238 -42.49419) (xy 48.747521 -42.475107) (xy 48.720278 -42.46336) (xy 48.690808 -42.459941)
			(xy 48.661598 -42.465138) (xy 48.648112 -42.47134) (xy 48.624972 -42.48243) (xy 48.576119 -42.498128)
			(xy 48.525431 -42.506109) (xy 48.499776 -42.506646) (xy 48.473787 -42.506135) (xy 48.42245 -42.498)
			(xy 48.373017 -42.481935) (xy 48.326705 -42.458335) (xy 48.284655 -42.427782) (xy 48.247903 -42.391026)
			(xy 48.217352 -42.348974) (xy 48.193756 -42.302661) (xy 48.177694 -42.253227) (xy 48.169564 -42.201889)
			(xy 48.169564 -42.149911) (xy 48.177694 -42.098573) (xy 48.193756 -42.049139) (xy 48.217352 -42.002826)
			(xy 48.247903 -41.960774) (xy 48.284655 -41.924018) (xy 48.326705 -41.893465) (xy 48.373017 -41.869865)
			(xy 48.42245 -41.8538) (xy 48.473787 -41.845665) (xy 48.499776 -41.84523) (xy 48.525434 -41.845731)
			(xy 48.576129 -41.853703) (xy 48.624978 -41.869426) (xy 48.648112 -41.880536) (xy 48.661585 -41.886751)
			(xy 48.690787 -41.891919) (xy 48.720243 -41.888481) (xy 48.747472 -41.876729) (xy 48.770177 -41.857651)
			(xy 48.786447 -41.832856) (xy 48.79491 -41.804433) (xy 48.795432 -41.789604) (xy 48.795432 -41.762426)
			(xy 48.794969 -41.747585) (xy 48.786525 -41.719132) (xy 48.770255 -41.69431) (xy 48.747534 -41.675215)
			(xy 48.720282 -41.663461) (xy 48.6908 -41.660041) (xy 48.66158 -41.665244) (xy 48.648112 -41.671494)
			(xy 48.624972 -41.682586) (xy 48.57612 -41.698286) (xy 48.525432 -41.706268) (xy 48.499776 -41.7068)
			(xy 48.47379 -41.706289) (xy 48.422459 -41.698155) (xy 48.373032 -41.682092) (xy 48.326727 -41.658495)
			(xy 48.284683 -41.627944) (xy 48.247935 -41.591193) (xy 48.217389 -41.549146) (xy 48.193796 -41.502838)
			(xy 48.177737 -41.45341) (xy 48.169609 -41.402078) (xy 48.169068 -41.376092) (xy 48.16954 -41.350914)
			(xy 48.177175 -41.30114) (xy 48.192268 -41.253098) (xy 48.214468 -41.207899) (xy 48.243264 -41.166589)
			(xy 48.260254 -41.148) (xy 48.269009 -41.138226) (xy 48.281676 -41.115257) (xy 48.288079 -41.089819)
			(xy 48.287796 -41.06359) (xy 48.280844 -41.038297) (xy 48.267683 -41.015607) (xy 48.25873 -41.006014)
			(xy 48.069754 -40.817038) (xy 48.060187 -40.808042) (xy 48.037505 -40.794826) (xy 48.012198 -40.787846)
			(xy 47.985947 -40.787568) (xy 47.960498 -40.794008) (xy 47.93754 -40.806739) (xy 47.927768 -40.815514)
			(xy 47.909199 -40.832525) (xy 47.867876 -40.861302) (xy 47.822671 -40.883489) (xy 47.774628 -40.898575)
			(xy 47.724854 -40.906212) (xy 47.699676 -40.9067) (xy 47.67369 -40.906189) (xy 47.622359 -40.898055)
			(xy 47.572932 -40.881992) (xy 47.526627 -40.858395) (xy 47.484583 -40.827844) (xy 47.447835 -40.791093)
			(xy 47.417289 -40.749046) (xy 47.393696 -40.702738) (xy 47.377637 -40.65331) (xy 47.369509 -40.601978)
			(xy 47.368968 -40.575992) (xy 47.36944 -40.550814) (xy 47.377075 -40.50104) (xy 47.392168 -40.452998)
			(xy 47.414368 -40.407799) (xy 47.443164 -40.366489) (xy 47.460154 -40.3479) (xy 47.468909 -40.338126)
			(xy 47.481576 -40.315157) (xy 47.487979 -40.289719) (xy 47.487696 -40.26349) (xy 47.480744 -40.238197)
			(xy 47.467583 -40.215507) (xy 47.45863 -40.205914) (xy 47.269908 -40.017192) (xy 47.260343 -40.008185)
			(xy 47.237658 -39.994948) (xy 47.212343 -39.987953) (xy 47.18608 -39.987664) (xy 47.160617 -39.9941)
			(xy 47.137646 -40.006835) (xy 47.127922 -40.015668) (xy 47.109353 -40.03268) (xy 47.06803 -40.061459)
			(xy 47.022826 -40.08365) (xy 46.974783 -40.098741) (xy 46.925009 -40.106385) (xy 46.89983 -40.106854)
			(xy 46.87384 -40.106347) (xy 46.822499 -40.09822) (xy 46.773062 -40.082162) (xy 46.726745 -40.058569)
			(xy 46.684689 -40.02802) (xy 46.647929 -39.991269) (xy 46.617371 -39.94922) (xy 46.593767 -39.902909)
			(xy 46.577698 -39.853475) (xy 46.569559 -39.802136) (xy 46.569122 -39.776146) (xy 46.56959 -39.750966)
			(xy 46.577217 -39.701187) (xy 46.592302 -39.653139) (xy 46.614495 -39.607933) (xy 46.643284 -39.566613)
			(xy 46.660308 -39.548054) (xy 46.669066 -39.538278) (xy 46.68174 -39.515304) (xy 46.688152 -39.489861)
			(xy 46.687878 -39.463625) (xy 46.680938 -39.438321) (xy 46.667787 -39.415616) (xy 46.658784 -39.406068)
			(xy 46.469808 -39.217092) (xy 46.460243 -39.208085) (xy 46.437558 -39.194848) (xy 46.412243 -39.187853)
			(xy 46.38598 -39.187564) (xy 46.360517 -39.194) (xy 46.337546 -39.206735) (xy 46.327822 -39.215568)
			(xy 46.309253 -39.23258) (xy 46.26793 -39.261359) (xy 46.222726 -39.28355) (xy 46.174683 -39.298641)
			(xy 46.124909 -39.306285) (xy 46.09973 -39.306754) (xy 46.07374 -39.306247) (xy 46.022399 -39.29812)
			(xy 45.972962 -39.282062) (xy 45.926645 -39.258469) (xy 45.884589 -39.22792) (xy 45.847829 -39.191169)
			(xy 45.817271 -39.14912) (xy 45.793667 -39.102809) (xy 45.777598 -39.053375) (xy 45.769459 -39.002036)
			(xy 45.769022 -38.976046) (xy 45.76949 -38.950866) (xy 45.777117 -38.901087) (xy 45.792202 -38.853039)
			(xy 45.814395 -38.807833) (xy 45.843184 -38.766513) (xy 45.860208 -38.747954) (xy 45.868966 -38.738178)
			(xy 45.88164 -38.715204) (xy 45.888052 -38.689761) (xy 45.887778 -38.663525) (xy 45.880838 -38.638221)
			(xy 45.867687 -38.615516) (xy 45.858684 -38.605968) (xy 44.437554 -37.184838) (xy 44.096432 -37.184838)
			(xy 44.089066 -37.226748) (xy 44.083688 -37.254267) (xy 44.065933 -37.30745) (xy 44.040584 -37.357463)
			(xy 44.008189 -37.403226) (xy 43.969444 -37.443755) (xy 43.925184 -37.478177) (xy 43.876363 -37.50575)
			(xy 43.824032 -37.525881) (xy 43.769318 -37.538135) (xy 43.7134 -37.54225) (xy 43.657482 -37.538135)
			(xy 43.602768 -37.525881) (xy 43.550437 -37.50575) (xy 43.501616 -37.478177) (xy 43.457356 -37.443755)
			(xy 43.418611 -37.403226) (xy 43.386216 -37.357463) (xy 43.360867 -37.30745) (xy 43.343112 -37.254267)
			(xy 43.337734 -37.226748) (xy 43.330368 -37.184838) (xy 39.291006 -37.184838) (xy 39.27983 -37.190426)
			(xy 39.252558 -37.203917) (xy 39.194797 -37.22303) (xy 39.134736 -37.232743) (xy 39.104316 -37.233352)
			(xy 39.073895 -37.232743) (xy 39.013829 -37.223049) (xy 38.956066 -37.203935) (xy 38.928802 -37.190426)
			(xy 38.917626 -37.184838) (xy 38.32606 -37.184838) (xy 38.314884 -37.190426) (xy 38.287611 -37.203914)
			(xy 38.22985 -37.22302) (xy 38.169789 -37.232725) (xy 38.13937 -37.233352) (xy 38.10895 -37.23274)
			(xy 38.048887 -37.223038) (xy 37.991128 -37.203918) (xy 37.963856 -37.190426) (xy 37.95268 -37.184838)
			(xy 37.387022 -37.184838) (xy 37.354764 -37.217096) (xy 37.354764 -38.227) (xy 40.740582 -38.227)
			(xy 40.744653 -38.171378) (xy 40.756779 -38.116941) (xy 40.776702 -38.06485) (xy 40.803998 -38.016215)
			(xy 40.838084 -37.972072) (xy 40.878233 -37.933363) (xy 40.923591 -37.900912) (xy 40.973191 -37.875411)
			(xy 41.025975 -37.857404) (xy 41.080818 -37.847274) (xy 41.136552 -37.845237) (xy 41.191989 -37.851337)
			(xy 41.245946 -37.865443) (xy 41.297275 -37.887255) (xy 41.344881 -37.916309) (xy 41.387749 -37.951984)
			(xy 41.424966 -37.993521) (xy 41.431891 -38.003988) (xy 41.703242 -38.003988) (xy 41.707313 -37.948366)
			(xy 41.719439 -37.893929) (xy 41.739362 -37.841838) (xy 41.766658 -37.793203) (xy 41.800744 -37.74906)
			(xy 41.840893 -37.710351) (xy 41.886251 -37.6779) (xy 41.935851 -37.652399) (xy 41.988635 -37.634392)
			(xy 42.043478 -37.624262) (xy 42.099212 -37.622225) (xy 42.154649 -37.628325) (xy 42.208606 -37.642431)
			(xy 42.259935 -37.664243) (xy 42.307541 -37.693297) (xy 42.350409 -37.728972) (xy 42.387626 -37.770509)
			(xy 42.418399 -37.817022) (xy 42.442071 -37.867519) (xy 42.458139 -37.920926) (xy 42.466259 -37.976102)
			(xy 42.466768 -38.003988) (xy 42.466259 -38.031874) (xy 42.458139 -38.08705) (xy 42.442071 -38.140457)
			(xy 42.418399 -38.190954) (xy 42.387626 -38.237467) (xy 42.350409 -38.279004) (xy 42.307541 -38.314679)
			(xy 42.259935 -38.343733) (xy 42.208606 -38.365545) (xy 42.154649 -38.379651) (xy 42.099212 -38.385751)
			(xy 42.043478 -38.383714) (xy 41.988635 -38.373584) (xy 41.935851 -38.355577) (xy 41.886251 -38.330076)
			(xy 41.840893 -38.297625) (xy 41.800744 -38.258916) (xy 41.766658 -38.214773) (xy 41.739362 -38.166138)
			(xy 41.719439 -38.114047) (xy 41.707313 -38.05961) (xy 41.703242 -38.003988) (xy 41.431891 -38.003988)
			(xy 41.455739 -38.040034) (xy 41.479411 -38.090531) (xy 41.495479 -38.143938) (xy 41.503599 -38.199114)
			(xy 41.504108 -38.227) (xy 41.503599 -38.254886) (xy 41.495479 -38.310062) (xy 41.479411 -38.363469)
			(xy 41.455739 -38.413966) (xy 41.424966 -38.460479) (xy 41.387749 -38.502016) (xy 41.344881 -38.537691)
			(xy 41.297275 -38.566745) (xy 41.245946 -38.588557) (xy 41.191989 -38.602663) (xy 41.136552 -38.608763)
			(xy 41.080818 -38.606726) (xy 41.025975 -38.596596) (xy 40.973191 -38.578589) (xy 40.923591 -38.553088)
			(xy 40.878233 -38.520637) (xy 40.838084 -38.481928) (xy 40.803998 -38.437785) (xy 40.776702 -38.38915)
			(xy 40.756779 -38.337059) (xy 40.744653 -38.282622) (xy 40.740582 -38.227) (xy 37.354764 -38.227)
			(xy 37.354764 -38.955247) (xy 43.533118 -38.955247) (xy 43.533118 -38.900753) (xy 43.540873 -38.846815)
			(xy 43.556224 -38.794529) (xy 43.57886 -38.74496) (xy 43.608319 -38.699116) (xy 43.644003 -38.657931)
			(xy 43.685184 -38.622243) (xy 43.731024 -38.592779) (xy 43.780591 -38.570138) (xy 43.832876 -38.554781)
			(xy 43.886814 -38.547021) (xy 43.91406 -38.546532) (xy 43.940224 -38.54698) (xy 43.99206 -38.554133)
			(xy 44.042434 -38.568298) (xy 44.090402 -38.589208) (xy 44.135065 -38.616472) (xy 44.175588 -38.64958)
			(xy 44.193714 -38.668452) (xy 44.204538 -38.679349) (xy 44.231146 -38.694662) (xy 44.261103 -38.701374)
			(xy 44.291701 -38.69888) (xy 44.320176 -38.687405) (xy 44.332398 -38.678104) (xy 44.354692 -38.660727)
			(xy 44.403965 -38.633035) (xy 44.457225 -38.614113) (xy 44.512925 -38.604512) (xy 44.541186 -38.603936)
			(xy 44.567179 -38.60433) (xy 44.618527 -38.612461) (xy 44.667969 -38.628524) (xy 44.714291 -38.652124)
			(xy 44.75635 -38.68268) (xy 44.793111 -38.71944) (xy 44.823669 -38.761497) (xy 44.847271 -38.807818)
			(xy 44.863336 -38.85726) (xy 44.871469 -38.908607) (xy 44.871469 -38.960593) (xy 44.863336 -39.01194)
			(xy 44.847271 -39.061382) (xy 44.823669 -39.107703) (xy 44.793111 -39.14976) (xy 44.75635 -39.18652)
			(xy 44.714291 -39.217076) (xy 44.667969 -39.240676) (xy 44.618527 -39.256739) (xy 44.567179 -39.26487)
			(xy 44.541186 -39.265352) (xy 44.517882 -39.264939) (xy 44.471737 -39.2584) (xy 44.426968 -39.24544)
			(xy 44.384466 -39.226315) (xy 44.345073 -39.201407) (xy 44.327064 -39.186612) (xy 44.314989 -39.177109)
			(xy 44.286746 -39.165052) (xy 44.256195 -39.16193) (xy 44.226097 -39.168026) (xy 44.199169 -39.182788)
			(xy 44.188126 -39.19347) (xy 44.170071 -39.211465) (xy 44.130044 -39.243029) (xy 44.086171 -39.268984)
			(xy 44.039234 -39.288868) (xy 43.990068 -39.302326) (xy 43.939547 -39.30912) (xy 43.91406 -39.309548)
			(xy 43.886814 -39.308979) (xy 43.832876 -39.301219) (xy 43.780591 -39.285862) (xy 43.731024 -39.263221)
			(xy 43.685184 -39.233757) (xy 43.644003 -39.198069) (xy 43.608319 -39.156884) (xy 43.57886 -39.11104)
			(xy 43.556224 -39.061471) (xy 43.540873 -39.009185) (xy 43.533118 -38.955247) (xy 37.354764 -38.955247)
			(xy 37.354764 -39.036498) (xy 37.454586 -39.13632) (xy 40.40124 -39.13632) (xy 40.44442 -39.1795)
			(xy 40.475154 -39.167308) (xy 40.49744 -39.158942) (xy 40.543566 -39.147181) (xy 40.590799 -39.141254)
			(xy 40.6146 -39.140892) (xy 40.643928 -39.141423) (xy 40.701893 -39.15039) (xy 40.757802 -39.168127)
			(xy 40.810335 -39.194217) (xy 40.858253 -39.228044) (xy 40.900426 -39.26881) (xy 40.935859 -39.315554)
			(xy 40.963716 -39.367172) (xy 40.97401 -39.394638) (xy 40.986202 -39.42842) (xy 41.275 -39.42842)
			(xy 41.69918 -39.8526) (xy 43.229782 -39.8526) (xy 43.233853 -39.796978) (xy 43.245979 -39.742541)
			(xy 43.265902 -39.69045) (xy 43.293198 -39.641815) (xy 43.327284 -39.597672) (xy 43.367433 -39.558963)
			(xy 43.412791 -39.526512) (xy 43.462391 -39.501011) (xy 43.515175 -39.483004) (xy 43.570018 -39.472874)
			(xy 43.625752 -39.470837) (xy 43.681189 -39.476937) (xy 43.735146 -39.491043) (xy 43.786475 -39.512855)
			(xy 43.834081 -39.541909) (xy 43.876949 -39.577584) (xy 43.914166 -39.619121) (xy 43.944939 -39.665634)
			(xy 43.968611 -39.716131) (xy 43.984679 -39.769538) (xy 43.989476 -39.802133) (xy 44.169586 -39.802133)
			(xy 44.169586 -39.750159) (xy 44.177716 -39.698824) (xy 44.193777 -39.649394) (xy 44.217373 -39.603084)
			(xy 44.247923 -39.561036) (xy 44.284674 -39.524285) (xy 44.326722 -39.493735) (xy 44.373032 -39.470139)
			(xy 44.422462 -39.454078) (xy 44.473797 -39.445948) (xy 44.525771 -39.445948) (xy 44.577106 -39.454078)
			(xy 44.626536 -39.470139) (xy 44.672846 -39.493735) (xy 44.714894 -39.524285) (xy 44.751645 -39.561036)
			(xy 44.782195 -39.603084) (xy 44.805791 -39.649394) (xy 44.821852 -39.698824) (xy 44.829982 -39.750159)
			(xy 44.830492 -39.776146) (xy 44.829982 -39.802133) (xy 44.969686 -39.802133) (xy 44.969686 -39.750159)
			(xy 44.977816 -39.698824) (xy 44.993877 -39.649394) (xy 45.017473 -39.603084) (xy 45.048023 -39.561036)
			(xy 45.084774 -39.524285) (xy 45.126822 -39.493735) (xy 45.173132 -39.470139) (xy 45.222562 -39.454078)
			(xy 45.273897 -39.445948) (xy 45.325871 -39.445948) (xy 45.377206 -39.454078) (xy 45.426636 -39.470139)
			(xy 45.472946 -39.493735) (xy 45.514994 -39.524285) (xy 45.551745 -39.561036) (xy 45.582295 -39.603084)
			(xy 45.605891 -39.649394) (xy 45.621952 -39.698824) (xy 45.630082 -39.750159) (xy 45.630592 -39.776146)
			(xy 45.630082 -39.802133) (xy 45.769532 -39.802133) (xy 45.769532 -39.750159) (xy 45.777662 -39.698824)
			(xy 45.793723 -39.649394) (xy 45.817319 -39.603084) (xy 45.847869 -39.561036) (xy 45.88462 -39.524285)
			(xy 45.926668 -39.493735) (xy 45.972978 -39.470139) (xy 46.022408 -39.454078) (xy 46.073743 -39.445948)
			(xy 46.125717 -39.445948) (xy 46.177052 -39.454078) (xy 46.226482 -39.470139) (xy 46.272792 -39.493735)
			(xy 46.31484 -39.524285) (xy 46.351591 -39.561036) (xy 46.382141 -39.603084) (xy 46.405737 -39.649394)
			(xy 46.421798 -39.698824) (xy 46.429928 -39.750159) (xy 46.430438 -39.776146) (xy 46.429928 -39.802133)
			(xy 46.421798 -39.853468) (xy 46.405737 -39.902898) (xy 46.382141 -39.949208) (xy 46.351591 -39.991256)
			(xy 46.31484 -40.028007) (xy 46.272792 -40.058557) (xy 46.226482 -40.082153) (xy 46.177052 -40.098214)
			(xy 46.125717 -40.106344) (xy 46.073743 -40.106344) (xy 46.022408 -40.098214) (xy 45.972978 -40.082153)
			(xy 45.926668 -40.058557) (xy 45.88462 -40.028007) (xy 45.847869 -39.991256) (xy 45.817319 -39.949208)
			(xy 45.793723 -39.902898) (xy 45.777662 -39.853468) (xy 45.769532 -39.802133) (xy 45.630082 -39.802133)
			(xy 45.621952 -39.853468) (xy 45.605891 -39.902898) (xy 45.582295 -39.949208) (xy 45.551745 -39.991256)
			(xy 45.514994 -40.028007) (xy 45.472946 -40.058557) (xy 45.426636 -40.082153) (xy 45.377206 -40.098214)
			(xy 45.325871 -40.106344) (xy 45.273897 -40.106344) (xy 45.222562 -40.098214) (xy 45.173132 -40.082153)
			(xy 45.126822 -40.058557) (xy 45.084774 -40.028007) (xy 45.048023 -39.991256) (xy 45.017473 -39.949208)
			(xy 44.993877 -39.902898) (xy 44.977816 -39.853468) (xy 44.969686 -39.802133) (xy 44.829982 -39.802133)
			(xy 44.821852 -39.853468) (xy 44.805791 -39.902898) (xy 44.782195 -39.949208) (xy 44.751645 -39.991256)
			(xy 44.714894 -40.028007) (xy 44.672846 -40.058557) (xy 44.626536 -40.082153) (xy 44.577106 -40.098214)
			(xy 44.525771 -40.106344) (xy 44.473797 -40.106344) (xy 44.422462 -40.098214) (xy 44.373032 -40.082153)
			(xy 44.326722 -40.058557) (xy 44.284674 -40.028007) (xy 44.247923 -39.991256) (xy 44.217373 -39.949208)
			(xy 44.193777 -39.902898) (xy 44.177716 -39.853468) (xy 44.169586 -39.802133) (xy 43.989476 -39.802133)
			(xy 43.992799 -39.824714) (xy 43.993308 -39.8526) (xy 43.992799 -39.880486) (xy 43.984679 -39.935662)
			(xy 43.968611 -39.989069) (xy 43.944939 -40.039566) (xy 43.914166 -40.086079) (xy 43.876949 -40.127616)
			(xy 43.834081 -40.163291) (xy 43.786475 -40.192345) (xy 43.735146 -40.214157) (xy 43.681189 -40.228263)
			(xy 43.625752 -40.234363) (xy 43.570018 -40.232326) (xy 43.515175 -40.222196) (xy 43.462391 -40.204189)
			(xy 43.412791 -40.178688) (xy 43.367433 -40.146237) (xy 43.327284 -40.107528) (xy 43.293198 -40.063385)
			(xy 43.265902 -40.01475) (xy 43.245979 -39.962659) (xy 43.233853 -39.908222) (xy 43.229782 -39.8526)
			(xy 41.69918 -39.8526) (xy 42.215816 -40.369236) (xy 44.24172 -40.369236) (xy 44.257512 -40.350258)
			(xy 44.293764 -40.316745) (xy 44.334595 -40.288992) (xy 44.379096 -40.267614) (xy 44.42628 -40.253088)
			(xy 44.475099 -40.245734) (xy 44.499784 -40.245284) (xy 44.526369 -40.245812) (xy 44.578856 -40.254312)
			(xy 44.629309 -40.271094) (xy 44.676429 -40.295728) (xy 44.719003 -40.32758) (xy 44.755937 -40.365829)
			(xy 44.78628 -40.409492) (xy 44.798234 -40.433244) (xy 44.81195 -40.4622) (xy 44.987718 -40.4622)
			(xy 45.001434 -40.433244) (xy 45.013401 -40.409501) (xy 45.043748 -40.365848) (xy 45.080683 -40.327608)
			(xy 45.123257 -40.295763) (xy 45.170373 -40.271134) (xy 45.22082 -40.254353) (xy 45.273301 -40.245851)
			(xy 45.299884 -40.245284) (xy 45.325874 -40.245766) (xy 45.377215 -40.253895) (xy 45.426652 -40.269956)
			(xy 45.472968 -40.293553) (xy 45.515023 -40.324104) (xy 45.55178 -40.360859) (xy 45.582335 -40.402911)
			(xy 45.605935 -40.449225) (xy 45.621999 -40.498661) (xy 45.630132 -40.550002) (xy 45.630592 -40.575992)
			(xy 45.630092 -40.601963) (xy 45.630089 -40.601979) (xy 45.769532 -40.601979) (xy 45.769532 -40.550005)
			(xy 45.777662 -40.49867) (xy 45.793723 -40.44924) (xy 45.817319 -40.40293) (xy 45.847869 -40.360882)
			(xy 45.88462 -40.324131) (xy 45.926668 -40.293581) (xy 45.972978 -40.269985) (xy 46.022408 -40.253924)
			(xy 46.073743 -40.245794) (xy 46.125717 -40.245794) (xy 46.177052 -40.253924) (xy 46.226482 -40.269985)
			(xy 46.272792 -40.293581) (xy 46.31484 -40.324131) (xy 46.351591 -40.360882) (xy 46.382141 -40.40293)
			(xy 46.405737 -40.44924) (xy 46.421798 -40.49867) (xy 46.429928 -40.550005) (xy 46.430438 -40.575992)
			(xy 46.429928 -40.601979) (xy 46.569632 -40.601979) (xy 46.569632 -40.550005) (xy 46.577762 -40.49867)
			(xy 46.593823 -40.44924) (xy 46.617419 -40.40293) (xy 46.647969 -40.360882) (xy 46.68472 -40.324131)
			(xy 46.726768 -40.293581) (xy 46.773078 -40.269985) (xy 46.822508 -40.253924) (xy 46.873843 -40.245794)
			(xy 46.925817 -40.245794) (xy 46.977152 -40.253924) (xy 47.026582 -40.269985) (xy 47.072892 -40.293581)
			(xy 47.11494 -40.324131) (xy 47.151691 -40.360882) (xy 47.182241 -40.40293) (xy 47.205837 -40.44924)
			(xy 47.221898 -40.49867) (xy 47.230028 -40.550005) (xy 47.230538 -40.575992) (xy 47.230028 -40.601979)
			(xy 47.221898 -40.653314) (xy 47.205837 -40.702744) (xy 47.182241 -40.749054) (xy 47.151691 -40.791102)
			(xy 47.11494 -40.827853) (xy 47.072892 -40.858403) (xy 47.026582 -40.881999) (xy 46.977152 -40.89806)
			(xy 46.925817 -40.90619) (xy 46.873843 -40.90619) (xy 46.822508 -40.89806) (xy 46.773078 -40.881999)
			(xy 46.726768 -40.858403) (xy 46.68472 -40.827853) (xy 46.647969 -40.791102) (xy 46.617419 -40.749054)
			(xy 46.593823 -40.702744) (xy 46.577762 -40.653314) (xy 46.569632 -40.601979) (xy 46.429928 -40.601979)
			(xy 46.421798 -40.653314) (xy 46.405737 -40.702744) (xy 46.382141 -40.749054) (xy 46.351591 -40.791102)
			(xy 46.31484 -40.827853) (xy 46.272792 -40.858403) (xy 46.226482 -40.881999) (xy 46.177052 -40.89806)
			(xy 46.125717 -40.90619) (xy 46.073743 -40.90619) (xy 46.022408 -40.89806) (xy 45.972978 -40.881999)
			(xy 45.926668 -40.858403) (xy 45.88462 -40.827853) (xy 45.847869 -40.791102) (xy 45.817319 -40.749054)
			(xy 45.793723 -40.702744) (xy 45.777662 -40.653314) (xy 45.769532 -40.601979) (xy 45.630089 -40.601979)
			(xy 45.621928 -40.653259) (xy 45.614336 -40.6781) (xy 45.604938 -40.707818) (xy 45.968158 -41.071038)
			(xy 45.997876 -41.061386) (xy 46.022672 -41.053905) (xy 46.073834 -41.04586) (xy 46.09973 -41.045384)
			(xy 46.125716 -41.045896) (xy 46.177047 -41.05403) (xy 46.226474 -41.070094) (xy 46.27278 -41.093691)
			(xy 46.314825 -41.124241) (xy 46.351573 -41.160992) (xy 46.382121 -41.203039) (xy 46.405715 -41.249346)
			(xy 46.421775 -41.298774) (xy 46.429906 -41.350106) (xy 46.430438 -41.376092) (xy 46.429996 -41.400575)
			(xy 46.429772 -41.402079) (xy 46.569632 -41.402079) (xy 46.569632 -41.350105) (xy 46.577762 -41.29877)
			(xy 46.593823 -41.24934) (xy 46.617419 -41.20303) (xy 46.647969 -41.160982) (xy 46.68472 -41.124231)
			(xy 46.726768 -41.093681) (xy 46.773078 -41.070085) (xy 46.822508 -41.054024) (xy 46.873843 -41.045894)
			(xy 46.925817 -41.045894) (xy 46.977152 -41.054024) (xy 47.026582 -41.070085) (xy 47.072892 -41.093681)
			(xy 47.11494 -41.124231) (xy 47.151691 -41.160982) (xy 47.182241 -41.20303) (xy 47.205837 -41.24934)
			(xy 47.221898 -41.29877) (xy 47.230028 -41.350105) (xy 47.230538 -41.376092) (xy 47.230028 -41.402079)
			(xy 47.369478 -41.402079) (xy 47.369478 -41.350105) (xy 47.377608 -41.29877) (xy 47.393669 -41.24934)
			(xy 47.417265 -41.20303) (xy 47.447815 -41.160982) (xy 47.484566 -41.124231) (xy 47.526614 -41.093681)
			(xy 47.572924 -41.070085) (xy 47.622354 -41.054024) (xy 47.673689 -41.045894) (xy 47.725663 -41.045894)
			(xy 47.776998 -41.054024) (xy 47.826428 -41.070085) (xy 47.872738 -41.093681) (xy 47.914786 -41.124231)
			(xy 47.951537 -41.160982) (xy 47.982087 -41.20303) (xy 48.005683 -41.24934) (xy 48.021744 -41.29877)
			(xy 48.029874 -41.350105) (xy 48.030384 -41.376092) (xy 48.029874 -41.402079) (xy 48.021744 -41.453414)
			(xy 48.005683 -41.502844) (xy 47.982087 -41.549154) (xy 47.951537 -41.591202) (xy 47.914786 -41.627953)
			(xy 47.872738 -41.658503) (xy 47.826428 -41.682099) (xy 47.776998 -41.69816) (xy 47.725663 -41.70629)
			(xy 47.673689 -41.70629) (xy 47.622354 -41.69816) (xy 47.572924 -41.682099) (xy 47.526614 -41.658503)
			(xy 47.484566 -41.627953) (xy 47.447815 -41.591202) (xy 47.417265 -41.549154) (xy 47.393669 -41.502844)
			(xy 47.377608 -41.453414) (xy 47.369478 -41.402079) (xy 47.230028 -41.402079) (xy 47.221898 -41.453414)
			(xy 47.205837 -41.502844) (xy 47.182241 -41.549154) (xy 47.151691 -41.591202) (xy 47.11494 -41.627953)
			(xy 47.072892 -41.658503) (xy 47.026582 -41.682099) (xy 46.977152 -41.69816) (xy 46.925817 -41.70629)
			(xy 46.873843 -41.70629) (xy 46.822508 -41.69816) (xy 46.773078 -41.682099) (xy 46.726768 -41.658503)
			(xy 46.68472 -41.627953) (xy 46.647969 -41.591202) (xy 46.617419 -41.549154) (xy 46.593823 -41.502844)
			(xy 46.577762 -41.453414) (xy 46.569632 -41.402079) (xy 46.429772 -41.402079) (xy 46.422775 -41.449005)
			(xy 46.408492 -41.49584) (xy 46.387457 -41.540057) (xy 46.36013 -41.580688) (xy 46.327111 -41.616845)
			(xy 46.28912 -41.647736) (xy 46.246988 -41.672687) (xy 46.201638 -41.691151) (xy 46.177962 -41.697402)
			(xy 46.1391 -41.7068) (xy 46.1391 -41.84523) (xy 46.177962 -41.854628) (xy 46.201646 -41.860851)
			(xy 46.246994 -41.879325) (xy 46.289124 -41.904283) (xy 46.327114 -41.935179) (xy 46.360133 -41.971338)
			(xy 46.38746 -42.011971) (xy 46.408499 -42.056188) (xy 46.422789 -42.103024) (xy 46.430017 -42.151454)
			(xy 46.430438 -42.175938) (xy 46.430306 -42.18837) (xy 46.428402 -42.213162) (xy 46.426628 -42.225468)
			(xy 46.42612 -42.229024) (xy 46.42612 -42.283888) (xy 46.503844 -42.283888) (xy 46.519846 -42.284142)
			(xy 46.531198 -42.284147) (xy 46.552167 -42.275531) (xy 46.5674 -42.258741) (xy 46.573942 -42.237034)
			(xy 46.572932 -42.225722) (xy 46.571156 -42.213352) (xy 46.569245 -42.188434) (xy 46.569122 -42.175938)
			(xy 46.569632 -42.149951) (xy 46.577762 -42.098616) (xy 46.593823 -42.049186) (xy 46.617419 -42.002876)
			(xy 46.647969 -41.960828) (xy 46.68472 -41.924077) (xy 46.726768 -41.893527) (xy 46.773078 -41.869931)
			(xy 46.822508 -41.85387) (xy 46.873843 -41.84574) (xy 46.925817 -41.84574) (xy 46.977152 -41.85387)
			(xy 47.026582 -41.869931) (xy 47.072892 -41.893527) (xy 47.11494 -41.924077) (xy 47.151691 -41.960828)
			(xy 47.182241 -42.002876) (xy 47.205837 -42.049186) (xy 47.221898 -42.098616) (xy 47.230028 -42.149951)
			(xy 47.230538 -42.175938) (xy 47.230093 -42.200426) (xy 47.229869 -42.201925) (xy 47.369478 -42.201925)
			(xy 47.369478 -42.149951) (xy 47.377608 -42.098616) (xy 47.393669 -42.049186) (xy 47.417265 -42.002876)
			(xy 47.447815 -41.960828) (xy 47.484566 -41.924077) (xy 47.526614 -41.893527) (xy 47.572924 -41.869931)
			(xy 47.622354 -41.85387) (xy 47.673689 -41.84574) (xy 47.725663 -41.84574) (xy 47.776998 -41.85387)
			(xy 47.826428 -41.869931) (xy 47.872738 -41.893527) (xy 47.914786 -41.924077) (xy 47.951537 -41.960828)
			(xy 47.982087 -42.002876) (xy 48.005683 -42.049186) (xy 48.021744 -42.098616) (xy 48.029874 -42.149951)
			(xy 48.030384 -42.175938) (xy 48.029874 -42.201925) (xy 48.021744 -42.25326) (xy 48.005683 -42.30269)
			(xy 47.982087 -42.349) (xy 47.951537 -42.391048) (xy 47.914786 -42.427799) (xy 47.872738 -42.458349)
			(xy 47.826428 -42.481945) (xy 47.776998 -42.498006) (xy 47.725663 -42.506136) (xy 47.673689 -42.506136)
			(xy 47.622354 -42.498006) (xy 47.572924 -42.481945) (xy 47.526614 -42.458349) (xy 47.484566 -42.427799)
			(xy 47.447815 -42.391048) (xy 47.417265 -42.349) (xy 47.393669 -42.30269) (xy 47.377608 -42.25326)
			(xy 47.369478 -42.201925) (xy 47.229869 -42.201925) (xy 47.222867 -42.248867) (xy 47.208579 -42.295713)
			(xy 47.18754 -42.33994) (xy 47.160211 -42.380583) (xy 47.127189 -42.416752) (xy 47.089195 -42.447658)
			(xy 47.04706 -42.472625) (xy 47.024544 -42.482262) (xy 47.011479 -42.488122) (xy 46.989023 -42.505867)
			(xy 46.972368 -42.529143) (xy 46.962818 -42.556124) (xy 46.961124 -42.584695) (xy 46.967418 -42.612616)
			(xy 46.981206 -42.637697) (xy 46.991016 -42.648124) (xy 47.00524 -42.662348) (xy 47.0154 -42.666158)
			(xy 47.03876 -42.675364) (xy 47.082614 -42.699812) (xy 47.122268 -42.730609) (xy 47.156811 -42.767048)
			(xy 47.185447 -42.808289) (xy 47.20752 -42.853386) (xy 47.222521 -42.901301) (xy 47.230106 -42.950934)
			(xy 47.230538 -42.976038) (xy 47.230101 -43.000809) (xy 47.229918 -43.002025) (xy 47.369478 -43.002025)
			(xy 47.369478 -42.950051) (xy 47.377608 -42.898716) (xy 47.393669 -42.849286) (xy 47.417265 -42.802976)
			(xy 47.447815 -42.760928) (xy 47.484566 -42.724177) (xy 47.526614 -42.693627) (xy 47.572924 -42.670031)
			(xy 47.622354 -42.65397) (xy 47.673689 -42.64584) (xy 47.725663 -42.64584) (xy 47.776998 -42.65397)
			(xy 47.826428 -42.670031) (xy 47.872738 -42.693627) (xy 47.914786 -42.724177) (xy 47.951537 -42.760928)
			(xy 47.982087 -42.802976) (xy 48.005683 -42.849286) (xy 48.021744 -42.898716) (xy 48.029874 -42.950051)
			(xy 48.030384 -42.976038) (xy 48.029874 -43.002025) (xy 48.021744 -43.05336) (xy 48.005683 -43.10279)
			(xy 47.982087 -43.1491) (xy 47.951537 -43.191148) (xy 47.914786 -43.227899) (xy 47.872738 -43.258449)
			(xy 47.826428 -43.282045) (xy 47.776998 -43.298106) (xy 47.725663 -43.306236) (xy 47.673689 -43.306236)
			(xy 47.622354 -43.298106) (xy 47.572924 -43.282045) (xy 47.526614 -43.258449) (xy 47.484566 -43.227899)
			(xy 47.447815 -43.191148) (xy 47.417265 -43.1491) (xy 47.393669 -43.10279) (xy 47.377608 -43.05336)
			(xy 47.369478 -43.002025) (xy 47.229918 -43.002025) (xy 47.222719 -43.049798) (xy 47.20811 -43.097138)
			(xy 47.186601 -43.141768) (xy 47.158675 -43.182689) (xy 47.124956 -43.218986) (xy 47.086198 -43.249845)
			(xy 47.06493 -43.26255) (xy 47.053535 -43.269532) (xy 47.03459 -43.288367) (xy 47.021191 -43.311479)
			(xy 47.014258 -43.337279) (xy 47.014268 -43.363994) (xy 47.021219 -43.389789) (xy 47.034635 -43.412891)
			(xy 47.043848 -43.42257) (xy 47.10811 -43.486832) (xy 47.10811 -43.518328) (xy 47.124366 -43.533314)
			(xy 47.144021 -43.552247) (xy 47.177463 -43.595368) (xy 47.20337 -43.643395) (xy 47.221041 -43.695024)
			(xy 47.229995 -43.748853) (xy 47.230538 -43.776138) (xy 47.23009 -43.800657) (xy 47.229871 -43.802125)
			(xy 47.369478 -43.802125) (xy 47.369478 -43.750151) (xy 47.377608 -43.698816) (xy 47.393669 -43.649386)
			(xy 47.417265 -43.603076) (xy 47.447815 -43.561028) (xy 47.484566 -43.524277) (xy 47.526614 -43.493727)
			(xy 47.572924 -43.470131) (xy 47.622354 -43.45407) (xy 47.673689 -43.44594) (xy 47.725663 -43.44594)
			(xy 47.776998 -43.45407) (xy 47.826428 -43.470131) (xy 47.872738 -43.493727) (xy 47.914786 -43.524277)
			(xy 47.951537 -43.561028) (xy 47.982087 -43.603076) (xy 48.005683 -43.649386) (xy 48.021744 -43.698816)
			(xy 48.029874 -43.750151) (xy 48.030384 -43.776138) (xy 48.029874 -43.802125) (xy 48.169578 -43.802125)
			(xy 48.169578 -43.750151) (xy 48.177708 -43.698816) (xy 48.193769 -43.649386) (xy 48.217365 -43.603076)
			(xy 48.247915 -43.561028) (xy 48.284666 -43.524277) (xy 48.326714 -43.493727) (xy 48.373024 -43.470131)
			(xy 48.422454 -43.45407) (xy 48.473789 -43.44594) (xy 48.525763 -43.44594) (xy 48.577098 -43.45407)
			(xy 48.626528 -43.470131) (xy 48.672838 -43.493727) (xy 48.714886 -43.524277) (xy 48.751637 -43.561028)
			(xy 48.782187 -43.603076) (xy 48.805783 -43.649386) (xy 48.821844 -43.698816) (xy 48.829974 -43.750151)
			(xy 48.830484 -43.776138) (xy 48.829974 -43.802125) (xy 48.821844 -43.85346) (xy 48.805783 -43.90289)
			(xy 48.782187 -43.9492) (xy 48.751637 -43.991248) (xy 48.714886 -44.027999) (xy 48.672838 -44.058549)
			(xy 48.626528 -44.082145) (xy 48.577098 -44.098206) (xy 48.525763 -44.106336) (xy 48.473789 -44.106336)
			(xy 48.422454 -44.098206) (xy 48.373024 -44.082145) (xy 48.326714 -44.058549) (xy 48.284666 -44.027999)
			(xy 48.247915 -43.991248) (xy 48.217365 -43.9492) (xy 48.193769 -43.90289) (xy 48.177708 -43.85346)
			(xy 48.169578 -43.802125) (xy 48.029874 -43.802125) (xy 48.021744 -43.85346) (xy 48.005683 -43.90289)
			(xy 47.982087 -43.9492) (xy 47.951537 -43.991248) (xy 47.914786 -44.027999) (xy 47.872738 -44.058549)
			(xy 47.826428 -44.082145) (xy 47.776998 -44.098206) (xy 47.725663 -44.106336) (xy 47.673689 -44.106336)
			(xy 47.622354 -44.098206) (xy 47.572924 -44.082145) (xy 47.526614 -44.058549) (xy 47.484566 -44.027999)
			(xy 47.447815 -43.991248) (xy 47.417265 -43.9492) (xy 47.393669 -43.90289) (xy 47.377608 -43.85346)
			(xy 47.369478 -43.802125) (xy 47.229871 -43.802125) (xy 47.222841 -43.849157) (xy 47.208508 -43.896054)
			(xy 47.187406 -43.940321) (xy 47.159997 -43.980984) (xy 47.126883 -44.017154) (xy 47.10811 -44.032932)
			(xy 47.10811 -44.31919) (xy 47.128575 -44.336431) (xy 47.164187 -44.37637) (xy 47.192899 -44.421524)
			(xy 47.213962 -44.470714) (xy 47.226824 -44.522655) (xy 47.23115 -44.57599) (xy 47.229044 -44.601971)
			(xy 47.369478 -44.601971) (xy 47.369478 -44.549997) (xy 47.377608 -44.498662) (xy 47.393669 -44.449232)
			(xy 47.417265 -44.402922) (xy 47.447815 -44.360874) (xy 47.484566 -44.324123) (xy 47.526614 -44.293573)
			(xy 47.572924 -44.269977) (xy 47.622354 -44.253916) (xy 47.673689 -44.245786) (xy 47.725663 -44.245786)
			(xy 47.776998 -44.253916) (xy 47.826428 -44.269977) (xy 47.872738 -44.293573) (xy 47.914786 -44.324123)
			(xy 47.951537 -44.360874) (xy 47.982087 -44.402922) (xy 48.005683 -44.449232) (xy 48.021744 -44.498662)
			(xy 48.029874 -44.549997) (xy 48.030384 -44.575984) (xy 48.029874 -44.601971) (xy 48.169578 -44.601971)
			(xy 48.169578 -44.549997) (xy 48.177708 -44.498662) (xy 48.193769 -44.449232) (xy 48.217365 -44.402922)
			(xy 48.247915 -44.360874) (xy 48.284666 -44.324123) (xy 48.326714 -44.293573) (xy 48.373024 -44.269977)
			(xy 48.422454 -44.253916) (xy 48.473789 -44.245786) (xy 48.525763 -44.245786) (xy 48.577098 -44.253916)
			(xy 48.626528 -44.269977) (xy 48.672838 -44.293573) (xy 48.714886 -44.324123) (xy 48.751637 -44.360874)
			(xy 48.782187 -44.402922) (xy 48.805783 -44.449232) (xy 48.821844 -44.498662) (xy 48.829974 -44.549997)
			(xy 48.830484 -44.575984) (xy 48.829974 -44.601971) (xy 48.821844 -44.653306) (xy 48.805783 -44.702736)
			(xy 48.782187 -44.749046) (xy 48.751637 -44.791094) (xy 48.714886 -44.827845) (xy 48.672838 -44.858395)
			(xy 48.626528 -44.881991) (xy 48.577098 -44.898052) (xy 48.525763 -44.906182) (xy 48.473789 -44.906182)
			(xy 48.422454 -44.898052) (xy 48.373024 -44.881991) (xy 48.326714 -44.858395) (xy 48.284666 -44.827845)
			(xy 48.247915 -44.791094) (xy 48.217365 -44.749046) (xy 48.193769 -44.702736) (xy 48.177708 -44.653306)
			(xy 48.169578 -44.601971) (xy 48.029874 -44.601971) (xy 48.021744 -44.653306) (xy 48.005683 -44.702736)
			(xy 47.982087 -44.749046) (xy 47.951537 -44.791094) (xy 47.914786 -44.827845) (xy 47.872738 -44.858395)
			(xy 47.826428 -44.881991) (xy 47.776998 -44.898052) (xy 47.725663 -44.906182) (xy 47.673689 -44.906182)
			(xy 47.622354 -44.898052) (xy 47.572924 -44.881991) (xy 47.526614 -44.858395) (xy 47.484566 -44.827845)
			(xy 47.447815 -44.791094) (xy 47.417265 -44.749046) (xy 47.393669 -44.702736) (xy 47.377608 -44.653306)
			(xy 47.369478 -44.601971) (xy 47.229044 -44.601971) (xy 47.226827 -44.629325) (xy 47.213968 -44.681267)
			(xy 47.192909 -44.730458) (xy 47.164199 -44.775614) (xy 47.12859 -44.815555) (xy 47.10811 -44.832778)
			(xy 47.10811 -45.11929) (xy 47.128575 -45.136531) (xy 47.164187 -45.17647) (xy 47.192899 -45.221624)
			(xy 47.213962 -45.270814) (xy 47.226824 -45.322755) (xy 47.23115 -45.37609) (xy 47.229044 -45.402071)
			(xy 47.369478 -45.402071) (xy 47.369478 -45.350097) (xy 47.377608 -45.298762) (xy 47.393669 -45.249332)
			(xy 47.417265 -45.203022) (xy 47.447815 -45.160974) (xy 47.484566 -45.124223) (xy 47.526614 -45.093673)
			(xy 47.572924 -45.070077) (xy 47.622354 -45.054016) (xy 47.673689 -45.045886) (xy 47.725663 -45.045886)
			(xy 47.776998 -45.054016) (xy 47.826428 -45.070077) (xy 47.872738 -45.093673) (xy 47.914786 -45.124223)
			(xy 47.951537 -45.160974) (xy 47.982087 -45.203022) (xy 48.005683 -45.249332) (xy 48.021744 -45.298762)
			(xy 48.029874 -45.350097) (xy 48.030384 -45.376084) (xy 48.029874 -45.402071) (xy 48.021744 -45.453406)
			(xy 48.005683 -45.502836) (xy 47.982087 -45.549146) (xy 47.951537 -45.591194) (xy 47.914786 -45.627945)
			(xy 47.872738 -45.658495) (xy 47.826428 -45.682091) (xy 47.776998 -45.698152) (xy 47.725663 -45.706282)
			(xy 47.673689 -45.706282) (xy 47.622354 -45.698152) (xy 47.572924 -45.682091) (xy 47.526614 -45.658495)
			(xy 47.484566 -45.627945) (xy 47.447815 -45.591194) (xy 47.417265 -45.549146) (xy 47.393669 -45.502836)
			(xy 47.377608 -45.453406) (xy 47.369478 -45.402071) (xy 47.229044 -45.402071) (xy 47.226827 -45.429425)
			(xy 47.213968 -45.481367) (xy 47.192909 -45.530558) (xy 47.164199 -45.575714) (xy 47.12859 -45.615655)
			(xy 47.10811 -45.632878) (xy 47.10811 -45.919136) (xy 47.128572 -45.936377) (xy 47.164176 -45.976315)
			(xy 47.192881 -46.021466) (xy 47.213937 -46.070653) (xy 47.226793 -46.12259) (xy 47.231115 -46.175919)
			(xy 47.229005 -46.201917) (xy 47.369478 -46.201917) (xy 47.369478 -46.149943) (xy 47.377608 -46.098608)
			(xy 47.393669 -46.049178) (xy 47.417265 -46.002868) (xy 47.447815 -45.96082) (xy 47.484566 -45.924069)
			(xy 47.526614 -45.893519) (xy 47.572924 -45.869923) (xy 47.622354 -45.853862) (xy 47.673689 -45.845732)
			(xy 47.725663 -45.845732) (xy 47.776998 -45.853862) (xy 47.826428 -45.869923) (xy 47.872738 -45.893519)
			(xy 47.914786 -45.924069) (xy 47.951537 -45.96082) (xy 47.982087 -46.002868) (xy 48.005683 -46.049178)
			(xy 48.021744 -46.098608) (xy 48.029874 -46.149943) (xy 48.030384 -46.17593) (xy 48.029874 -46.201917)
			(xy 48.021744 -46.253252) (xy 48.005683 -46.302682) (xy 47.982087 -46.348992) (xy 47.951537 -46.39104)
			(xy 47.914786 -46.427791) (xy 47.872738 -46.458341) (xy 47.826428 -46.481937) (xy 47.776998 -46.497998)
			(xy 47.725663 -46.506128) (xy 47.673689 -46.506128) (xy 47.622354 -46.497998) (xy 47.572924 -46.481937)
			(xy 47.526614 -46.458341) (xy 47.484566 -46.427791) (xy 47.447815 -46.39104) (xy 47.417265 -46.348992)
			(xy 47.393669 -46.302682) (xy 47.377608 -46.253252) (xy 47.369478 -46.201917) (xy 47.229005 -46.201917)
			(xy 47.226787 -46.229248) (xy 47.213925 -46.281183) (xy 47.192864 -46.330367) (xy 47.164153 -46.375516)
			(xy 47.128544 -46.415449) (xy 47.10811 -46.432724) (xy 47.10811 -46.719236) (xy 47.126881 -46.735017)
			(xy 47.160004 -46.771179) (xy 47.187417 -46.81184) (xy 47.208516 -46.856107) (xy 47.222839 -46.903008)
			(xy 47.23007 -46.95151) (xy 47.230538 -46.97603) (xy 47.230538 -46.981618) (xy 47.230717 -46.995095)
			(xy 47.237311 -47.02122) (xy 47.250512 -47.044708) (xy 47.2694 -47.063923) (xy 47.292658 -47.077526)
			(xy 47.318666 -47.084567) (xy 47.332138 -47.084996) (xy 47.43196 -47.084996) (xy 47.455242 -47.08541)
			(xy 47.501239 -47.092658) (xy 47.545534 -47.107014) (xy 47.587038 -47.128123) (xy 47.624728 -47.155467)
			(xy 47.64151 -47.17161) (xy 47.739808 -47.269908)
		)
		(stroke
			(width 0)
			(type solid)
		)
		(fill yes)
		(layer "In2.Cu")
		(net "P3V3_P2V5_P1V8_RVDD")
	)
	(gr_poly
		(pts
			(xy 86.703916 -48.621442) (xy 86.703447 -48.607302) (xy 86.695676 -48.580109) (xy 86.680746 -48.55609)
			(xy 86.659802 -48.537086) (xy 86.63445 -48.524553) (xy 86.606632 -48.519453) (xy 86.578483 -48.522177)
			(xy 86.552159 -48.532516) (xy 86.540594 -48.54067) (xy 86.520581 -48.555446) (xy 86.477452 -48.580238)
			(xy 86.431464 -48.599207) (xy 86.383399 -48.61203) (xy 86.334073 -48.618491) (xy 86.3092 -48.618902)
			(xy 86.281949 -48.618416) (xy 86.228002 -48.61066) (xy 86.175708 -48.595305) (xy 86.126132 -48.572664)
			(xy 86.080282 -48.543198) (xy 86.039093 -48.507507) (xy 86.003402 -48.466318) (xy 85.973936 -48.420468)
			(xy 85.951295 -48.370892) (xy 85.93594 -48.318598) (xy 85.928184 -48.264651) (xy 85.928184 -48.210149)
			(xy 85.93594 -48.156202) (xy 85.951295 -48.103908) (xy 85.973936 -48.054332) (xy 86.003402 -48.008482)
			(xy 86.039093 -47.967293) (xy 86.080282 -47.931602) (xy 86.126132 -47.902136) (xy 86.175708 -47.879495)
			(xy 86.228002 -47.86414) (xy 86.281949 -47.856384) (xy 86.3092 -47.855886) (xy 86.334074 -47.856288)
			(xy 86.383399 -47.862756) (xy 86.431464 -47.875582) (xy 86.477455 -47.894548) (xy 86.520589 -47.919332)
			(xy 86.540594 -47.934118) (xy 86.552116 -47.942344) (xy 86.578452 -47.952701) (xy 86.60662 -47.955433)
			(xy 86.634456 -47.95033) (xy 86.659822 -47.937784) (xy 86.680772 -47.918758) (xy 86.695695 -47.894713)
			(xy 86.703447 -47.867496) (xy 86.703916 -47.853346) (xy 86.703916 -47.605442) (xy 86.703447 -47.591302)
			(xy 86.695676 -47.564109) (xy 86.680746 -47.54009) (xy 86.659802 -47.521086) (xy 86.63445 -47.508553)
			(xy 86.606632 -47.503453) (xy 86.578483 -47.506177) (xy 86.552159 -47.516516) (xy 86.540594 -47.52467)
			(xy 86.520581 -47.539446) (xy 86.477452 -47.564238) (xy 86.431464 -47.583207) (xy 86.383399 -47.59603)
			(xy 86.334073 -47.602491) (xy 86.3092 -47.602902) (xy 86.281949 -47.602416) (xy 86.228002 -47.59466)
			(xy 86.175708 -47.579305) (xy 86.126132 -47.556664) (xy 86.080282 -47.527198) (xy 86.039093 -47.491507)
			(xy 86.003402 -47.450318) (xy 85.973936 -47.404468) (xy 85.951295 -47.354892) (xy 85.93594 -47.302598)
			(xy 85.928184 -47.248651) (xy 85.928184 -47.194149) (xy 85.93594 -47.140202) (xy 85.951295 -47.087908)
			(xy 85.973936 -47.038332) (xy 86.003402 -46.992482) (xy 86.039093 -46.951293) (xy 86.080282 -46.915602)
			(xy 86.126132 -46.886136) (xy 86.175708 -46.863495) (xy 86.228002 -46.84814) (xy 86.281949 -46.840384)
			(xy 86.3092 -46.839886) (xy 86.334074 -46.840288) (xy 86.383399 -46.846756) (xy 86.431464 -46.859582)
			(xy 86.477455 -46.878548) (xy 86.520589 -46.903332) (xy 86.540594 -46.918118) (xy 86.552116 -46.926344)
			(xy 86.578452 -46.936701) (xy 86.60662 -46.939433) (xy 86.634456 -46.93433) (xy 86.659822 -46.921784)
			(xy 86.680772 -46.902758) (xy 86.695695 -46.878713) (xy 86.703447 -46.851496) (xy 86.703916 -46.837346)
			(xy 86.703916 -46.081442) (xy 86.703447 -46.067302) (xy 86.695676 -46.040109) (xy 86.680746 -46.01609)
			(xy 86.659802 -45.997086) (xy 86.63445 -45.984553) (xy 86.606632 -45.979453) (xy 86.578483 -45.982177)
			(xy 86.552159 -45.992516) (xy 86.540594 -46.00067) (xy 86.520581 -46.015446) (xy 86.477452 -46.040238)
			(xy 86.431464 -46.059207) (xy 86.383399 -46.07203) (xy 86.334073 -46.078491) (xy 86.3092 -46.078902)
			(xy 86.281947 -46.078439) (xy 86.227997 -46.070682) (xy 86.175699 -46.055326) (xy 86.126119 -46.032683)
			(xy 86.080267 -46.003215) (xy 86.039075 -45.967521) (xy 86.003382 -45.926328) (xy 85.973914 -45.880475)
			(xy 85.951272 -45.830895) (xy 85.935917 -45.778597) (xy 85.928161 -45.724647) (xy 85.927692 -45.697394)
			(xy 85.928227 -45.668477) (xy 85.936954 -45.611307) (xy 85.954209 -45.556107) (xy 85.979595 -45.504144)
			(xy 86.012531 -45.456606) (xy 86.052264 -45.414582) (xy 86.074758 -45.396404) (xy 86.086565 -45.386508)
			(xy 86.104086 -45.361186) (xy 86.113263 -45.331793) (xy 86.113262 -45.301) (xy 86.104083 -45.271607)
			(xy 86.08656 -45.246286) (xy 86.074758 -45.236384) (xy 86.052269 -45.218196) (xy 86.01252 -45.176183)
			(xy 85.979569 -45.12865) (xy 85.954172 -45.076688) (xy 85.93691 -45.021487) (xy 85.92818 -44.964312)
			(xy 85.927692 -44.935394) (xy 85.928178 -44.908143) (xy 85.935935 -44.854196) (xy 85.951291 -44.801902)
			(xy 85.973933 -44.752325) (xy 86.003399 -44.706476) (xy 86.039091 -44.665286) (xy 86.080281 -44.629595)
			(xy 86.126131 -44.60013) (xy 86.175708 -44.577489) (xy 86.228002 -44.562134) (xy 86.281949 -44.554378)
			(xy 86.3092 -44.553886) (xy 86.334074 -44.554288) (xy 86.383399 -44.560756) (xy 86.431464 -44.573582)
			(xy 86.477455 -44.592548) (xy 86.520589 -44.617332) (xy 86.540594 -44.632118) (xy 86.552116 -44.640344)
			(xy 86.578452 -44.650701) (xy 86.60662 -44.653433) (xy 86.634456 -44.64833) (xy 86.659822 -44.635784)
			(xy 86.680772 -44.616758) (xy 86.695695 -44.592713) (xy 86.703447 -44.565496) (xy 86.703916 -44.551346)
			(xy 86.703916 -43.541442) (xy 86.703447 -43.527302) (xy 86.695676 -43.500109) (xy 86.680746 -43.47609)
			(xy 86.659802 -43.457086) (xy 86.63445 -43.444553) (xy 86.606632 -43.439453) (xy 86.578483 -43.442177)
			(xy 86.552159 -43.452516) (xy 86.540594 -43.46067) (xy 86.520581 -43.475446) (xy 86.477452 -43.500238)
			(xy 86.431464 -43.519207) (xy 86.383399 -43.53203) (xy 86.334073 -43.538491) (xy 86.3092 -43.538902)
			(xy 86.281949 -43.538416) (xy 86.228002 -43.53066) (xy 86.175708 -43.515305) (xy 86.126132 -43.492664)
			(xy 86.080282 -43.463198) (xy 86.039093 -43.427507) (xy 86.003402 -43.386318) (xy 85.973936 -43.340468)
			(xy 85.951295 -43.290892) (xy 85.93594 -43.238598) (xy 85.928184 -43.184651) (xy 85.928184 -43.130149)
			(xy 85.93594 -43.076202) (xy 85.951295 -43.023908) (xy 85.973936 -42.974332) (xy 86.003402 -42.928482)
			(xy 86.039093 -42.887293) (xy 86.080282 -42.851602) (xy 86.126132 -42.822136) (xy 86.175708 -42.799495)
			(xy 86.228002 -42.78414) (xy 86.281949 -42.776384) (xy 86.3092 -42.775886) (xy 86.334074 -42.776288)
			(xy 86.383399 -42.782756) (xy 86.431464 -42.795582) (xy 86.477455 -42.814548) (xy 86.520589 -42.839332)
			(xy 86.540594 -42.854118) (xy 86.552116 -42.862344) (xy 86.578452 -42.872701) (xy 86.60662 -42.875433)
			(xy 86.634456 -42.87033) (xy 86.659822 -42.857784) (xy 86.680772 -42.838758) (xy 86.695695 -42.814713)
			(xy 86.703447 -42.787496) (xy 86.703916 -42.773346) (xy 86.703916 -42.525442) (xy 86.703447 -42.511302)
			(xy 86.695676 -42.484109) (xy 86.680746 -42.46009) (xy 86.659802 -42.441086) (xy 86.63445 -42.428553)
			(xy 86.606632 -42.423453) (xy 86.578483 -42.426177) (xy 86.552159 -42.436516) (xy 86.540594 -42.44467)
			(xy 86.520581 -42.459446) (xy 86.477452 -42.484238) (xy 86.431464 -42.503207) (xy 86.383399 -42.51603)
			(xy 86.334073 -42.522491) (xy 86.3092 -42.522902) (xy 86.281949 -42.522416) (xy 86.228002 -42.51466)
			(xy 86.175708 -42.499305) (xy 86.126132 -42.476664) (xy 86.080282 -42.447198) (xy 86.039093 -42.411507)
			(xy 86.003402 -42.370318) (xy 85.973936 -42.324468) (xy 85.951295 -42.274892) (xy 85.93594 -42.222598)
			(xy 85.928184 -42.168651) (xy 85.928184 -42.114149) (xy 85.93594 -42.060202) (xy 85.951295 -42.007908)
			(xy 85.973936 -41.958332) (xy 86.003402 -41.912482) (xy 86.039093 -41.871293) (xy 86.080282 -41.835602)
			(xy 86.126132 -41.806136) (xy 86.175708 -41.783495) (xy 86.228002 -41.76814) (xy 86.281949 -41.760384)
			(xy 86.3092 -41.759886) (xy 86.334074 -41.760288) (xy 86.383399 -41.766756) (xy 86.431464 -41.779582)
			(xy 86.477455 -41.798548) (xy 86.520589 -41.823332) (xy 86.540594 -41.838118) (xy 86.552116 -41.846344)
			(xy 86.578452 -41.856701) (xy 86.60662 -41.859433) (xy 86.634456 -41.85433) (xy 86.659822 -41.841784)
			(xy 86.680772 -41.822758) (xy 86.695695 -41.798713) (xy 86.703447 -41.771496) (xy 86.703916 -41.757346)
			(xy 86.703916 -40.917876) (xy 86.544912 -40.917876) (xy 86.53145 -40.927274) (xy 86.50701 -40.944121)
			(xy 86.454011 -40.970849) (xy 86.397513 -40.989051) (xy 86.338878 -40.998286) (xy 86.3092 -40.998902)
			(xy 86.283875 -40.998487) (xy 86.233671 -40.991778) (xy 86.184798 -40.978477) (xy 86.138118 -40.95882)
			(xy 86.094453 -40.933153) (xy 86.07425 -40.917876) (xy 84.41182 -40.917876) (xy 84.389347 -40.934822)
			(xy 84.340406 -40.962615) (xy 84.287909 -40.98291) (xy 84.233 -40.995267) (xy 84.17687 -40.999416)
			(xy 84.12074 -40.995267) (xy 84.065831 -40.98291) (xy 84.013334 -40.962615) (xy 83.964393 -40.934822)
			(xy 83.94192 -40.917876) (xy 82.621628 -40.917876) (xy 82.606249 -40.918405) (xy 82.576884 -40.927562)
			(xy 82.551582 -40.945051) (xy 82.53264 -40.969285) (xy 82.521778 -40.998062) (xy 82.520282 -41.01338)
			(xy 82.517992 -41.0421) (xy 82.505854 -41.09842) (xy 82.485386 -41.152274) (xy 82.457053 -41.202438)
			(xy 82.4215 -41.247772) (xy 82.379533 -41.287244) (xy 82.332109 -41.319958) (xy 82.280305 -41.345168)
			(xy 82.225299 -41.362302) (xy 82.168342 -41.37097) (xy 82.139536 -41.37152) (xy 82.112565 -41.37105)
			(xy 82.059161 -41.363445) (xy 82.00736 -41.348395) (xy 81.958195 -41.326201) (xy 81.912645 -41.297305)
			(xy 81.871618 -41.262282) (xy 81.835932 -41.221831) (xy 81.806298 -41.176758) (xy 81.79435 -41.152572)
			(xy 81.787961 -41.140221) (xy 81.769711 -41.119259) (xy 81.746486 -41.103991) (xy 81.720005 -41.095548)
			(xy 81.692229 -41.094555) (xy 81.665213 -41.101085) (xy 81.640956 -41.114655) (xy 81.630774 -41.124124)
			(xy 81.46288 -41.292018) (xy 81.46288 -42.006012) (xy 81.757518 -42.006012) (xy 81.761589 -41.95039)
			(xy 81.773715 -41.895953) (xy 81.793638 -41.843862) (xy 81.820934 -41.795227) (xy 81.85502 -41.751084)
			(xy 81.895169 -41.712375) (xy 81.940527 -41.679924) (xy 81.990127 -41.654423) (xy 82.042911 -41.636416)
			(xy 82.097754 -41.626286) (xy 82.153488 -41.624249) (xy 82.208925 -41.630349) (xy 82.262882 -41.644455)
			(xy 82.314211 -41.666267) (xy 82.361817 -41.695321) (xy 82.404685 -41.730996) (xy 82.441902 -41.772533)
			(xy 82.472675 -41.819046) (xy 82.496347 -41.869543) (xy 82.501718 -41.887394) (xy 83.794852 -41.887394)
			(xy 83.798923 -41.831772) (xy 83.811049 -41.777335) (xy 83.830972 -41.725244) (xy 83.858268 -41.676609)
			(xy 83.892354 -41.632466) (xy 83.932503 -41.593757) (xy 83.977861 -41.561306) (xy 84.027461 -41.535805)
			(xy 84.080245 -41.517798) (xy 84.135088 -41.507668) (xy 84.190822 -41.505631) (xy 84.246259 -41.511731)
			(xy 84.300216 -41.525837) (xy 84.351545 -41.547649) (xy 84.399151 -41.576703) (xy 84.442019 -41.612378)
			(xy 84.479236 -41.653915) (xy 84.510009 -41.700428) (xy 84.533681 -41.750925) (xy 84.549749 -41.804332)
			(xy 84.557869 -41.859508) (xy 84.558378 -41.887394) (xy 84.557869 -41.91528) (xy 84.549749 -41.970456)
			(xy 84.533681 -42.023863) (xy 84.510009 -42.07436) (xy 84.479236 -42.120873) (xy 84.442019 -42.16241)
			(xy 84.399151 -42.198085) (xy 84.351545 -42.227139) (xy 84.300216 -42.248951) (xy 84.246259 -42.263057)
			(xy 84.190822 -42.269157) (xy 84.135088 -42.26712) (xy 84.080245 -42.25699) (xy 84.027461 -42.238983)
			(xy 83.977861 -42.213482) (xy 83.932503 -42.181031) (xy 83.892354 -42.142322) (xy 83.858268 -42.098179)
			(xy 83.830972 -42.049544) (xy 83.811049 -41.997453) (xy 83.798923 -41.943016) (xy 83.794852 -41.887394)
			(xy 82.501718 -41.887394) (xy 82.512415 -41.92295) (xy 82.520535 -41.978126) (xy 82.521044 -42.006012)
			(xy 82.520535 -42.033898) (xy 82.512415 -42.089074) (xy 82.496347 -42.142481) (xy 82.472675 -42.192978)
			(xy 82.441902 -42.239491) (xy 82.404685 -42.281028) (xy 82.361817 -42.316703) (xy 82.314211 -42.345757)
			(xy 82.262882 -42.367569) (xy 82.208925 -42.381675) (xy 82.153488 -42.387775) (xy 82.097754 -42.385738)
			(xy 82.042911 -42.375608) (xy 81.990127 -42.357601) (xy 81.940527 -42.3321) (xy 81.895169 -42.299649)
			(xy 81.85502 -42.26094) (xy 81.820934 -42.216797) (xy 81.793638 -42.168162) (xy 81.773715 -42.116071)
			(xy 81.761589 -42.061634) (xy 81.757518 -42.006012) (xy 81.46288 -42.006012) (xy 81.46288 -43.022012)
			(xy 81.757518 -43.022012) (xy 81.761589 -42.96639) (xy 81.773715 -42.911953) (xy 81.793638 -42.859862)
			(xy 81.820934 -42.811227) (xy 81.85502 -42.767084) (xy 81.895169 -42.728375) (xy 81.940527 -42.695924)
			(xy 81.990127 -42.670423) (xy 82.042911 -42.652416) (xy 82.097754 -42.642286) (xy 82.153488 -42.640249)
			(xy 82.208925 -42.646349) (xy 82.262882 -42.660455) (xy 82.314211 -42.682267) (xy 82.361817 -42.711321)
			(xy 82.404685 -42.746996) (xy 82.441902 -42.788533) (xy 82.472675 -42.835046) (xy 82.496347 -42.885543)
			(xy 82.512415 -42.93895) (xy 82.520535 -42.994126) (xy 82.521044 -43.022012) (xy 82.520535 -43.049898)
			(xy 82.512415 -43.105074) (xy 82.496674 -43.157394) (xy 83.794852 -43.157394) (xy 83.798923 -43.101772)
			(xy 83.811049 -43.047335) (xy 83.830972 -42.995244) (xy 83.858268 -42.946609) (xy 83.892354 -42.902466)
			(xy 83.932503 -42.863757) (xy 83.977861 -42.831306) (xy 84.027461 -42.805805) (xy 84.080245 -42.787798)
			(xy 84.135088 -42.777668) (xy 84.190822 -42.775631) (xy 84.246259 -42.781731) (xy 84.300216 -42.795837)
			(xy 84.351545 -42.817649) (xy 84.399151 -42.846703) (xy 84.442019 -42.882378) (xy 84.479236 -42.923915)
			(xy 84.510009 -42.970428) (xy 84.533681 -43.020925) (xy 84.549749 -43.074332) (xy 84.557869 -43.129508)
			(xy 84.558378 -43.157394) (xy 84.557869 -43.18528) (xy 84.549749 -43.240456) (xy 84.533681 -43.293863)
			(xy 84.510009 -43.34436) (xy 84.479236 -43.390873) (xy 84.442019 -43.43241) (xy 84.399151 -43.468085)
			(xy 84.351545 -43.497139) (xy 84.300216 -43.518951) (xy 84.246259 -43.533057) (xy 84.190822 -43.539157)
			(xy 84.135088 -43.53712) (xy 84.080245 -43.52699) (xy 84.027461 -43.508983) (xy 83.977861 -43.483482)
			(xy 83.932503 -43.451031) (xy 83.892354 -43.412322) (xy 83.858268 -43.368179) (xy 83.830972 -43.319544)
			(xy 83.811049 -43.267453) (xy 83.798923 -43.213016) (xy 83.794852 -43.157394) (xy 82.496674 -43.157394)
			(xy 82.496347 -43.158481) (xy 82.472675 -43.208978) (xy 82.441902 -43.255491) (xy 82.404685 -43.297028)
			(xy 82.361817 -43.332703) (xy 82.314211 -43.361757) (xy 82.262882 -43.383569) (xy 82.208925 -43.397675)
			(xy 82.153488 -43.403775) (xy 82.097754 -43.401738) (xy 82.042911 -43.391608) (xy 81.990127 -43.373601)
			(xy 81.940527 -43.3481) (xy 81.895169 -43.315649) (xy 81.85502 -43.27694) (xy 81.820934 -43.232797)
			(xy 81.793638 -43.184162) (xy 81.773715 -43.132071) (xy 81.761589 -43.077634) (xy 81.757518 -43.022012)
			(xy 81.46288 -43.022012) (xy 81.46288 -44.038012) (xy 81.757518 -44.038012) (xy 81.761589 -43.98239)
			(xy 81.773715 -43.927953) (xy 81.793638 -43.875862) (xy 81.820934 -43.827227) (xy 81.85502 -43.783084)
			(xy 81.895169 -43.744375) (xy 81.940527 -43.711924) (xy 81.990127 -43.686423) (xy 82.042911 -43.668416)
			(xy 82.097754 -43.658286) (xy 82.153488 -43.656249) (xy 82.208925 -43.662349) (xy 82.262882 -43.676455)
			(xy 82.314211 -43.698267) (xy 82.361817 -43.727321) (xy 82.404685 -43.762996) (xy 82.441902 -43.804533)
			(xy 82.472675 -43.851046) (xy 82.496347 -43.901543) (xy 82.512415 -43.95495) (xy 82.520535 -44.010126)
			(xy 82.521044 -44.038012) (xy 82.520535 -44.065898) (xy 82.512415 -44.121074) (xy 82.496347 -44.174481)
			(xy 82.472675 -44.224978) (xy 82.441902 -44.271491) (xy 82.404685 -44.313028) (xy 82.361817 -44.348703)
			(xy 82.314211 -44.377757) (xy 82.262882 -44.399569) (xy 82.208925 -44.413675) (xy 82.153488 -44.419775)
			(xy 82.097754 -44.417738) (xy 82.042911 -44.407608) (xy 81.990127 -44.389601) (xy 81.940527 -44.3641)
			(xy 81.895169 -44.331649) (xy 81.85502 -44.29294) (xy 81.820934 -44.248797) (xy 81.793638 -44.200162)
			(xy 81.773715 -44.148071) (xy 81.761589 -44.093634) (xy 81.757518 -44.038012) (xy 81.46288 -44.038012)
			(xy 81.46288 -45.054012) (xy 81.757518 -45.054012) (xy 81.761589 -44.99839) (xy 81.773715 -44.943953)
			(xy 81.793638 -44.891862) (xy 81.820934 -44.843227) (xy 81.85502 -44.799084) (xy 81.895169 -44.760375)
			(xy 81.940527 -44.727924) (xy 81.990127 -44.702423) (xy 82.042911 -44.684416) (xy 82.097754 -44.674286)
			(xy 82.153488 -44.672249) (xy 82.208925 -44.678349) (xy 82.262882 -44.692455) (xy 82.314211 -44.714267)
			(xy 82.361817 -44.743321) (xy 82.404685 -44.778996) (xy 82.441902 -44.820533) (xy 82.472675 -44.867046)
			(xy 82.496347 -44.917543) (xy 82.512415 -44.97095) (xy 82.520535 -45.026126) (xy 82.521044 -45.054012)
			(xy 82.520535 -45.081898) (xy 82.512415 -45.137074) (xy 82.496347 -45.190481) (xy 82.472675 -45.240978)
			(xy 82.441902 -45.287491) (xy 82.404685 -45.329028) (xy 82.361817 -45.364703) (xy 82.314211 -45.393757)
			(xy 82.262882 -45.415569) (xy 82.208925 -45.429675) (xy 82.153488 -45.435775) (xy 82.097754 -45.433738)
			(xy 82.042911 -45.423608) (xy 81.990127 -45.405601) (xy 81.940527 -45.3801) (xy 81.895169 -45.347649)
			(xy 81.85502 -45.30894) (xy 81.820934 -45.264797) (xy 81.793638 -45.216162) (xy 81.773715 -45.164071)
			(xy 81.761589 -45.109634) (xy 81.757518 -45.054012) (xy 81.46288 -45.054012) (xy 81.46288 -46.463204)
			(xy 83.795362 -46.463204) (xy 83.795913 -46.434108) (xy 83.804744 -46.376589) (xy 83.822216 -46.321081)
			(xy 83.847923 -46.268875) (xy 83.881267 -46.221182) (xy 83.921474 -46.179114) (xy 83.944206 -46.160944)
			(xy 83.954557 -46.152525) (xy 83.970815 -46.13138) (xy 83.981036 -46.106743) (xy 83.984523 -46.080299)
			(xy 83.981036 -46.053856) (xy 83.970814 -46.029219) (xy 83.954556 -46.008074) (xy 83.944206 -45.999654)
			(xy 83.921451 -45.981513) (xy 83.881258 -45.93943) (xy 83.847923 -45.891729) (xy 83.822221 -45.839518)
			(xy 83.804748 -45.78401) (xy 83.79591 -45.726491) (xy 83.795362 -45.697394) (xy 83.795809 -45.670023)
			(xy 83.803629 -45.615842) (xy 83.819122 -45.563339) (xy 83.841968 -45.513592) (xy 83.871698 -45.467626)
			(xy 83.889342 -45.446696) (xy 83.898581 -45.435372) (xy 83.910753 -45.408812) (xy 83.914922 -45.379895)
			(xy 83.91075 -45.350979) (xy 83.898576 -45.324421) (xy 83.889342 -45.313092) (xy 83.871695 -45.292164)
			(xy 83.841969 -45.246196) (xy 83.819123 -45.196449) (xy 83.803627 -45.143946) (xy 83.795798 -45.089767)
			(xy 83.795799 -45.035024) (xy 83.803629 -44.980845) (xy 83.819126 -44.928343) (xy 83.841973 -44.878596)
			(xy 83.8717 -44.832628) (xy 83.889342 -44.811696) (xy 83.898581 -44.800372) (xy 83.910753 -44.773812)
			(xy 83.914922 -44.744895) (xy 83.91075 -44.715979) (xy 83.898576 -44.689421) (xy 83.889342 -44.678092)
			(xy 83.871692 -44.657168) (xy 83.841981 -44.611194) (xy 83.819146 -44.561444) (xy 83.803658 -44.508942)
			(xy 83.795833 -44.454764) (xy 83.795362 -44.427394) (xy 83.795848 -44.400143) (xy 83.803604 -44.346195)
			(xy 83.818959 -44.2939) (xy 83.841601 -44.244323) (xy 83.871067 -44.198473) (xy 83.906758 -44.157282)
			(xy 83.947949 -44.121591) (xy 83.993799 -44.092125) (xy 84.043376 -44.069483) (xy 84.095671 -44.054128)
			(xy 84.149619 -44.046372) (xy 84.204121 -44.046372) (xy 84.258069 -44.054128) (xy 84.310364 -44.069483)
			(xy 84.359941 -44.092125) (xy 84.405791 -44.121591) (xy 84.446982 -44.157282) (xy 84.482673 -44.198473)
			(xy 84.512139 -44.244323) (xy 84.534781 -44.2939) (xy 84.550136 -44.346195) (xy 84.557892 -44.400143)
			(xy 84.558378 -44.427394) (xy 84.557914 -44.454764) (xy 84.550096 -44.508944) (xy 84.534607 -44.561447)
			(xy 84.511765 -44.611194) (xy 84.48204 -44.657161) (xy 84.464398 -44.678092) (xy 84.455167 -44.689424)
			(xy 84.442989 -44.71598) (xy 84.438816 -44.744895) (xy 84.442987 -44.773811) (xy 84.455162 -44.800369)
			(xy 84.464398 -44.811696) (xy 84.482032 -44.832634) (xy 84.511755 -44.878601) (xy 84.534599 -44.928347)
			(xy 84.550095 -44.980848) (xy 84.557923 -45.035025) (xy 84.557924 -45.089766) (xy 84.550097 -45.143943)
			(xy 84.534602 -45.196444) (xy 84.511759 -45.246191) (xy 84.482037 -45.292159) (xy 84.464398 -45.313092)
			(xy 84.455167 -45.324424) (xy 84.442989 -45.35098) (xy 84.438816 -45.379895) (xy 84.442987 -45.408811)
			(xy 84.455162 -45.435369) (xy 84.464398 -45.446696) (xy 84.482048 -45.467619) (xy 84.511759 -45.513594)
			(xy 84.534592 -45.563344) (xy 84.550081 -45.615847) (xy 84.557906 -45.670024) (xy 84.558378 -45.697394)
			(xy 84.55781 -45.72649) (xy 84.54898 -45.784007) (xy 84.531511 -45.839513) (xy 84.505807 -45.89172)
			(xy 84.472467 -45.939412) (xy 84.432264 -45.981483) (xy 84.409534 -45.999654) (xy 84.399261 -46.008131)
			(xy 84.383097 -46.029289) (xy 84.37294 -46.053901) (xy 84.369476 -46.080299) (xy 84.37294 -46.106698)
			(xy 84.383097 -46.13131) (xy 84.39926 -46.152468) (xy 84.409534 -46.160944) (xy 84.432275 -46.179102)
			(xy 84.472472 -46.22118) (xy 84.50581 -46.268877) (xy 84.531514 -46.321084) (xy 84.54899 -46.376591)
			(xy 84.557829 -46.434108) (xy 84.558378 -46.463204) (xy 84.557892 -46.490455) (xy 84.550136 -46.544403)
			(xy 84.534781 -46.596698) (xy 84.512139 -46.646275) (xy 84.482673 -46.692125) (xy 84.446982 -46.733316)
			(xy 84.405791 -46.769007) (xy 84.359941 -46.798473) (xy 84.310364 -46.821115) (xy 84.258069 -46.83647)
			(xy 84.204121 -46.844226) (xy 84.149619 -46.844226) (xy 84.095671 -46.83647) (xy 84.043376 -46.821115)
			(xy 83.993799 -46.798473) (xy 83.947949 -46.769007) (xy 83.906758 -46.733316) (xy 83.871067 -46.692125)
			(xy 83.841601 -46.646275) (xy 83.818959 -46.596698) (xy 83.803604 -46.544403) (xy 83.795848 -46.490455)
			(xy 83.795362 -46.463204) (xy 81.46288 -46.463204) (xy 81.46288 -48.872394) (xy 83.795362 -48.872394)
			(xy 83.795809 -48.845023) (xy 83.803629 -48.790842) (xy 83.819122 -48.738339) (xy 83.841968 -48.688592)
			(xy 83.871698 -48.642626) (xy 83.889342 -48.621696) (xy 83.898581 -48.610372) (xy 83.910753 -48.583812)
			(xy 83.914922 -48.554895) (xy 83.91075 -48.525979) (xy 83.898576 -48.499421) (xy 83.889342 -48.488092)
			(xy 83.871695 -48.467164) (xy 83.841969 -48.421196) (xy 83.819123 -48.371449) (xy 83.803627 -48.318946)
			(xy 83.795798 -48.264767) (xy 83.795799 -48.210024) (xy 83.803629 -48.155845) (xy 83.819126 -48.103343)
			(xy 83.841973 -48.053596) (xy 83.8717 -48.007628) (xy 83.889342 -47.986696) (xy 83.898581 -47.975372)
			(xy 83.910753 -47.948812) (xy 83.914922 -47.919895) (xy 83.91075 -47.890979) (xy 83.898576 -47.864421)
			(xy 83.889342 -47.853092) (xy 83.871692 -47.832168) (xy 83.841981 -47.786194) (xy 83.819146 -47.736444)
			(xy 83.803658 -47.683942) (xy 83.795833 -47.629764) (xy 83.795362 -47.602394) (xy 83.795848 -47.575143)
			(xy 83.803604 -47.521195) (xy 83.818959 -47.4689) (xy 83.841601 -47.419323) (xy 83.871067 -47.373473)
			(xy 83.906758 -47.332282) (xy 83.947949 -47.296591) (xy 83.993799 -47.267125) (xy 84.043376 -47.244483)
			(xy 84.095671 -47.229128) (xy 84.149619 -47.221372) (xy 84.204121 -47.221372) (xy 84.258069 -47.229128)
			(xy 84.310364 -47.244483) (xy 84.359941 -47.267125) (xy 84.405791 -47.296591) (xy 84.446982 -47.332282)
			(xy 84.482673 -47.373473) (xy 84.512139 -47.419323) (xy 84.534781 -47.4689) (xy 84.550136 -47.521195)
			(xy 84.557892 -47.575143) (xy 84.558378 -47.602394) (xy 84.557914 -47.629764) (xy 84.550096 -47.683944)
			(xy 84.534607 -47.736447) (xy 84.511765 -47.786194) (xy 84.48204 -47.832161) (xy 84.464398 -47.853092)
			(xy 84.455167 -47.864424) (xy 84.442989 -47.89098) (xy 84.438816 -47.919895) (xy 84.442987 -47.948811)
			(xy 84.455162 -47.975369) (xy 84.464398 -47.986696) (xy 84.482032 -48.007634) (xy 84.511755 -48.053601)
			(xy 84.534599 -48.103347) (xy 84.550095 -48.155848) (xy 84.557923 -48.210025) (xy 84.557924 -48.264766)
			(xy 84.550097 -48.318943) (xy 84.534602 -48.371444) (xy 84.511759 -48.421191) (xy 84.482037 -48.467159)
			(xy 84.464398 -48.488092) (xy 84.455167 -48.499424) (xy 84.442989 -48.52598) (xy 84.438816 -48.554895)
			(xy 84.442987 -48.583811) (xy 84.455162 -48.610369) (xy 84.464398 -48.621696) (xy 84.482048 -48.642619)
			(xy 84.511759 -48.688594) (xy 84.534592 -48.738344) (xy 84.550081 -48.790847) (xy 84.557906 -48.845024)
			(xy 84.558378 -48.872394) (xy 84.557892 -48.899645) (xy 84.550136 -48.953593) (xy 84.534781 -49.005888)
			(xy 84.512139 -49.055465) (xy 84.482673 -49.101315) (xy 84.446982 -49.142506) (xy 84.405791 -49.178197)
			(xy 84.359941 -49.207663) (xy 84.310364 -49.230305) (xy 84.258069 -49.24566) (xy 84.204121 -49.253416)
			(xy 84.149619 -49.253416) (xy 84.095671 -49.24566) (xy 84.043376 -49.230305) (xy 83.993799 -49.207663)
			(xy 83.947949 -49.178197) (xy 83.906758 -49.142506) (xy 83.871067 -49.101315) (xy 83.841601 -49.055465)
			(xy 83.818959 -49.005888) (xy 83.803604 -48.953593) (xy 83.795848 -48.899645) (xy 83.795362 -48.872394)
			(xy 81.46288 -48.872394) (xy 81.46288 -49.172622) (xy 81.005426 -49.630076) (xy 81.005426 -50.038)
			(xy 85.237064 -50.038) (xy 85.241135 -49.982378) (xy 85.253261 -49.927941) (xy 85.273184 -49.87585)
			(xy 85.30048 -49.827215) (xy 85.334566 -49.783072) (xy 85.374715 -49.744363) (xy 85.420073 -49.711912)
			(xy 85.469673 -49.686411) (xy 85.522457 -49.668404) (xy 85.5773 -49.658274) (xy 85.633034 -49.656237)
			(xy 85.688471 -49.662337) (xy 85.742428 -49.676443) (xy 85.793757 -49.698255) (xy 85.841363 -49.727309)
			(xy 85.884231 -49.762984) (xy 85.921448 -49.804521) (xy 85.952221 -49.851034) (xy 85.975893 -49.901531)
			(xy 85.991961 -49.954938) (xy 86.000081 -50.010114) (xy 86.00059 -50.038) (xy 86.000081 -50.065886)
			(xy 85.991961 -50.121062) (xy 85.975893 -50.174469) (xy 85.952221 -50.224966) (xy 85.921448 -50.271479)
			(xy 85.884231 -50.313016) (xy 85.841363 -50.348691) (xy 85.793757 -50.377745) (xy 85.742428 -50.399557)
			(xy 85.688471 -50.413663) (xy 85.633034 -50.419763) (xy 85.5773 -50.417726) (xy 85.522457 -50.407596)
			(xy 85.469673 -50.389589) (xy 85.420073 -50.364088) (xy 85.374715 -50.331637) (xy 85.334566 -50.292928)
			(xy 85.30048 -50.248785) (xy 85.273184 -50.20015) (xy 85.253261 -50.148059) (xy 85.241135 -50.093622)
			(xy 85.237064 -50.038) (xy 81.005426 -50.038) (xy 81.005426 -50.628042) (xy 81.094072 -50.716688)
			(xy 81.119472 -50.712624) (xy 81.134172 -50.710468) (xy 81.163797 -50.708178) (xy 81.178654 -50.708052)
			(xy 81.20591 -50.708512) (xy 81.259868 -50.716263) (xy 81.312174 -50.731615) (xy 81.361762 -50.754254)
			(xy 81.407624 -50.78372) (xy 81.448826 -50.819413) (xy 81.484528 -50.860607) (xy 81.514005 -50.906462)
			(xy 81.536655 -50.956045) (xy 81.552019 -51.008348) (xy 81.559782 -51.062304) (xy 81.560162 -51.08956)
			(xy 81.56003 -51.104417) (xy 81.557743 -51.134042) (xy 81.55559 -51.148742) (xy 81.551526 -51.174142)
			(xy 81.554574 -51.17719) (xy 82.608164 -51.17719) (xy 82.612235 -51.121568) (xy 82.624361 -51.067131)
			(xy 82.644284 -51.01504) (xy 82.67158 -50.966405) (xy 82.705666 -50.922262) (xy 82.745815 -50.883553)
			(xy 82.791173 -50.851102) (xy 82.840773 -50.825601) (xy 82.893557 -50.807594) (xy 82.9484 -50.797464)
			(xy 83.004134 -50.795427) (xy 83.059571 -50.801527) (xy 83.113528 -50.815633) (xy 83.164857 -50.837445)
			(xy 83.212463 -50.866499) (xy 83.255331 -50.902174) (xy 83.292548 -50.943711) (xy 83.323321 -50.990224)
			(xy 83.346993 -51.040721) (xy 83.363061 -51.094128) (xy 83.371181 -51.149304) (xy 83.37169 -51.17719)
			(xy 83.371181 -51.205076) (xy 83.363061 -51.260252) (xy 83.346993 -51.313659) (xy 83.336191 -51.336702)
			(xy 85.216998 -51.336702) (xy 85.221069 -51.28108) (xy 85.233195 -51.226643) (xy 85.253118 -51.174552)
			(xy 85.280414 -51.125917) (xy 85.3145 -51.081774) (xy 85.354649 -51.043065) (xy 85.400007 -51.010614)
			(xy 85.449607 -50.985113) (xy 85.502391 -50.967106) (xy 85.557234 -50.956976) (xy 85.612968 -50.954939)
			(xy 85.668405 -50.961039) (xy 85.722362 -50.975145) (xy 85.773691 -50.996957) (xy 85.821297 -51.026011)
			(xy 85.864165 -51.061686) (xy 85.901382 -51.103223) (xy 85.932155 -51.149736) (xy 85.955827 -51.200233)
			(xy 85.971895 -51.25364) (xy 85.980015 -51.308816) (xy 85.980524 -51.336702) (xy 85.980015 -51.364588)
			(xy 85.971895 -51.419764) (xy 85.955827 -51.473171) (xy 85.932155 -51.523668) (xy 85.901382 -51.570181)
			(xy 85.864165 -51.611718) (xy 85.821297 -51.647393) (xy 85.773691 -51.676447) (xy 85.722362 -51.698259)
			(xy 85.668405 -51.712365) (xy 85.612968 -51.718465) (xy 85.557234 -51.716428) (xy 85.502391 -51.706298)
			(xy 85.449607 -51.688291) (xy 85.400007 -51.66279) (xy 85.354649 -51.630339) (xy 85.3145 -51.59163)
			(xy 85.280414 -51.547487) (xy 85.253118 -51.498852) (xy 85.233195 -51.446761) (xy 85.221069 -51.392324)
			(xy 85.216998 -51.336702) (xy 83.336191 -51.336702) (xy 83.323321 -51.364156) (xy 83.292548 -51.410669)
			(xy 83.255331 -51.452206) (xy 83.212463 -51.487881) (xy 83.164857 -51.516935) (xy 83.113528 -51.538747)
			(xy 83.059571 -51.552853) (xy 83.004134 -51.558953) (xy 82.9484 -51.556916) (xy 82.893557 -51.546786)
			(xy 82.840773 -51.528779) (xy 82.791173 -51.503278) (xy 82.745815 -51.470827) (xy 82.705666 -51.432118)
			(xy 82.67158 -51.387975) (xy 82.644284 -51.33934) (xy 82.624361 -51.287249) (xy 82.612235 -51.232812)
			(xy 82.608164 -51.17719) (xy 81.554574 -51.17719) (xy 81.816194 -51.43881) (xy 81.816194 -52.24399)
			(xy 82.65871 -52.24399) (xy 82.662781 -52.188368) (xy 82.674907 -52.133931) (xy 82.69483 -52.08184)
			(xy 82.722126 -52.033205) (xy 82.756212 -51.989062) (xy 82.796361 -51.950353) (xy 82.841719 -51.917902)
			(xy 82.891319 -51.892401) (xy 82.944103 -51.874394) (xy 82.998946 -51.864264) (xy 83.05468 -51.862227)
			(xy 83.110117 -51.868327) (xy 83.164074 -51.882433) (xy 83.215403 -51.904245) (xy 83.263009 -51.933299)
			(xy 83.305877 -51.968974) (xy 83.343094 -52.010511) (xy 83.373867 -52.057024) (xy 83.397539 -52.107521)
			(xy 83.413607 -52.160928) (xy 83.421727 -52.216104) (xy 83.422236 -52.24399) (xy 83.421727 -52.271876)
			(xy 83.413607 -52.327052) (xy 83.40589 -52.352702) (xy 85.216998 -52.352702) (xy 85.221069 -52.29708)
			(xy 85.233195 -52.242643) (xy 85.253118 -52.190552) (xy 85.280414 -52.141917) (xy 85.3145 -52.097774)
			(xy 85.354649 -52.059065) (xy 85.400007 -52.026614) (xy 85.449607 -52.001113) (xy 85.502391 -51.983106)
			(xy 85.557234 -51.972976) (xy 85.612968 -51.970939) (xy 85.668405 -51.977039) (xy 85.722362 -51.991145)
			(xy 85.773691 -52.012957) (xy 85.821297 -52.042011) (xy 85.864165 -52.077686) (xy 85.901382 -52.119223)
			(xy 85.932155 -52.165736) (xy 85.955827 -52.216233) (xy 85.971895 -52.26964) (xy 85.980015 -52.324816)
			(xy 85.980524 -52.352702) (xy 85.980015 -52.380588) (xy 85.971895 -52.435764) (xy 85.955827 -52.489171)
			(xy 85.932155 -52.539668) (xy 85.901382 -52.586181) (xy 85.864165 -52.627718) (xy 85.821297 -52.663393)
			(xy 85.773691 -52.692447) (xy 85.722362 -52.714259) (xy 85.668405 -52.728365) (xy 85.612968 -52.734465)
			(xy 85.557234 -52.732428) (xy 85.502391 -52.722298) (xy 85.449607 -52.704291) (xy 85.400007 -52.67879)
			(xy 85.354649 -52.646339) (xy 85.3145 -52.60763) (xy 85.280414 -52.563487) (xy 85.253118 -52.514852)
			(xy 85.233195 -52.462761) (xy 85.221069 -52.408324) (xy 85.216998 -52.352702) (xy 83.40589 -52.352702)
			(xy 83.397539 -52.380459) (xy 83.373867 -52.430956) (xy 83.343094 -52.477469) (xy 83.305877 -52.519006)
			(xy 83.263009 -52.554681) (xy 83.215403 -52.583735) (xy 83.164074 -52.605547) (xy 83.110117 -52.619653)
			(xy 83.05468 -52.625753) (xy 82.998946 -52.623716) (xy 82.944103 -52.613586) (xy 82.891319 -52.595579)
			(xy 82.841719 -52.570078) (xy 82.796361 -52.537627) (xy 82.756212 -52.498918) (xy 82.722126 -52.454775)
			(xy 82.69483 -52.40614) (xy 82.674907 -52.354049) (xy 82.662781 -52.299612) (xy 82.65871 -52.24399)
			(xy 81.816194 -52.24399) (xy 81.816194 -53.136546) (xy 81.83496 -53.156131) (xy 81.86733 -53.199652)
			(xy 81.893211 -53.247319) (xy 81.912079 -53.29817) (xy 81.914811 -53.31079) (xy 82.608164 -53.31079)
			(xy 82.612235 -53.255168) (xy 82.624361 -53.200731) (xy 82.644284 -53.14864) (xy 82.67158 -53.100005)
			(xy 82.705666 -53.055862) (xy 82.745815 -53.017153) (xy 82.791173 -52.984702) (xy 82.840773 -52.959201)
			(xy 82.893557 -52.941194) (xy 82.9484 -52.931064) (xy 83.004134 -52.929027) (xy 83.059571 -52.935127)
			(xy 83.113528 -52.949233) (xy 83.164857 -52.971045) (xy 83.212463 -53.000099) (xy 83.255331 -53.035774)
			(xy 83.292548 -53.077311) (xy 83.323321 -53.123824) (xy 83.346993 -53.174321) (xy 83.363061 -53.227728)
			(xy 83.371181 -53.282904) (xy 83.37169 -53.31079) (xy 83.371181 -53.338676) (xy 83.366762 -53.368702)
			(xy 85.216998 -53.368702) (xy 85.221069 -53.31308) (xy 85.233195 -53.258643) (xy 85.253118 -53.206552)
			(xy 85.280414 -53.157917) (xy 85.3145 -53.113774) (xy 85.354649 -53.075065) (xy 85.400007 -53.042614)
			(xy 85.449607 -53.017113) (xy 85.502391 -52.999106) (xy 85.557234 -52.988976) (xy 85.612968 -52.986939)
			(xy 85.668405 -52.993039) (xy 85.722362 -53.007145) (xy 85.773691 -53.028957) (xy 85.821297 -53.058011)
			(xy 85.864165 -53.093686) (xy 85.901382 -53.135223) (xy 85.932155 -53.181736) (xy 85.955827 -53.232233)
			(xy 85.971895 -53.28564) (xy 85.980015 -53.340816) (xy 85.980524 -53.368702) (xy 85.980015 -53.396588)
			(xy 85.971895 -53.451764) (xy 85.955827 -53.505171) (xy 85.932155 -53.555668) (xy 85.901382 -53.602181)
			(xy 85.864165 -53.643718) (xy 85.821297 -53.679393) (xy 85.773691 -53.708447) (xy 85.722362 -53.730259)
			(xy 85.668405 -53.744365) (xy 85.612968 -53.750465) (xy 85.557234 -53.748428) (xy 85.502391 -53.738298)
			(xy 85.449607 -53.720291) (xy 85.400007 -53.69479) (xy 85.354649 -53.662339) (xy 85.3145 -53.62363)
			(xy 85.280414 -53.579487) (xy 85.253118 -53.530852) (xy 85.233195 -53.478761) (xy 85.221069 -53.424324)
			(xy 85.216998 -53.368702) (xy 83.366762 -53.368702) (xy 83.363061 -53.393852) (xy 83.346993 -53.447259)
			(xy 83.323321 -53.497756) (xy 83.292548 -53.544269) (xy 83.255331 -53.585806) (xy 83.212463 -53.621481)
			(xy 83.164857 -53.650535) (xy 83.113528 -53.672347) (xy 83.059571 -53.686453) (xy 83.004134 -53.692553)
			(xy 82.9484 -53.690516) (xy 82.893557 -53.680386) (xy 82.840773 -53.662379) (xy 82.791173 -53.636878)
			(xy 82.745815 -53.604427) (xy 82.705666 -53.565718) (xy 82.67158 -53.521575) (xy 82.644284 -53.47294)
			(xy 82.624361 -53.420849) (xy 82.612235 -53.366412) (xy 82.608164 -53.31079) (xy 81.914811 -53.31079)
			(xy 81.923555 -53.351182) (xy 81.927408 -53.405284) (xy 81.92356 -53.459387) (xy 81.912088 -53.5124)
			(xy 81.893223 -53.563253) (xy 81.867347 -53.610922) (xy 81.83498 -53.654446) (xy 81.816194 -53.67401)
			(xy 81.816194 -53.8226) (xy 81.8261 -53.836062) (xy 81.843389 -53.860711) (xy 81.87081 -53.914309)
			(xy 81.889482 -53.971546) (xy 81.898943 -54.031003) (xy 81.899506 -54.061106) (xy 81.899086 -54.086816)
			(xy 81.892182 -54.13777) (xy 81.8785 -54.187335) (xy 81.858288 -54.234616) (xy 81.83918 -54.266592)
			(xy 82.607656 -54.266592) (xy 82.611727 -54.21097) (xy 82.623853 -54.156533) (xy 82.643776 -54.104442)
			(xy 82.671072 -54.055807) (xy 82.705158 -54.011664) (xy 82.745307 -53.972955) (xy 82.790665 -53.940504)
			(xy 82.840265 -53.915003) (xy 82.893049 -53.896996) (xy 82.947892 -53.886866) (xy 83.003626 -53.884829)
			(xy 83.059063 -53.890929) (xy 83.11302 -53.905035) (xy 83.164349 -53.926847) (xy 83.211955 -53.955901)
			(xy 83.254823 -53.991576) (xy 83.29204 -54.033113) (xy 83.322813 -54.079626) (xy 83.346485 -54.130123)
			(xy 83.362553 -54.18353) (xy 83.370673 -54.238706) (xy 83.371182 -54.266592) (xy 83.370673 -54.294478)
			(xy 83.362553 -54.349654) (xy 83.346485 -54.403061) (xy 83.322813 -54.453558) (xy 83.29204 -54.500071)
			(xy 83.254823 -54.541608) (xy 83.211955 -54.577283) (xy 83.164349 -54.606337) (xy 83.11302 -54.628149)
			(xy 83.059063 -54.642255) (xy 83.003626 -54.648355) (xy 82.947892 -54.646318) (xy 82.893049 -54.636188)
			(xy 82.840265 -54.618181) (xy 82.790665 -54.59268) (xy 82.745307 -54.560229) (xy 82.705158 -54.52152)
			(xy 82.671072 -54.477377) (xy 82.643776 -54.428742) (xy 82.623853 -54.376651) (xy 82.611727 -54.322214)
			(xy 82.607656 -54.266592) (xy 81.83918 -54.266592) (xy 81.831912 -54.278755) (xy 81.816194 -54.299104)
			(xy 81.816194 -54.472332) (xy 81.831618 -54.492585) (xy 81.857528 -54.536406) (xy 81.877375 -54.583285)
			(xy 81.890806 -54.632389) (xy 81.897582 -54.682844) (xy 81.897982 -54.708298) (xy 81.89752 -54.734821)
			(xy 81.890161 -54.787354) (xy 81.875598 -54.838362) (xy 81.854112 -54.886863) (xy 81.826117 -54.93192)
			(xy 81.792152 -54.972667) (xy 81.752872 -55.008318) (xy 81.709034 -55.038186) (xy 81.661482 -55.061696)
			(xy 81.611132 -55.078394) (xy 81.558955 -55.08796) (xy 81.532476 -55.089552) (xy 81.512664 -55.090314)
			(xy 80.927702 -55.675276) (xy 80.926178 -55.693818) (xy 80.923478 -55.720106) (xy 80.911749 -55.771633)
			(xy 80.89302 -55.821047) (xy 80.867649 -55.867404) (xy 80.852264 -55.88889) (xy 80.842104 -55.902606)
			(xy 80.842104 -55.96636) (xy 80.84169 -55.989642) (xy 80.834442 -56.035639) (xy 80.820086 -56.079934)
			(xy 80.798977 -56.121438) (xy 80.771633 -56.159128) (xy 80.75549 -56.17591) (xy 80.30845 -56.62295)
			(xy 80.29167 -56.639094) (xy 80.253979 -56.666433) (xy 80.212474 -56.687537) (xy 80.168178 -56.701886)
			(xy 80.122182 -56.709126) (xy 80.0989 -56.709564) (xy 77.50683 -56.709564) (xy 76.734416 -57.029858)
			(xy 76.722196 -57.035374) (xy 76.700974 -57.051743) (xy 76.684743 -57.073071) (xy 76.674622 -57.097888)
			(xy 76.671308 -57.124484) (xy 76.67503 -57.151026) (xy 76.685531 -57.175685) (xy 76.702088 -57.196761)
			(xy 76.712572 -57.205118) (xy 76.735951 -57.22325) (xy 76.777345 -57.26552) (xy 76.811718 -57.313673)
			(xy 76.838244 -57.366555) (xy 76.856287 -57.422899) (xy 76.865416 -57.481353) (xy 76.865988 -57.510934)
			(xy 76.865556 -57.537159) (xy 76.858376 -57.589116) (xy 76.844142 -57.639598) (xy 76.823122 -57.687653)
			(xy 76.795714 -57.732372) (xy 76.762436 -57.772913) (xy 76.723914 -57.80851) (xy 76.680877 -57.838491)
			(xy 76.657708 -57.850786) (xy 76.645429 -57.857522) (xy 76.624855 -57.87651) (xy 76.610215 -57.900374)
			(xy 76.602612 -57.927318) (xy 76.602616 -57.955315) (xy 76.610229 -57.982257) (xy 76.624876 -58.006116)
			(xy 76.645456 -58.025097) (xy 76.657708 -58.031888) (xy 76.680875 -58.044185) (xy 76.723902 -58.074178)
			(xy 76.762416 -58.109781) (xy 76.795692 -58.150322) (xy 76.823103 -58.195039) (xy 76.844132 -58.243088)
			(xy 76.858383 -58.293564) (xy 76.865587 -58.345516) (xy 76.865895 -58.365644) (xy 78.236826 -58.365644)
			(xy 78.237277 -58.339422) (xy 78.244479 -58.287474) (xy 78.258725 -58.237001) (xy 78.279748 -58.188955)
			(xy 78.307152 -58.144239) (xy 78.34042 -58.103696) (xy 78.378925 -58.068091) (xy 78.421943 -58.038092)
			(xy 78.445106 -58.025792) (xy 78.457353 -58.018994) (xy 78.47793 -58.000013) (xy 78.492575 -57.976155)
			(xy 78.500186 -57.949216) (xy 78.500191 -57.921221) (xy 78.49259 -57.894279) (xy 78.477953 -57.870415)
			(xy 78.457383 -57.851427) (xy 78.445106 -57.84469) (xy 78.421919 -57.832429) (xy 78.378885 -57.80244)
			(xy 78.340367 -57.766836) (xy 78.307092 -57.726289) (xy 78.279687 -57.681565) (xy 78.25867 -57.633508)
			(xy 78.244438 -57.583023) (xy 78.237258 -57.531064) (xy 78.236826 -57.504838) (xy 78.237312 -57.477587)
			(xy 78.245068 -57.423639) (xy 78.260423 -57.371344) (xy 78.283065 -57.321767) (xy 78.312531 -57.275917)
			(xy 78.348222 -57.234726) (xy 78.389413 -57.199035) (xy 78.435263 -57.169569) (xy 78.48484 -57.146927)
			(xy 78.537135 -57.131572) (xy 78.591083 -57.123816) (xy 78.645585 -57.123816) (xy 78.699533 -57.131572)
			(xy 78.751828 -57.146927) (xy 78.801405 -57.169569) (xy 78.847255 -57.199035) (xy 78.888446 -57.234726)
			(xy 78.924137 -57.275917) (xy 78.953603 -57.321767) (xy 78.976245 -57.371344) (xy 78.9916 -57.423639)
			(xy 78.999356 -57.477587) (xy 78.999842 -57.504838) (xy 78.999394 -57.53106) (xy 78.992194 -57.583009)
			(xy 78.977948 -57.633483) (xy 78.956925 -57.68153) (xy 78.929521 -57.726246) (xy 78.896252 -57.766789)
			(xy 78.857745 -57.802394) (xy 78.814725 -57.832391) (xy 78.791562 -57.84469) (xy 78.779284 -57.851398)
			(xy 78.758784 -57.870431) (xy 78.744204 -57.894303) (xy 78.736634 -57.921232) (xy 78.736639 -57.949205)
			(xy 78.744219 -57.976131) (xy 78.758808 -57.999998) (xy 78.779315 -58.019023) (xy 78.791562 -58.025792)
			(xy 78.814734 -58.03808) (xy 78.857769 -58.068064) (xy 78.896288 -58.103664) (xy 78.929565 -58.144206)
			(xy 78.956972 -58.188926) (xy 78.977991 -58.236981) (xy 78.992226 -58.287462) (xy 78.999409 -58.339419)
			(xy 78.999741 -58.359548) (xy 80.37068 -58.359548) (xy 80.371105 -58.333325) (xy 80.378307 -58.281374)
			(xy 80.392556 -58.2309) (xy 80.413582 -58.182852) (xy 80.440989 -58.138135) (xy 80.474261 -58.097593)
			(xy 80.512772 -58.061989) (xy 80.555795 -58.031994) (xy 80.57896 -58.019696) (xy 80.591198 -58.012889)
			(xy 80.611764 -57.993905) (xy 80.6264 -57.970049) (xy 80.634008 -57.943114) (xy 80.634013 -57.915126)
			(xy 80.626417 -57.888189) (xy 80.61179 -57.864327) (xy 80.591231 -57.845335) (xy 80.57896 -57.838594)
			(xy 80.555787 -57.826307) (xy 80.512751 -57.796323) (xy 80.474231 -57.760725) (xy 80.440953 -57.720182)
			(xy 80.413546 -57.675462) (xy 80.392527 -57.627407) (xy 80.378293 -57.576924) (xy 80.371112 -57.524967)
			(xy 80.37068 -57.498742) (xy 80.371166 -57.471491) (xy 80.378922 -57.417543) (xy 80.394277 -57.365248)
			(xy 80.416919 -57.315671) (xy 80.446385 -57.269821) (xy 80.482076 -57.22863) (xy 80.523267 -57.192939)
			(xy 80.569117 -57.163473) (xy 80.618694 -57.140831) (xy 80.670989 -57.125476) (xy 80.724937 -57.11772)
			(xy 80.779439 -57.11772) (xy 80.833387 -57.125476) (xy 80.885682 -57.140831) (xy 80.935259 -57.163473)
			(xy 80.981109 -57.192939) (xy 81.0223 -57.22863) (xy 81.057991 -57.269821) (xy 81.087457 -57.315671)
			(xy 81.110099 -57.365248) (xy 81.125454 -57.417543) (xy 81.13321 -57.471491) (xy 81.133696 -57.498742)
			(xy 81.133276 -57.524966) (xy 81.126074 -57.576917) (xy 81.111826 -57.627392) (xy 81.0908 -57.675441)
			(xy 81.063392 -57.720157) (xy 81.030118 -57.760699) (xy 80.991607 -57.796303) (xy 80.948582 -57.826297)
			(xy 80.925416 -57.838594) (xy 80.913139 -57.8453) (xy 80.892647 -57.864336) (xy 80.878074 -57.888209)
			(xy 80.870508 -57.915136) (xy 80.870514 -57.943105) (xy 80.878091 -57.970029) (xy 80.892674 -57.993896)
			(xy 80.913173 -58.012924) (xy 80.925416 -58.019696) (xy 80.948579 -58.032001) (xy 80.991616 -58.061981)
			(xy 81.030137 -58.097576) (xy 81.063416 -58.138116) (xy 81.090824 -58.182834) (xy 81.111845 -58.230887)
			(xy 81.126081 -58.281368) (xy 81.133263 -58.333323) (xy 81.133595 -58.353452) (xy 82.504534 -58.353452)
			(xy 82.504987 -58.32723) (xy 82.512188 -58.275282) (xy 82.526434 -58.224809) (xy 82.547457 -58.176762)
			(xy 82.57486 -58.132046) (xy 82.608128 -58.091504) (xy 82.646633 -58.055898) (xy 82.689651 -58.0259)
			(xy 82.712814 -58.0136) (xy 82.725053 -58.00679) (xy 82.745627 -57.987811) (xy 82.760271 -57.963955)
			(xy 82.767882 -57.937018) (xy 82.767889 -57.909026) (xy 82.760289 -57.882086) (xy 82.745656 -57.858224)
			(xy 82.725089 -57.839235) (xy 82.712814 -57.832498) (xy 82.689632 -57.820227) (xy 82.646598 -57.79024)
			(xy 82.60808 -57.754638) (xy 82.574804 -57.714093) (xy 82.547399 -57.66937) (xy 82.526381 -57.621313)
			(xy 82.512147 -57.57083) (xy 82.504967 -57.518872) (xy 82.504534 -57.492646) (xy 82.50502 -57.465395)
			(xy 82.512776 -57.411447) (xy 82.528131 -57.359152) (xy 82.550773 -57.309575) (xy 82.580239 -57.263725)
			(xy 82.61593 -57.222534) (xy 82.657121 -57.186843) (xy 82.702971 -57.157377) (xy 82.752548 -57.134735)
			(xy 82.804843 -57.11938) (xy 82.858791 -57.111624) (xy 82.913293 -57.111624) (xy 82.967241 -57.11938)
			(xy 83.019536 -57.134735) (xy 83.069113 -57.157377) (xy 83.114963 -57.186843) (xy 83.156154 -57.222534)
			(xy 83.191845 -57.263725) (xy 83.221311 -57.309575) (xy 83.243953 -57.359152) (xy 83.259308 -57.411447)
			(xy 83.267064 -57.465395) (xy 83.26755 -57.492646) (xy 83.267104 -57.518869) (xy 83.259903 -57.570817)
			(xy 83.245656 -57.62129) (xy 83.224633 -57.669338) (xy 83.197229 -57.714054) (xy 83.16396 -57.754596)
			(xy 83.125453 -57.790201) (xy 83.082433 -57.820199) (xy 83.05927 -57.832498) (xy 83.046984 -57.839194)
			(xy 83.026482 -57.858228) (xy 83.0119 -57.882103) (xy 83.00433 -57.909034) (xy 83.004336 -57.93701)
			(xy 83.011918 -57.963938) (xy 83.02651 -57.987807) (xy 83.047021 -58.006832) (xy 83.05927 -58.0136)
			(xy 83.082447 -58.025879) (xy 83.125482 -58.055865) (xy 83.164001 -58.091465) (xy 83.197277 -58.132009)
			(xy 83.224683 -58.176731) (xy 83.245702 -58.224786) (xy 83.259936 -58.275269) (xy 83.267117 -58.327226)
			(xy 83.26755 -58.353452) (xy 84.638134 -58.353452) (xy 84.638587 -58.32723) (xy 84.645788 -58.275282)
			(xy 84.660034 -58.224809) (xy 84.681057 -58.176762) (xy 84.70846 -58.132046) (xy 84.741728 -58.091504)
			(xy 84.780233 -58.055898) (xy 84.823251 -58.0259) (xy 84.846414 -58.0136) (xy 84.858653 -58.00679)
			(xy 84.879227 -57.987811) (xy 84.893871 -57.963955) (xy 84.901482 -57.937018) (xy 84.901489 -57.909026)
			(xy 84.893889 -57.882086) (xy 84.879256 -57.858224) (xy 84.858689 -57.839235) (xy 84.846414 -57.832498)
			(xy 84.823232 -57.820227) (xy 84.780198 -57.79024) (xy 84.74168 -57.754638) (xy 84.708404 -57.714093)
			(xy 84.680999 -57.66937) (xy 84.659981 -57.621313) (xy 84.645747 -57.57083) (xy 84.638567 -57.518872)
			(xy 84.638134 -57.492646) (xy 84.63862 -57.465395) (xy 84.646376 -57.411447) (xy 84.661731 -57.359152)
			(xy 84.684373 -57.309575) (xy 84.713839 -57.263725) (xy 84.74953 -57.222534) (xy 84.790721 -57.186843)
			(xy 84.836571 -57.157377) (xy 84.886148 -57.134735) (xy 84.938443 -57.11938) (xy 84.992391 -57.111624)
			(xy 85.046893 -57.111624) (xy 85.100841 -57.11938) (xy 85.153136 -57.134735) (xy 85.202713 -57.157377)
			(xy 85.248563 -57.186843) (xy 85.289754 -57.222534) (xy 85.325445 -57.263725) (xy 85.354911 -57.309575)
			(xy 85.377553 -57.359152) (xy 85.392908 -57.411447) (xy 85.400664 -57.465395) (xy 85.40115 -57.492646)
			(xy 85.400704 -57.518869) (xy 85.393503 -57.570817) (xy 85.379256 -57.62129) (xy 85.358233 -57.669338)
			(xy 85.330829 -57.714054) (xy 85.29756 -57.754596) (xy 85.259053 -57.790201) (xy 85.216033 -57.820199)
			(xy 85.19287 -57.832498) (xy 85.180584 -57.839194) (xy 85.160082 -57.858228) (xy 85.1455 -57.882103)
			(xy 85.13793 -57.909034) (xy 85.137936 -57.93701) (xy 85.145518 -57.963938) (xy 85.16011 -57.987807)
			(xy 85.180621 -58.006832) (xy 85.19287 -58.0136) (xy 85.216047 -58.025879) (xy 85.259082 -58.055865)
			(xy 85.297601 -58.091465) (xy 85.330877 -58.132009) (xy 85.358283 -58.176731) (xy 85.379302 -58.224786)
			(xy 85.393536 -58.275269) (xy 85.400717 -58.327226) (xy 85.40115 -58.353452) (xy 85.400664 -58.380703)
			(xy 85.392908 -58.434651) (xy 85.377553 -58.486946) (xy 85.354911 -58.536523) (xy 85.325445 -58.582373)
			(xy 85.289754 -58.623564) (xy 85.248563 -58.659255) (xy 85.202713 -58.688721) (xy 85.153136 -58.711363)
			(xy 85.100841 -58.726718) (xy 85.046893 -58.734474) (xy 84.992391 -58.734474) (xy 84.938443 -58.726718)
			(xy 84.886148 -58.711363) (xy 84.836571 -58.688721) (xy 84.790721 -58.659255) (xy 84.74953 -58.623564)
			(xy 84.713839 -58.582373) (xy 84.684373 -58.536523) (xy 84.661731 -58.486946) (xy 84.646376 -58.434651)
			(xy 84.63862 -58.380703) (xy 84.638134 -58.353452) (xy 83.26755 -58.353452) (xy 83.267064 -58.380703)
			(xy 83.259308 -58.434651) (xy 83.243953 -58.486946) (xy 83.221311 -58.536523) (xy 83.191845 -58.582373)
			(xy 83.156154 -58.623564) (xy 83.114963 -58.659255) (xy 83.069113 -58.688721) (xy 83.019536 -58.711363)
			(xy 82.967241 -58.726718) (xy 82.913293 -58.734474) (xy 82.858791 -58.734474) (xy 82.804843 -58.726718)
			(xy 82.752548 -58.711363) (xy 82.702971 -58.688721) (xy 82.657121 -58.659255) (xy 82.61593 -58.623564)
			(xy 82.580239 -58.582373) (xy 82.550773 -58.536523) (xy 82.528131 -58.486946) (xy 82.512776 -58.434651)
			(xy 82.50502 -58.380703) (xy 82.504534 -58.353452) (xy 81.133595 -58.353452) (xy 81.133696 -58.359548)
			(xy 81.13321 -58.386799) (xy 81.125454 -58.440747) (xy 81.110099 -58.493042) (xy 81.087457 -58.542619)
			(xy 81.057991 -58.588469) (xy 81.0223 -58.62966) (xy 80.981109 -58.665351) (xy 80.935259 -58.694817)
			(xy 80.885682 -58.717459) (xy 80.833387 -58.732814) (xy 80.779439 -58.74057) (xy 80.724937 -58.74057)
			(xy 80.670989 -58.732814) (xy 80.618694 -58.717459) (xy 80.569117 -58.694817) (xy 80.523267 -58.665351)
			(xy 80.482076 -58.62966) (xy 80.446385 -58.588469) (xy 80.416919 -58.542619) (xy 80.394277 -58.493042)
			(xy 80.378922 -58.440747) (xy 80.371166 -58.386799) (xy 80.37068 -58.359548) (xy 78.999741 -58.359548)
			(xy 78.999842 -58.365644) (xy 78.999356 -58.392895) (xy 78.9916 -58.446843) (xy 78.976245 -58.499138)
			(xy 78.953603 -58.548715) (xy 78.924137 -58.594565) (xy 78.888446 -58.635756) (xy 78.847255 -58.671447)
			(xy 78.801405 -58.700913) (xy 78.751828 -58.723555) (xy 78.699533 -58.73891) (xy 78.645585 -58.746666)
			(xy 78.591083 -58.746666) (xy 78.537135 -58.73891) (xy 78.48484 -58.723555) (xy 78.435263 -58.700913)
			(xy 78.389413 -58.671447) (xy 78.348222 -58.635756) (xy 78.312531 -58.594565) (xy 78.283065 -58.548715)
			(xy 78.260423 -58.499138) (xy 78.245068 -58.446843) (xy 78.237312 -58.392895) (xy 78.236826 -58.365644)
			(xy 76.865895 -58.365644) (xy 76.865988 -58.37174) (xy 76.865502 -58.398991) (xy 76.857746 -58.452939)
			(xy 76.842391 -58.505234) (xy 76.819749 -58.554811) (xy 76.790283 -58.600661) (xy 76.754592 -58.641852)
			(xy 76.713401 -58.677543) (xy 76.667551 -58.707009) (xy 76.617974 -58.729651) (xy 76.565679 -58.745006)
			(xy 76.511731 -58.752762) (xy 76.457229 -58.752762) (xy 76.403281 -58.745006) (xy 76.350986 -58.729651)
			(xy 76.301409 -58.707009) (xy 76.255559 -58.677543) (xy 76.214368 -58.641852) (xy 76.178677 -58.600661)
			(xy 76.149211 -58.554811) (xy 76.126569 -58.505234) (xy 76.111214 -58.452939) (xy 76.103458 -58.398991)
			(xy 76.102972 -58.37174) (xy 76.103405 -58.345515) (xy 76.110588 -58.29356) (xy 76.124824 -58.243079)
			(xy 76.145844 -58.195025) (xy 76.173252 -58.150306) (xy 76.20653 -58.109765) (xy 76.24505 -58.074168)
			(xy 76.288085 -58.044185) (xy 76.311252 -58.031888) (xy 76.323497 -58.025118) (xy 76.344001 -58.006093)
			(xy 76.358586 -57.982226) (xy 76.366165 -57.955302) (xy 76.366169 -57.927332) (xy 76.3586 -57.900405)
			(xy 76.344022 -57.876534) (xy 76.323525 -57.857501) (xy 76.311252 -57.850786) (xy 76.287116 -57.837951)
			(xy 76.242458 -57.806422) (xy 76.202755 -57.768847) (xy 76.168817 -57.725992) (xy 76.141339 -57.678735)
			(xy 76.120882 -57.628041) (xy 76.113894 -57.601612) (xy 76.110592 -57.587896) (xy 76.064618 -57.541922)
			(xy 75.994514 -57.612026) (xy 75.994514 -60.773818) (xy 76.182474 -60.961778) (xy 86.703916 -60.961778)
		)
		(stroke
			(width 0)
			(type solid)
		)
		(fill yes)
		(layer "In2.Cu")
		(net "P1V2_AUX")
	)
	(gr_poly
		(pts
			(xy 58.770266 -68.318888) (xy 58.782168 -68.290852) (xy 58.813564 -68.238664) (xy 58.85286 -68.192135)
			(xy 58.899057 -68.152447) (xy 58.924698 -68.136008) (xy 58.936012 -68.128497) (xy 58.954512 -68.108631)
			(xy 58.967133 -68.084596) (xy 58.972984 -68.058088) (xy 58.971652 -68.030974) (xy 58.963233 -68.005166)
			(xy 58.948319 -67.982483) (xy 58.938414 -67.973194) (xy 58.918431 -67.955) (xy 58.883289 -67.913945)
			(xy 58.854294 -67.86834) (xy 58.832029 -67.819098) (xy 58.816938 -67.767206) (xy 58.809325 -67.713703)
			(xy 58.808874 -67.686682) (xy 58.80936 -67.659431) (xy 58.817116 -67.605483) (xy 58.832471 -67.553188)
			(xy 58.855113 -67.503611) (xy 58.884579 -67.457761) (xy 58.92027 -67.41657) (xy 58.961461 -67.380879)
			(xy 59.007311 -67.351413) (xy 59.056888 -67.328771) (xy 59.109183 -67.313416) (xy 59.163131 -67.30566)
			(xy 59.217633 -67.30566) (xy 59.271581 -67.313416) (xy 59.323876 -67.328771) (xy 59.373453 -67.351413)
			(xy 59.419303 -67.380879) (xy 59.460494 -67.41657) (xy 59.496185 -67.457761) (xy 59.525651 -67.503611)
			(xy 59.548293 -67.553188) (xy 59.563648 -67.605483) (xy 59.571404 -67.659431) (xy 59.57189 -67.686682)
			(xy 59.571388 -67.714495) (xy 59.563315 -67.76953) (xy 59.547336 -67.822811) (xy 59.52379 -67.873207)
			(xy 59.493178 -67.919651) (xy 59.456146 -67.961157) (xy 59.41348 -67.996847) (xy 59.390026 -68.011802)
			(xy 59.378711 -68.019312) (xy 59.360209 -68.039176) (xy 59.347588 -68.06321) (xy 59.341737 -68.089719)
			(xy 59.34307 -68.116832) (xy 59.351493 -68.142639) (xy 59.366411 -68.165319) (xy 59.37631 -68.174616)
			(xy 59.398266 -68.194688) (xy 59.436298 -68.240428) (xy 59.466783 -68.291509) (xy 59.478418 -68.318888)
			(xy 59.491118 -68.350638) (xy 59.919362 -68.350638) (xy 60.41771 -67.85229) (xy 60.41771 -67.164458)
			(xy 60.392599 -67.151458) (xy 60.34618 -67.119171) (xy 60.305036 -67.080385) (xy 60.270068 -67.03595)
			(xy 60.242044 -66.98684) (xy 60.221576 -66.934131) (xy 60.209114 -66.878977) (xy 60.204931 -66.822588)
			(xy 60.209118 -66.7662) (xy 60.221583 -66.711047) (xy 60.242054 -66.658339) (xy 60.270081 -66.609231)
			(xy 60.305051 -66.564798) (xy 60.346198 -66.526014) (xy 60.392619 -66.49373) (xy 60.41771 -66.48069)
			(xy 60.41771 -65.808606) (xy 60.417248 -65.798723) (xy 60.409777 -65.780422) (xy 60.395943 -65.766304)
			(xy 60.377798 -65.758463) (xy 60.367926 -65.757806) (xy 60.339761 -65.756719) (xy 60.284194 -65.747279)
			(xy 60.23062 -65.729769) (xy 60.180204 -65.704568) (xy 60.134044 -65.672225) (xy 60.093144 -65.633444)
			(xy 60.058393 -65.589068) (xy 60.030548 -65.540064) (xy 60.010214 -65.487496) (xy 59.997835 -65.43251)
			(xy 59.993678 -65.3763) (xy 59.997835 -65.32009) (xy 60.010214 -65.265104) (xy 60.030548 -65.212536)
			(xy 60.058393 -65.163532) (xy 60.093144 -65.119156) (xy 60.134044 -65.080375) (xy 60.180204 -65.048032)
			(xy 60.23062 -65.022831) (xy 60.284194 -65.005321) (xy 60.339761 -64.995881) (xy 60.367926 -64.99479)
			(xy 60.377797 -64.994127) (xy 60.395939 -64.986287) (xy 60.409771 -64.97217) (xy 60.417239 -64.953872)
			(xy 60.41771 -64.94399) (xy 60.41771 -63.445644) (xy 60.417263 -63.435888) (xy 60.409971 -63.417788)
			(xy 60.396458 -63.403709) (xy 60.378672 -63.395681) (xy 60.368942 -63.394844) (xy 60.34112 -63.393282)
			(xy 60.286337 -63.383092) (xy 60.233619 -63.365042) (xy 60.184087 -63.339514) (xy 60.138796 -63.307053)
			(xy 60.098709 -63.268348) (xy 60.064679 -63.224224) (xy 60.037429 -63.175618) (xy 60.01754 -63.123566)
			(xy 60.005435 -63.069174) (xy 60.001371 -63.0136) (xy 60.005435 -62.958025) (xy 60.017541 -62.903633)
			(xy 60.037429 -62.851581) (xy 60.064679 -62.802975) (xy 60.098709 -62.758851) (xy 60.138796 -62.720147)
			(xy 60.184088 -62.687685) (xy 60.233619 -62.662158) (xy 60.286337 -62.644108) (xy 60.341121 -62.633918)
			(xy 60.368942 -62.632336) (xy 60.378675 -62.631504) (xy 60.396469 -62.62349) (xy 60.40998 -62.609406)
			(xy 60.41725 -62.591295) (xy 60.41771 -62.581536) (xy 60.41771 -62.235842) (xy 59.968384 -61.563504)
			(xy 59.959052 -61.549235) (xy 59.942899 -61.519207) (xy 59.936126 -61.50356) (xy 59.71032 -60.957968)
			(xy 59.345068 -60.592716) (xy 59.345068 -60.07608) (xy 59.038998 -59.337448) (xy 59.03214 -59.31916)
			(xy 59.028557 -59.310439) (xy 59.016241 -59.296184) (xy 58.999623 -59.287314) (xy 58.980926 -59.285016)
			(xy 58.971688 -59.286902) (xy 58.951641 -59.29166) (xy 58.910755 -59.296756) (xy 58.890154 -59.297062)
			(xy 58.864171 -59.296548) (xy 58.812844 -59.288412) (xy 58.763423 -59.272346) (xy 58.717123 -59.248747)
			(xy 58.675085 -59.218196) (xy 58.638344 -59.181445) (xy 58.607805 -59.139398) (xy 58.584218 -59.093092)
			(xy 58.568167 -59.043666) (xy 58.560044 -58.992338) (xy 58.559446 -58.966354) (xy 58.560139 -58.936402)
			(xy 58.570996 -58.877488) (xy 58.581036 -58.84926) (xy 58.556214 -58.836249) (xy 58.510779 -58.803443)
			(xy 58.490612 -58.783982) (xy 58.27268 -58.56605) (xy 58.253253 -58.545855) (xy 58.220461 -58.500419)
			(xy 58.207402 -58.475626) (xy 58.179176 -58.485672) (xy 58.120261 -58.496535) (xy 58.090308 -58.497216)
			(xy 58.06432 -58.496707) (xy 58.012984 -58.488578) (xy 57.963552 -58.472517) (xy 57.917241 -58.448922)
			(xy 57.875191 -58.418373) (xy 57.838438 -58.381621) (xy 57.807886 -58.339573) (xy 57.784289 -58.293263)
			(xy 57.768226 -58.243831) (xy 57.760094 -58.192496) (xy 57.7596 -58.166508) (xy 57.759787 -58.15092)
			(xy 57.762713 -58.119881) (xy 57.765442 -58.104532) (xy 57.747598 -58.095214) (xy 57.713982 -58.073064)
			(xy 57.698386 -58.060336) (xy 57.690091 -58.054078) (xy 57.67018 -58.048204) (xy 57.64957 -58.05069)
			(xy 57.631627 -58.061129) (xy 57.619279 -58.077817) (xy 57.614544 -58.098029) (xy 57.615836 -58.108342)
			(xy 57.618224 -58.122765) (xy 57.620764 -58.15189) (xy 57.620916 -58.166508) (xy 57.620432 -58.192498)
			(xy 57.6123 -58.243838) (xy 57.596236 -58.293273) (xy 57.572636 -58.339587) (xy 57.542082 -58.381638)
			(xy 57.505326 -58.418393) (xy 57.463273 -58.448945) (xy 57.416958 -58.472542) (xy 57.367522 -58.488603)
			(xy 57.316182 -58.496733) (xy 57.264202 -58.496732) (xy 57.212862 -58.4886) (xy 57.163427 -58.472536)
			(xy 57.117113 -58.448936) (xy 57.075062 -58.418382) (xy 57.038307 -58.381626) (xy 57.007755 -58.339573)
			(xy 56.984158 -58.293258) (xy 56.968097 -58.243822) (xy 56.959967 -58.192482) (xy 56.959968 -58.140502)
			(xy 56.9681 -58.089162) (xy 56.984164 -58.039727) (xy 57.007764 -57.993413) (xy 57.038318 -57.951362)
			(xy 57.075074 -57.914607) (xy 57.117127 -57.884055) (xy 57.163442 -57.860458) (xy 57.212878 -57.844397)
			(xy 57.264218 -57.836267) (xy 57.290208 -57.8358) (xy 57.310088 -57.836062) (xy 57.349567 -57.840768)
			(xy 57.368948 -57.845198) (xy 57.378645 -57.847133) (xy 57.398194 -57.844294) (xy 57.415214 -57.834265)
			(xy 57.427169 -57.818539) (xy 57.43228 -57.799457) (xy 57.429787 -57.77986) (xy 57.425336 -57.77103)
			(xy 57.419223 -57.760017) (xy 57.408413 -57.737263) (xy 57.403746 -57.725564) (xy 57.399118 -57.715008)
			(xy 57.382329 -57.699251) (xy 57.360348 -57.692393) (xy 57.348882 -57.69356) (xy 57.336696 -57.69524)
			(xy 57.31216 -57.697019) (xy 57.29986 -57.697116) (xy 57.273875 -57.696603) (xy 57.222545 -57.688468)
			(xy 57.173119 -57.672404) (xy 57.126814 -57.648806) (xy 57.084771 -57.618255) (xy 57.048024 -57.581505)
			(xy 57.017478 -57.539458) (xy 56.993884 -57.493152) (xy 56.977825 -57.443724) (xy 56.969694 -57.392393)
			(xy 56.969152 -57.366408) (xy 56.96966 -57.347612) (xy 56.96966 -57.293764) (xy 56.82996 -57.293764)
			(xy 56.82996 -57.347612) (xy 56.830468 -57.366408) (xy 56.829958 -57.392395) (xy 56.821828 -57.44373)
			(xy 56.805767 -57.49316) (xy 56.782171 -57.53947) (xy 56.751621 -57.581518) (xy 56.71487 -57.618269)
			(xy 56.672822 -57.648819) (xy 56.626512 -57.672415) (xy 56.577082 -57.688476) (xy 56.525747 -57.696606)
			(xy 56.473773 -57.696606) (xy 56.422438 -57.688476) (xy 56.373008 -57.672415) (xy 56.326698 -57.648819)
			(xy 56.28465 -57.618269) (xy 56.247899 -57.581518) (xy 56.217349 -57.53947) (xy 56.193753 -57.49316)
			(xy 56.177692 -57.44373) (xy 56.169562 -57.392395) (xy 56.169052 -57.366408) (xy 56.169514 -57.341374)
			(xy 56.177066 -57.291879) (xy 56.191998 -57.244089) (xy 56.213969 -57.199099) (xy 56.242476 -57.157939)
			(xy 56.276866 -57.12155) (xy 56.316353 -57.090766) (xy 56.337962 -57.078118) (xy 56.349461 -57.071194)
			(xy 56.368628 -57.052413) (xy 56.382241 -57.029288) (xy 56.389359 -57.003415) (xy 56.389491 -56.976581)
			(xy 56.382628 -56.950639) (xy 56.369244 -56.927381) (xy 56.36006 -56.91759) (xy 56.254396 -56.811926)
			(xy 56.235473 -56.792286) (xy 56.203419 -56.748164) (xy 56.178667 -56.699569) (xy 56.161825 -56.647698)
			(xy 56.153311 -56.59383) (xy 56.152796 -56.566562) (xy 56.153333 -56.539292) (xy 56.161866 -56.485425)
			(xy 56.178717 -56.433554) (xy 56.203471 -56.384956) (xy 56.235519 -56.340827) (xy 56.274073 -56.30225)
			(xy 56.318184 -56.270177) (xy 56.366768 -56.245395) (xy 56.418628 -56.228514) (xy 56.472491 -56.219949)
			(xy 56.49976 -56.219344) (xy 56.52704 -56.219864) (xy 56.580923 -56.228429) (xy 56.632802 -56.245321)
			(xy 56.681398 -56.270125) (xy 56.725513 -56.302229) (xy 56.745124 -56.321198) (xy 56.852566 -56.428386)
			(xy 56.862285 -56.437546) (xy 56.885409 -56.450888) (xy 56.911203 -56.457775) (xy 56.937901 -56.457735)
			(xy 56.963674 -56.450771) (xy 56.986759 -56.437359) (xy 57.005574 -56.418417) (xy 57.012586 -56.40705)
			(xy 57.027369 -56.382393) (xy 57.064051 -56.338131) (xy 57.107812 -56.300854) (xy 57.157343 -56.271677)
			(xy 57.184036 -56.261) (xy 57.217056 -56.248808) (xy 57.217056 -56.091074) (xy 57.182766 -56.079136)
			(xy 57.158672 -56.070361) (xy 57.113322 -56.046435) (xy 57.072211 -56.015792) (xy 57.036326 -55.979168)
			(xy 57.006526 -55.937442) (xy 56.983528 -55.891614) (xy 56.967883 -55.842785) (xy 56.959967 -55.792125)
			(xy 56.959969 -55.74085) (xy 56.967889 -55.690191) (xy 56.983538 -55.641363) (xy 57.006539 -55.595537)
			(xy 57.036342 -55.553813) (xy 57.07223 -55.517192) (xy 57.113343 -55.486552) (xy 57.158695 -55.462629)
			(xy 57.182766 -55.453788) (xy 57.217056 -55.44185) (xy 57.217056 -55.21452) (xy 57.1246 -55.122064)
			(xy 57.1246 -53.118004) (xy 57.217056 -53.025548) (xy 57.217056 -52.672742) (xy 57.473088 -52.41671)
			(xy 57.473088 -50.60061) (xy 57.472567 -50.585683) (xy 57.463939 -50.557104) (xy 57.447419 -50.532238)
			(xy 57.424415 -50.51321) (xy 57.396893 -50.501645) (xy 57.367203 -50.498529) (xy 57.352438 -50.500788)
			(xy 57.337029 -50.503544) (xy 57.305861 -50.506473) (xy 57.290208 -50.50663) (xy 57.264217 -50.506147)
			(xy 57.212874 -50.498017) (xy 57.163435 -50.481954) (xy 57.117117 -50.458355) (xy 57.075062 -50.427801)
			(xy 57.038304 -50.391044) (xy 57.007749 -50.348989) (xy 56.984149 -50.302673) (xy 56.968085 -50.253234)
			(xy 56.959953 -50.201891) (xy 56.959953 -50.149909) (xy 56.968085 -50.098566) (xy 56.984149 -50.049127)
			(xy 57.007749 -50.002811) (xy 57.038304 -49.960756) (xy 57.075062 -49.923999) (xy 57.117117 -49.893445)
			(xy 57.163435 -49.869846) (xy 57.212874 -49.853783) (xy 57.264217 -49.845653) (xy 57.290208 -49.845214)
			(xy 57.30586 -49.845385) (xy 57.337028 -49.848308) (xy 57.352438 -49.851056) (xy 57.367199 -49.853344)
			(xy 57.396893 -49.850228) (xy 57.424416 -49.838658) (xy 57.447418 -49.819622) (xy 57.463932 -49.794749)
			(xy 57.472547 -49.766163) (xy 57.473088 -49.751234) (xy 57.473088 -49.000664) (xy 57.472561 -48.985742)
			(xy 57.463926 -48.957174) (xy 57.447403 -48.932321) (xy 57.424403 -48.913303) (xy 57.396888 -48.901743)
			(xy 57.367207 -48.898629) (xy 57.352438 -48.900842) (xy 57.337029 -48.903598) (xy 57.305861 -48.906527)
			(xy 57.290208 -48.906684) (xy 57.26422 -48.906202) (xy 57.212884 -48.898072) (xy 57.163452 -48.882012)
			(xy 57.117141 -48.858416) (xy 57.075092 -48.827866) (xy 57.038339 -48.791114) (xy 57.007788 -48.749065)
			(xy 56.984192 -48.702755) (xy 56.96813 -48.653323) (xy 56.959999 -48.601988) (xy 56.959999 -48.550012)
			(xy 56.96813 -48.498677) (xy 56.984192 -48.449245) (xy 57.007788 -48.402935) (xy 57.038339 -48.360886)
			(xy 57.075092 -48.324134) (xy 57.117141 -48.293584) (xy 57.163452 -48.269988) (xy 57.212884 -48.253928)
			(xy 57.26422 -48.245798) (xy 57.290208 -48.245268) (xy 57.30586 -48.245439) (xy 57.337028 -48.248362)
			(xy 57.352438 -48.25111) (xy 57.367202 -48.253398) (xy 57.3969 -48.250281) (xy 57.424429 -48.238712)
			(xy 57.447439 -48.219679) (xy 57.463964 -48.194806) (xy 57.472593 -48.166219) (xy 57.473088 -48.151288)
			(xy 57.473088 -48.083216) (xy 57.413144 -48.083216) (xy 57.404762 -48.086264) (xy 57.377095 -48.095837)
			(xy 57.319477 -48.106184) (xy 57.290208 -48.106838) (xy 57.264216 -48.106355) (xy 57.212872 -48.098224)
			(xy 57.163432 -48.082161) (xy 57.117113 -48.058562) (xy 57.075057 -48.028007) (xy 57.038298 -47.991249)
			(xy 57.007742 -47.949194) (xy 56.984142 -47.902876) (xy 56.968077 -47.853436) (xy 56.959945 -47.802092)
			(xy 56.959945 -47.750108) (xy 56.968077 -47.698764) (xy 56.984142 -47.649324) (xy 57.007742 -47.603006)
			(xy 57.038298 -47.560951) (xy 57.075057 -47.524193) (xy 57.117113 -47.493638) (xy 57.163432 -47.470039)
			(xy 57.212872 -47.453976) (xy 57.264216 -47.445845) (xy 57.290208 -47.445422) (xy 57.30586 -47.445593)
			(xy 57.337028 -47.448516) (xy 57.352438 -47.451264) (xy 57.3672 -47.453552) (xy 57.396894 -47.450435)
			(xy 57.424418 -47.438866) (xy 57.447421 -47.419831) (xy 57.463936 -47.394957) (xy 57.472554 -47.366371)
			(xy 57.473088 -47.351442) (xy 57.473088 -47.283116) (xy 57.413144 -47.283116) (xy 57.404762 -47.286164)
			(xy 57.377095 -47.295737) (xy 57.319477 -47.306084) (xy 57.290208 -47.306738) (xy 57.264216 -47.306255)
			(xy 57.212872 -47.298124) (xy 57.163432 -47.282061) (xy 57.117113 -47.258462) (xy 57.075057 -47.227907)
			(xy 57.038298 -47.191149) (xy 57.007742 -47.149094) (xy 56.984142 -47.102776) (xy 56.968077 -47.053336)
			(xy 56.959945 -47.001992) (xy 56.959945 -46.950008) (xy 56.968077 -46.898664) (xy 56.984142 -46.849224)
			(xy 57.007742 -46.802906) (xy 57.038298 -46.760851) (xy 57.075057 -46.724093) (xy 57.117113 -46.693538)
			(xy 57.163432 -46.669939) (xy 57.212872 -46.653876) (xy 57.264216 -46.645745) (xy 57.290208 -46.645322)
			(xy 57.30586 -46.645493) (xy 57.337028 -46.648416) (xy 57.352438 -46.651164) (xy 57.3672 -46.653452)
			(xy 57.396894 -46.650335) (xy 57.424418 -46.638766) (xy 57.447421 -46.619731) (xy 57.463936 -46.594857)
			(xy 57.472554 -46.566271) (xy 57.473088 -46.551342) (xy 57.473088 -45.803058) (xy 57.36844 -45.69841)
			(xy 57.342786 -45.702474) (xy 57.329733 -45.704476) (xy 57.303412 -45.706634) (xy 57.290208 -45.706792)
			(xy 57.264219 -45.706309) (xy 57.21288 -45.698179) (xy 57.163446 -45.682117) (xy 57.117132 -45.65852)
			(xy 57.075081 -45.627967) (xy 57.038327 -45.591213) (xy 57.007776 -45.549161) (xy 56.98418 -45.502847)
			(xy 56.968119 -45.453412) (xy 56.95999 -45.402073) (xy 56.9595 -45.376084) (xy 56.959993 -45.349989)
			(xy 56.968196 -45.298447) (xy 56.984394 -45.248835) (xy 57.008187 -45.202384) (xy 57.038982 -45.160248)
			(xy 57.076016 -45.123473) (xy 57.118367 -45.092974) (xy 57.164984 -45.069509) (xy 57.214709 -45.053658)
			(xy 57.240424 -45.049186) (xy 57.283604 -45.042582) (xy 57.283604 -43.30954) (xy 57.240424 -43.302936)
			(xy 57.214697 -43.298522) (xy 57.164969 -43.282657) (xy 57.118352 -43.259177) (xy 57.076001 -43.228665)
			(xy 57.038969 -43.19188) (xy 57.008176 -43.149734) (xy 56.984386 -43.103273) (xy 56.968189 -43.053653)
			(xy 56.959989 -43.002104) (xy 56.959988 -42.949907) (xy 56.968187 -42.898358) (xy 56.984381 -42.848737)
			(xy 57.00817 -42.802276) (xy 57.038962 -42.760129) (xy 57.075992 -42.723342) (xy 57.118342 -42.692829)
			(xy 57.164959 -42.669348) (xy 57.214686 -42.653481) (xy 57.240424 -42.64914) (xy 57.283604 -42.642536)
			(xy 57.283604 -42.50944) (xy 57.240424 -42.502836) (xy 57.214697 -42.498422) (xy 57.164969 -42.482557)
			(xy 57.118352 -42.459077) (xy 57.076001 -42.428565) (xy 57.038969 -42.39178) (xy 57.008176 -42.349634)
			(xy 56.984386 -42.303173) (xy 56.968189 -42.253553) (xy 56.959989 -42.202004) (xy 56.959988 -42.149807)
			(xy 56.968187 -42.098258) (xy 56.984381 -42.048637) (xy 57.00817 -42.002176) (xy 57.038962 -41.960029)
			(xy 57.075992 -41.923242) (xy 57.118342 -41.892729) (xy 57.164959 -41.869248) (xy 57.214686 -41.853381)
			(xy 57.240424 -41.84904) (xy 57.283604 -41.842436) (xy 57.283604 -41.709594) (xy 57.240424 -41.70299)
			(xy 57.2147 -41.698576) (xy 57.16498 -41.682712) (xy 57.118369 -41.659234) (xy 57.076025 -41.628726)
			(xy 57.038999 -41.591945) (xy 57.008211 -41.549804) (xy 56.984425 -41.50335) (xy 56.968232 -41.453736)
			(xy 56.960033 -41.402194) (xy 56.960034 -41.350004) (xy 56.968232 -41.298462) (xy 56.984426 -41.248848)
			(xy 57.008212 -41.202394) (xy 57.039001 -41.160253) (xy 57.076027 -41.123472) (xy 57.118371 -41.092965)
			(xy 57.164982 -41.069487) (xy 57.214703 -41.053624) (xy 57.240424 -41.049194) (xy 57.283604 -41.04259)
			(xy 57.283604 -40.909494) (xy 57.240424 -40.90289) (xy 57.2147 -40.898476) (xy 57.16498 -40.882612)
			(xy 57.118369 -40.859134) (xy 57.076025 -40.828626) (xy 57.038999 -40.791845) (xy 57.008211 -40.749704)
			(xy 56.984425 -40.70325) (xy 56.968232 -40.653636) (xy 56.960033 -40.602094) (xy 56.960034 -40.549904)
			(xy 56.968232 -40.498362) (xy 56.984426 -40.448748) (xy 57.008212 -40.402294) (xy 57.039001 -40.360153)
			(xy 57.076027 -40.323372) (xy 57.118371 -40.292865) (xy 57.164982 -40.269387) (xy 57.214703 -40.253524)
			(xy 57.240424 -40.249094) (xy 57.283604 -40.24249) (xy 57.283604 -40.109648) (xy 57.240424 -40.103044)
			(xy 57.214696 -40.09863) (xy 57.164968 -40.082764) (xy 57.118349 -40.059284) (xy 57.075997 -40.028772)
			(xy 57.038964 -39.991986) (xy 57.00817 -39.949839) (xy 56.984379 -39.903378) (xy 56.968182 -39.853756)
			(xy 56.959981 -39.802206) (xy 56.95998 -39.750008) (xy 56.968179 -39.698458) (xy 56.984374 -39.648835)
			(xy 57.008163 -39.602373) (xy 57.038955 -39.560225) (xy 57.075986 -39.523437) (xy 57.118337 -39.492923)
			(xy 57.164955 -39.469441) (xy 57.214683 -39.453574) (xy 57.240424 -39.449248) (xy 57.283604 -39.442644)
			(xy 57.283604 -39.287196) (xy 57.24398 -39.278306) (xy 57.218498 -39.272015) (xy 57.169785 -39.252476)
			(xy 57.124769 -39.225489) (xy 57.084579 -39.191733) (xy 57.050224 -39.152054) (xy 57.022566 -39.107447)
			(xy 57.002299 -39.059033) (xy 56.989931 -39.008026) (xy 56.985773 -38.955706) (xy 56.989929 -38.903385)
			(xy 57.002295 -38.852378) (xy 57.022561 -38.803963) (xy 57.050218 -38.759355) (xy 57.084571 -38.719675)
			(xy 57.12476 -38.685917) (xy 57.169775 -38.65893) (xy 57.218487 -38.639389) (xy 57.24398 -38.633146)
			(xy 57.283604 -38.624256) (xy 57.283604 -38.118542) (xy 61.220604 -34.181542) (xy 68.551298 -34.181542)
			(xy 68.56597 -34.181058) (xy 68.594106 -34.172721) (xy 68.618713 -34.156734) (xy 68.637765 -34.134415)
			(xy 68.64969 -34.107603) (xy 68.653507 -34.078508) (xy 68.648899 -34.049527) (xy 68.636248 -34.02305)
			(xy 68.626736 -34.01187) (xy 68.608366 -33.990756) (xy 68.577377 -33.944155) (xy 68.553536 -33.893522)
			(xy 68.537356 -33.839947) (xy 68.529186 -33.784582) (xy 68.528692 -33.7566) (xy 68.528692 -33.753044)
			(xy 68.528269 -33.73781) (xy 68.519577 -33.708616) (xy 68.502681 -33.683273) (xy 68.479075 -33.664023)
			(xy 68.450851 -33.65257) (xy 68.435728 -33.650682) (xy 68.407549 -33.647727) (xy 68.352444 -33.634554)
			(xy 68.299892 -33.613378) (xy 68.251049 -33.584664) (xy 68.206988 -33.549044) (xy 68.168678 -33.507301)
			(xy 68.136962 -33.460352) (xy 68.112536 -33.40923) (xy 68.095937 -33.355058) (xy 68.087531 -33.299027)
			(xy 68.086986 -33.270698) (xy 68.087472 -33.243447) (xy 68.095228 -33.189499) (xy 68.110583 -33.137204)
			(xy 68.133225 -33.087627) (xy 68.162691 -33.041777) (xy 68.198382 -33.000586) (xy 68.239573 -32.964895)
			(xy 68.285423 -32.935429) (xy 68.335 -32.912787) (xy 68.387295 -32.897432) (xy 68.441243 -32.889676)
			(xy 68.495745 -32.889676) (xy 68.549693 -32.897432) (xy 68.601988 -32.912787) (xy 68.651565 -32.935429)
			(xy 68.697415 -32.964895) (xy 68.738606 -33.000586) (xy 68.774297 -33.041777) (xy 68.803763 -33.087627)
			(xy 68.826405 -33.137204) (xy 68.84176 -33.189499) (xy 68.849516 -33.243447) (xy 68.850002 -33.270698)
			(xy 68.850002 -33.274254) (xy 68.850425 -33.289489) (xy 68.859116 -33.318683) (xy 68.876012 -33.344028)
			(xy 68.899617 -33.36328) (xy 68.927842 -33.374735) (xy 68.942966 -33.376616) (xy 68.971146 -33.379571)
			(xy 69.026252 -33.392743) (xy 69.078804 -33.413919) (xy 69.112566 -33.433766) (xy 69.340982 -33.433766)
			(xy 69.345053 -33.378144) (xy 69.357179 -33.323707) (xy 69.377102 -33.271616) (xy 69.404398 -33.222981)
			(xy 69.438484 -33.178838) (xy 69.478633 -33.140129) (xy 69.523991 -33.107678) (xy 69.573591 -33.082177)
			(xy 69.626375 -33.06417) (xy 69.681218 -33.05404) (xy 69.736952 -33.052003) (xy 69.792389 -33.058103)
			(xy 69.846346 -33.072209) (xy 69.897675 -33.094021) (xy 69.945281 -33.123075) (xy 69.988149 -33.15875)
			(xy 70.025366 -33.200287) (xy 70.056139 -33.2468) (xy 70.079811 -33.297297) (xy 70.095879 -33.350704)
			(xy 70.103999 -33.40588) (xy 70.104508 -33.433766) (xy 70.103999 -33.461652) (xy 70.095879 -33.516828)
			(xy 70.079811 -33.570235) (xy 70.056139 -33.620732) (xy 70.025366 -33.667245) (xy 69.988149 -33.708782)
			(xy 69.945281 -33.744457) (xy 69.897675 -33.773511) (xy 69.846346 -33.795323) (xy 69.792389 -33.809429)
			(xy 69.736952 -33.815529) (xy 69.681218 -33.813492) (xy 69.626375 -33.803362) (xy 69.573591 -33.785355)
			(xy 69.523991 -33.759854) (xy 69.478633 -33.727403) (xy 69.438484 -33.688694) (xy 69.404398 -33.644551)
			(xy 69.377102 -33.595916) (xy 69.357179 -33.543825) (xy 69.345053 -33.489388) (xy 69.340982 -33.433766)
			(xy 69.112566 -33.433766) (xy 69.127648 -33.442632) (xy 69.17171 -33.478252) (xy 69.21002 -33.519995)
			(xy 69.241738 -33.566944) (xy 69.266164 -33.618067) (xy 69.282764 -33.67224) (xy 69.291171 -33.728271)
			(xy 69.291708 -33.7566) (xy 69.291216 -33.784582) (xy 69.283038 -33.839946) (xy 69.266857 -33.89352)
			(xy 69.243021 -33.944155) (xy 69.212041 -33.990763) (xy 69.193664 -34.01187) (xy 69.184203 -34.023084)
			(xy 69.17156 -34.049545) (xy 69.166955 -34.078508) (xy 69.170769 -34.107586) (xy 69.182687 -34.134382)
			(xy 69.201727 -34.156688) (xy 69.22632 -34.172665) (xy 69.254439 -34.180997) (xy 69.269102 -34.181542)
			(xy 71.02856 -34.181542) (xy 71.354188 -33.855914) (xy 71.354188 -33.798256) (xy 71.353634 -33.783151)
			(xy 71.344795 -33.754263) (xy 71.327901 -33.729218) (xy 71.304426 -33.710202) (xy 71.27642 -33.698874)
			(xy 71.246327 -33.696224) (xy 71.216772 -33.702482) (xy 71.203312 -33.709356) (xy 71.17483 -33.724375)
			(xy 71.11407 -33.745674) (xy 71.050593 -33.756452) (xy 71.0184 -33.757108) (xy 70.991149 -33.756622)
			(xy 70.937201 -33.748866) (xy 70.884906 -33.733511) (xy 70.835329 -33.710869) (xy 70.789479 -33.681403)
			(xy 70.748288 -33.645712) (xy 70.712597 -33.604521) (xy 70.683131 -33.558671) (xy 70.660489 -33.509094)
			(xy 70.645134 -33.456799) (xy 70.637378 -33.402851) (xy 70.637378 -33.348349) (xy 70.645134 -33.294401)
			(xy 70.660489 -33.242106) (xy 70.683131 -33.192529) (xy 70.712597 -33.146679) (xy 70.748288 -33.105488)
			(xy 70.789479 -33.069797) (xy 70.835329 -33.040331) (xy 70.884906 -33.017689) (xy 70.937201 -33.002334)
			(xy 70.991149 -32.994578) (xy 71.0184 -32.994092) (xy 71.05059 -32.994765) (xy 71.114059 -33.005565)
			(xy 71.174822 -33.026844) (xy 71.203312 -33.041844) (xy 71.21679 -33.048693) (xy 71.246346 -33.054982)
			(xy 71.276449 -33.052352) (xy 71.304466 -33.041031) (xy 71.327946 -33.022011) (xy 71.344836 -32.996954)
			(xy 71.353659 -32.968053) (xy 71.354188 -32.952944) (xy 71.354188 -32.486092) (xy 71.353717 -32.472221)
			(xy 71.346245 -32.445504) (xy 71.331854 -32.421787) (xy 71.311608 -32.402821) (xy 71.287002 -32.390007)
			(xy 71.259855 -32.384293) (xy 71.245984 -32.384746) (xy 71.2216 -32.385508) (xy 71.194349 -32.385022)
			(xy 71.140401 -32.377266) (xy 71.088106 -32.361911) (xy 71.038529 -32.339269) (xy 70.992679 -32.309803)
			(xy 70.951488 -32.274112) (xy 70.915797 -32.232921) (xy 70.886331 -32.187071) (xy 70.863689 -32.137494)
			(xy 70.848334 -32.085199) (xy 70.840578 -32.031251) (xy 70.840578 -31.976749) (xy 70.848334 -31.922801)
			(xy 70.863689 -31.870506) (xy 70.886331 -31.820929) (xy 70.915797 -31.775079) (xy 70.951488 -31.733888)
			(xy 70.992679 -31.698197) (xy 71.038529 -31.668731) (xy 71.088106 -31.646089) (xy 71.140401 -31.630734)
			(xy 71.194349 -31.622978) (xy 71.2216 -31.622492) (xy 71.245984 -31.623254) (xy 71.259858 -31.623689)
			(xy 71.287011 -31.617977) (xy 71.311624 -31.605168) (xy 71.331882 -31.586208) (xy 71.346291 -31.562496)
			(xy 71.353786 -31.535781) (xy 71.354188 -31.521908) (xy 71.354188 -31.39313) (xy 71.009002 -31.047944)
			(xy 69.3039 -31.047944) (xy 69.288647 -31.069907) (xy 69.252976 -31.109742) (xy 69.212093 -31.144206)
			(xy 69.166798 -31.172624) (xy 69.117979 -31.19444) (xy 69.066592 -31.209226) (xy 69.013644 -31.216692)
			(xy 68.960172 -31.216692) (xy 68.907224 -31.209226) (xy 68.855837 -31.19444) (xy 68.807018 -31.172624)
			(xy 68.761723 -31.144206) (xy 68.72084 -31.109742) (xy 68.685169 -31.069907) (xy 68.669916 -31.047944)
			(xy 68.511674 -31.047944) (xy 68.496863 -31.072145) (xy 68.461211 -31.116281) (xy 68.41942 -31.154657)
			(xy 68.372411 -31.186426) (xy 68.321218 -31.210889) (xy 68.266969 -31.227508) (xy 68.210859 -31.235917)
			(xy 68.18249 -31.236412) (xy 68.157161 -31.235985) (xy 68.106955 -31.229233) (xy 68.082414 -31.22295)
			(xy 68.069422 -31.219825) (xy 68.042708 -31.219728) (xy 68.016884 -31.226565) (xy 67.993717 -31.239865)
			(xy 67.974793 -31.25872) (xy 67.961407 -31.281838) (xy 67.954477 -31.307637) (xy 67.954144 -31.320994)
			(xy 67.954144 -31.74492) (xy 67.953726 -31.766198) (xy 67.947072 -31.808232) (xy 67.93393 -31.848709)
			(xy 67.914624 -31.886634) (xy 67.889628 -31.921077) (xy 67.874896 -31.936436) (xy 67.636136 -32.175196)
			(xy 67.620787 -32.189943) (xy 67.586346 -32.214949) (xy 67.548419 -32.234263) (xy 67.507939 -32.247411)
			(xy 67.465901 -32.254068) (xy 67.44462 -32.254444) (xy 66.81978 -32.254444) (xy 66.798502 -32.254026)
			(xy 66.756468 -32.247372) (xy 66.715991 -32.23423) (xy 66.678066 -32.214924) (xy 66.643623 -32.189928)
			(xy 66.628264 -32.175196) (xy 66.474086 -32.021272) (xy 66.407792 -32.021272) (xy 66.393314 -32.034226)
			(xy 66.372214 -32.052503) (xy 66.325674 -32.08333) (xy 66.27514 -32.107046) (xy 66.221689 -32.123146)
			(xy 66.166463 -32.131287) (xy 66.138552 -32.131762) (xy 66.111306 -32.131273) (xy 66.05737 -32.123511)
			(xy 66.005088 -32.108154) (xy 65.955523 -32.085513) (xy 65.909684 -32.056049) (xy 65.868504 -32.020362)
			(xy 65.832822 -31.979178) (xy 65.803364 -31.933335) (xy 65.780729 -31.883767) (xy 65.765378 -31.831483)
			(xy 65.757624 -31.777546) (xy 65.757624 -31.723054) (xy 65.765378 -31.669117) (xy 65.780729 -31.616833)
			(xy 65.803364 -31.567265) (xy 65.832822 -31.521422) (xy 65.868504 -31.480238) (xy 65.909684 -31.444551)
			(xy 65.955523 -31.415087) (xy 66.005088 -31.392446) (xy 66.05737 -31.377089) (xy 66.111306 -31.369327)
			(xy 66.138552 -31.368746) (xy 66.168376 -31.369303) (xy 66.227302 -31.378552) (xy 66.28407 -31.396861)
			(xy 66.337294 -31.423786) (xy 66.385678 -31.458669) (xy 66.407284 -31.479236) (xy 66.586354 -31.479236)
			(xy 66.607643 -31.479673) (xy 66.649693 -31.48637) (xy 66.690178 -31.499559) (xy 66.728103 -31.518916)
			(xy 66.762534 -31.543965) (xy 66.77787 -31.558738) (xy 66.932048 -31.712916) (xy 67.332352 -31.712916)
			(xy 67.412616 -31.632652) (xy 67.412616 -31.047944) (xy 67.166744 -31.047944) (xy 66.3321 -30.2133)
			(xy 64.749934 -30.2133) (xy 64.736377 -30.213734) (xy 64.710221 -30.220883) (xy 64.686866 -30.23466)
			(xy 64.667958 -30.254095) (xy 64.654827 -30.277819) (xy 64.648398 -30.304161) (xy 64.649125 -30.331267)
			(xy 64.652652 -30.344364) (xy 64.660264 -30.371284) (xy 64.668422 -30.426629) (xy 64.668908 -30.4546)
			(xy 64.668422 -30.481851) (xy 64.660666 -30.535799) (xy 64.645311 -30.588094) (xy 64.622669 -30.637671)
			(xy 64.593203 -30.683521) (xy 64.557512 -30.724712) (xy 64.516321 -30.760403) (xy 64.470471 -30.789869)
			(xy 64.420894 -30.812511) (xy 64.368599 -30.827866) (xy 64.314651 -30.835622) (xy 64.260149 -30.835622)
			(xy 64.206201 -30.827866) (xy 64.153906 -30.812511) (xy 64.104329 -30.789869) (xy 64.058479 -30.760403)
			(xy 64.017288 -30.724712) (xy 63.981597 -30.683521) (xy 63.952131 -30.637671) (xy 63.929489 -30.588094)
			(xy 63.914134 -30.535799) (xy 63.906378 -30.481851) (xy 63.905892 -30.4546) (xy 63.906374 -30.4274)
			(xy 63.9141 -30.37355) (xy 63.929394 -30.321344) (xy 63.951948 -30.271838) (xy 63.981304 -30.226038)
			(xy 64.016866 -30.18487) (xy 64.057914 -30.14917) (xy 64.103616 -30.119661) (xy 64.128142 -30.10789)
			(xy 64.140659 -30.101637) (xy 64.161931 -30.083477) (xy 64.177481 -30.060228) (xy 64.186141 -30.033633)
			(xy 64.187263 -30.005686) (xy 64.180763 -29.978482) (xy 64.167127 -29.954061) (xy 64.157606 -29.943806)
			(xy 63.6524 -29.4386) (xy 62.7126 -29.4386) (xy 61.995304 -30.155896) (xy 61.896244 -30.155896) (xy 61.883544 -30.164278)
			(xy 61.860104 -30.179049) (xy 61.809862 -30.2024) (xy 61.756772 -30.218242) (xy 61.70195 -30.226244)
			(xy 61.674248 -30.226762) (xy 61.644695 -30.226204) (xy 61.586296 -30.217081) (xy 61.530003 -30.199062)
			(xy 61.477162 -30.172578) (xy 61.45276 -30.155896) (xy 61.172598 -30.155896) (xy 61.149951 -30.173321)
			(xy 61.100474 -30.201907) (xy 61.047288 -30.222794) (xy 60.991581 -30.235517) (xy 60.9346 -30.239789)
			(xy 60.877619 -30.235517) (xy 60.821912 -30.222794) (xy 60.768726 -30.201907) (xy 60.719249 -30.173321)
			(xy 60.696602 -30.155896) (xy 59.988704 -30.155896) (xy 59.96178 -30.128972) (xy 59.950379 -30.118327)
			(xy 59.922741 -30.103901) (xy 59.89204 -30.098474) (xy 59.861131 -30.102551) (xy 59.832887 -30.115752)
			(xy 59.821064 -30.125924) (xy 59.799836 -30.144737) (xy 59.752857 -30.176518) (xy 59.701687 -30.200985)
			(xy 59.647455 -30.217598) (xy 59.59136 -30.225989) (xy 59.563 -30.226508) (xy 59.535749 -30.226022)
			(xy 59.481801 -30.218266) (xy 59.429506 -30.202911) (xy 59.379929 -30.180269) (xy 59.334079 -30.150803)
			(xy 59.292888 -30.115112) (xy 59.257197 -30.073921) (xy 59.227731 -30.028071) (xy 59.205089 -29.978494)
			(xy 59.189734 -29.926199) (xy 59.181978 -29.872251) (xy 59.181492 -29.845) (xy 59.181975 -29.817786)
			(xy 59.189708 -29.76391) (xy 59.205018 -29.71168) (xy 59.227594 -29.662154) (xy 59.256977 -29.616339)
			(xy 59.292572 -29.575164) (xy 59.31281 -29.556964) (xy 59.31408 -29.555948) (xy 59.351164 -29.51861)
			(xy 59.268614 -29.43606) (xy 58.88355 -29.43606) (xy 58.869519 -29.4365) (xy 58.842514 -29.444129)
			(xy 58.818608 -29.458824) (xy 58.799607 -29.479474) (xy 58.786948 -29.504518) (xy 58.781588 -29.532062)
			(xy 58.783932 -29.560026) (xy 58.793803 -29.586294) (xy 58.801762 -29.597858) (xy 58.819225 -29.622579)
			(xy 58.846935 -29.676384) (xy 58.865798 -29.733892) (xy 58.87534 -29.793657) (xy 58.87593 -29.823918)
			(xy 58.875444 -29.851169) (xy 58.867688 -29.905117) (xy 58.852333 -29.957412) (xy 58.829691 -30.006989)
			(xy 58.800225 -30.052839) (xy 58.764534 -30.09403) (xy 58.723343 -30.129721) (xy 58.677493 -30.159187)
			(xy 58.627916 -30.181829) (xy 58.575621 -30.197184) (xy 58.521673 -30.20494) (xy 58.467171 -30.20494)
			(xy 58.413223 -30.197184) (xy 58.360928 -30.181829) (xy 58.311351 -30.159187) (xy 58.265501 -30.129721)
			(xy 58.22431 -30.09403) (xy 58.188619 -30.052839) (xy 58.159153 -30.006989) (xy 58.136511 -29.957412)
			(xy 58.121156 -29.905117) (xy 58.1134 -29.851169) (xy 58.112914 -29.823918) (xy 58.113491 -29.793656)
			(xy 58.12304 -29.73389) (xy 58.141901 -29.67638) (xy 58.169602 -29.622567) (xy 58.187082 -29.597858)
			(xy 58.195025 -29.586296) (xy 58.204856 -29.560035) (xy 58.207174 -29.53209) (xy 58.201804 -29.504567)
			(xy 58.189152 -29.479543) (xy 58.17017 -29.458903) (xy 58.146291 -29.444203) (xy 58.119314 -29.436552)
			(xy 58.105294 -29.43606) (xy 58.039 -29.43606) (xy 58.025458 -29.436485) (xy 57.999328 -29.443612)
			(xy 57.975995 -29.457363) (xy 57.957102 -29.47677) (xy 57.943982 -29.500464) (xy 57.937558 -29.526775)
			(xy 57.938285 -29.553849) (xy 57.94611 -29.579778) (xy 57.952894 -29.591508) (xy 57.966629 -29.614311)
			(xy 57.988289 -29.662938) (xy 58.002967 -29.714107) (xy 58.010375 -29.766822) (xy 58.010806 -29.793438)
			(xy 58.01032 -29.820689) (xy 58.002564 -29.874637) (xy 57.987209 -29.926932) (xy 57.964567 -29.976509)
			(xy 57.935101 -30.022359) (xy 57.89941 -30.06355) (xy 57.858219 -30.099241) (xy 57.812369 -30.128707)
			(xy 57.762792 -30.151349) (xy 57.710497 -30.166704) (xy 57.656549 -30.17446) (xy 57.602047 -30.17446)
			(xy 57.548099 -30.166704) (xy 57.495804 -30.151349) (xy 57.446227 -30.128707) (xy 57.400377 -30.099241)
			(xy 57.359186 -30.06355) (xy 57.323495 -30.022359) (xy 57.294029 -29.976509) (xy 57.271387 -29.926932)
			(xy 57.256032 -29.874637) (xy 57.248276 -29.820689) (xy 57.24779 -29.793438) (xy 57.248275 -29.766827)
			(xy 57.25571 -29.714125) (xy 57.270384 -29.662965) (xy 57.292015 -29.614335) (xy 57.305702 -29.591508)
			(xy 57.312511 -29.579799) (xy 57.320306 -29.55387) (xy 57.321012 -29.526803) (xy 57.314578 -29.500503)
			(xy 57.301457 -29.476819) (xy 57.282571 -29.457417) (xy 57.25925 -29.443661) (xy 57.233133 -29.43652)
			(xy 57.219596 -29.43606) (xy 57.110376 -29.43606) (xy 57.096443 -29.436524) (xy 57.069631 -29.444122)
			(xy 57.045873 -29.458688) (xy 57.02694 -29.479138) (xy 57.014246 -29.503947) (xy 57.008735 -29.531264)
			(xy 57.010818 -29.559054) (xy 57.020341 -29.585245) (xy 57.02808 -29.596842) (xy 57.044961 -29.621336)
			(xy 57.071729 -29.674458) (xy 57.089932 -29.731088) (xy 57.099129 -29.789857) (xy 57.099708 -29.8196)
			(xy 57.099222 -29.846851) (xy 57.091466 -29.900799) (xy 57.076111 -29.953094) (xy 57.053469 -30.002671)
			(xy 57.024003 -30.048521) (xy 56.988312 -30.089712) (xy 56.947121 -30.125403) (xy 56.901271 -30.154869)
			(xy 56.851694 -30.177511) (xy 56.799399 -30.192866) (xy 56.745451 -30.200622) (xy 56.690949 -30.200622)
			(xy 56.637001 -30.192866) (xy 56.584706 -30.177511) (xy 56.535129 -30.154869) (xy 56.489279 -30.125403)
			(xy 56.448088 -30.089712) (xy 56.412397 -30.048521) (xy 56.382931 -30.002671) (xy 56.360289 -29.953094)
			(xy 56.344934 -29.900799) (xy 56.337178 -29.846851) (xy 56.336692 -29.8196) (xy 56.337239 -29.789855)
			(xy 56.346432 -29.73108) (xy 56.36464 -29.674447) (xy 56.391423 -29.621327) (xy 56.40832 -29.596842)
			(xy 56.416076 -29.585265) (xy 56.425567 -29.559075) (xy 56.427628 -29.531295) (xy 56.422106 -29.503992)
			(xy 56.409411 -29.479196) (xy 56.390489 -29.458753) (xy 56.366747 -29.444183) (xy 56.339951 -29.43657)
			(xy 56.326024 -29.43606) (xy 55.598568 -29.43606) (xy 55.368952 -29.206444) (xy 55.368952 -27.97048)
			(xy 55.186072 -27.7876) (xy 52.873148 -27.7876) (xy 52.705508 -27.955494) (xy 52.705508 -29.718)
			(xy 53.305962 -29.718) (xy 53.310033 -29.662378) (xy 53.322159 -29.607941) (xy 53.342082 -29.55585)
			(xy 53.369378 -29.507215) (xy 53.403464 -29.463072) (xy 53.443613 -29.424363) (xy 53.488971 -29.391912)
			(xy 53.538571 -29.366411) (xy 53.591355 -29.348404) (xy 53.646198 -29.338274) (xy 53.701932 -29.336237)
			(xy 53.757369 -29.342337) (xy 53.811326 -29.356443) (xy 53.862655 -29.378255) (xy 53.910261 -29.407309)
			(xy 53.953129 -29.442984) (xy 53.990346 -29.484521) (xy 54.021119 -29.531034) (xy 54.044791 -29.581531)
			(xy 54.060859 -29.634938) (xy 54.068979 -29.690114) (xy 54.069488 -29.718) (xy 54.069052 -29.741876)
			(xy 54.302658 -29.741876) (xy 54.306729 -29.686254) (xy 54.318855 -29.631817) (xy 54.338778 -29.579726)
			(xy 54.366074 -29.531091) (xy 54.40016 -29.486948) (xy 54.440309 -29.448239) (xy 54.485667 -29.415788)
			(xy 54.535267 -29.390287) (xy 54.588051 -29.37228) (xy 54.642894 -29.36215) (xy 54.698628 -29.360113)
			(xy 54.754065 -29.366213) (xy 54.808022 -29.380319) (xy 54.859351 -29.402131) (xy 54.906957 -29.431185)
			(xy 54.949825 -29.46686) (xy 54.987042 -29.508397) (xy 55.017815 -29.55491) (xy 55.041487 -29.605407)
			(xy 55.057555 -29.658814) (xy 55.065675 -29.71399) (xy 55.066184 -29.741876) (xy 55.065675 -29.769762)
			(xy 55.057555 -29.824938) (xy 55.041487 -29.878345) (xy 55.017815 -29.928842) (xy 54.987042 -29.975355)
			(xy 54.949825 -30.016892) (xy 54.906957 -30.052567) (xy 54.859351 -30.081621) (xy 54.808022 -30.103433)
			(xy 54.754065 -30.117539) (xy 54.698628 -30.123639) (xy 54.642894 -30.121602) (xy 54.588051 -30.111472)
			(xy 54.535267 -30.093465) (xy 54.485667 -30.067964) (xy 54.440309 -30.035513) (xy 54.40016 -29.996804)
			(xy 54.366074 -29.952661) (xy 54.338778 -29.904026) (xy 54.318855 -29.851935) (xy 54.306729 -29.797498)
			(xy 54.302658 -29.741876) (xy 54.069052 -29.741876) (xy 54.068979 -29.745886) (xy 54.060859 -29.801062)
			(xy 54.044791 -29.854469) (xy 54.021119 -29.904966) (xy 53.990346 -29.951479) (xy 53.953129 -29.993016)
			(xy 53.910261 -30.028691) (xy 53.862655 -30.057745) (xy 53.811326 -30.079557) (xy 53.757369 -30.093663)
			(xy 53.701932 -30.099763) (xy 53.646198 -30.097726) (xy 53.591355 -30.087596) (xy 53.538571 -30.069589)
			(xy 53.488971 -30.044088) (xy 53.443613 -30.011637) (xy 53.403464 -29.972928) (xy 53.369378 -29.928785)
			(xy 53.342082 -29.88015) (xy 53.322159 -29.828059) (xy 53.310033 -29.773622) (xy 53.305962 -29.718)
			(xy 52.705508 -29.718) (xy 52.705508 -30.275022) (xy 53.904388 -31.474156) (xy 54.1655 -31.474156)
			(xy 54.186779 -31.474572) (xy 54.228814 -31.481224) (xy 54.269293 -31.494363) (xy 54.307221 -31.513667)
			(xy 54.341665 -31.538662) (xy 54.357016 -31.553404) (xy 54.579012 -31.7754) (xy 55.878982 -31.7754)
			(xy 55.883053 -31.719778) (xy 55.895179 -31.665341) (xy 55.915102 -31.61325) (xy 55.942398 -31.564615)
			(xy 55.976484 -31.520472) (xy 56.016633 -31.481763) (xy 56.061991 -31.449312) (xy 56.111591 -31.423811)
			(xy 56.164375 -31.405804) (xy 56.219218 -31.395674) (xy 56.274952 -31.393637) (xy 56.330389 -31.399737)
			(xy 56.384346 -31.413843) (xy 56.435675 -31.435655) (xy 56.483281 -31.464709) (xy 56.526149 -31.500384)
			(xy 56.563366 -31.541921) (xy 56.594139 -31.588434) (xy 56.617811 -31.638931) (xy 56.633879 -31.692338)
			(xy 56.641999 -31.747514) (xy 56.642508 -31.7754) (xy 56.642044 -31.8008) (xy 56.844182 -31.8008)
			(xy 56.848253 -31.745178) (xy 56.860379 -31.690741) (xy 56.880302 -31.63865) (xy 56.907598 -31.590015)
			(xy 56.941684 -31.545872) (xy 56.981833 -31.507163) (xy 57.027191 -31.474712) (xy 57.076791 -31.449211)
			(xy 57.129575 -31.431204) (xy 57.184418 -31.421074) (xy 57.240152 -31.419037) (xy 57.295589 -31.425137)
			(xy 57.349546 -31.439243) (xy 57.400875 -31.461055) (xy 57.448481 -31.490109) (xy 57.491349 -31.525784)
			(xy 57.528566 -31.567321) (xy 57.559339 -31.613834) (xy 57.583011 -31.664331) (xy 57.599079 -31.717738)
			(xy 57.607199 -31.772914) (xy 57.607708 -31.8008) (xy 57.607199 -31.828686) (xy 57.599079 -31.883862)
			(xy 57.593502 -31.9024) (xy 58.317382 -31.9024) (xy 58.321453 -31.846778) (xy 58.333579 -31.792341)
			(xy 58.353502 -31.74025) (xy 58.380798 -31.691615) (xy 58.414884 -31.647472) (xy 58.455033 -31.608763)
			(xy 58.500391 -31.576312) (xy 58.549991 -31.550811) (xy 58.602775 -31.532804) (xy 58.657618 -31.522674)
			(xy 58.713352 -31.520637) (xy 58.768789 -31.526737) (xy 58.822746 -31.540843) (xy 58.874075 -31.562655)
			(xy 58.921681 -31.591709) (xy 58.964549 -31.627384) (xy 59.001766 -31.668921) (xy 59.032539 -31.715434)
			(xy 59.056211 -31.765931) (xy 59.072279 -31.819338) (xy 59.080399 -31.874514) (xy 59.080908 -31.9024)
			(xy 59.080399 -31.930286) (xy 59.072279 -31.985462) (xy 59.05906 -32.0294) (xy 59.282582 -32.0294)
			(xy 59.286653 -31.973778) (xy 59.298779 -31.919341) (xy 59.318702 -31.86725) (xy 59.345998 -31.818615)
			(xy 59.380084 -31.774472) (xy 59.420233 -31.735763) (xy 59.465591 -31.703312) (xy 59.515191 -31.677811)
			(xy 59.567975 -31.659804) (xy 59.622818 -31.649674) (xy 59.678552 -31.647637) (xy 59.733989 -31.653737)
			(xy 59.787946 -31.667843) (xy 59.839275 -31.689655) (xy 59.886881 -31.718709) (xy 59.929749 -31.754384)
			(xy 59.966966 -31.795921) (xy 59.997739 -31.842434) (xy 60.021411 -31.892931) (xy 60.037479 -31.946338)
			(xy 60.045599 -32.001514) (xy 60.046108 -32.0294) (xy 60.045599 -32.057286) (xy 60.037479 -32.112462)
			(xy 60.021411 -32.165869) (xy 59.997739 -32.216366) (xy 59.966966 -32.262879) (xy 59.929749 -32.304416)
			(xy 59.886881 -32.340091) (xy 59.839275 -32.369145) (xy 59.787946 -32.390957) (xy 59.733989 -32.405063)
			(xy 59.678552 -32.411163) (xy 59.622818 -32.409126) (xy 59.567975 -32.398996) (xy 59.515191 -32.380989)
			(xy 59.465591 -32.355488) (xy 59.420233 -32.323037) (xy 59.380084 -32.284328) (xy 59.345998 -32.240185)
			(xy 59.318702 -32.19155) (xy 59.298779 -32.139459) (xy 59.286653 -32.085022) (xy 59.282582 -32.0294)
			(xy 59.05906 -32.0294) (xy 59.056211 -32.038869) (xy 59.032539 -32.089366) (xy 59.001766 -32.135879)
			(xy 58.964549 -32.177416) (xy 58.921681 -32.213091) (xy 58.874075 -32.242145) (xy 58.822746 -32.263957)
			(xy 58.768789 -32.278063) (xy 58.713352 -32.284163) (xy 58.657618 -32.282126) (xy 58.602775 -32.271996)
			(xy 58.549991 -32.253989) (xy 58.500391 -32.228488) (xy 58.455033 -32.196037) (xy 58.414884 -32.157328)
			(xy 58.380798 -32.113185) (xy 58.353502 -32.06455) (xy 58.333579 -32.012459) (xy 58.321453 -31.958022)
			(xy 58.317382 -31.9024) (xy 57.593502 -31.9024) (xy 57.583011 -31.937269) (xy 57.559339 -31.987766)
			(xy 57.528566 -32.034279) (xy 57.491349 -32.075816) (xy 57.448481 -32.111491) (xy 57.400875 -32.140545)
			(xy 57.349546 -32.162357) (xy 57.295589 -32.176463) (xy 57.240152 -32.182563) (xy 57.184418 -32.180526)
			(xy 57.129575 -32.170396) (xy 57.076791 -32.152389) (xy 57.027191 -32.126888) (xy 56.981833 -32.094437)
			(xy 56.941684 -32.055728) (xy 56.907598 -32.011585) (xy 56.880302 -31.96295) (xy 56.860379 -31.910859)
			(xy 56.848253 -31.856422) (xy 56.844182 -31.8008) (xy 56.642044 -31.8008) (xy 56.641999 -31.803286)
			(xy 56.633879 -31.858462) (xy 56.617811 -31.911869) (xy 56.594139 -31.962366) (xy 56.563366 -32.008879)
			(xy 56.526149 -32.050416) (xy 56.483281 -32.086091) (xy 56.435675 -32.115145) (xy 56.384346 -32.136957)
			(xy 56.330389 -32.151063) (xy 56.274952 -32.157163) (xy 56.219218 -32.155126) (xy 56.164375 -32.144996)
			(xy 56.111591 -32.126989) (xy 56.061991 -32.101488) (xy 56.016633 -32.069037) (xy 55.976484 -32.030328)
			(xy 55.942398 -31.986185) (xy 55.915102 -31.93755) (xy 55.895179 -31.885459) (xy 55.883053 -31.831022)
			(xy 55.878982 -31.7754) (xy 54.579012 -31.7754) (xy 54.844696 -32.041084) (xy 54.859442 -32.056433)
			(xy 54.884445 -32.090875) (xy 54.903757 -32.128802) (xy 54.916901 -32.169282) (xy 54.923555 -32.21132)
			(xy 54.923944 -32.2326) (xy 54.923944 -32.384492) (xy 54.924422 -32.398353) (xy 54.931895 -32.425051)
			(xy 54.946266 -32.448759) (xy 54.966478 -32.467735) (xy 54.991046 -32.480582) (xy 55.018162 -32.486356)
			(xy 55.045832 -32.484633) (xy 55.059072 -32.480504) (xy 55.089488 -32.470577) (xy 55.15256 -32.45985)
			(xy 55.184548 -32.459168) (xy 55.211798 -32.459657) (xy 55.265741 -32.467419) (xy 55.318032 -32.482778)
			(xy 55.367605 -32.505422) (xy 55.413451 -32.534889) (xy 55.454637 -32.57058) (xy 55.490326 -32.611769)
			(xy 55.51979 -32.657617) (xy 55.54243 -32.707191) (xy 55.557786 -32.759482) (xy 55.565545 -32.813426)
			(xy 55.566056 -32.840676) (xy 55.565524 -32.869593) (xy 55.556799 -32.926765) (xy 55.539546 -32.981966)
			(xy 55.51416 -33.03393) (xy 55.481222 -33.081469) (xy 55.441488 -33.123492) (xy 55.41899 -33.141666)
			(xy 55.407183 -33.151565) (xy 55.389663 -33.176891) (xy 55.380483 -33.206287) (xy 55.380479 -33.237083)
			(xy 55.38965 -33.266482) (xy 55.407163 -33.291814) (xy 55.41899 -33.301686) (xy 55.441473 -33.319877)
			(xy 55.481209 -33.361894) (xy 55.514147 -33.409429) (xy 55.539531 -33.461391) (xy 55.556781 -33.51659)
			(xy 55.5655 -33.57376) (xy 55.566056 -33.602676) (xy 55.823104 -33.602676) (xy 55.823675 -33.573761)
			(xy 55.832393 -33.516592) (xy 55.84964 -33.461394) (xy 55.875022 -33.409432) (xy 55.907956 -33.361897)
			(xy 55.947689 -33.319878) (xy 55.97017 -33.301686) (xy 55.982001 -33.291816) (xy 55.999521 -33.266486)
			(xy 56.008696 -33.237085) (xy 56.008691 -33.206286) (xy 55.999508 -33.176888) (xy 55.981981 -33.151562)
			(xy 55.97017 -33.141666) (xy 55.947664 -33.123502) (xy 55.907932 -33.081476) (xy 55.874996 -33.033935)
			(xy 55.849612 -32.981968) (xy 55.83236 -32.926767) (xy 55.823636 -32.869593) (xy 55.823104 -32.840676)
			(xy 55.82359 -32.813425) (xy 55.831346 -32.759477) (xy 55.846701 -32.707182) (xy 55.869343 -32.657605)
			(xy 55.898809 -32.611755) (xy 55.9345 -32.570564) (xy 55.975691 -32.534873) (xy 56.021541 -32.505407)
			(xy 56.071118 -32.482765) (xy 56.123413 -32.46741) (xy 56.177361 -32.459654) (xy 56.231863 -32.459654)
			(xy 56.285811 -32.46741) (xy 56.338106 -32.482765) (xy 56.387683 -32.505407) (xy 56.433533 -32.534873)
			(xy 56.474724 -32.570564) (xy 56.510415 -32.611755) (xy 56.539881 -32.657605) (xy 56.562523 -32.707182)
			(xy 56.577878 -32.759477) (xy 56.585634 -32.813425) (xy 56.58612 -32.840676) (xy 56.585615 -32.869594)
			(xy 56.576887 -32.926767) (xy 56.559629 -32.981967) (xy 56.534235 -33.03393) (xy 56.501288 -33.081463)
			(xy 56.461542 -33.123478) (xy 56.439054 -33.141666) (xy 56.427269 -33.151587) (xy 56.409744 -33.176902)
			(xy 56.400561 -33.206291) (xy 56.400557 -33.23708) (xy 56.409731 -33.266471) (xy 56.427249 -33.291791)
			(xy 56.439054 -33.301686) (xy 56.461542 -33.319871) (xy 56.501274 -33.361894) (xy 56.534211 -33.40943)
			(xy 56.559598 -33.461393) (xy 56.576854 -33.51659) (xy 56.585584 -33.57376) (xy 56.58612 -33.602676)
			(xy 56.840628 -33.602676) (xy 56.84119 -33.573761) (xy 56.849908 -33.516591) (xy 56.867157 -33.461392)
			(xy 56.89254 -33.40943) (xy 56.925477 -33.361895) (xy 56.965211 -33.319877) (xy 56.987694 -33.301686)
			(xy 56.999523 -33.291814) (xy 57.017039 -33.266483) (xy 57.026211 -33.237084) (xy 57.026207 -33.206287)
			(xy 57.017026 -33.17689) (xy 56.999502 -33.151564) (xy 56.987694 -33.141666) (xy 56.965193 -33.123496)
			(xy 56.925459 -33.081471) (xy 56.892522 -33.033932) (xy 56.867137 -32.981967) (xy 56.849885 -32.926766)
			(xy 56.84116 -32.869593) (xy 56.840628 -32.840676) (xy 56.841114 -32.813425) (xy 56.84887 -32.759477)
			(xy 56.864225 -32.707182) (xy 56.886867 -32.657605) (xy 56.916333 -32.611755) (xy 56.952024 -32.570564)
			(xy 56.993215 -32.534873) (xy 57.039065 -32.505407) (xy 57.088642 -32.482765) (xy 57.140937 -32.46741)
			(xy 57.194885 -32.459654) (xy 57.249387 -32.459654) (xy 57.303335 -32.46741) (xy 57.35563 -32.482765)
			(xy 57.405207 -32.505407) (xy 57.451057 -32.534873) (xy 57.492248 -32.570564) (xy 57.527939 -32.611755)
			(xy 57.557405 -32.657605) (xy 57.580047 -32.707182) (xy 57.595402 -32.759477) (xy 57.603158 -32.813425)
			(xy 57.603399 -32.82696) (xy 57.87136 -32.82696) (xy 57.871846 -32.799709) (xy 57.879602 -32.745761)
			(xy 57.894957 -32.693466) (xy 57.917599 -32.643889) (xy 57.947065 -32.598039) (xy 57.982756 -32.556848)
			(xy 58.023947 -32.521157) (xy 58.069797 -32.491691) (xy 58.119374 -32.469049) (xy 58.171669 -32.453694)
			(xy 58.225617 -32.445938) (xy 58.280119 -32.445938) (xy 58.334067 -32.453694) (xy 58.386362 -32.469049)
			(xy 58.435939 -32.491691) (xy 58.481789 -32.521157) (xy 58.52298 -32.556848) (xy 58.558671 -32.598039)
			(xy 58.588137 -32.643889) (xy 58.610779 -32.693466) (xy 58.626134 -32.745761) (xy 58.63389 -32.799709)
			(xy 58.634376 -32.82696) (xy 58.633856 -32.856057) (xy 58.625017 -32.913577) (xy 58.623978 -32.916876)
			(xy 58.929776 -32.916876) (xy 58.933847 -32.861254) (xy 58.945973 -32.806817) (xy 58.965896 -32.754726)
			(xy 58.993192 -32.706091) (xy 59.027278 -32.661948) (xy 59.067427 -32.623239) (xy 59.112785 -32.590788)
			(xy 59.162385 -32.565287) (xy 59.215169 -32.54728) (xy 59.270012 -32.53715) (xy 59.325746 -32.535113)
			(xy 59.381183 -32.541213) (xy 59.43514 -32.555319) (xy 59.486469 -32.577131) (xy 59.534075 -32.606185)
			(xy 59.576943 -32.64186) (xy 59.61416 -32.683397) (xy 59.644933 -32.72991) (xy 59.661851 -32.766)
			(xy 61.213492 -32.766) (xy 61.213978 -32.738749) (xy 61.221734 -32.684801) (xy 61.237089 -32.632506)
			(xy 61.259731 -32.582929) (xy 61.289197 -32.537079) (xy 61.324888 -32.495888) (xy 61.366079 -32.460197)
			(xy 61.411929 -32.430731) (xy 61.461506 -32.408089) (xy 61.513801 -32.392734) (xy 61.567749 -32.384978)
			(xy 61.595 -32.384492) (xy 61.625261 -32.385087) (xy 61.685025 -32.39463) (xy 61.742532 -32.413491)
			(xy 61.796339 -32.441199) (xy 61.82106 -32.45866) (xy 61.833217 -32.46705) (xy 61.861006 -32.477035)
			(xy 61.890489 -32.478657) (xy 61.919205 -32.471779) (xy 61.944755 -32.456977) (xy 61.965005 -32.435486)
			(xy 61.978264 -32.409102) (xy 61.981334 -32.394652) (xy 61.986442 -32.368512) (xy 62.002937 -32.317871)
			(xy 62.026315 -32.270016) (xy 62.056122 -32.225878) (xy 62.091779 -32.186315) (xy 62.132592 -32.152096)
			(xy 62.177768 -32.123887) (xy 62.226429 -32.102236) (xy 62.277628 -32.087564) (xy 62.33037 -32.080155)
			(xy 62.357 -32.079692) (xy 62.384251 -32.080178) (xy 62.438199 -32.087934) (xy 62.490494 -32.103289)
			(xy 62.540071 -32.125931) (xy 62.585921 -32.155397) (xy 62.627112 -32.191088) (xy 62.662803 -32.232279)
			(xy 62.692269 -32.278129) (xy 62.714911 -32.327706) (xy 62.730266 -32.380001) (xy 62.738022 -32.433949)
			(xy 62.738508 -32.4612) (xy 62.738067 -32.487274) (xy 62.730975 -32.538939) (xy 62.71691 -32.589155)
			(xy 62.696135 -32.636986) (xy 62.669036 -32.681541) (xy 62.63612 -32.721988) (xy 62.61735 -32.740092)
			(xy 62.607353 -32.749964) (xy 62.592798 -32.773985) (xy 62.585337 -32.801063) (xy 62.585533 -32.829149)
			(xy 62.593371 -32.85612) (xy 62.60826 -32.879936) (xy 62.618366 -32.889698) (xy 62.637707 -32.907877)
			(xy 62.671698 -32.948643) (xy 62.699712 -32.993726) (xy 62.72121 -33.042255) (xy 62.735777 -33.093295)
			(xy 62.743131 -33.145861) (xy 62.743588 -33.1724) (xy 62.743145 -33.199654) (xy 62.735387 -33.253606)
			(xy 62.72003 -33.305906) (xy 62.697386 -33.355487) (xy 62.667916 -33.401341) (xy 62.63222 -33.442535)
			(xy 62.591025 -33.478228) (xy 62.54517 -33.507696) (xy 62.495587 -33.530337) (xy 62.443287 -33.545691)
			(xy 62.389334 -33.553446) (xy 62.36208 -33.553908) (xy 62.33366 -33.553414) (xy 62.277445 -33.54501)
			(xy 62.223098 -33.528361) (xy 62.197234 -33.51657) (xy 62.184173 -33.51096) (xy 62.156159 -33.506254)
			(xy 62.127932 -33.509441) (xy 62.101672 -33.520277) (xy 62.079411 -33.537922) (xy 62.062867 -33.561015)
			(xy 62.060237 -33.568386) (xy 63.720978 -33.568386) (xy 63.725049 -33.512764) (xy 63.737175 -33.458327)
			(xy 63.757098 -33.406236) (xy 63.784394 -33.357601) (xy 63.81848 -33.313458) (xy 63.858629 -33.274749)
			(xy 63.903987 -33.242298) (xy 63.953587 -33.216797) (xy 64.006371 -33.19879) (xy 64.061214 -33.18866)
			(xy 64.116948 -33.186623) (xy 64.172385 -33.192723) (xy 64.226342 -33.206829) (xy 64.277671 -33.228641)
			(xy 64.325277 -33.257695) (xy 64.368145 -33.29337) (xy 64.405362 -33.334907) (xy 64.436135 -33.38142)
			(xy 64.459807 -33.431917) (xy 64.475875 -33.485324) (xy 64.483995 -33.5405) (xy 64.484504 -33.568386)
			(xy 64.483995 -33.596272) (xy 64.479277 -33.62833) (xy 65.708782 -33.62833) (xy 65.712853 -33.572708)
			(xy 65.724979 -33.518271) (xy 65.744902 -33.46618) (xy 65.772198 -33.417545) (xy 65.806284 -33.373402)
			(xy 65.846433 -33.334693) (xy 65.891791 -33.302242) (xy 65.941391 -33.276741) (xy 65.994175 -33.258734)
			(xy 66.049018 -33.248604) (xy 66.104752 -33.246567) (xy 66.160189 -33.252667) (xy 66.214146 -33.266773)
			(xy 66.265475 -33.288585) (xy 66.313081 -33.317639) (xy 66.355949 -33.353314) (xy 66.393166 -33.394851)
			(xy 66.423939 -33.441364) (xy 66.447611 -33.491861) (xy 66.463679 -33.545268) (xy 66.471799 -33.600444)
			(xy 66.472308 -33.62833) (xy 66.471799 -33.656216) (xy 66.463679 -33.711392) (xy 66.447611 -33.764799)
			(xy 66.423939 -33.815296) (xy 66.393166 -33.861809) (xy 66.355949 -33.903346) (xy 66.313081 -33.939021)
			(xy 66.265475 -33.968075) (xy 66.214146 -33.989887) (xy 66.160189 -34.003993) (xy 66.104752 -34.010093)
			(xy 66.049018 -34.008056) (xy 65.994175 -33.997926) (xy 65.941391 -33.979919) (xy 65.891791 -33.954418)
			(xy 65.846433 -33.921967) (xy 65.806284 -33.883258) (xy 65.772198 -33.839115) (xy 65.744902 -33.79048)
			(xy 65.724979 -33.738389) (xy 65.712853 -33.683952) (xy 65.708782 -33.62833) (xy 64.479277 -33.62833)
			(xy 64.475875 -33.651448) (xy 64.459807 -33.704855) (xy 64.436135 -33.755352) (xy 64.405362 -33.801865)
			(xy 64.368145 -33.843402) (xy 64.325277 -33.879077) (xy 64.277671 -33.908131) (xy 64.226342 -33.929943)
			(xy 64.172385 -33.944049) (xy 64.116948 -33.950149) (xy 64.061214 -33.948112) (xy 64.006371 -33.937982)
			(xy 63.953587 -33.919975) (xy 63.903987 -33.894474) (xy 63.858629 -33.862023) (xy 63.81848 -33.823314)
			(xy 63.784394 -33.779171) (xy 63.757098 -33.730536) (xy 63.737175 -33.678445) (xy 63.725049 -33.624008)
			(xy 63.720978 -33.568386) (xy 62.060237 -33.568386) (xy 62.053321 -33.587769) (xy 62.051946 -33.601914)
			(xy 62.049648 -33.630647) (xy 62.037553 -33.687002) (xy 62.017115 -33.740896) (xy 61.988802 -33.791101)
			(xy 61.953256 -33.836475) (xy 61.911288 -33.875983) (xy 61.863853 -33.908726) (xy 61.812031 -33.933959)
			(xy 61.757002 -33.951107) (xy 61.700019 -33.95978) (xy 61.6712 -33.960308) (xy 61.643949 -33.959822)
			(xy 61.590001 -33.952066) (xy 61.537706 -33.936711) (xy 61.488129 -33.914069) (xy 61.442279 -33.884603)
			(xy 61.401088 -33.848912) (xy 61.365397 -33.807721) (xy 61.335931 -33.761871) (xy 61.313289 -33.712294)
			(xy 61.297934 -33.659999) (xy 61.290178 -33.606051) (xy 61.289692 -33.5788) (xy 61.290233 -33.549747)
			(xy 61.299032 -33.492311) (xy 61.31644 -33.436874) (xy 61.342057 -33.384719) (xy 61.375288 -33.337053)
			(xy 61.415364 -33.29498) (xy 61.438028 -33.276794) (xy 61.449246 -33.267426) (xy 61.466323 -33.243726)
			(xy 61.47599 -33.216162) (xy 61.477457 -33.186988) (xy 61.470604 -33.158592) (xy 61.45599 -33.1333)
			(xy 61.434813 -33.11318) (xy 61.422026 -33.106106) (xy 61.39885 -33.093778) (xy 61.355774 -33.063779)
			(xy 61.317214 -33.028161) (xy 61.283899 -32.987595) (xy 61.256457 -32.942847) (xy 61.235405 -32.89476)
			(xy 61.221142 -32.844242) (xy 61.213935 -32.792246) (xy 61.213492 -32.766) (xy 59.661851 -32.766)
			(xy 59.668605 -32.780407) (xy 59.684673 -32.833814) (xy 59.692793 -32.88899) (xy 59.693302 -32.916876)
			(xy 59.692793 -32.944762) (xy 59.684673 -32.999938) (xy 59.668605 -33.053345) (xy 59.644933 -33.103842)
			(xy 59.61416 -33.150355) (xy 59.576943 -33.191892) (xy 59.534075 -33.227567) (xy 59.486469 -33.256621)
			(xy 59.43514 -33.278433) (xy 59.381183 -33.292539) (xy 59.325746 -33.298639) (xy 59.270012 -33.296602)
			(xy 59.215169 -33.286472) (xy 59.162385 -33.268465) (xy 59.112785 -33.242964) (xy 59.067427 -33.210513)
			(xy 59.027278 -33.171804) (xy 58.993192 -33.127661) (xy 58.965896 -33.079026) (xy 58.945973 -33.026935)
			(xy 58.933847 -32.972498) (xy 58.929776 -32.916876) (xy 58.623978 -32.916876) (xy 58.607538 -32.969084)
			(xy 58.581825 -33.021291) (xy 58.548476 -33.068982) (xy 58.508266 -33.11105) (xy 58.485532 -33.12922)
			(xy 58.475056 -33.137818) (xy 58.458737 -33.159446) (xy 58.448679 -33.184604) (xy 58.445591 -33.211521)
			(xy 58.44969 -33.238303) (xy 58.460686 -33.263065) (xy 58.477807 -33.284064) (xy 58.48858 -33.292288)
			(xy 58.509364 -33.307746) (xy 58.547018 -33.343311) (xy 58.579518 -33.383641) (xy 58.606264 -33.427996)
			(xy 58.626768 -33.47556) (xy 58.64065 -33.52546) (xy 58.647658 -33.576778) (xy 58.648092 -33.602676)
			(xy 58.647606 -33.629927) (xy 58.63985 -33.683875) (xy 58.624495 -33.73617) (xy 58.601853 -33.785747)
			(xy 58.572387 -33.831597) (xy 58.536696 -33.872788) (xy 58.495505 -33.908479) (xy 58.449655 -33.937945)
			(xy 58.400078 -33.960587) (xy 58.347783 -33.975942) (xy 58.293835 -33.983698) (xy 58.239333 -33.983698)
			(xy 58.185385 -33.975942) (xy 58.13309 -33.960587) (xy 58.083513 -33.937945) (xy 58.037663 -33.908479)
			(xy 57.996472 -33.872788) (xy 57.960781 -33.831597) (xy 57.931315 -33.785747) (xy 57.908673 -33.73617)
			(xy 57.893318 -33.683875) (xy 57.885562 -33.629927) (xy 57.885076 -33.602676) (xy 57.885602 -33.573579)
			(xy 57.894437 -33.516058) (xy 57.911914 -33.46055) (xy 57.937625 -33.408343) (xy 57.970974 -33.360652)
			(xy 58.011185 -33.318585) (xy 58.03392 -33.300416) (xy 58.044354 -33.291774) (xy 58.060665 -33.270154)
			(xy 58.070719 -33.245007) (xy 58.07381 -33.218101) (xy 58.069721 -33.191329) (xy 58.058739 -33.166574)
			(xy 58.041636 -33.145575) (xy 58.030872 -33.137348) (xy 58.010047 -33.121943) (xy 57.972396 -33.086368)
			(xy 57.939902 -33.046028) (xy 57.913161 -33.001664) (xy 57.892664 -32.954092) (xy 57.878789 -32.904185)
			(xy 57.87179 -32.85286) (xy 57.87136 -32.82696) (xy 57.603399 -32.82696) (xy 57.603644 -32.840676)
			(xy 57.60313 -32.869593) (xy 57.594403 -32.926766) (xy 57.577146 -32.981966) (xy 57.551753 -33.033928)
			(xy 57.518808 -33.081461) (xy 57.479065 -33.123477) (xy 57.456578 -33.141666) (xy 57.4448 -33.151592)
			(xy 57.427288 -33.176909) (xy 57.418114 -33.206294) (xy 57.418109 -33.237077) (xy 57.427275 -33.266464)
			(xy 57.44478 -33.291787) (xy 57.456578 -33.301686) (xy 57.47905 -33.31989) (xy 57.518787 -33.361907)
			(xy 57.551728 -33.409439) (xy 57.577119 -33.461397) (xy 57.594377 -33.516593) (xy 57.603108 -33.573761)
			(xy 57.603644 -33.602676) (xy 57.603158 -33.629927) (xy 57.595402 -33.683875) (xy 57.580047 -33.73617)
			(xy 57.557405 -33.785747) (xy 57.527939 -33.831597) (xy 57.492248 -33.872788) (xy 57.451057 -33.908479)
			(xy 57.405207 -33.937945) (xy 57.35563 -33.960587) (xy 57.303335 -33.975942) (xy 57.249387 -33.983698)
			(xy 57.194885 -33.983698) (xy 57.140937 -33.975942) (xy 57.088642 -33.960587) (xy 57.039065 -33.937945)
			(xy 56.993215 -33.908479) (xy 56.952024 -33.872788) (xy 56.916333 -33.831597) (xy 56.886867 -33.785747)
			(xy 56.864225 -33.73617) (xy 56.84887 -33.683875) (xy 56.841114 -33.629927) (xy 56.840628 -33.602676)
			(xy 56.58612 -33.602676) (xy 56.585634 -33.629927) (xy 56.577878 -33.683875) (xy 56.562523 -33.73617)
			(xy 56.539881 -33.785747) (xy 56.510415 -33.831597) (xy 56.474724 -33.872788) (xy 56.433533 -33.908479)
			(xy 56.387683 -33.937945) (xy 56.338106 -33.960587) (xy 56.285811 -33.975942) (xy 56.231863 -33.983698)
			(xy 56.177361 -33.983698) (xy 56.123413 -33.975942) (xy 56.071118 -33.960587) (xy 56.021541 -33.937945)
			(xy 55.975691 -33.908479) (xy 55.9345 -33.872788) (xy 55.898809 -33.831597) (xy 55.869343 -33.785747)
			(xy 55.846701 -33.73617) (xy 55.831346 -33.683875) (xy 55.82359 -33.629927) (xy 55.823104 -33.602676)
			(xy 55.566056 -33.602676) (xy 55.565572 -33.62993) (xy 55.557818 -33.683883) (xy 55.542466 -33.736183)
			(xy 55.519827 -33.785766) (xy 55.490362 -33.831623) (xy 55.454671 -33.87282) (xy 55.413481 -33.908519)
			(xy 55.367629 -33.937992) (xy 55.31805 -33.960641) (xy 55.265753 -33.976003) (xy 55.211802 -33.983767)
			(xy 55.184548 -33.984184) (xy 55.164648 -33.983902) (xy 55.125069 -33.979705) (xy 55.105554 -33.975802)
			(xy 55.090657 -33.973208) (xy 55.060553 -33.975869) (xy 55.032543 -33.987219) (xy 55.009079 -34.006266)
			(xy 54.992213 -34.031344) (xy 54.983421 -34.060258) (xy 54.982872 -34.07537) (xy 54.982872 -39.802133)
			(xy 55.360064 -39.802133) (xy 55.360064 -39.750159) (xy 55.368194 -39.698824) (xy 55.384255 -39.649394)
			(xy 55.407851 -39.603084) (xy 55.438401 -39.561036) (xy 55.475152 -39.524285) (xy 55.5172 -39.493735)
			(xy 55.56351 -39.470139) (xy 55.61294 -39.454078) (xy 55.664275 -39.445948) (xy 55.716249 -39.445948)
			(xy 55.767584 -39.454078) (xy 55.817014 -39.470139) (xy 55.863324 -39.493735) (xy 55.905372 -39.524285)
			(xy 55.942123 -39.561036) (xy 55.972673 -39.603084) (xy 55.996269 -39.649394) (xy 56.01233 -39.698824)
			(xy 56.02046 -39.750159) (xy 56.02097 -39.776146) (xy 56.02046 -39.802133) (xy 56.15991 -39.802133)
			(xy 56.15991 -39.750159) (xy 56.16804 -39.698824) (xy 56.184101 -39.649394) (xy 56.207697 -39.603084)
			(xy 56.238247 -39.561036) (xy 56.274998 -39.524285) (xy 56.317046 -39.493735) (xy 56.363356 -39.470139)
			(xy 56.412786 -39.454078) (xy 56.464121 -39.445948) (xy 56.516095 -39.445948) (xy 56.56743 -39.454078)
			(xy 56.61686 -39.470139) (xy 56.66317 -39.493735) (xy 56.705218 -39.524285) (xy 56.741969 -39.561036)
			(xy 56.772519 -39.603084) (xy 56.796115 -39.649394) (xy 56.812176 -39.698824) (xy 56.820306 -39.750159)
			(xy 56.820816 -39.776146) (xy 56.820306 -39.802133) (xy 56.812176 -39.853468) (xy 56.796115 -39.902898)
			(xy 56.772519 -39.949208) (xy 56.741969 -39.991256) (xy 56.705218 -40.028007) (xy 56.66317 -40.058557)
			(xy 56.61686 -40.082153) (xy 56.56743 -40.098214) (xy 56.516095 -40.106344) (xy 56.464121 -40.106344)
			(xy 56.412786 -40.098214) (xy 56.363356 -40.082153) (xy 56.317046 -40.058557) (xy 56.274998 -40.028007)
			(xy 56.238247 -39.991256) (xy 56.207697 -39.949208) (xy 56.184101 -39.902898) (xy 56.16804 -39.853468)
			(xy 56.15991 -39.802133) (xy 56.02046 -39.802133) (xy 56.01233 -39.853468) (xy 55.996269 -39.902898)
			(xy 55.972673 -39.949208) (xy 55.942123 -39.991256) (xy 55.905372 -40.028007) (xy 55.863324 -40.058557)
			(xy 55.817014 -40.082153) (xy 55.767584 -40.098214) (xy 55.716249 -40.106344) (xy 55.664275 -40.106344)
			(xy 55.61294 -40.098214) (xy 55.56351 -40.082153) (xy 55.5172 -40.058557) (xy 55.475152 -40.028007)
			(xy 55.438401 -39.991256) (xy 55.407851 -39.949208) (xy 55.384255 -39.902898) (xy 55.368194 -39.853468)
			(xy 55.360064 -39.802133) (xy 54.982872 -39.802133) (xy 54.982872 -40.601979) (xy 55.360064 -40.601979)
			(xy 55.360064 -40.550005) (xy 55.368194 -40.49867) (xy 55.384255 -40.44924) (xy 55.407851 -40.40293)
			(xy 55.438401 -40.360882) (xy 55.475152 -40.324131) (xy 55.5172 -40.293581) (xy 55.56351 -40.269985)
			(xy 55.61294 -40.253924) (xy 55.664275 -40.245794) (xy 55.716249 -40.245794) (xy 55.767584 -40.253924)
			(xy 55.817014 -40.269985) (xy 55.863324 -40.293581) (xy 55.905372 -40.324131) (xy 55.942123 -40.360882)
			(xy 55.972673 -40.40293) (xy 55.996269 -40.44924) (xy 56.01233 -40.49867) (xy 56.02046 -40.550005)
			(xy 56.02097 -40.575992) (xy 56.02046 -40.601979) (xy 56.15991 -40.601979) (xy 56.15991 -40.550005)
			(xy 56.16804 -40.49867) (xy 56.184101 -40.44924) (xy 56.207697 -40.40293) (xy 56.238247 -40.360882)
			(xy 56.274998 -40.324131) (xy 56.317046 -40.293581) (xy 56.363356 -40.269985) (xy 56.412786 -40.253924)
			(xy 56.464121 -40.245794) (xy 56.516095 -40.245794) (xy 56.56743 -40.253924) (xy 56.61686 -40.269985)
			(xy 56.66317 -40.293581) (xy 56.705218 -40.324131) (xy 56.741969 -40.360882) (xy 56.772519 -40.40293)
			(xy 56.796115 -40.44924) (xy 56.812176 -40.49867) (xy 56.820306 -40.550005) (xy 56.820816 -40.575992)
			(xy 56.820306 -40.601979) (xy 56.812176 -40.653314) (xy 56.796115 -40.702744) (xy 56.772519 -40.749054)
			(xy 56.741969 -40.791102) (xy 56.705218 -40.827853) (xy 56.66317 -40.858403) (xy 56.61686 -40.881999)
			(xy 56.56743 -40.89806) (xy 56.516095 -40.90619) (xy 56.464121 -40.90619) (xy 56.412786 -40.89806)
			(xy 56.363356 -40.881999) (xy 56.317046 -40.858403) (xy 56.274998 -40.827853) (xy 56.238247 -40.791102)
			(xy 56.207697 -40.749054) (xy 56.184101 -40.702744) (xy 56.16804 -40.653314) (xy 56.15991 -40.601979)
			(xy 56.02046 -40.601979) (xy 56.01233 -40.653314) (xy 55.996269 -40.702744) (xy 55.972673 -40.749054)
			(xy 55.942123 -40.791102) (xy 55.905372 -40.827853) (xy 55.863324 -40.858403) (xy 55.817014 -40.881999)
			(xy 55.767584 -40.89806) (xy 55.716249 -40.90619) (xy 55.664275 -40.90619) (xy 55.61294 -40.89806)
			(xy 55.56351 -40.881999) (xy 55.5172 -40.858403) (xy 55.475152 -40.827853) (xy 55.438401 -40.791102)
			(xy 55.407851 -40.749054) (xy 55.384255 -40.702744) (xy 55.368194 -40.653314) (xy 55.360064 -40.601979)
			(xy 54.982872 -40.601979) (xy 54.982872 -41.402079) (xy 55.360064 -41.402079) (xy 55.360064 -41.350105)
			(xy 55.368194 -41.29877) (xy 55.384255 -41.24934) (xy 55.407851 -41.20303) (xy 55.438401 -41.160982)
			(xy 55.475152 -41.124231) (xy 55.5172 -41.093681) (xy 55.56351 -41.070085) (xy 55.61294 -41.054024)
			(xy 55.664275 -41.045894) (xy 55.716249 -41.045894) (xy 55.767584 -41.054024) (xy 55.817014 -41.070085)
			(xy 55.863324 -41.093681) (xy 55.905372 -41.124231) (xy 55.942123 -41.160982) (xy 55.972673 -41.20303)
			(xy 55.996269 -41.24934) (xy 56.01233 -41.29877) (xy 56.02046 -41.350105) (xy 56.02097 -41.376092)
			(xy 56.02046 -41.402079) (xy 56.15991 -41.402079) (xy 56.15991 -41.350105) (xy 56.16804 -41.29877)
			(xy 56.184101 -41.24934) (xy 56.207697 -41.20303) (xy 56.238247 -41.160982) (xy 56.274998 -41.124231)
			(xy 56.317046 -41.093681) (xy 56.363356 -41.070085) (xy 56.412786 -41.054024) (xy 56.464121 -41.045894)
			(xy 56.516095 -41.045894) (xy 56.56743 -41.054024) (xy 56.61686 -41.070085) (xy 56.66317 -41.093681)
			(xy 56.705218 -41.124231) (xy 56.741969 -41.160982) (xy 56.772519 -41.20303) (xy 56.796115 -41.24934)
			(xy 56.812176 -41.29877) (xy 56.820306 -41.350105) (xy 56.820816 -41.376092) (xy 56.820306 -41.402079)
			(xy 56.812176 -41.453414) (xy 56.796115 -41.502844) (xy 56.772519 -41.549154) (xy 56.741969 -41.591202)
			(xy 56.705218 -41.627953) (xy 56.66317 -41.658503) (xy 56.61686 -41.682099) (xy 56.56743 -41.69816)
			(xy 56.516095 -41.70629) (xy 56.464121 -41.70629) (xy 56.412786 -41.69816) (xy 56.363356 -41.682099)
			(xy 56.317046 -41.658503) (xy 56.274998 -41.627953) (xy 56.238247 -41.591202) (xy 56.207697 -41.549154)
			(xy 56.184101 -41.502844) (xy 56.16804 -41.453414) (xy 56.15991 -41.402079) (xy 56.02046 -41.402079)
			(xy 56.01233 -41.453414) (xy 55.996269 -41.502844) (xy 55.972673 -41.549154) (xy 55.942123 -41.591202)
			(xy 55.905372 -41.627953) (xy 55.863324 -41.658503) (xy 55.817014 -41.682099) (xy 55.767584 -41.69816)
			(xy 55.716249 -41.70629) (xy 55.664275 -41.70629) (xy 55.61294 -41.69816) (xy 55.56351 -41.682099)
			(xy 55.5172 -41.658503) (xy 55.475152 -41.627953) (xy 55.438401 -41.591202) (xy 55.407851 -41.549154)
			(xy 55.384255 -41.502844) (xy 55.368194 -41.453414) (xy 55.360064 -41.402079) (xy 54.982872 -41.402079)
			(xy 54.982872 -42.201925) (xy 55.360064 -42.201925) (xy 55.360064 -42.149951) (xy 55.368194 -42.098616)
			(xy 55.384255 -42.049186) (xy 55.407851 -42.002876) (xy 55.438401 -41.960828) (xy 55.475152 -41.924077)
			(xy 55.5172 -41.893527) (xy 55.56351 -41.869931) (xy 55.61294 -41.85387) (xy 55.664275 -41.84574)
			(xy 55.716249 -41.84574) (xy 55.767584 -41.85387) (xy 55.817014 -41.869931) (xy 55.863324 -41.893527)
			(xy 55.905372 -41.924077) (xy 55.942123 -41.960828) (xy 55.972673 -42.002876) (xy 55.996269 -42.049186)
			(xy 56.01233 -42.098616) (xy 56.02046 -42.149951) (xy 56.02097 -42.175938) (xy 56.02046 -42.201925)
			(xy 56.15991 -42.201925) (xy 56.15991 -42.149951) (xy 56.16804 -42.098616) (xy 56.184101 -42.049186)
			(xy 56.207697 -42.002876) (xy 56.238247 -41.960828) (xy 56.274998 -41.924077) (xy 56.317046 -41.893527)
			(xy 56.363356 -41.869931) (xy 56.412786 -41.85387) (xy 56.464121 -41.84574) (xy 56.516095 -41.84574)
			(xy 56.56743 -41.85387) (xy 56.61686 -41.869931) (xy 56.66317 -41.893527) (xy 56.705218 -41.924077)
			(xy 56.741969 -41.960828) (xy 56.772519 -42.002876) (xy 56.796115 -42.049186) (xy 56.812176 -42.098616)
			(xy 56.820306 -42.149951) (xy 56.820816 -42.175938) (xy 56.820306 -42.201925) (xy 56.812176 -42.25326)
			(xy 56.796115 -42.30269) (xy 56.772519 -42.349) (xy 56.741969 -42.391048) (xy 56.705218 -42.427799)
			(xy 56.66317 -42.458349) (xy 56.61686 -42.481945) (xy 56.56743 -42.498006) (xy 56.516095 -42.506136)
			(xy 56.464121 -42.506136) (xy 56.412786 -42.498006) (xy 56.363356 -42.481945) (xy 56.317046 -42.458349)
			(xy 56.274998 -42.427799) (xy 56.238247 -42.391048) (xy 56.207697 -42.349) (xy 56.184101 -42.30269)
			(xy 56.16804 -42.25326) (xy 56.15991 -42.201925) (xy 56.02046 -42.201925) (xy 56.01233 -42.25326)
			(xy 55.996269 -42.30269) (xy 55.972673 -42.349) (xy 55.942123 -42.391048) (xy 55.905372 -42.427799)
			(xy 55.863324 -42.458349) (xy 55.817014 -42.481945) (xy 55.767584 -42.498006) (xy 55.716249 -42.506136)
			(xy 55.664275 -42.506136) (xy 55.61294 -42.498006) (xy 55.56351 -42.481945) (xy 55.5172 -42.458349)
			(xy 55.475152 -42.427799) (xy 55.438401 -42.391048) (xy 55.407851 -42.349) (xy 55.384255 -42.30269)
			(xy 55.368194 -42.25326) (xy 55.360064 -42.201925) (xy 54.982872 -42.201925) (xy 54.982872 -43.002025)
			(xy 55.360064 -43.002025) (xy 55.360064 -42.950051) (xy 55.368194 -42.898716) (xy 55.384255 -42.849286)
			(xy 55.407851 -42.802976) (xy 55.438401 -42.760928) (xy 55.475152 -42.724177) (xy 55.5172 -42.693627)
			(xy 55.56351 -42.670031) (xy 55.61294 -42.65397) (xy 55.664275 -42.64584) (xy 55.716249 -42.64584)
			(xy 55.767584 -42.65397) (xy 55.817014 -42.670031) (xy 55.863324 -42.693627) (xy 55.905372 -42.724177)
			(xy 55.942123 -42.760928) (xy 55.972673 -42.802976) (xy 55.996269 -42.849286) (xy 56.01233 -42.898716)
			(xy 56.02046 -42.950051) (xy 56.02097 -42.976038) (xy 56.02046 -43.002025) (xy 56.15991 -43.002025)
			(xy 56.15991 -42.950051) (xy 56.16804 -42.898716) (xy 56.184101 -42.849286) (xy 56.207697 -42.802976)
			(xy 56.238247 -42.760928) (xy 56.274998 -42.724177) (xy 56.317046 -42.693627) (xy 56.363356 -42.670031)
			(xy 56.412786 -42.65397) (xy 56.464121 -42.64584) (xy 56.516095 -42.64584) (xy 56.56743 -42.65397)
			(xy 56.61686 -42.670031) (xy 56.66317 -42.693627) (xy 56.705218 -42.724177) (xy 56.741969 -42.760928)
			(xy 56.772519 -42.802976) (xy 56.796115 -42.849286) (xy 56.812176 -42.898716) (xy 56.820306 -42.950051)
			(xy 56.820816 -42.976038) (xy 56.820306 -43.002025) (xy 56.812176 -43.05336) (xy 56.796115 -43.10279)
			(xy 56.772519 -43.1491) (xy 56.741969 -43.191148) (xy 56.705218 -43.227899) (xy 56.66317 -43.258449)
			(xy 56.61686 -43.282045) (xy 56.56743 -43.298106) (xy 56.516095 -43.306236) (xy 56.464121 -43.306236)
			(xy 56.412786 -43.298106) (xy 56.363356 -43.282045) (xy 56.317046 -43.258449) (xy 56.274998 -43.227899)
			(xy 56.238247 -43.191148) (xy 56.207697 -43.1491) (xy 56.184101 -43.10279) (xy 56.16804 -43.05336)
			(xy 56.15991 -43.002025) (xy 56.02046 -43.002025) (xy 56.01233 -43.05336) (xy 55.996269 -43.10279)
			(xy 55.972673 -43.1491) (xy 55.942123 -43.191148) (xy 55.905372 -43.227899) (xy 55.863324 -43.258449)
			(xy 55.817014 -43.282045) (xy 55.767584 -43.298106) (xy 55.716249 -43.306236) (xy 55.664275 -43.306236)
			(xy 55.61294 -43.298106) (xy 55.56351 -43.282045) (xy 55.5172 -43.258449) (xy 55.475152 -43.227899)
			(xy 55.438401 -43.191148) (xy 55.407851 -43.1491) (xy 55.384255 -43.10279) (xy 55.368194 -43.05336)
			(xy 55.360064 -43.002025) (xy 54.982872 -43.002025) (xy 54.982872 -43.25874) (xy 54.21376 -44.027852)
			(xy 54.21376 -44.10837) (xy 54.214134 -44.117808) (xy 54.220959 -44.135408) (xy 54.233694 -44.149342)
			(xy 54.25061 -44.157718) (xy 54.269412 -44.159401) (xy 54.287546 -44.154161) (xy 54.295294 -44.148756)
			(xy 54.316981 -44.132989) (xy 54.364389 -44.107946) (xy 54.415216 -44.090878) (xy 54.46813 -44.082235)
			(xy 54.494938 -44.0817) (xy 54.520923 -44.082212) (xy 54.572251 -44.090347) (xy 54.621676 -44.106411)
			(xy 54.667979 -44.130009) (xy 54.710021 -44.160558) (xy 54.746766 -44.197308) (xy 54.777311 -44.239354)
			(xy 54.800903 -44.28566) (xy 54.816961 -44.335086) (xy 54.825091 -44.386415) (xy 54.825091 -44.438385)
			(xy 54.825089 -44.438395) (xy 54.96484 -44.438395) (xy 54.96484 -44.386421) (xy 54.97297 -44.335086)
			(xy 54.989031 -44.285656) (xy 55.012627 -44.239346) (xy 55.043177 -44.197298) (xy 55.079928 -44.160547)
			(xy 55.121976 -44.129997) (xy 55.168286 -44.106401) (xy 55.217716 -44.09034) (xy 55.269051 -44.08221)
			(xy 55.321025 -44.08221) (xy 55.37236 -44.09034) (xy 55.42179 -44.106401) (xy 55.4681 -44.129997)
			(xy 55.510148 -44.160547) (xy 55.546899 -44.197298) (xy 55.577449 -44.239346) (xy 55.601045 -44.285656)
			(xy 55.617106 -44.335086) (xy 55.625236 -44.386421) (xy 55.625746 -44.412408) (xy 55.625236 -44.438395)
			(xy 55.617106 -44.48973) (xy 55.601045 -44.53916) (xy 55.577449 -44.58547) (xy 55.546899 -44.627518)
			(xy 55.510148 -44.664269) (xy 55.4681 -44.694819) (xy 55.42179 -44.718415) (xy 55.37236 -44.734476)
			(xy 55.321025 -44.742606) (xy 55.269051 -44.742606) (xy 55.217716 -44.734476) (xy 55.168286 -44.718415)
			(xy 55.121976 -44.694819) (xy 55.079928 -44.664269) (xy 55.043177 -44.627518) (xy 55.012627 -44.58547)
			(xy 54.989031 -44.53916) (xy 54.97297 -44.48973) (xy 54.96484 -44.438395) (xy 54.825089 -44.438395)
			(xy 54.816961 -44.489714) (xy 54.800903 -44.53914) (xy 54.777311 -44.585446) (xy 54.746766 -44.627492)
			(xy 54.710021 -44.664242) (xy 54.667979 -44.694791) (xy 54.621676 -44.718389) (xy 54.572251 -44.734453)
			(xy 54.520923 -44.742588) (xy 54.494938 -44.743116) (xy 54.471308 -44.742672) (xy 54.424534 -44.735911)
			(xy 54.379193 -44.722578) (xy 54.357524 -44.713144) (xy 54.34409 -44.707591) (xy 54.315329 -44.703478)
			(xy 54.286573 -44.707631) (xy 54.26015 -44.719714) (xy 54.2382 -44.738749) (xy 54.222498 -44.763195)
			(xy 54.214316 -44.791073) (xy 54.21376 -44.8056) (xy 54.21376 -45.402071) (xy 55.360064 -45.402071)
			(xy 55.360064 -45.350097) (xy 55.368194 -45.298762) (xy 55.384255 -45.249332) (xy 55.407851 -45.203022)
			(xy 55.438401 -45.160974) (xy 55.475152 -45.124223) (xy 55.5172 -45.093673) (xy 55.56351 -45.070077)
			(xy 55.61294 -45.054016) (xy 55.664275 -45.045886) (xy 55.716249 -45.045886) (xy 55.767584 -45.054016)
			(xy 55.817014 -45.070077) (xy 55.863324 -45.093673) (xy 55.905372 -45.124223) (xy 55.942123 -45.160974)
			(xy 55.972673 -45.203022) (xy 55.996269 -45.249332) (xy 56.01233 -45.298762) (xy 56.02046 -45.350097)
			(xy 56.02097 -45.376084) (xy 56.02046 -45.402071) (xy 56.15991 -45.402071) (xy 56.15991 -45.350097)
			(xy 56.16804 -45.298762) (xy 56.184101 -45.249332) (xy 56.207697 -45.203022) (xy 56.238247 -45.160974)
			(xy 56.274998 -45.124223) (xy 56.317046 -45.093673) (xy 56.363356 -45.070077) (xy 56.412786 -45.054016)
			(xy 56.464121 -45.045886) (xy 56.516095 -45.045886) (xy 56.56743 -45.054016) (xy 56.61686 -45.070077)
			(xy 56.66317 -45.093673) (xy 56.705218 -45.124223) (xy 56.741969 -45.160974) (xy 56.772519 -45.203022)
			(xy 56.796115 -45.249332) (xy 56.812176 -45.298762) (xy 56.820306 -45.350097) (xy 56.820816 -45.376084)
			(xy 56.820306 -45.402071) (xy 56.812176 -45.453406) (xy 56.796115 -45.502836) (xy 56.772519 -45.549146)
			(xy 56.741969 -45.591194) (xy 56.705218 -45.627945) (xy 56.66317 -45.658495) (xy 56.61686 -45.682091)
			(xy 56.56743 -45.698152) (xy 56.516095 -45.706282) (xy 56.464121 -45.706282) (xy 56.412786 -45.698152)
			(xy 56.363356 -45.682091) (xy 56.317046 -45.658495) (xy 56.274998 -45.627945) (xy 56.238247 -45.591194)
			(xy 56.207697 -45.549146) (xy 56.184101 -45.502836) (xy 56.16804 -45.453406) (xy 56.15991 -45.402071)
			(xy 56.02046 -45.402071) (xy 56.01233 -45.453406) (xy 55.996269 -45.502836) (xy 55.972673 -45.549146)
			(xy 55.942123 -45.591194) (xy 55.905372 -45.627945) (xy 55.863324 -45.658495) (xy 55.817014 -45.682091)
			(xy 55.767584 -45.698152) (xy 55.716249 -45.706282) (xy 55.664275 -45.706282) (xy 55.61294 -45.698152)
			(xy 55.56351 -45.682091) (xy 55.5172 -45.658495) (xy 55.475152 -45.627945) (xy 55.438401 -45.591194)
			(xy 55.407851 -45.549146) (xy 55.384255 -45.502836) (xy 55.368194 -45.453406) (xy 55.360064 -45.402071)
			(xy 54.21376 -45.402071) (xy 54.21376 -45.863764) (xy 54.242716 -45.877734) (xy 54.266431 -45.889695)
			(xy 54.31003 -45.920022) (xy 54.348223 -45.956927) (xy 54.380025 -45.999462) (xy 54.404621 -46.046533)
			(xy 54.421378 -46.096931) (xy 54.429864 -46.149358) (xy 54.429862 -46.202468) (xy 54.421371 -46.254895)
			(xy 54.404611 -46.305291) (xy 54.380012 -46.35236) (xy 54.348205 -46.394893) (xy 54.31001 -46.431795)
			(xy 54.266408 -46.462118) (xy 54.242716 -46.474126) (xy 54.21376 -46.488096) (xy 54.21376 -46.663864)
			(xy 54.242716 -46.677834) (xy 54.266431 -46.689795) (xy 54.31003 -46.720122) (xy 54.348223 -46.757027)
			(xy 54.380025 -46.799562) (xy 54.404621 -46.846633) (xy 54.421378 -46.897031) (xy 54.429864 -46.949458)
			(xy 54.429862 -47.002568) (xy 54.421371 -47.054995) (xy 54.404611 -47.105391) (xy 54.380012 -47.15246)
			(xy 54.348205 -47.194993) (xy 54.31001 -47.231895) (xy 54.266408 -47.262218) (xy 54.242716 -47.274226)
			(xy 54.21376 -47.288196) (xy 54.21376 -47.802117) (xy 55.360064 -47.802117) (xy 55.360064 -47.750143)
			(xy 55.368194 -47.698808) (xy 55.384255 -47.649378) (xy 55.407851 -47.603068) (xy 55.438401 -47.56102)
			(xy 55.475152 -47.524269) (xy 55.5172 -47.493719) (xy 55.56351 -47.470123) (xy 55.61294 -47.454062)
			(xy 55.664275 -47.445932) (xy 55.716249 -47.445932) (xy 55.767584 -47.454062) (xy 55.817014 -47.470123)
			(xy 55.863324 -47.493719) (xy 55.905372 -47.524269) (xy 55.942123 -47.56102) (xy 55.972673 -47.603068)
			(xy 55.996269 -47.649378) (xy 56.01233 -47.698808) (xy 56.02046 -47.750143) (xy 56.02097 -47.77613)
			(xy 56.02046 -47.802117) (xy 56.01233 -47.853452) (xy 55.996269 -47.902882) (xy 55.972673 -47.949192)
			(xy 55.942123 -47.99124) (xy 55.905372 -48.027991) (xy 55.863324 -48.058541) (xy 55.817014 -48.082137)
			(xy 55.767584 -48.098198) (xy 55.716249 -48.106328) (xy 55.664275 -48.106328) (xy 55.61294 -48.098198)
			(xy 55.56351 -48.082137) (xy 55.5172 -48.058541) (xy 55.475152 -48.027991) (xy 55.438401 -47.99124)
			(xy 55.407851 -47.949192) (xy 55.384255 -47.902882) (xy 55.368194 -47.853452) (xy 55.360064 -47.802117)
			(xy 54.21376 -47.802117) (xy 54.21376 -48.592565) (xy 55.369462 -48.592565) (xy 55.369462 -48.540591)
			(xy 55.377592 -48.489256) (xy 55.393653 -48.439826) (xy 55.417249 -48.393516) (xy 55.447799 -48.351468)
			(xy 55.48455 -48.314717) (xy 55.526598 -48.284167) (xy 55.572908 -48.260571) (xy 55.622338 -48.24451)
			(xy 55.673673 -48.23638) (xy 55.725647 -48.23638) (xy 55.776982 -48.24451) (xy 55.826412 -48.260571)
			(xy 55.872722 -48.284167) (xy 55.91477 -48.314717) (xy 55.951521 -48.351468) (xy 55.982071 -48.393516)
			(xy 56.005667 -48.439826) (xy 56.021728 -48.489256) (xy 56.029858 -48.540591) (xy 56.030368 -48.566578)
			(xy 56.029858 -48.592565) (xy 56.02837 -48.601963) (xy 56.15991 -48.601963) (xy 56.15991 -48.549989)
			(xy 56.16804 -48.498654) (xy 56.184101 -48.449224) (xy 56.207697 -48.402914) (xy 56.238247 -48.360866)
			(xy 56.274998 -48.324115) (xy 56.317046 -48.293565) (xy 56.363356 -48.269969) (xy 56.412786 -48.253908)
			(xy 56.464121 -48.245778) (xy 56.516095 -48.245778) (xy 56.56743 -48.253908) (xy 56.61686 -48.269969)
			(xy 56.66317 -48.293565) (xy 56.705218 -48.324115) (xy 56.741969 -48.360866) (xy 56.772519 -48.402914)
			(xy 56.796115 -48.449224) (xy 56.812176 -48.498654) (xy 56.820306 -48.549989) (xy 56.820816 -48.575976)
			(xy 56.820306 -48.601963) (xy 56.812176 -48.653298) (xy 56.796115 -48.702728) (xy 56.772519 -48.749038)
			(xy 56.741969 -48.791086) (xy 56.705218 -48.827837) (xy 56.66317 -48.858387) (xy 56.61686 -48.881983)
			(xy 56.56743 -48.898044) (xy 56.516095 -48.906174) (xy 56.464121 -48.906174) (xy 56.412786 -48.898044)
			(xy 56.363356 -48.881983) (xy 56.317046 -48.858387) (xy 56.274998 -48.827837) (xy 56.238247 -48.791086)
			(xy 56.207697 -48.749038) (xy 56.184101 -48.702728) (xy 56.16804 -48.653298) (xy 56.15991 -48.601963)
			(xy 56.02837 -48.601963) (xy 56.021728 -48.6439) (xy 56.005667 -48.69333) (xy 55.982071 -48.73964)
			(xy 55.951521 -48.781688) (xy 55.91477 -48.818439) (xy 55.872722 -48.848989) (xy 55.826412 -48.872585)
			(xy 55.776982 -48.888646) (xy 55.725647 -48.896776) (xy 55.673673 -48.896776) (xy 55.622338 -48.888646)
			(xy 55.572908 -48.872585) (xy 55.526598 -48.848989) (xy 55.48455 -48.818439) (xy 55.447799 -48.781688)
			(xy 55.417249 -48.73964) (xy 55.393653 -48.69333) (xy 55.377592 -48.6439) (xy 55.369462 -48.592565)
			(xy 54.21376 -48.592565) (xy 54.21376 -49.854358) (xy 54.242716 -49.868328) (xy 54.266431 -49.880289)
			(xy 54.310032 -49.910616) (xy 54.348225 -49.947521) (xy 54.380029 -49.990057) (xy 54.404625 -50.037129)
			(xy 54.421382 -50.087527) (xy 54.429869 -50.139955) (xy 54.429867 -50.192511) (xy 55.360064 -50.192511)
			(xy 55.360064 -50.140537) (xy 55.368194 -50.089202) (xy 55.384255 -50.039772) (xy 55.407851 -49.993462)
			(xy 55.438401 -49.951414) (xy 55.475152 -49.914663) (xy 55.5172 -49.884113) (xy 55.56351 -49.860517)
			(xy 55.61294 -49.844456) (xy 55.664275 -49.836326) (xy 55.716249 -49.836326) (xy 55.767584 -49.844456)
			(xy 55.817014 -49.860517) (xy 55.863324 -49.884113) (xy 55.905372 -49.914663) (xy 55.942123 -49.951414)
			(xy 55.972673 -49.993462) (xy 55.996269 -50.039772) (xy 56.01233 -50.089202) (xy 56.02046 -50.140537)
			(xy 56.02097 -50.166524) (xy 56.02046 -50.192511) (xy 56.15991 -50.192511) (xy 56.15991 -50.140537)
			(xy 56.16804 -50.089202) (xy 56.184101 -50.039772) (xy 56.207697 -49.993462) (xy 56.238247 -49.951414)
			(xy 56.274998 -49.914663) (xy 56.317046 -49.884113) (xy 56.363356 -49.860517) (xy 56.412786 -49.844456)
			(xy 56.464121 -49.836326) (xy 56.516095 -49.836326) (xy 56.56743 -49.844456) (xy 56.61686 -49.860517)
			(xy 56.66317 -49.884113) (xy 56.705218 -49.914663) (xy 56.741969 -49.951414) (xy 56.772519 -49.993462)
			(xy 56.796115 -50.039772) (xy 56.812176 -50.089202) (xy 56.820306 -50.140537) (xy 56.820816 -50.166524)
			(xy 56.820306 -50.192511) (xy 56.812176 -50.243846) (xy 56.796115 -50.293276) (xy 56.772519 -50.339586)
			(xy 56.741969 -50.381634) (xy 56.705218 -50.418385) (xy 56.66317 -50.448935) (xy 56.61686 -50.472531)
			(xy 56.56743 -50.488592) (xy 56.516095 -50.496722) (xy 56.464121 -50.496722) (xy 56.412786 -50.488592)
			(xy 56.363356 -50.472531) (xy 56.317046 -50.448935) (xy 56.274998 -50.418385) (xy 56.238247 -50.381634)
			(xy 56.207697 -50.339586) (xy 56.184101 -50.293276) (xy 56.16804 -50.243846) (xy 56.15991 -50.192511)
			(xy 56.02046 -50.192511) (xy 56.01233 -50.243846) (xy 55.996269 -50.293276) (xy 55.972673 -50.339586)
			(xy 55.942123 -50.381634) (xy 55.905372 -50.418385) (xy 55.863324 -50.448935) (xy 55.817014 -50.472531)
			(xy 55.767584 -50.488592) (xy 55.716249 -50.496722) (xy 55.664275 -50.496722) (xy 55.61294 -50.488592)
			(xy 55.56351 -50.472531) (xy 55.5172 -50.448935) (xy 55.475152 -50.418385) (xy 55.438401 -50.381634)
			(xy 55.407851 -50.339586) (xy 55.384255 -50.293276) (xy 55.368194 -50.243846) (xy 55.360064 -50.192511)
			(xy 54.429867 -50.192511) (xy 54.429867 -50.193066) (xy 54.421377 -50.245493) (xy 54.404617 -50.29589)
			(xy 54.380018 -50.342961) (xy 54.348211 -50.385494) (xy 54.310016 -50.422397) (xy 54.266413 -50.452722)
			(xy 54.242716 -50.46472) (xy 54.21376 -50.47869) (xy 54.21376 -50.654204) (xy 54.242716 -50.668174)
			(xy 54.266435 -50.680135) (xy 54.310045 -50.710463) (xy 54.348246 -50.747372) (xy 54.380057 -50.789911)
			(xy 54.404661 -50.836988) (xy 54.421424 -50.887392) (xy 54.429916 -50.939828) (xy 54.429918 -50.992357)
			(xy 55.360064 -50.992357) (xy 55.360064 -50.940383) (xy 55.368194 -50.889048) (xy 55.384255 -50.839618)
			(xy 55.407851 -50.793308) (xy 55.438401 -50.75126) (xy 55.475152 -50.714509) (xy 55.5172 -50.683959)
			(xy 55.56351 -50.660363) (xy 55.61294 -50.644302) (xy 55.664275 -50.636172) (xy 55.716249 -50.636172)
			(xy 55.767584 -50.644302) (xy 55.817014 -50.660363) (xy 55.863324 -50.683959) (xy 55.905372 -50.714509)
			(xy 55.942123 -50.75126) (xy 55.972673 -50.793308) (xy 55.996269 -50.839618) (xy 56.01233 -50.889048)
			(xy 56.02046 -50.940383) (xy 56.02097 -50.96637) (xy 56.02046 -50.992357) (xy 56.01233 -51.043692)
			(xy 55.996269 -51.093122) (xy 55.972673 -51.139432) (xy 55.942123 -51.18148) (xy 55.905372 -51.218231)
			(xy 55.863324 -51.248781) (xy 55.817014 -51.272377) (xy 55.767584 -51.288438) (xy 55.716249 -51.296568)
			(xy 55.664275 -51.296568) (xy 55.61294 -51.288438) (xy 55.56351 -51.272377) (xy 55.5172 -51.248781)
			(xy 55.475152 -51.218231) (xy 55.438401 -51.18148) (xy 55.407851 -51.139432) (xy 55.384255 -51.093122)
			(xy 55.368194 -51.043692) (xy 55.360064 -50.992357) (xy 54.429918 -50.992357) (xy 54.429918 -50.992946)
			(xy 54.42143 -51.045382) (xy 54.404671 -51.095788) (xy 54.380071 -51.142867) (xy 54.348263 -51.185409)
			(xy 54.310065 -51.22232) (xy 54.266458 -51.252652) (xy 54.242716 -51.264566) (xy 54.21376 -51.278536)
			(xy 54.21376 -51.454304) (xy 54.242716 -51.468274) (xy 54.266435 -51.480235) (xy 54.310045 -51.510563)
			(xy 54.348246 -51.547472) (xy 54.380057 -51.590011) (xy 54.404661 -51.637088) (xy 54.421424 -51.687492)
			(xy 54.429916 -51.739928) (xy 54.429918 -51.792457) (xy 55.360064 -51.792457) (xy 55.360064 -51.740483)
			(xy 55.368194 -51.689148) (xy 55.384255 -51.639718) (xy 55.407851 -51.593408) (xy 55.438401 -51.55136)
			(xy 55.475152 -51.514609) (xy 55.5172 -51.484059) (xy 55.56351 -51.460463) (xy 55.61294 -51.444402)
			(xy 55.664275 -51.436272) (xy 55.716249 -51.436272) (xy 55.767584 -51.444402) (xy 55.817014 -51.460463)
			(xy 55.863324 -51.484059) (xy 55.905372 -51.514609) (xy 55.942123 -51.55136) (xy 55.972673 -51.593408)
			(xy 55.996269 -51.639718) (xy 56.01233 -51.689148) (xy 56.02046 -51.740483) (xy 56.02097 -51.76647)
			(xy 56.02046 -51.792457) (xy 56.01233 -51.843792) (xy 55.996269 -51.893222) (xy 55.972673 -51.939532)
			(xy 55.942123 -51.98158) (xy 55.905372 -52.018331) (xy 55.863324 -52.048881) (xy 55.817014 -52.072477)
			(xy 55.767584 -52.088538) (xy 55.716249 -52.096668) (xy 55.664275 -52.096668) (xy 55.61294 -52.088538)
			(xy 55.56351 -52.072477) (xy 55.5172 -52.048881) (xy 55.475152 -52.018331) (xy 55.438401 -51.98158)
			(xy 55.407851 -51.939532) (xy 55.384255 -51.893222) (xy 55.368194 -51.843792) (xy 55.360064 -51.792457)
			(xy 54.429918 -51.792457) (xy 54.429918 -51.793046) (xy 54.42143 -51.845482) (xy 54.404671 -51.895888)
			(xy 54.380071 -51.942967) (xy 54.348263 -51.985509) (xy 54.310065 -52.02242) (xy 54.266458 -52.052752)
			(xy 54.242716 -52.064666) (xy 54.21376 -52.078636) (xy 54.21376 -52.254404) (xy 54.242716 -52.268374)
			(xy 54.266435 -52.280335) (xy 54.310045 -52.310663) (xy 54.348246 -52.347572) (xy 54.380057 -52.390111)
			(xy 54.404661 -52.437188) (xy 54.421424 -52.487592) (xy 54.429916 -52.540028) (xy 54.429918 -52.592557)
			(xy 55.360064 -52.592557) (xy 55.360064 -52.540583) (xy 55.368194 -52.489248) (xy 55.384255 -52.439818)
			(xy 55.407851 -52.393508) (xy 55.438401 -52.35146) (xy 55.475152 -52.314709) (xy 55.5172 -52.284159)
			(xy 55.56351 -52.260563) (xy 55.61294 -52.244502) (xy 55.664275 -52.236372) (xy 55.716249 -52.236372)
			(xy 55.767584 -52.244502) (xy 55.817014 -52.260563) (xy 55.863324 -52.284159) (xy 55.905372 -52.314709)
			(xy 55.942123 -52.35146) (xy 55.972673 -52.393508) (xy 55.996269 -52.439818) (xy 56.01233 -52.489248)
			(xy 56.02046 -52.540583) (xy 56.02097 -52.56657) (xy 56.02046 -52.592557) (xy 56.15991 -52.592557)
			(xy 56.15991 -52.540583) (xy 56.16804 -52.489248) (xy 56.184101 -52.439818) (xy 56.207697 -52.393508)
			(xy 56.238247 -52.35146) (xy 56.274998 -52.314709) (xy 56.317046 -52.284159) (xy 56.363356 -52.260563)
			(xy 56.412786 -52.244502) (xy 56.464121 -52.236372) (xy 56.516095 -52.236372) (xy 56.56743 -52.244502)
			(xy 56.61686 -52.260563) (xy 56.66317 -52.284159) (xy 56.705218 -52.314709) (xy 56.741969 -52.35146)
			(xy 56.772519 -52.393508) (xy 56.796115 -52.439818) (xy 56.812176 -52.489248) (xy 56.820306 -52.540583)
			(xy 56.820816 -52.56657) (xy 56.820306 -52.592557) (xy 56.812176 -52.643892) (xy 56.796115 -52.693322)
			(xy 56.772519 -52.739632) (xy 56.741969 -52.78168) (xy 56.705218 -52.818431) (xy 56.66317 -52.848981)
			(xy 56.61686 -52.872577) (xy 56.56743 -52.888638) (xy 56.516095 -52.896768) (xy 56.464121 -52.896768)
			(xy 56.412786 -52.888638) (xy 56.363356 -52.872577) (xy 56.317046 -52.848981) (xy 56.274998 -52.818431)
			(xy 56.238247 -52.78168) (xy 56.207697 -52.739632) (xy 56.184101 -52.693322) (xy 56.16804 -52.643892)
			(xy 56.15991 -52.592557) (xy 56.02046 -52.592557) (xy 56.01233 -52.643892) (xy 55.996269 -52.693322)
			(xy 55.972673 -52.739632) (xy 55.942123 -52.78168) (xy 55.905372 -52.818431) (xy 55.863324 -52.848981)
			(xy 55.817014 -52.872577) (xy 55.767584 -52.888638) (xy 55.716249 -52.896768) (xy 55.664275 -52.896768)
			(xy 55.61294 -52.888638) (xy 55.56351 -52.872577) (xy 55.5172 -52.848981) (xy 55.475152 -52.818431)
			(xy 55.438401 -52.78168) (xy 55.407851 -52.739632) (xy 55.384255 -52.693322) (xy 55.368194 -52.643892)
			(xy 55.360064 -52.592557) (xy 54.429918 -52.592557) (xy 54.429918 -52.593146) (xy 54.42143 -52.645582)
			(xy 54.404671 -52.695988) (xy 54.380071 -52.743067) (xy 54.348263 -52.785609) (xy 54.310065 -52.82252)
			(xy 54.266458 -52.852852) (xy 54.242716 -52.864766) (xy 54.21376 -52.878736) (xy 54.21376 -53.05425)
			(xy 54.242716 -53.06822) (xy 54.266432 -53.080181) (xy 54.310034 -53.110508) (xy 54.348228 -53.147414)
			(xy 54.380033 -53.18995) (xy 54.40463 -53.237023) (xy 54.421388 -53.287422) (xy 54.429876 -53.339851)
			(xy 54.429875 -53.392403) (xy 55.360064 -53.392403) (xy 55.360064 -53.340429) (xy 55.368194 -53.289094)
			(xy 55.384255 -53.239664) (xy 55.407851 -53.193354) (xy 55.438401 -53.151306) (xy 55.475152 -53.114555)
			(xy 55.5172 -53.084005) (xy 55.56351 -53.060409) (xy 55.61294 -53.044348) (xy 55.664275 -53.036218)
			(xy 55.716249 -53.036218) (xy 55.767584 -53.044348) (xy 55.817014 -53.060409) (xy 55.863324 -53.084005)
			(xy 55.905372 -53.114555) (xy 55.942123 -53.151306) (xy 55.972673 -53.193354) (xy 55.996269 -53.239664)
			(xy 56.01233 -53.289094) (xy 56.02046 -53.340429) (xy 56.02097 -53.366416) (xy 56.02046 -53.392403)
			(xy 56.01233 -53.443738) (xy 55.996269 -53.493168) (xy 55.972673 -53.539478) (xy 55.942123 -53.581526)
			(xy 55.905372 -53.618277) (xy 55.863324 -53.648827) (xy 55.817014 -53.672423) (xy 55.767584 -53.688484)
			(xy 55.716249 -53.696614) (xy 55.664275 -53.696614) (xy 55.61294 -53.688484) (xy 55.56351 -53.672423)
			(xy 55.5172 -53.648827) (xy 55.475152 -53.618277) (xy 55.438401 -53.581526) (xy 55.407851 -53.539478)
			(xy 55.384255 -53.493168) (xy 55.368194 -53.443738) (xy 55.360064 -53.392403) (xy 54.429875 -53.392403)
			(xy 54.429875 -53.392963) (xy 54.421385 -53.445392) (xy 54.404625 -53.49579) (xy 54.380025 -53.542861)
			(xy 54.348219 -53.585396) (xy 54.310023 -53.622301) (xy 54.26642 -53.652626) (xy 54.242716 -53.664612)
			(xy 54.21376 -53.678582) (xy 54.21376 -53.85435) (xy 54.242716 -53.86832) (xy 54.266432 -53.880281)
			(xy 54.310034 -53.910608) (xy 54.348228 -53.947514) (xy 54.380033 -53.99005) (xy 54.40463 -54.037123)
			(xy 54.421388 -54.087522) (xy 54.429876 -54.139951) (xy 54.429875 -54.192503) (xy 55.360064 -54.192503)
			(xy 55.360064 -54.140529) (xy 55.368194 -54.089194) (xy 55.384255 -54.039764) (xy 55.407851 -53.993454)
			(xy 55.438401 -53.951406) (xy 55.475152 -53.914655) (xy 55.5172 -53.884105) (xy 55.56351 -53.860509)
			(xy 55.61294 -53.844448) (xy 55.664275 -53.836318) (xy 55.716249 -53.836318) (xy 55.767584 -53.844448)
			(xy 55.817014 -53.860509) (xy 55.863324 -53.884105) (xy 55.905372 -53.914655) (xy 55.942123 -53.951406)
			(xy 55.972673 -53.993454) (xy 55.996269 -54.039764) (xy 56.01233 -54.089194) (xy 56.02046 -54.140529)
			(xy 56.02097 -54.166516) (xy 56.02046 -54.192503) (xy 56.15991 -54.192503) (xy 56.15991 -54.140529)
			(xy 56.16804 -54.089194) (xy 56.184101 -54.039764) (xy 56.207697 -53.993454) (xy 56.238247 -53.951406)
			(xy 56.274998 -53.914655) (xy 56.317046 -53.884105) (xy 56.363356 -53.860509) (xy 56.412786 -53.844448)
			(xy 56.464121 -53.836318) (xy 56.516095 -53.836318) (xy 56.56743 -53.844448) (xy 56.61686 -53.860509)
			(xy 56.66317 -53.884105) (xy 56.705218 -53.914655) (xy 56.741969 -53.951406) (xy 56.772519 -53.993454)
			(xy 56.796115 -54.039764) (xy 56.812176 -54.089194) (xy 56.820306 -54.140529) (xy 56.820816 -54.166516)
			(xy 56.820306 -54.192503) (xy 56.812176 -54.243838) (xy 56.796115 -54.293268) (xy 56.772519 -54.339578)
			(xy 56.741969 -54.381626) (xy 56.705218 -54.418377) (xy 56.66317 -54.448927) (xy 56.61686 -54.472523)
			(xy 56.56743 -54.488584) (xy 56.516095 -54.496714) (xy 56.464121 -54.496714) (xy 56.412786 -54.488584)
			(xy 56.363356 -54.472523) (xy 56.317046 -54.448927) (xy 56.274998 -54.418377) (xy 56.238247 -54.381626)
			(xy 56.207697 -54.339578) (xy 56.184101 -54.293268) (xy 56.16804 -54.243838) (xy 56.15991 -54.192503)
			(xy 56.02046 -54.192503) (xy 56.01233 -54.243838) (xy 55.996269 -54.293268) (xy 55.972673 -54.339578)
			(xy 55.942123 -54.381626) (xy 55.905372 -54.418377) (xy 55.863324 -54.448927) (xy 55.817014 -54.472523)
			(xy 55.767584 -54.488584) (xy 55.716249 -54.496714) (xy 55.664275 -54.496714) (xy 55.61294 -54.488584)
			(xy 55.56351 -54.472523) (xy 55.5172 -54.448927) (xy 55.475152 -54.418377) (xy 55.438401 -54.381626)
			(xy 55.407851 -54.339578) (xy 55.384255 -54.293268) (xy 55.368194 -54.243838) (xy 55.360064 -54.192503)
			(xy 54.429875 -54.192503) (xy 54.429875 -54.193063) (xy 54.421385 -54.245492) (xy 54.404625 -54.29589)
			(xy 54.380025 -54.342961) (xy 54.348219 -54.385496) (xy 54.310023 -54.422401) (xy 54.26642 -54.452726)
			(xy 54.242716 -54.464712) (xy 54.21376 -54.478682) (xy 54.21376 -55.454296) (xy 54.242716 -55.468266)
			(xy 54.266436 -55.480227) (xy 54.310047 -55.510555) (xy 54.348249 -55.547464) (xy 54.380062 -55.590005)
			(xy 54.404666 -55.637082) (xy 54.42143 -55.687487) (xy 54.429923 -55.739924) (xy 54.429925 -55.793043)
			(xy 54.428459 -55.802101) (xy 54.559964 -55.802101) (xy 54.559964 -55.750127) (xy 54.568094 -55.698792)
			(xy 54.584155 -55.649362) (xy 54.607751 -55.603052) (xy 54.638301 -55.561004) (xy 54.675052 -55.524253)
			(xy 54.7171 -55.493703) (xy 54.76341 -55.470107) (xy 54.81284 -55.454046) (xy 54.864175 -55.445916)
			(xy 54.916149 -55.445916) (xy 54.967484 -55.454046) (xy 55.016914 -55.470107) (xy 55.063224 -55.493703)
			(xy 55.105272 -55.524253) (xy 55.142023 -55.561004) (xy 55.172573 -55.603052) (xy 55.196169 -55.649362)
			(xy 55.21223 -55.698792) (xy 55.22036 -55.750127) (xy 55.22087 -55.776114) (xy 55.220549 -55.792449)
			(xy 55.360064 -55.792449) (xy 55.360064 -55.740475) (xy 55.368194 -55.68914) (xy 55.384255 -55.63971)
			(xy 55.407851 -55.5934) (xy 55.438401 -55.551352) (xy 55.475152 -55.514601) (xy 55.5172 -55.484051)
			(xy 55.56351 -55.460455) (xy 55.61294 -55.444394) (xy 55.664275 -55.436264) (xy 55.716249 -55.436264)
			(xy 55.767584 -55.444394) (xy 55.817014 -55.460455) (xy 55.863324 -55.484051) (xy 55.905372 -55.514601)
			(xy 55.942123 -55.551352) (xy 55.972673 -55.5934) (xy 55.996269 -55.63971) (xy 56.01233 -55.68914)
			(xy 56.02046 -55.740475) (xy 56.02097 -55.766462) (xy 56.02046 -55.792449) (xy 56.15991 -55.792449)
			(xy 56.15991 -55.740475) (xy 56.16804 -55.68914) (xy 56.184101 -55.63971) (xy 56.207697 -55.5934)
			(xy 56.238247 -55.551352) (xy 56.274998 -55.514601) (xy 56.317046 -55.484051) (xy 56.363356 -55.460455)
			(xy 56.412786 -55.444394) (xy 56.464121 -55.436264) (xy 56.516095 -55.436264) (xy 56.56743 -55.444394)
			(xy 56.61686 -55.460455) (xy 56.66317 -55.484051) (xy 56.705218 -55.514601) (xy 56.741969 -55.551352)
			(xy 56.772519 -55.5934) (xy 56.796115 -55.63971) (xy 56.812176 -55.68914) (xy 56.820306 -55.740475)
			(xy 56.820816 -55.766462) (xy 56.820306 -55.792449) (xy 56.812176 -55.843784) (xy 56.796115 -55.893214)
			(xy 56.772519 -55.939524) (xy 56.741969 -55.981572) (xy 56.705218 -56.018323) (xy 56.66317 -56.048873)
			(xy 56.61686 -56.072469) (xy 56.56743 -56.08853) (xy 56.516095 -56.09666) (xy 56.464121 -56.09666)
			(xy 56.412786 -56.08853) (xy 56.363356 -56.072469) (xy 56.317046 -56.048873) (xy 56.274998 -56.018323)
			(xy 56.238247 -55.981572) (xy 56.207697 -55.939524) (xy 56.184101 -55.893214) (xy 56.16804 -55.843784)
			(xy 56.15991 -55.792449) (xy 56.02046 -55.792449) (xy 56.01233 -55.843784) (xy 55.996269 -55.893214)
			(xy 55.972673 -55.939524) (xy 55.942123 -55.981572) (xy 55.905372 -56.018323) (xy 55.863324 -56.048873)
			(xy 55.817014 -56.072469) (xy 55.767584 -56.08853) (xy 55.716249 -56.09666) (xy 55.664275 -56.09666)
			(xy 55.61294 -56.08853) (xy 55.56351 -56.072469) (xy 55.5172 -56.048873) (xy 55.475152 -56.018323)
			(xy 55.438401 -55.981572) (xy 55.407851 -55.939524) (xy 55.384255 -55.893214) (xy 55.368194 -55.843784)
			(xy 55.360064 -55.792449) (xy 55.220549 -55.792449) (xy 55.22036 -55.802101) (xy 55.21223 -55.853436)
			(xy 55.196169 -55.902866) (xy 55.172573 -55.949176) (xy 55.142023 -55.991224) (xy 55.105272 -56.027975)
			(xy 55.063224 -56.058525) (xy 55.016914 -56.082121) (xy 54.967484 -56.098182) (xy 54.916149 -56.106312)
			(xy 54.864175 -56.106312) (xy 54.81284 -56.098182) (xy 54.76341 -56.082121) (xy 54.7171 -56.058525)
			(xy 54.675052 -56.027975) (xy 54.638301 -55.991224) (xy 54.607751 -55.949176) (xy 54.584155 -55.902866)
			(xy 54.568094 -55.853436) (xy 54.559964 -55.802101) (xy 54.428459 -55.802101) (xy 54.421438 -55.845481)
			(xy 54.404679 -55.895887) (xy 54.380079 -55.942968) (xy 54.348271 -55.985511) (xy 54.310072 -56.022424)
			(xy 54.266465 -56.052757) (xy 54.242716 -56.064658) (xy 54.21376 -56.078628) (xy 54.21376 -56.263794)
			(xy 54.242716 -56.277764) (xy 54.26643 -56.289726) (xy 54.310029 -56.320055) (xy 54.348219 -56.356964)
			(xy 54.380019 -56.399502) (xy 54.40461 -56.446576) (xy 54.421361 -56.496976) (xy 54.42984 -56.549405)
			(xy 54.430422 -56.57596) (xy 54.430009 -56.600854) (xy 54.422607 -56.650087) (xy 54.41569 -56.674004)
			(xy 54.412791 -56.685531) (xy 54.416669 -56.708953) (xy 54.430586 -56.728188) (xy 54.440836 -56.734202)
			(xy 54.461071 -56.745075) (xy 54.498197 -56.772123) (xy 54.51475 -56.78805) (xy 54.596792 -56.870092)
			(xy 54.664102 -56.802782) (xy 54.637178 -56.767476) (xy 54.621179 -56.745705) (xy 54.595742 -56.698044)
			(xy 54.5784 -56.646879) (xy 54.569615 -56.593574) (xy 54.569106 -56.566562) (xy 54.569618 -56.540577)
			(xy 54.577754 -56.489247) (xy 54.593819 -56.439822) (xy 54.617418 -56.393518) (xy 54.647969 -56.351476)
			(xy 54.684721 -56.314731) (xy 54.726768 -56.284187) (xy 54.773076 -56.260596) (xy 54.822504 -56.24454)
			(xy 54.873835 -56.236414) (xy 54.925806 -56.236417) (xy 54.977136 -56.24455) (xy 55.026562 -56.260612)
			(xy 55.072867 -56.284209) (xy 55.114911 -56.314758) (xy 55.151658 -56.351508) (xy 55.182204 -56.393554)
			(xy 55.205797 -56.43986) (xy 55.221856 -56.489287) (xy 55.229985 -56.540618) (xy 55.229984 -56.592549)
			(xy 55.369462 -56.592549) (xy 55.369462 -56.540575) (xy 55.377592 -56.48924) (xy 55.393653 -56.43981)
			(xy 55.417249 -56.3935) (xy 55.447799 -56.351452) (xy 55.48455 -56.314701) (xy 55.526598 -56.284151)
			(xy 55.572908 -56.260555) (xy 55.622338 -56.244494) (xy 55.673673 -56.236364) (xy 55.725647 -56.236364)
			(xy 55.776982 -56.244494) (xy 55.826412 -56.260555) (xy 55.872722 -56.284151) (xy 55.91477 -56.314701)
			(xy 55.951521 -56.351452) (xy 55.982071 -56.3935) (xy 56.005667 -56.43981) (xy 56.021728 -56.48924)
			(xy 56.029858 -56.540575) (xy 56.030368 -56.566562) (xy 56.029858 -56.592549) (xy 56.021728 -56.643884)
			(xy 56.005667 -56.693314) (xy 55.982071 -56.739624) (xy 55.951521 -56.781672) (xy 55.91477 -56.818423)
			(xy 55.872722 -56.848973) (xy 55.826412 -56.872569) (xy 55.776982 -56.88863) (xy 55.725647 -56.89676)
			(xy 55.673673 -56.89676) (xy 55.622338 -56.88863) (xy 55.572908 -56.872569) (xy 55.526598 -56.848973)
			(xy 55.48455 -56.818423) (xy 55.447799 -56.781672) (xy 55.417249 -56.739624) (xy 55.393653 -56.693314)
			(xy 55.377592 -56.643884) (xy 55.369462 -56.592549) (xy 55.229984 -56.592549) (xy 55.229984 -56.592589)
			(xy 55.221854 -56.643919) (xy 55.205794 -56.693346) (xy 55.182201 -56.739652) (xy 55.151654 -56.781697)
			(xy 55.114905 -56.818447) (xy 55.072861 -56.848995) (xy 55.026556 -56.87259) (xy 54.977129 -56.888652)
			(xy 54.925799 -56.896783) (xy 54.899814 -56.89727) (xy 54.87543 -56.896254) (xy 54.861704 -56.895712)
			(xy 54.834779 -56.901103) (xy 54.810264 -56.913475) (xy 54.789934 -56.931933) (xy 54.77526 -56.955142)
			(xy 54.767302 -56.981423) (xy 54.766636 -57.008874) (xy 54.773312 -57.03551) (xy 54.786845 -57.059403)
			(xy 54.796182 -57.069482) (xy 55.04815 -57.32145) (xy 55.064294 -57.33823) (xy 55.091633 -57.375921)
			(xy 55.10001 -57.392395) (xy 55.369462 -57.392395) (xy 55.369462 -57.340421) (xy 55.377592 -57.289086)
			(xy 55.393653 -57.239656) (xy 55.417249 -57.193346) (xy 55.447799 -57.151298) (xy 55.48455 -57.114547)
			(xy 55.526598 -57.083997) (xy 55.572908 -57.060401) (xy 55.622338 -57.04434) (xy 55.673673 -57.03621)
			(xy 55.725647 -57.03621) (xy 55.776982 -57.04434) (xy 55.826412 -57.060401) (xy 55.872722 -57.083997)
			(xy 55.91477 -57.114547) (xy 55.951521 -57.151298) (xy 55.982071 -57.193346) (xy 56.005667 -57.239656)
			(xy 56.021728 -57.289086) (xy 56.029858 -57.340421) (xy 56.030368 -57.366408) (xy 56.029858 -57.392395)
			(xy 56.021728 -57.44373) (xy 56.005667 -57.49316) (xy 55.982071 -57.53947) (xy 55.951521 -57.581518)
			(xy 55.91477 -57.618269) (xy 55.872722 -57.648819) (xy 55.826412 -57.672415) (xy 55.776982 -57.688476)
			(xy 55.725647 -57.696606) (xy 55.673673 -57.696606) (xy 55.622338 -57.688476) (xy 55.572908 -57.672415)
			(xy 55.526598 -57.648819) (xy 55.48455 -57.618269) (xy 55.447799 -57.581518) (xy 55.417249 -57.53947)
			(xy 55.393653 -57.49316) (xy 55.377592 -57.44373) (xy 55.369462 -57.392395) (xy 55.10001 -57.392395)
			(xy 55.112737 -57.417426) (xy 55.127086 -57.461722) (xy 55.134326 -57.507718) (xy 55.134764 -57.531)
			(xy 55.134764 -57.80913) (xy 55.286656 -57.961022) (xy 55.296936 -57.970666) (xy 55.32154 -57.984399)
			(xy 55.348958 -57.990896) (xy 55.377108 -57.989663) (xy 55.403853 -57.980793) (xy 55.427161 -57.96496)
			(xy 55.436516 -57.954418) (xy 55.452315 -57.936194) (xy 55.488289 -57.90407) (xy 55.528548 -57.877512)
			(xy 55.572237 -57.857083) (xy 55.61843 -57.843216) (xy 55.666147 -57.836205) (xy 55.690262 -57.8358)
			(xy 55.716253 -57.83628) (xy 55.767596 -57.844407) (xy 55.817035 -57.860466) (xy 55.863353 -57.884062)
			(xy 55.905409 -57.914613) (xy 55.942167 -57.951368) (xy 55.972723 -57.993422) (xy 55.996323 -58.039737)
			(xy 56.012386 -58.089175) (xy 56.020517 -58.140517) (xy 56.02097 -58.166508) (xy 56.020741 -58.185015)
			(xy 56.016669 -58.221805) (xy 56.012842 -58.239914) (xy 56.011211 -58.248708) (xy 56.013504 -58.266435)
			(xy 56.021745 -58.282296) (xy 56.034933 -58.294362) (xy 56.043068 -58.29808) (xy 56.057791 -58.304357)
			(xy 56.08592 -58.319629) (xy 56.099202 -58.32856) (xy 56.108216 -58.334095) (xy 56.12898 -58.338008)
			(xy 56.149561 -58.333224) (xy 56.16647 -58.320554) (xy 56.17684 -58.302145) (xy 56.178915 -58.281118)
			(xy 56.176164 -58.270902) (xy 56.168323 -58.245519) (xy 56.1599 -58.193069) (xy 56.1594 -58.166508)
			(xy 56.15991 -58.140521) (xy 56.16804 -58.089186) (xy 56.184101 -58.039756) (xy 56.207697 -57.993446)
			(xy 56.238247 -57.951398) (xy 56.274998 -57.914647) (xy 56.317046 -57.884097) (xy 56.363356 -57.860501)
			(xy 56.412786 -57.84444) (xy 56.464121 -57.83631) (xy 56.516095 -57.83631) (xy 56.56743 -57.84444)
			(xy 56.61686 -57.860501) (xy 56.66317 -57.884097) (xy 56.705218 -57.914647) (xy 56.741969 -57.951398)
			(xy 56.772519 -57.993446) (xy 56.796115 -58.039756) (xy 56.812176 -58.089186) (xy 56.820306 -58.140521)
			(xy 56.820816 -58.166508) (xy 56.820366 -58.191389) (xy 56.812909 -58.240589) (xy 56.798166 -58.288116)
			(xy 56.776468 -58.332898) (xy 56.748306 -58.373924) (xy 56.714315 -58.410268) (xy 56.675263 -58.441109)
			(xy 56.63203 -58.46575) (xy 56.585594 -58.483637) (xy 56.537003 -58.494365) (xy 56.512206 -58.496454)
			(xy 56.497703 -58.49791) (xy 56.47037 -58.508004) (xy 56.446993 -58.525398) (xy 56.429472 -58.548679)
			(xy 56.419228 -58.575956) (xy 56.417094 -58.605015) (xy 56.423242 -58.633497) (xy 56.437174 -58.659088)
			(xy 56.447182 -58.669682) (xy 57.15635 -59.37885) (xy 57.172494 -59.39563) (xy 57.199833 -59.433321)
			(xy 57.220937 -59.474826) (xy 57.235286 -59.519122) (xy 57.242526 -59.565118) (xy 57.242964 -59.5884)
			(xy 57.242964 -59.917584) (xy 57.38368 -60.0583) (xy 57.38368 -62.119256) (xy 58.173872 -62.119256)
			(xy 58.177943 -62.063634) (xy 58.190069 -62.009197) (xy 58.209992 -61.957106) (xy 58.237288 -61.908471)
			(xy 58.271374 -61.864328) (xy 58.311523 -61.825619) (xy 58.356881 -61.793168) (xy 58.406481 -61.767667)
			(xy 58.459265 -61.74966) (xy 58.514108 -61.73953) (xy 58.569842 -61.737493) (xy 58.625279 -61.743593)
			(xy 58.679236 -61.757699) (xy 58.730565 -61.779511) (xy 58.778171 -61.808565) (xy 58.821039 -61.84424)
			(xy 58.858256 -61.885777) (xy 58.889029 -61.93229) (xy 58.912701 -61.982787) (xy 58.928769 -62.036194)
			(xy 58.936889 -62.09137) (xy 58.937398 -62.119256) (xy 58.936889 -62.147142) (xy 58.928769 -62.202318)
			(xy 58.912701 -62.255725) (xy 58.889029 -62.306222) (xy 58.858256 -62.352735) (xy 58.821039 -62.394272)
			(xy 58.778171 -62.429947) (xy 58.730565 -62.459001) (xy 58.679236 -62.480813) (xy 58.625279 -62.494919)
			(xy 58.569842 -62.501019) (xy 58.514108 -62.498982) (xy 58.459265 -62.488852) (xy 58.406481 -62.470845)
			(xy 58.356881 -62.445344) (xy 58.311523 -62.412893) (xy 58.271374 -62.374184) (xy 58.237288 -62.330041)
			(xy 58.209992 -62.281406) (xy 58.190069 -62.229315) (xy 58.177943 -62.174878) (xy 58.173872 -62.119256)
			(xy 57.38368 -62.119256) (xy 57.38368 -62.139576) (xy 57.407762 -62.151523) (xy 57.452601 -62.181178)
			(xy 57.49283 -62.216837) (xy 57.527652 -62.257793) (xy 57.556376 -62.303234) (xy 57.578432 -62.352259)
			(xy 57.593384 -62.403896) (xy 57.600935 -62.457121) (xy 57.600935 -62.510879) (xy 57.593384 -62.564104)
			(xy 57.578432 -62.615741) (xy 57.556376 -62.664766) (xy 57.527652 -62.710207) (xy 57.49283 -62.751163)
			(xy 57.452601 -62.786822) (xy 57.407762 -62.816477) (xy 57.38368 -62.828424) (xy 57.38368 -63.03518)
			(xy 57.53735 -63.18885) (xy 57.553494 -63.20563) (xy 57.580833 -63.243321) (xy 57.601937 -63.284826)
			(xy 57.616286 -63.329122) (xy 57.623526 -63.375118) (xy 57.623964 -63.3984) (xy 57.623964 -64.718946)
			(xy 57.624396 -64.732499) (xy 57.63154 -64.758648) (xy 57.645312 -64.781996) (xy 57.664742 -64.800897)
			(xy 57.688461 -64.814021) (xy 57.714797 -64.820441) (xy 57.728358 -64.820546) (xy 57.738264 -64.820292)
			(xy 57.769828 -64.82094) (xy 57.832096 -64.831324) (xy 57.891806 -64.851814) (xy 57.919874 -64.866266)
			(xy 57.932824 -64.872675) (xy 57.961065 -64.878716) (xy 57.989869 -64.876612) (xy 58.016933 -64.866532)
			(xy 58.040094 -64.849279) (xy 58.057501 -64.826235) (xy 58.06313 -64.812926) (xy 58.073826 -64.786123)
			(xy 58.102124 -64.735831) (xy 58.137674 -64.690375) (xy 58.179664 -64.650791) (xy 58.227137 -64.617982)
			(xy 58.279009 -64.592698) (xy 58.334098 -64.575514) (xy 58.391147 -64.566823) (xy 58.42 -64.566292)
			(xy 58.447251 -64.566778) (xy 58.501199 -64.574534) (xy 58.553494 -64.589889) (xy 58.603071 -64.612531)
			(xy 58.648921 -64.641997) (xy 58.690112 -64.677688) (xy 58.725803 -64.718879) (xy 58.755269 -64.764729)
			(xy 58.777911 -64.814306) (xy 58.793266 -64.866601) (xy 58.801022 -64.920549) (xy 58.801022 -64.975051)
			(xy 58.793266 -65.028999) (xy 58.777911 -65.081294) (xy 58.755269 -65.130871) (xy 58.725803 -65.176721)
			(xy 58.690112 -65.217912) (xy 58.648921 -65.253603) (xy 58.603071 -65.283069) (xy 58.553494 -65.305711)
			(xy 58.501199 -65.321066) (xy 58.447251 -65.328822) (xy 58.42 -65.329308) (xy 58.388437 -65.328657)
			(xy 58.326171 -65.318268) (xy 58.266465 -65.297773) (xy 58.23839 -65.283334) (xy 58.225437 -65.276915)
			(xy 58.197185 -65.270857) (xy 58.168366 -65.272949) (xy 58.141285 -65.283024) (xy 58.118107 -65.300277)
			(xy 58.100684 -65.323328) (xy 58.095134 -65.336674) (xy 58.084438 -65.363476) (xy 58.056138 -65.413764)
			(xy 58.020588 -65.459217) (xy 57.978597 -65.498797) (xy 57.931124 -65.531602) (xy 57.879252 -65.556881)
			(xy 57.824163 -65.57406) (xy 57.767116 -65.582746) (xy 57.738264 -65.583308) (xy 57.705001 -65.582608)
			(xy 57.639478 -65.57111) (xy 57.607962 -65.560448) (xy 57.594692 -65.55608) (xy 57.566843 -65.553991)
			(xy 57.53947 -65.559525) (xy 57.51462 -65.572268) (xy 57.494152 -65.591268) (xy 57.479597 -65.615102)
			(xy 57.472045 -65.641988) (xy 57.471564 -65.655952) (xy 57.471564 -66.3448) (xy 58.622182 -66.3448)
			(xy 58.626253 -66.289178) (xy 58.638379 -66.234741) (xy 58.658302 -66.18265) (xy 58.685598 -66.134015)
			(xy 58.719684 -66.089872) (xy 58.759833 -66.051163) (xy 58.805191 -66.018712) (xy 58.854791 -65.993211)
			(xy 58.907575 -65.975204) (xy 58.962418 -65.965074) (xy 59.018152 -65.963037) (xy 59.073589 -65.969137)
			(xy 59.127546 -65.983243) (xy 59.178875 -66.005055) (xy 59.226481 -66.034109) (xy 59.269349 -66.069784)
			(xy 59.306566 -66.111321) (xy 59.337339 -66.157834) (xy 59.361011 -66.208331) (xy 59.377079 -66.261738)
			(xy 59.385199 -66.316914) (xy 59.385708 -66.3448) (xy 59.385199 -66.372686) (xy 59.377079 -66.427862)
			(xy 59.361011 -66.481269) (xy 59.337339 -66.531766) (xy 59.306566 -66.578279) (xy 59.269349 -66.619816)
			(xy 59.226481 -66.655491) (xy 59.178875 -66.684545) (xy 59.127546 -66.706357) (xy 59.073589 -66.720463)
			(xy 59.018152 -66.726563) (xy 58.962418 -66.724526) (xy 58.907575 -66.714396) (xy 58.854791 -66.696389)
			(xy 58.805191 -66.670888) (xy 58.759833 -66.638437) (xy 58.719684 -66.599728) (xy 58.685598 -66.555585)
			(xy 58.658302 -66.50695) (xy 58.638379 -66.454859) (xy 58.626253 -66.400422) (xy 58.622182 -66.3448)
			(xy 57.471564 -66.3448) (xy 57.471564 -67.1068) (xy 57.4715 -67.118596) (xy 57.469719 -67.142119)
			(xy 57.468008 -67.15379) (xy 57.467394 -67.158616) (xy 57.944002 -67.158616) (xy 57.948073 -67.102994)
			(xy 57.960199 -67.048557) (xy 57.980122 -66.996466) (xy 58.007418 -66.947831) (xy 58.041504 -66.903688)
			(xy 58.081653 -66.864979) (xy 58.127011 -66.832528) (xy 58.176611 -66.807027) (xy 58.229395 -66.78902)
			(xy 58.284238 -66.77889) (xy 58.339972 -66.776853) (xy 58.395409 -66.782953) (xy 58.449366 -66.797059)
			(xy 58.500695 -66.818871) (xy 58.548301 -66.847925) (xy 58.591169 -66.8836) (xy 58.628386 -66.925137)
			(xy 58.659159 -66.97165) (xy 58.682831 -67.022147) (xy 58.698899 -67.075554) (xy 58.707019 -67.13073)
			(xy 58.707528 -67.158616) (xy 58.707019 -67.186502) (xy 58.698899 -67.241678) (xy 58.682831 -67.295085)
			(xy 58.659159 -67.345582) (xy 58.628386 -67.392095) (xy 58.591169 -67.433632) (xy 58.548301 -67.469307)
			(xy 58.500695 -67.498361) (xy 58.449366 -67.520173) (xy 58.395409 -67.534279) (xy 58.339972 -67.540379)
			(xy 58.284238 -67.538342) (xy 58.229395 -67.528212) (xy 58.176611 -67.510205) (xy 58.127011 -67.484704)
			(xy 58.081653 -67.452253) (xy 58.041504 -67.413544) (xy 58.007418 -67.369401) (xy 57.980122 -67.320766)
			(xy 57.960199 -67.268675) (xy 57.948073 -67.214238) (xy 57.944002 -67.158616) (xy 57.467394 -67.158616)
			(xy 57.466293 -67.167275) (xy 57.469238 -67.194288) (xy 57.479195 -67.219571) (xy 57.49546 -67.241338)
			(xy 57.516885 -67.258052) (xy 57.541956 -67.268532) (xy 57.555384 -67.27063) (xy 57.582646 -67.274612)
			(xy 57.635717 -67.289403) (xy 57.686108 -67.311674) (xy 57.73277 -67.340964) (xy 57.774734 -67.376661)
			(xy 57.811127 -67.418024) (xy 57.84119 -67.464192) (xy 57.864299 -67.514204) (xy 57.879973 -67.567021)
			(xy 57.887886 -67.621543) (xy 57.888378 -67.64909) (xy 57.887873 -67.676843) (xy 57.87982 -67.731763)
			(xy 57.863896 -67.784937) (xy 57.840439 -67.835243) (xy 57.809941 -67.881621) (xy 57.773048 -67.923093)
			(xy 57.730536 -67.958783) (xy 57.683303 -67.987939) (xy 57.632345 -68.009945) (xy 57.605676 -68.017644)
			(xy 57.591137 -68.022157) (xy 57.5654 -68.038386) (xy 57.545578 -68.06147) (xy 57.533426 -68.089365)
			(xy 57.53002 -68.1196) (xy 57.535662 -68.149499) (xy 57.549852 -68.176414) (xy 57.56021 -68.18757)
			(xy 57.70753 -68.33489) (xy 57.72785 -68.335652) (xy 57.750488 -68.336607) (xy 57.795313 -68.343223)
			(xy 57.817258 -68.34886) (xy 57.823862 -68.350638) (xy 58.757566 -68.350638)
		)
		(stroke
			(width 0)
			(type solid)
		)
		(fill yes)
		(layer "In2.Cu")
		(net "P3V3_RGM")
	)
	(gr_poly
		(pts
			(xy -3.999992 -119.892064) (xy -3.944185 -119.891542) (xy -3.832883 -119.883201) (xy -3.722516 -119.866566)
			(xy -3.6137 -119.841729) (xy -3.507045 -119.80883) (xy -3.403146 -119.768053) (xy -3.302586 -119.719626)
			(xy -3.205925 -119.663818) (xy -3.113705 -119.600944) (xy -3.026442 -119.531354) (xy -2.944623 -119.455437)
			(xy -2.868706 -119.373618) (xy -2.799116 -119.286355) (xy -2.736242 -119.194135) (xy -2.680434 -119.097474)
			(xy -2.632007 -118.996914) (xy -2.59123 -118.893015) (xy -2.558331 -118.78636) (xy -2.533494 -118.677544)
			(xy -2.516859 -118.567177) (xy -2.508518 -118.455875) (xy -2.507996 -118.400068) (xy -2.507996 -6.59003)
			(xy -2.508518 -6.534223) (xy -2.516859 -6.422921) (xy -2.533494 -6.312554) (xy -2.558331 -6.203738)
			(xy -2.59123 -6.097083) (xy -2.632007 -5.993184) (xy -2.680434 -5.892624) (xy -2.736242 -5.795963)
			(xy -2.799116 -5.703743) (xy -2.868706 -5.61648) (xy -2.944623 -5.534661) (xy -3.026442 -5.458744)
			(xy -3.113705 -5.389154) (xy -3.205925 -5.32628) (xy -3.302586 -5.270472) (xy -3.403146 -5.222045)
			(xy -3.507045 -5.181268) (xy -3.6137 -5.148369) (xy -3.722516 -5.123532) (xy -3.832883 -5.106897)
			(xy -3.944185 -5.098556) (xy -3.999992 -5.098034) (xy -17.78 -5.098034) (xy -17.835807 -5.098556)
			(xy -17.947109 -5.106897) (xy -18.057476 -5.123532) (xy -18.166292 -5.148369) (xy -18.272947 -5.181268)
			(xy -18.376846 -5.222045) (xy -18.477406 -5.270472) (xy -18.574067 -5.32628) (xy -18.666287 -5.389154)
			(xy -18.75355 -5.458744) (xy -18.835369 -5.534661) (xy -18.911286 -5.61648) (xy -18.980876 -5.703743)
			(xy -19.04375 -5.795963) (xy -19.099558 -5.892624) (xy -19.147985 -5.993184) (xy -19.188762 -6.097083)
			(xy -19.221661 -6.203738) (xy -19.246498 -6.312554) (xy -19.263133 -6.422921) (xy -19.271474 -6.534223)
			(xy -19.271996 -6.59003) (xy -19.271996 -115.464644) (xy -16.875771 -115.464644) (xy -16.875771 -115.335504)
			(xy -16.867821 -115.206609) (xy -16.851951 -115.078449) (xy -16.828222 -114.951508) (xy -16.796723 -114.826269)
			(xy -16.757574 -114.703206) (xy -16.710923 -114.582787) (xy -16.656948 -114.465468) (xy -16.595853 -114.351694)
			(xy -16.52787 -114.241897) (xy -16.453256 -114.136494) (xy -16.372295 -114.035884) (xy -16.285295 -113.940449)
			(xy -16.192584 -113.85055) (xy -16.094514 -113.766529) (xy -15.991459 -113.688705) (xy -15.883808 -113.617373)
			(xy -15.771969 -113.552803) (xy -15.656368 -113.495241) (xy -15.537443 -113.444904) (xy -15.415644 -113.401984)
			(xy -15.291434 -113.366643) (xy -15.165285 -113.339016) (xy -15.037673 -113.319207) (xy -14.909084 -113.307291)
			(xy -14.780006 -113.303315) (xy -14.650928 -113.307291) (xy -14.522339 -113.319207) (xy -14.394727 -113.339016)
			(xy -14.268578 -113.366643) (xy -14.144368 -113.401984) (xy -14.022569 -113.444904) (xy -13.903644 -113.495241)
			(xy -13.788043 -113.552803) (xy -13.676204 -113.617373) (xy -13.568553 -113.688705) (xy -13.465498 -113.766529)
			(xy -13.367428 -113.85055) (xy -13.274717 -113.940449) (xy -13.187717 -114.035884) (xy -13.106756 -114.136494)
			(xy -13.032142 -114.241897) (xy -12.964159 -114.351694) (xy -12.903064 -114.465468) (xy -12.849089 -114.582787)
			(xy -12.802438 -114.703206) (xy -12.763289 -114.826269) (xy -12.73179 -114.951508) (xy -12.708061 -115.078449)
			(xy -12.692191 -115.206609) (xy -12.684241 -115.335504) (xy -12.683744 -115.400074) (xy -12.684241 -115.464644)
			(xy -12.692191 -115.593539) (xy -12.708061 -115.721699) (xy -12.73179 -115.84864) (xy -12.763289 -115.973879)
			(xy -12.802438 -116.096942) (xy -12.849089 -116.217361) (xy -12.903064 -116.33468) (xy -12.964159 -116.448454)
			(xy -13.032142 -116.558251) (xy -13.106756 -116.663654) (xy -13.187717 -116.764264) (xy -13.274717 -116.859699)
			(xy -13.367428 -116.949598) (xy -13.465498 -117.033619) (xy -13.568553 -117.111443) (xy -13.676204 -117.182775)
			(xy -13.788043 -117.247345) (xy -13.903644 -117.304907) (xy -14.022569 -117.355244) (xy -14.144368 -117.398164)
			(xy -14.268578 -117.433505) (xy -14.394727 -117.461132) (xy -14.522339 -117.480941) (xy -14.650928 -117.492857)
			(xy -14.780006 -117.496834) (xy -14.909084 -117.492857) (xy -15.037673 -117.480941) (xy -15.165285 -117.461132)
			(xy -15.291434 -117.433505) (xy -15.415644 -117.398164) (xy -15.537443 -117.355244) (xy -15.656368 -117.304907)
			(xy -15.771969 -117.247345) (xy -15.883808 -117.182775) (xy -15.991459 -117.111443) (xy -16.094514 -117.033619)
			(xy -16.192584 -116.949598) (xy -16.285295 -116.859699) (xy -16.372295 -116.764264) (xy -16.453256 -116.663654)
			(xy -16.52787 -116.558251) (xy -16.595853 -116.448454) (xy -16.656948 -116.33468) (xy -16.710923 -116.217361)
			(xy -16.757574 -116.096942) (xy -16.796723 -115.973879) (xy -16.828222 -115.84864) (xy -16.851951 -115.721699)
			(xy -16.867821 -115.593539) (xy -16.875771 -115.464644) (xy -19.271996 -115.464644) (xy -19.271996 -118.400068)
			(xy -19.271474 -118.455875) (xy -19.263133 -118.567177) (xy -19.246498 -118.677544) (xy -19.221661 -118.78636)
			(xy -19.188762 -118.893015) (xy -19.147985 -118.996914) (xy -19.099558 -119.097474) (xy -19.04375 -119.194135)
			(xy -18.980876 -119.286355) (xy -18.911286 -119.373618) (xy -18.835369 -119.455437) (xy -18.75355 -119.531354)
			(xy -18.666287 -119.600944) (xy -18.574067 -119.663818) (xy -18.477406 -119.719626) (xy -18.376846 -119.768053)
			(xy -18.272947 -119.80883) (xy -18.166292 -119.841729) (xy -18.057476 -119.866566) (xy -17.947109 -119.883201)
			(xy -17.835807 -119.891542) (xy -17.78 -119.892064)
		)
		(stroke
			(width 0)
			(type solid)
		)
		(fill yes)
		(layer "In3.Cu")
		(net "T_GND")
	)
	(gr_poly
		(pts
			(xy 10.256012 -118.78437) (xy 10.256012 -114.799872) (xy 10.256503 -114.755847) (xy 10.264197 -114.668134)
			(xy 10.279504 -114.581425) (xy 10.302308 -114.49638) (xy 10.332434 -114.413645) (xy 10.369655 -114.333849)
			(xy 10.413686 -114.257599) (xy 10.464194 -114.185476) (xy 10.520793 -114.118028) (xy 10.583054 -114.055768)
			(xy 10.650503 -113.999169) (xy 10.722626 -113.948662) (xy 10.798876 -113.904631) (xy 10.878672 -113.867411)
			(xy 10.961408 -113.837285) (xy 11.046453 -113.814482) (xy 11.133162 -113.799176) (xy 11.220875 -113.791483)
			(xy 11.2649 -113.790984) (xy 12.765024 -113.790984) (xy 12.809049 -113.791474) (xy 12.896764 -113.799165)
			(xy 12.983474 -113.81447) (xy 13.068521 -113.837272) (xy 13.078373 -113.840859) (xy 20.444184 -113.840859)
			(xy 20.444184 -113.786321) (xy 20.451946 -113.732337) (xy 20.467311 -113.680007) (xy 20.489968 -113.630397)
			(xy 20.519454 -113.584516) (xy 20.555169 -113.543299) (xy 20.596386 -113.507584) (xy 20.642267 -113.478098)
			(xy 20.691877 -113.455441) (xy 20.744207 -113.440076) (xy 20.798191 -113.432314) (xy 20.82546 -113.431828)
			(xy 21.71446 -113.431828) (xy 21.741732 -113.432309) (xy 21.795722 -113.440066) (xy 21.848058 -113.455428)
			(xy 21.897675 -113.478083) (xy 21.943562 -113.507569) (xy 21.984786 -113.543285) (xy 22.020507 -113.584506)
			(xy 22.049998 -113.63039) (xy 22.072658 -113.680004) (xy 22.088025 -113.732339) (xy 22.095788 -113.786328)
			(xy 22.095788 -113.840872) (xy 22.088025 -113.894861) (xy 22.072658 -113.947196) (xy 22.049998 -113.99681)
			(xy 22.020507 -114.042694) (xy 21.984786 -114.083915) (xy 21.943562 -114.119631) (xy 21.897675 -114.149117)
			(xy 21.848058 -114.171772) (xy 21.795722 -114.187134) (xy 21.741732 -114.194891) (xy 21.71446 -114.195352)
			(xy 20.82546 -114.195352) (xy 20.798191 -114.194866) (xy 20.744207 -114.187104) (xy 20.691877 -114.171739)
			(xy 20.642267 -114.149082) (xy 20.596386 -114.119596) (xy 20.555169 -114.083881) (xy 20.519454 -114.042664)
			(xy 20.489968 -113.996783) (xy 20.467311 -113.947173) (xy 20.451946 -113.894843) (xy 20.444184 -113.840859)
			(xy 13.078373 -113.840859) (xy 13.151258 -113.867397) (xy 13.231056 -113.904617) (xy 13.307307 -113.948648)
			(xy 13.379432 -113.999155) (xy 13.446881 -114.055754) (xy 13.509143 -114.118016) (xy 13.565743 -114.185465)
			(xy 13.61625 -114.25759) (xy 13.660282 -114.33384) (xy 13.697502 -114.413638) (xy 13.727627 -114.496375)
			(xy 13.750429 -114.581422) (xy 13.765734 -114.668132) (xy 13.773426 -114.755847) (xy 13.773912 -114.799872)
			(xy 13.773912 -116.038376) (xy 13.96492 -116.038376) (xy 13.96492 -115.149376) (xy 13.965406 -115.122125)
			(xy 13.973162 -115.068177) (xy 13.988517 -115.015882) (xy 14.011159 -114.966305) (xy 14.040625 -114.920455)
			(xy 14.076316 -114.879264) (xy 14.117507 -114.843573) (xy 14.163357 -114.814107) (xy 14.212934 -114.791465)
			(xy 14.265229 -114.77611) (xy 14.319177 -114.768354) (xy 14.373679 -114.768354) (xy 14.427627 -114.77611)
			(xy 14.479922 -114.791465) (xy 14.529499 -114.814107) (xy 14.575349 -114.843573) (xy 14.61654 -114.879264)
			(xy 14.652231 -114.920455) (xy 14.681697 -114.966305) (xy 14.704339 -115.015882) (xy 14.719694 -115.068177)
			(xy 14.72745 -115.122125) (xy 14.727936 -115.149376) (xy 14.727936 -116.038376) (xy 15.764764 -116.038376)
			(xy 15.764764 -115.149376) (xy 15.76525 -115.122107) (xy 15.773012 -115.068123) (xy 15.788377 -115.015793)
			(xy 15.811034 -114.966183) (xy 15.84052 -114.920302) (xy 15.876235 -114.879085) (xy 15.917452 -114.84337)
			(xy 15.963333 -114.813884) (xy 16.012943 -114.791227) (xy 16.065273 -114.775862) (xy 16.119257 -114.7681)
			(xy 16.173795 -114.7681) (xy 16.227779 -114.775862) (xy 16.280109 -114.791227) (xy 16.329719 -114.813884)
			(xy 16.3756 -114.84337) (xy 16.416817 -114.879085) (xy 16.452532 -114.920302) (xy 16.482018 -114.966183)
			(xy 16.504675 -115.015793) (xy 16.510811 -115.036691) (xy 23.190153 -115.036691) (xy 23.190153 -114.982149)
			(xy 23.197916 -114.928162) (xy 23.213282 -114.875829) (xy 23.23594 -114.826216) (xy 23.265428 -114.780333)
			(xy 23.301145 -114.739113) (xy 23.342366 -114.703395) (xy 23.38825 -114.673908) (xy 23.437863 -114.651251)
			(xy 23.490196 -114.635885) (xy 23.544183 -114.628123) (xy 23.571454 -114.62766) (xy 24.460454 -114.62766)
			(xy 24.487723 -114.628143) (xy 24.541707 -114.635905) (xy 24.594036 -114.651271) (xy 24.643646 -114.673927)
			(xy 24.689527 -114.703413) (xy 24.730744 -114.739129) (xy 24.766459 -114.780347) (xy 24.795945 -114.826227)
			(xy 24.818601 -114.875838) (xy 24.833966 -114.928167) (xy 24.841728 -114.982151) (xy 24.841728 -115.036689)
			(xy 24.833966 -115.090673) (xy 24.818601 -115.143002) (xy 24.795945 -115.192613) (xy 24.766459 -115.238493)
			(xy 24.730744 -115.279711) (xy 24.689527 -115.315427) (xy 24.643646 -115.344913) (xy 24.594036 -115.367569)
			(xy 24.541707 -115.382935) (xy 24.487723 -115.390697) (xy 24.460454 -115.391184) (xy 23.571454 -115.391184)
			(xy 23.544183 -115.390717) (xy 23.490196 -115.382955) (xy 23.437863 -115.367589) (xy 23.38825 -115.344932)
			(xy 23.342366 -115.315445) (xy 23.301145 -115.279727) (xy 23.265428 -115.238507) (xy 23.23594 -115.192624)
			(xy 23.213282 -115.143011) (xy 23.197916 -115.090678) (xy 23.190153 -115.036691) (xy 16.510811 -115.036691)
			(xy 16.52004 -115.068123) (xy 16.527802 -115.122107) (xy 16.528288 -115.149376) (xy 16.528288 -116.038376)
			(xy 16.527802 -116.065645) (xy 16.52004 -116.119629) (xy 16.504675 -116.171959) (xy 16.482018 -116.221569)
			(xy 16.452532 -116.26745) (xy 16.416817 -116.308667) (xy 16.3756 -116.344382) (xy 16.329719 -116.373868)
			(xy 16.280109 -116.396525) (xy 16.227779 -116.41189) (xy 16.173795 -116.419652) (xy 16.119257 -116.419652)
			(xy 16.065273 -116.41189) (xy 16.012943 -116.396525) (xy 15.963333 -116.373868) (xy 15.917452 -116.344382)
			(xy 15.876235 -116.308667) (xy 15.84052 -116.26745) (xy 15.811034 -116.221569) (xy 15.788377 -116.171959)
			(xy 15.773012 -116.119629) (xy 15.76525 -116.065645) (xy 15.764764 -116.038376) (xy 14.727936 -116.038376)
			(xy 14.72745 -116.065627) (xy 14.719694 -116.119575) (xy 14.704339 -116.17187) (xy 14.681697 -116.221447)
			(xy 14.652231 -116.267297) (xy 14.61654 -116.308488) (xy 14.575349 -116.344179) (xy 14.529499 -116.373645)
			(xy 14.479922 -116.396287) (xy 14.427627 -116.411642) (xy 14.373679 -116.419398) (xy 14.319177 -116.419398)
			(xy 14.265229 -116.411642) (xy 14.212934 -116.396287) (xy 14.163357 -116.373645) (xy 14.117507 -116.344179)
			(xy 14.076316 -116.308488) (xy 14.040625 -116.267297) (xy 14.011159 -116.221447) (xy 13.988517 -116.17187)
			(xy 13.973162 -116.119575) (xy 13.965406 -116.065627) (xy 13.96492 -116.038376) (xy 13.773912 -116.038376)
			(xy 13.773912 -117.3734) (xy 31.116016 -117.3734) (xy 31.116016 -114.77498) (xy 31.116505 -114.713316)
			(xy 31.124564 -114.590252) (xy 31.140653 -114.467979) (xy 31.164706 -114.34702) (xy 31.196619 -114.227893)
			(xy 31.236255 -114.111108) (xy 31.283445 -113.997166) (xy 31.337986 -113.886554) (xy 31.399645 -113.779747)
			(xy 31.468158 -113.677201) (xy 31.543231 -113.579356) (xy 31.624543 -113.48663) (xy 31.711746 -113.399422)
			(xy 31.804466 -113.318103) (xy 31.902306 -113.243024) (xy 32.004847 -113.174504) (xy 32.11165 -113.112838)
			(xy 32.222258 -113.058289) (xy 32.336197 -113.011092) (xy 32.452979 -112.971448) (xy 32.572104 -112.939527)
			(xy 32.693062 -112.915466) (xy 32.815334 -112.899368) (xy 32.938397 -112.891302) (xy 33.061725 -112.891302)
			(xy 33.184788 -112.899368) (xy 33.30706 -112.915466) (xy 33.428018 -112.939527) (xy 33.547143 -112.971448)
			(xy 33.663925 -113.011092) (xy 33.777864 -113.058289) (xy 33.888472 -113.112838) (xy 33.995275 -113.174504)
			(xy 34.097816 -113.243024) (xy 34.195656 -113.318103) (xy 34.288376 -113.399422) (xy 34.375579 -113.48663)
			(xy 34.456891 -113.579356) (xy 34.531964 -113.677201) (xy 34.600477 -113.779747) (xy 34.662136 -113.886554)
			(xy 34.716677 -113.997166) (xy 34.763867 -114.111108) (xy 34.803503 -114.227893) (xy 34.835416 -114.34702)
			(xy 34.859469 -114.467979) (xy 34.875558 -114.590252) (xy 34.883617 -114.713316) (xy 34.884106 -114.77498)
			(xy 34.884106 -117.3734) (xy 43.825922 -117.3734) (xy 43.825922 -114.324892) (xy 43.826423 -114.271251)
			(xy 43.83444 -114.164269) (xy 43.85043 -114.058186) (xy 43.874302 -113.953594) (xy 43.905924 -113.851078)
			(xy 43.945119 -113.751213) (xy 43.991666 -113.654555) (xy 44.045307 -113.561646) (xy 44.105741 -113.473006)
			(xy 44.17263 -113.38913) (xy 44.245601 -113.310487) (xy 44.324244 -113.237516) (xy 44.40812 -113.170627)
			(xy 44.49676 -113.110193) (xy 44.589669 -113.056552) (xy 44.686327 -113.010005) (xy 44.786192 -112.97081)
			(xy 44.888708 -112.939188) (xy 44.9933 -112.915316) (xy 45.099383 -112.899326) (xy 45.206365 -112.891309)
			(xy 45.313647 -112.891309) (xy 45.420629 -112.899326) (xy 45.526712 -112.915316) (xy 45.631304 -112.939188)
			(xy 45.73382 -112.97081) (xy 45.833685 -113.010005) (xy 45.930343 -113.056552) (xy 46.023252 -113.110193)
			(xy 46.111892 -113.170627) (xy 46.195768 -113.237516) (xy 46.274411 -113.310487) (xy 46.347382 -113.38913)
			(xy 46.414271 -113.473006) (xy 46.474705 -113.561646) (xy 46.528346 -113.654555) (xy 46.574893 -113.751213)
			(xy 46.614088 -113.851078) (xy 46.64571 -113.953594) (xy 46.669582 -114.058186) (xy 46.685572 -114.164269)
			(xy 46.693589 -114.271251) (xy 46.69409 -114.324892) (xy 46.69409 -117.3734) (xy 64.026034 -117.3734)
			(xy 64.026034 -114.525044) (xy 64.026532 -114.468001) (xy 64.03449 -114.354194) (xy 64.050367 -114.24122)
			(xy 64.074087 -114.129628) (xy 64.105533 -114.019962) (xy 64.144553 -113.912757) (xy 64.190955 -113.808535)
			(xy 64.244515 -113.707804) (xy 64.304971 -113.611054) (xy 64.372028 -113.518758) (xy 64.445361 -113.431363)
			(xy 64.524611 -113.349297) (xy 64.609393 -113.27296) (xy 64.699293 -113.202722) (xy 64.793874 -113.138926)
			(xy 64.892674 -113.081884) (xy 64.995213 -113.031872) (xy 65.100991 -112.989135) (xy 65.209492 -112.953881)
			(xy 65.320188 -112.926281) (xy 65.43254 -112.906471) (xy 65.546 -112.894546) (xy 65.660016 -112.890564)
			(xy 65.774032 -112.894546) (xy 65.887492 -112.906471) (xy 65.999844 -112.926281) (xy 66.11054 -112.953881)
			(xy 66.219041 -112.989135) (xy 66.324819 -113.031872) (xy 66.427358 -113.081884) (xy 66.526158 -113.138926)
			(xy 66.620739 -113.202722) (xy 66.710639 -113.27296) (xy 66.795421 -113.349297) (xy 66.874671 -113.431363)
			(xy 66.948004 -113.518758) (xy 67.015061 -113.611054) (xy 67.075517 -113.707804) (xy 67.129077 -113.808535)
			(xy 67.175479 -113.912757) (xy 67.214499 -114.019962) (xy 67.245945 -114.129628) (xy 67.269665 -114.24122)
			(xy 67.285542 -114.354194) (xy 67.2935 -114.468001) (xy 67.293998 -114.525044) (xy 67.293998 -117.3734)
			(xy 76.230988 -117.3734) (xy 76.230988 -114.799872) (xy 76.231478 -114.755847) (xy 76.23917 -114.668133)
			(xy 76.254475 -114.581423) (xy 76.277277 -114.496376) (xy 76.307402 -114.413639) (xy 76.344622 -114.333842)
			(xy 76.388653 -114.257592) (xy 76.439161 -114.185468) (xy 76.49576 -114.118018) (xy 76.558021 -114.055757)
			(xy 76.625471 -113.999158) (xy 76.697595 -113.948651) (xy 76.773846 -113.90462) (xy 76.853643 -113.867401)
			(xy 76.93638 -113.837275) (xy 77.021427 -113.814474) (xy 77.108137 -113.799169) (xy 77.195851 -113.791478)
			(xy 77.239876 -113.790984) (xy 78.74 -113.790984) (xy 78.784039 -113.79145) (xy 78.871783 -113.799127)
			(xy 78.958523 -113.814422) (xy 79.043601 -113.837219) (xy 79.126367 -113.867344) (xy 79.206193 -113.904568)
			(xy 79.282471 -113.948608) (xy 79.354621 -113.999129) (xy 79.422092 -114.055745) (xy 79.484372 -114.118027)
			(xy 79.540987 -114.1855) (xy 79.591506 -114.257651) (xy 79.635544 -114.33393) (xy 79.672766 -114.413757)
			(xy 79.702889 -114.496524) (xy 79.725684 -114.581602) (xy 79.740976 -114.668343) (xy 79.748651 -114.756087)
			(xy 79.749142 -114.800126) (xy 79.749142 -118.7196) (xy 79.85379 -118.824248) (xy 80.16875 -118.824248)
			(xy 80.272636 -118.720616) (xy 83.93684 -118.720616) (xy 84.094574 -118.878096) (xy 84.394548 -118.878096)
			(xy 84.491068 -118.781576) (xy 84.491068 -114.799872) (xy 84.491558 -114.755847) (xy 84.49925 -114.668132)
			(xy 84.514555 -114.581421) (xy 84.537356 -114.496374) (xy 84.567482 -114.413636) (xy 84.604701 -114.333838)
			(xy 84.648732 -114.257587) (xy 84.69924 -114.185462) (xy 84.755839 -114.118012) (xy 84.8181 -114.05575)
			(xy 84.885549 -113.999149) (xy 84.957674 -113.948641) (xy 85.033924 -113.904609) (xy 85.113722 -113.867388)
			(xy 85.196458 -113.837261) (xy 85.281506 -113.814458) (xy 85.368216 -113.799152) (xy 85.455931 -113.791459)
			(xy 85.499956 -113.790984) (xy 88.000078 -113.790984) (xy 88.055848 -113.790476) (xy 88.167076 -113.782142)
			(xy 88.277371 -113.76552) (xy 88.386115 -113.740701) (xy 88.4927 -113.707825) (xy 88.596531 -113.667076)
			(xy 88.697025 -113.618682) (xy 88.793622 -113.562913) (xy 88.885782 -113.500081) (xy 88.972988 -113.430538)
			(xy 89.054754 -113.354672) (xy 89.130621 -113.272908) (xy 89.200166 -113.185703) (xy 89.262999 -113.093545)
			(xy 89.31877 -112.996948) (xy 89.367166 -112.896454) (xy 89.407917 -112.792625) (xy 89.440794 -112.68604)
			(xy 89.465615 -112.577297) (xy 89.48224 -112.467002) (xy 89.490575 -112.355774) (xy 89.491058 -112.300004)
			(xy 89.491058 -85.5091) (xy 87.749888 -85.5091) (xy 87.705865 -85.508603) (xy 87.618157 -85.500897)
			(xy 87.531453 -85.485581) (xy 87.446413 -85.46277) (xy 87.363683 -85.432637) (xy 87.283893 -85.395413)
			(xy 87.207648 -85.351379) (xy 87.13553 -85.300871) (xy 87.068085 -85.244273) (xy 87.005827 -85.182015)
			(xy 86.949229 -85.11457) (xy 86.898721 -85.042452) (xy 86.854687 -84.966207) (xy 86.817463 -84.886417)
			(xy 86.78733 -84.803687) (xy 86.764519 -84.718647) (xy 86.749203 -84.631943) (xy 86.741497 -84.544235)
			(xy 86.741 -84.500212) (xy 86.741 -81.999836) (xy 86.741491 -81.955812) (xy 86.749186 -81.868101)
			(xy 86.764493 -81.781393) (xy 86.787298 -81.69635) (xy 86.817425 -81.613616) (xy 86.854646 -81.533822)
			(xy 86.898678 -81.457575) (xy 86.949186 -81.385454) (xy 87.005786 -81.318008) (xy 87.068047 -81.255751)
			(xy 87.135495 -81.199154) (xy 87.207619 -81.14865) (xy 87.283869 -81.104622) (xy 87.363664 -81.067405)
			(xy 87.446399 -81.037282) (xy 87.531444 -81.014482) (xy 87.618152 -80.999179) (xy 87.705864 -80.991489)
			(xy 87.749888 -80.990948) (xy 89.491058 -80.990948) (xy 89.491058 -69.07022) (xy 89.492074 -69.069204)
			(xy 89.492074 -67.757802) (xy 89.491058 -67.756786) (xy 89.491058 -1.999996) (xy 89.490549 -1.944227)
			(xy 89.482214 -1.833001) (xy 89.465589 -1.722708) (xy 89.440769 -1.613967) (xy 89.407892 -1.507384)
			(xy 89.367142 -1.403556) (xy 89.318747 -1.303064) (xy 89.262977 -1.206469) (xy 89.200145 -1.114313)
			(xy 89.130601 -1.027109) (xy 89.054735 -0.945346) (xy 88.972971 -0.869482) (xy 88.885767 -0.79994)
			(xy 88.793609 -0.737109) (xy 88.697013 -0.681341) (xy 88.59652 -0.632947) (xy 88.492692 -0.592199)
			(xy 88.386108 -0.559324) (xy 88.277366 -0.534506) (xy 88.167074 -0.517883) (xy 88.055847 -0.50955)
			(xy 88.000078 -0.509016) (xy 1.999996 -0.509016) (xy 1.944227 -0.509538) (xy 1.833001 -0.517873)
			(xy 1.722709 -0.534497) (xy 1.613967 -0.559317) (xy 1.507385 -0.592194) (xy 1.403557 -0.632943) (xy 1.303065 -0.681338)
			(xy 1.20647 -0.737107) (xy 1.114313 -0.799938) (xy 1.027109 -0.869481) (xy 0.945346 -0.945346) (xy 0.869481 -1.027109)
			(xy 0.799938 -1.114313) (xy 0.737107 -1.20647) (xy 0.681338 -1.303065) (xy 0.632943 -1.403557) (xy 0.592194 -1.507385)
			(xy 0.559317 -1.613967) (xy 0.534497 -1.722709) (xy 0.517873 -1.833001) (xy 0.509538 -1.944227) (xy 0.509016 -1.999996)
			(xy 0.509016 -4.69011) (xy 3.634743 -4.69011) (xy 3.638781 -4.606614) (xy 3.65086 -4.523897) (xy 3.670865 -4.442732)
			(xy 3.69861 -4.363877) (xy 3.733837 -4.288068) (xy 3.776216 -4.216013) (xy 3.825351 -4.148384) (xy 3.880784 -4.085813)
			(xy 3.941997 -4.028884) (xy 4.008419 -3.978129) (xy 4.079429 -3.934021) (xy 4.154365 -3.896973) (xy 4.232527 -3.867331)
			(xy 4.313184 -3.84537) (xy 4.395585 -3.831296) (xy 4.478959 -3.825241) (xy 4.562529 -3.827261) (xy 4.645513 -3.837337)
			(xy 4.727138 -3.855375) (xy 4.80664 -3.881207) (xy 4.883279 -3.914592) (xy 4.956337 -3.955217) (xy 5.025133 -4.002704)
			(xy 5.089025 -4.056609) (xy 5.147417 -4.116428) (xy 5.199762 -4.181604) (xy 5.245572 -4.251528) (xy 5.284421 -4.325547)
			(xy 5.315943 -4.402969) (xy 5.339847 -4.483073) (xy 5.355907 -4.565109) (xy 5.363975 -4.648313) (xy 5.36448 -4.69011)
			(xy 10.635237 -4.69011) (xy 10.639274 -4.606638) (xy 10.651349 -4.523946) (xy 10.671348 -4.442805)
			(xy 10.699086 -4.363973) (xy 10.734302 -4.288186) (xy 10.776668 -4.216152) (xy 10.825789 -4.148543)
			(xy 10.881206 -4.08599) (xy 10.942401 -4.029078) (xy 11.008803 -3.978338) (xy 11.079793 -3.934243)
			(xy 11.154707 -3.897206) (xy 11.232845 -3.867572) (xy 11.313479 -3.845618) (xy 11.395856 -3.831548)
			(xy 11.479206 -3.825495) (xy 11.562751 -3.827514) (xy 11.645711 -3.837588) (xy 11.727311 -3.85562)
			(xy 11.80679 -3.881445) (xy 11.883406 -3.914819) (xy 11.956443 -3.955433) (xy 12.025219 -4.002906)
			(xy 12.089092 -4.056795) (xy 12.147467 -4.116597) (xy 12.199797 -4.181754) (xy 12.245594 -4.251657)
			(xy 12.28443 -4.325654) (xy 12.315944 -4.403054) (xy 12.33984 -4.483134) (xy 12.355896 -4.565146)
			(xy 12.363962 -4.648325) (xy 12.364466 -4.69011) (xy 12.363962 -4.731895) (xy 12.355896 -4.815074)
			(xy 12.33984 -4.897086) (xy 12.315944 -4.977166) (xy 12.28443 -5.054566) (xy 12.265749 -5.09016)
			(xy 66.234821 -5.09016) (xy 66.238859 -5.006664) (xy 66.250938 -4.923947) (xy 66.270943 -4.842782)
			(xy 66.298688 -4.763927) (xy 66.333915 -4.688118) (xy 66.376294 -4.616063) (xy 66.425429 -4.548434)
			(xy 66.480862 -4.485863) (xy 66.542075 -4.428934) (xy 66.608497 -4.378179) (xy 66.679507 -4.334071)
			(xy 66.754443 -4.297023) (xy 66.832605 -4.267381) (xy 66.913262 -4.24542) (xy 66.995663 -4.231346)
			(xy 67.079037 -4.225291) (xy 67.162607 -4.227311) (xy 67.245591 -4.237387) (xy 67.327216 -4.255425)
			(xy 67.406718 -4.281257) (xy 67.483357 -4.314642) (xy 67.556415 -4.355267) (xy 67.625211 -4.402754)
			(xy 67.689103 -4.456659) (xy 67.747495 -4.516478) (xy 67.79984 -4.581654) (xy 67.84565 -4.651578)
			(xy 67.884499 -4.725597) (xy 67.916021 -4.803019) (xy 67.939925 -4.883123) (xy 67.955985 -4.965159)
			(xy 67.964053 -5.048363) (xy 67.964558 -5.09016) (xy 73.235315 -5.09016) (xy 73.239352 -5.006688)
			(xy 73.251427 -4.923996) (xy 73.271426 -4.842855) (xy 73.299164 -4.764023) (xy 73.33438 -4.688236)
			(xy 73.376746 -4.616202) (xy 73.425867 -4.548593) (xy 73.481284 -4.48604) (xy 73.542479 -4.429128)
			(xy 73.608881 -4.378388) (xy 73.679871 -4.334293) (xy 73.754785 -4.297256) (xy 73.832923 -4.267622)
			(xy 73.913557 -4.245668) (xy 73.995934 -4.231598) (xy 74.079284 -4.225545) (xy 74.162829 -4.227564)
			(xy 74.245789 -4.237638) (xy 74.327389 -4.25567) (xy 74.406868 -4.281495) (xy 74.483484 -4.314869)
			(xy 74.556521 -4.355483) (xy 74.625297 -4.402956) (xy 74.68917 -4.456845) (xy 74.747545 -4.516647)
			(xy 74.799875 -4.581804) (xy 74.845672 -4.651707) (xy 74.865827 -4.69011) (xy 77.634595 -4.69011)
			(xy 77.638634 -4.606589) (xy 77.650716 -4.523848) (xy 77.670728 -4.44266) (xy 77.698481 -4.363781)
			(xy 77.733718 -4.28795) (xy 77.776109 -4.215873) (xy 77.825259 -4.148225) (xy 77.880708 -4.085635)
			(xy 77.941939 -4.02869) (xy 78.008381 -3.97792) (xy 78.079412 -3.933799) (xy 78.15437 -3.89674) (xy 78.232554 -3.867089)
			(xy 78.313236 -3.845122) (xy 78.395661 -3.831044) (xy 78.479059 -3.824987) (xy 78.562653 -3.827008)
			(xy 78.645662 -3.837087) (xy 78.727311 -3.85513) (xy 78.806836 -3.88097) (xy 78.883497 -3.914364)
			(xy 78.956577 -3.955001) (xy 79.025394 -4.002502) (xy 79.089304 -4.056423) (xy 79.147713 -4.11626)
			(xy 79.200073 -4.181455) (xy 79.245897 -4.251399) (xy 79.284757 -4.32544) (xy 79.316289 -4.402885)
			(xy 79.340199 -4.483012) (xy 79.356265 -4.565073) (xy 79.364335 -4.648301) (xy 79.36484 -4.69011)
			(xy 84.635089 -4.69011) (xy 84.639127 -4.606614) (xy 84.651206 -4.523897) (xy 84.671211 -4.442732)
			(xy 84.698956 -4.363877) (xy 84.734183 -4.288068) (xy 84.776562 -4.216013) (xy 84.825697 -4.148384)
			(xy 84.88113 -4.085813) (xy 84.942343 -4.028884) (xy 85.008765 -3.978129) (xy 85.079775 -3.934021)
			(xy 85.154711 -3.896973) (xy 85.232873 -3.867331) (xy 85.31353 -3.84537) (xy 85.395931 -3.831296)
			(xy 85.479305 -3.825241) (xy 85.562875 -3.827261) (xy 85.645859 -3.837337) (xy 85.727484 -3.855375)
			(xy 85.806986 -3.881207) (xy 85.883625 -3.914592) (xy 85.956683 -3.955217) (xy 86.025479 -4.002704)
			(xy 86.089371 -4.056609) (xy 86.147763 -4.116428) (xy 86.200108 -4.181604) (xy 86.245918 -4.251528)
			(xy 86.284767 -4.325547) (xy 86.316289 -4.402969) (xy 86.340193 -4.483073) (xy 86.356253 -4.565109)
			(xy 86.364321 -4.648313) (xy 86.364826 -4.69011) (xy 86.364321 -4.731907) (xy 86.356253 -4.815111)
			(xy 86.340193 -4.897147) (xy 86.316289 -4.977251) (xy 86.284767 -5.054673) (xy 86.245918 -5.128692)
			(xy 86.200108 -5.198616) (xy 86.147763 -5.263792) (xy 86.089371 -5.323611) (xy 86.025479 -5.377516)
			(xy 85.956683 -5.425003) (xy 85.883625 -5.465628) (xy 85.806986 -5.499013) (xy 85.727484 -5.524845)
			(xy 85.645859 -5.542883) (xy 85.562875 -5.552959) (xy 85.479305 -5.554979) (xy 85.395931 -5.548924)
			(xy 85.31353 -5.53485) (xy 85.232873 -5.512889) (xy 85.154711 -5.483247) (xy 85.079775 -5.446199)
			(xy 85.008765 -5.402091) (xy 84.942343 -5.351336) (xy 84.88113 -5.294407) (xy 84.825697 -5.231836)
			(xy 84.776562 -5.164207) (xy 84.734183 -5.092152) (xy 84.698956 -5.016343) (xy 84.671211 -4.937488)
			(xy 84.651206 -4.856323) (xy 84.639127 -4.773606) (xy 84.635089 -4.69011) (xy 79.36484 -4.69011)
			(xy 79.364335 -4.731919) (xy 79.356265 -4.815147) (xy 79.340199 -4.897208) (xy 79.316289 -4.977335)
			(xy 79.284757 -5.05478) (xy 79.245897 -5.128821) (xy 79.200073 -5.198765) (xy 79.147713 -5.26396)
			(xy 79.089304 -5.323797) (xy 79.025394 -5.377718) (xy 78.956577 -5.425219) (xy 78.883497 -5.465856)
			(xy 78.806836 -5.49925) (xy 78.727311 -5.52509) (xy 78.645662 -5.543133) (xy 78.562653 -5.553212)
			(xy 78.479059 -5.555233) (xy 78.395661 -5.549176) (xy 78.313236 -5.535098) (xy 78.232554 -5.513131)
			(xy 78.15437 -5.48348) (xy 78.079412 -5.446421) (xy 78.008381 -5.4023) (xy 77.941939 -5.35153) (xy 77.880708 -5.294585)
			(xy 77.825259 -5.231995) (xy 77.776109 -5.164347) (xy 77.733718 -5.09227) (xy 77.698481 -5.016439)
			(xy 77.670728 -4.93756) (xy 77.650716 -4.856372) (xy 77.638634 -4.773631) (xy 77.634595 -4.69011)
			(xy 74.865827 -4.69011) (xy 74.884508 -4.725704) (xy 74.916022 -4.803104) (xy 74.939918 -4.883184)
			(xy 74.955974 -4.965196) (xy 74.96404 -5.048375) (xy 74.964544 -5.09016) (xy 74.96404 -5.131945)
			(xy 74.955974 -5.215124) (xy 74.939918 -5.297136) (xy 74.916022 -5.377216) (xy 74.884508 -5.454616)
			(xy 74.845672 -5.528613) (xy 74.799875 -5.598516) (xy 74.747545 -5.663673) (xy 74.68917 -5.723475)
			(xy 74.625297 -5.777364) (xy 74.556521 -5.824837) (xy 74.483484 -5.865451) (xy 74.406868 -5.898825)
			(xy 74.327389 -5.92465) (xy 74.245789 -5.942682) (xy 74.162829 -5.952756) (xy 74.079284 -5.954775)
			(xy 73.995934 -5.948722) (xy 73.913557 -5.934652) (xy 73.832923 -5.912698) (xy 73.754785 -5.883064)
			(xy 73.679871 -5.846027) (xy 73.608881 -5.801932) (xy 73.542479 -5.751192) (xy 73.481284 -5.69428)
			(xy 73.425867 -5.631727) (xy 73.376746 -5.564118) (xy 73.33438 -5.492084) (xy 73.299164 -5.416297)
			(xy 73.271426 -5.337465) (xy 73.251427 -5.256324) (xy 73.239352 -5.173632) (xy 73.235315 -5.09016)
			(xy 67.964558 -5.09016) (xy 67.964053 -5.131957) (xy 67.955985 -5.215161) (xy 67.939925 -5.297197)
			(xy 67.916021 -5.377301) (xy 67.884499 -5.454723) (xy 67.84565 -5.528742) (xy 67.79984 -5.598666)
			(xy 67.747495 -5.663842) (xy 67.689103 -5.723661) (xy 67.625211 -5.777566) (xy 67.556415 -5.825053)
			(xy 67.483357 -5.865678) (xy 67.406718 -5.899063) (xy 67.327216 -5.924895) (xy 67.245591 -5.942933)
			(xy 67.162607 -5.953009) (xy 67.079037 -5.955029) (xy 66.995663 -5.948974) (xy 66.913262 -5.9349)
			(xy 66.832605 -5.912939) (xy 66.754443 -5.883297) (xy 66.679507 -5.846249) (xy 66.608497 -5.802141)
			(xy 66.542075 -5.751386) (xy 66.480862 -5.694457) (xy 66.425429 -5.631886) (xy 66.376294 -5.564257)
			(xy 66.333915 -5.492202) (xy 66.298688 -5.416393) (xy 66.270943 -5.337538) (xy 66.250938 -5.256373)
			(xy 66.238859 -5.173656) (xy 66.234821 -5.09016) (xy 12.265749 -5.09016) (xy 12.245594 -5.128563)
			(xy 12.199797 -5.198466) (xy 12.147467 -5.263623) (xy 12.089092 -5.323425) (xy 12.025219 -5.377314)
			(xy 11.956443 -5.424787) (xy 11.883406 -5.465401) (xy 11.80679 -5.498775) (xy 11.727311 -5.5246)
			(xy 11.645711 -5.542632) (xy 11.562751 -5.552706) (xy 11.479206 -5.554725) (xy 11.395856 -5.548672)
			(xy 11.313479 -5.534602) (xy 11.232845 -5.512648) (xy 11.154707 -5.483014) (xy 11.079793 -5.445977)
			(xy 11.008803 -5.401882) (xy 10.942401 -5.351142) (xy 10.881206 -5.29423) (xy 10.825789 -5.231677)
			(xy 10.776668 -5.164068) (xy 10.734302 -5.092034) (xy 10.699086 -5.016247) (xy 10.671348 -4.937415)
			(xy 10.651349 -4.856274) (xy 10.639274 -4.773582) (xy 10.635237 -4.69011) (xy 5.36448 -4.69011) (xy 5.363975 -4.731907)
			(xy 5.355907 -4.815111) (xy 5.339847 -4.897147) (xy 5.315943 -4.977251) (xy 5.284421 -5.054673) (xy 5.245572 -5.128692)
			(xy 5.199762 -5.198616) (xy 5.147417 -5.263792) (xy 5.089025 -5.323611) (xy 5.025133 -5.377516) (xy 4.956337 -5.425003)
			(xy 4.883279 -5.465628) (xy 4.80664 -5.499013) (xy 4.727138 -5.524845) (xy 4.645513 -5.542883) (xy 4.562529 -5.552959)
			(xy 4.478959 -5.554979) (xy 4.395585 -5.548924) (xy 4.313184 -5.53485) (xy 4.232527 -5.512889) (xy 4.154365 -5.483247)
			(xy 4.079429 -5.446199) (xy 4.008419 -5.402091) (xy 3.941997 -5.351336) (xy 3.880784 -5.294407) (xy 3.825351 -5.231836)
			(xy 3.776216 -5.164207) (xy 3.733837 -5.092152) (xy 3.69861 -5.016343) (xy 3.670865 -4.937488) (xy 3.65086 -4.856323)
			(xy 3.638781 -4.773606) (xy 3.634743 -4.69011) (xy 0.509016 -4.69011) (xy 0.509016 -13.417248) (xy 41.210697 -13.417248)
			(xy 41.210697 -13.342672) (xy 41.218492 -13.268505) (xy 41.233997 -13.195559) (xy 41.257043 -13.124633)
			(xy 41.287375 -13.056505) (xy 41.324663 -12.991921) (xy 41.368498 -12.931588) (xy 41.418399 -12.876167)
			(xy 41.473819 -12.826266) (xy 41.534152 -12.782432) (xy 41.598737 -12.745144) (xy 41.666865 -12.714812)
			(xy 41.737791 -12.691767) (xy 41.810737 -12.676262) (xy 41.884904 -12.668467) (xy 41.922192 -12.667996)
			(xy 43.922188 -12.667996) (xy 43.959474 -12.668551) (xy 44.033637 -12.676344) (xy 44.106579 -12.691848)
			(xy 44.177502 -12.714891) (xy 44.245627 -12.745221) (xy 44.310208 -12.782506) (xy 44.370538 -12.826338)
			(xy 44.425956 -12.876235) (xy 44.475855 -12.931652) (xy 44.519687 -12.991982) (xy 44.556974 -13.056563)
			(xy 44.587305 -13.124687) (xy 44.610349 -13.195609) (xy 44.625854 -13.268551) (xy 44.633649 -13.342714)
			(xy 44.633649 -13.417286) (xy 44.625854 -13.491449) (xy 44.610349 -13.564391) (xy 44.587305 -13.635313)
			(xy 44.556974 -13.703437) (xy 44.519687 -13.768018) (xy 44.475855 -13.828348) (xy 44.425956 -13.883765)
			(xy 44.370538 -13.933662) (xy 44.310208 -13.977494) (xy 44.245627 -14.014779) (xy 44.177502 -14.045109)
			(xy 44.106579 -14.068152) (xy 44.033637 -14.083656) (xy 43.959474 -14.091449) (xy 43.922188 -14.09192)
			(xy 41.922192 -14.09192) (xy 41.884904 -14.091453) (xy 41.810737 -14.083658) (xy 41.737791 -14.068153)
			(xy 41.666865 -14.045108) (xy 41.598737 -14.014776) (xy 41.534152 -13.977488) (xy 41.473819 -13.933654)
			(xy 41.418399 -13.883753) (xy 41.368498 -13.828332) (xy 41.324663 -13.767999) (xy 41.287375 -13.703415)
			(xy 41.257043 -13.635287) (xy 41.233997 -13.564361) (xy 41.218492 -13.491415) (xy 41.210697 -13.417248)
			(xy 0.509016 -13.417248) (xy 0.509016 -14.917388) (xy 38.210708 -14.917388) (xy 38.210708 -14.842812)
			(xy 38.218503 -14.768646) (xy 38.234008 -14.6957) (xy 38.257053 -14.624775) (xy 38.287386 -14.556647)
			(xy 38.324673 -14.492062) (xy 38.368507 -14.43173) (xy 38.418408 -14.376309) (xy 38.473828 -14.326409)
			(xy 38.534161 -14.282574) (xy 38.598745 -14.245287) (xy 38.666873 -14.214954) (xy 38.737798 -14.191909)
			(xy 38.810744 -14.176403) (xy 38.88491 -14.168608) (xy 38.922198 -14.16812) (xy 40.922194 -14.16812)
			(xy 40.959481 -14.168627) (xy 41.033646 -14.176422) (xy 41.106591 -14.191926) (xy 41.177515 -14.21497)
			(xy 41.245641 -14.245301) (xy 41.310224 -14.282588) (xy 41.370556 -14.326421) (xy 41.425975 -14.37632)
			(xy 41.475875 -14.431739) (xy 41.519709 -14.492071) (xy 41.556996 -14.556653) (xy 41.587328 -14.62478)
			(xy 41.610373 -14.695704) (xy 41.625877 -14.768648) (xy 41.633673 -14.842813) (xy 41.633673 -14.917387)
			(xy 44.210708 -14.917387) (xy 44.210708 -14.842813) (xy 44.218503 -14.768647) (xy 44.234008 -14.695702)
			(xy 44.257052 -14.624777) (xy 44.287384 -14.55665) (xy 44.324671 -14.492066) (xy 44.368504 -14.431734)
			(xy 44.418404 -14.376314) (xy 44.473823 -14.326413) (xy 44.534154 -14.282578) (xy 44.598737 -14.24529)
			(xy 44.666864 -14.214957) (xy 44.737788 -14.191911) (xy 44.810733 -14.176405) (xy 44.884899 -14.168609)
			(xy 44.922186 -14.16812) (xy 46.922182 -14.16812) (xy 46.959469 -14.168626) (xy 47.033636 -14.17642)
			(xy 47.106581 -14.191923) (xy 47.177506 -14.214967) (xy 47.245634 -14.245298) (xy 47.310218 -14.282584)
			(xy 47.370551 -14.326417) (xy 47.425971 -14.376316) (xy 47.475872 -14.431735) (xy 47.519706 -14.492067)
			(xy 47.556994 -14.55665) (xy 47.587327 -14.624777) (xy 47.610372 -14.695702) (xy 47.625877 -14.768647)
			(xy 47.633673 -14.842813) (xy 47.633673 -14.917387) (xy 47.625877 -14.991553) (xy 47.610372 -15.064498)
			(xy 47.587327 -15.135423) (xy 47.556994 -15.20355) (xy 47.519706 -15.268133) (xy 47.475872 -15.328465)
			(xy 47.425971 -15.383884) (xy 47.370551 -15.433783) (xy 47.310218 -15.477616) (xy 47.245634 -15.514902)
			(xy 47.177506 -15.545233) (xy 47.106581 -15.568277) (xy 47.033636 -15.58378) (xy 46.959469 -15.591574)
			(xy 46.922182 -15.592044) (xy 44.922186 -15.592044) (xy 44.884899 -15.591591) (xy 44.810733 -15.583795)
			(xy 44.737788 -15.568289) (xy 44.666864 -15.545243) (xy 44.598737 -15.51491) (xy 44.534154 -15.477622)
			(xy 44.473823 -15.433787) (xy 44.418404 -15.383886) (xy 44.368504 -15.328466) (xy 44.324671 -15.268134)
			(xy 44.287384 -15.20355) (xy 44.257052 -15.135423) (xy 44.234008 -15.064498) (xy 44.218503 -14.991553)
			(xy 44.210708 -14.917387) (xy 41.633673 -14.917387) (xy 41.625877 -14.991552) (xy 41.610373 -15.064496)
			(xy 41.587328 -15.13542) (xy 41.556996 -15.203547) (xy 41.519709 -15.268129) (xy 41.475875 -15.328461)
			(xy 41.425975 -15.38388) (xy 41.370556 -15.433779) (xy 41.310224 -15.477612) (xy 41.245641 -15.514899)
			(xy 41.177515 -15.54523) (xy 41.106591 -15.568274) (xy 41.033646 -15.583778) (xy 40.959481 -15.591573)
			(xy 40.922194 -15.592044) (xy 38.922198 -15.592044) (xy 38.88491 -15.591592) (xy 38.810744 -15.583797)
			(xy 38.737798 -15.568291) (xy 38.666873 -15.545246) (xy 38.598745 -15.514913) (xy 38.534161 -15.477626)
			(xy 38.473828 -15.433791) (xy 38.418408 -15.383891) (xy 38.368507 -15.32847) (xy 38.324673 -15.268138)
			(xy 38.287386 -15.203553) (xy 38.257053 -15.135425) (xy 38.234008 -15.0645) (xy 38.218503 -14.991554)
			(xy 38.210708 -14.917388) (xy 0.509016 -14.917388) (xy 0.509016 -17.38737) (xy 4.838435 -17.38737)
			(xy 4.838435 -17.25823) (xy 4.846385 -17.129335) (xy 4.862255 -17.001175) (xy 4.885984 -16.874234)
			(xy 4.917483 -16.748995) (xy 4.956632 -16.625932) (xy 5.003283 -16.505513) (xy 5.057258 -16.388194)
			(xy 5.118353 -16.27442) (xy 5.186336 -16.164623) (xy 5.26095 -16.05922) (xy 5.341911 -15.95861) (xy 5.428911 -15.863175)
			(xy 5.521622 -15.773276) (xy 5.619692 -15.689255) (xy 5.722747 -15.611431) (xy 5.830398 -15.540099)
			(xy 5.942237 -15.475529) (xy 6.057838 -15.417967) (xy 6.176763 -15.36763) (xy 6.298562 -15.32471)
			(xy 6.422772 -15.289369) (xy 6.548921 -15.261742) (xy 6.676533 -15.241933) (xy 6.805122 -15.230017)
			(xy 6.9342 -15.226041) (xy 7.063278 -15.230017) (xy 7.191867 -15.241933) (xy 7.319479 -15.261742)
			(xy 7.445628 -15.289369) (xy 7.569838 -15.32471) (xy 7.691637 -15.36763) (xy 7.810562 -15.417967)
			(xy 7.926163 -15.475529) (xy 8.038002 -15.540099) (xy 8.145653 -15.611431) (xy 8.248708 -15.689255)
			(xy 8.346778 -15.773276) (xy 8.439489 -15.863175) (xy 8.526489 -15.95861) (xy 8.60745 -16.05922)
			(xy 8.682064 -16.164623) (xy 8.750047 -16.27442) (xy 8.811142 -16.388194) (xy 8.865117 -16.505513)
			(xy 8.911768 -16.625932) (xy 8.950917 -16.748995) (xy 8.982416 -16.874234) (xy 8.996233 -16.94815)
			(xy 25.574752 -16.94815) (xy 25.574752 -16.05915) (xy 25.575238 -16.031899) (xy 25.582994 -15.977951)
			(xy 25.598349 -15.925656) (xy 25.620991 -15.876079) (xy 25.650457 -15.830229) (xy 25.686148 -15.789038)
			(xy 25.727339 -15.753347) (xy 25.773189 -15.723881) (xy 25.822766 -15.701239) (xy 25.875061 -15.685884)
			(xy 25.929009 -15.678128) (xy 25.983511 -15.678128) (xy 26.037459 -15.685884) (xy 26.089754 -15.701239)
			(xy 26.139331 -15.723881) (xy 26.185181 -15.753347) (xy 26.226372 -15.789038) (xy 26.262063 -15.830229)
			(xy 26.291529 -15.876079) (xy 26.314171 -15.925656) (xy 26.329526 -15.977951) (xy 26.337282 -16.031899)
			(xy 26.337768 -16.05915) (xy 26.337768 -16.94815) (xy 26.337282 -16.975401) (xy 26.329526 -17.029349)
			(xy 26.314171 -17.081644) (xy 26.291529 -17.131221) (xy 26.262063 -17.177071) (xy 26.226372 -17.218262)
			(xy 26.185181 -17.253953) (xy 26.139331 -17.283419) (xy 26.089754 -17.306061) (xy 26.037459 -17.321416)
			(xy 25.983511 -17.329172) (xy 25.929009 -17.329172) (xy 25.875061 -17.321416) (xy 25.822766 -17.306061)
			(xy 25.773189 -17.283419) (xy 25.727339 -17.253953) (xy 25.686148 -17.218262) (xy 25.650457 -17.177071)
			(xy 25.620991 -17.131221) (xy 25.598349 -17.081644) (xy 25.582994 -17.029349) (xy 25.575238 -16.975401)
			(xy 25.574752 -16.94815) (xy 8.996233 -16.94815) (xy 9.006145 -17.001175) (xy 9.022015 -17.129335)
			(xy 9.029965 -17.25823) (xy 9.030462 -17.3228) (xy 9.029965 -17.38737) (xy 9.022015 -17.516265) (xy 9.006145 -17.644425)
			(xy 8.982416 -17.771366) (xy 8.950917 -17.896605) (xy 8.911768 -18.019668) (xy 8.865117 -18.140087)
			(xy 8.811142 -18.257406) (xy 8.750047 -18.37118) (xy 8.682064 -18.480977) (xy 8.60745 -18.58638)
			(xy 8.526489 -18.68699) (xy 8.439489 -18.782425) (xy 8.346778 -18.872324) (xy 8.248708 -18.956345)
			(xy 8.145653 -19.034169) (xy 8.038002 -19.105501) (xy 7.926163 -19.170071) (xy 7.810562 -19.227633)
			(xy 7.691637 -19.27797) (xy 7.569838 -19.32089) (xy 7.445628 -19.356231) (xy 7.319479 -19.383858)
			(xy 7.191867 -19.403667) (xy 7.063278 -19.415583) (xy 6.9342 -19.41956) (xy 6.805122 -19.415583)
			(xy 6.676533 -19.403667) (xy 6.548921 -19.383858) (xy 6.422772 -19.356231) (xy 6.298562 -19.32089)
			(xy 6.176763 -19.27797) (xy 6.057838 -19.227633) (xy 5.942237 -19.170071) (xy 5.830398 -19.105501)
			(xy 5.722747 -19.034169) (xy 5.619692 -18.956345) (xy 5.521622 -18.872324) (xy 5.428911 -18.782425)
			(xy 5.341911 -18.68699) (xy 5.26095 -18.58638) (xy 5.186336 -18.480977) (xy 5.118353 -18.37118) (xy 5.057258 -18.257406)
			(xy 5.003283 -18.140087) (xy 4.956632 -18.019668) (xy 4.917483 -17.896605) (xy 4.885984 -17.771366)
			(xy 4.862255 -17.644425) (xy 4.846385 -17.516265) (xy 4.838435 -17.38737) (xy 0.509016 -17.38737)
			(xy 0.509016 -24.482675) (xy 40.239076 -24.482675) (xy 40.239076 -24.428125) (xy 40.246839 -24.374131)
			(xy 40.262209 -24.321791) (xy 40.284871 -24.272172) (xy 40.314365 -24.226283) (xy 40.350089 -24.185059)
			(xy 40.391317 -24.149339) (xy 40.437209 -24.119851) (xy 40.486831 -24.097194) (xy 40.539172 -24.08183)
			(xy 40.593167 -24.074073) (xy 40.620442 -24.073612) (xy 41.509442 -24.073612) (xy 41.536708 -24.074153)
			(xy 41.590683 -24.081919) (xy 41.643004 -24.097287) (xy 41.692605 -24.119944) (xy 41.738478 -24.149429)
			(xy 41.779688 -24.185142) (xy 41.815396 -24.226356) (xy 41.844876 -24.272232) (xy 41.867528 -24.321836)
			(xy 41.88289 -24.374158) (xy 41.89065 -24.428134) (xy 41.89065 -24.482666) (xy 41.890649 -24.482675)
			(xy 42.632776 -24.482675) (xy 42.632776 -24.428125) (xy 42.640539 -24.374132) (xy 42.655909 -24.321792)
			(xy 42.67857 -24.272173) (xy 42.708064 -24.226285) (xy 42.743788 -24.185061) (xy 42.785015 -24.149341)
			(xy 42.830907 -24.119852) (xy 42.880528 -24.097195) (xy 42.932869 -24.081831) (xy 42.986863 -24.074073)
			(xy 43.014138 -24.073612) (xy 43.903138 -24.073612) (xy 43.930404 -24.074153) (xy 43.98438 -24.081918)
			(xy 44.036701 -24.097286) (xy 44.086303 -24.119943) (xy 44.132176 -24.149428) (xy 44.173386 -24.185141)
			(xy 44.209095 -24.226354) (xy 44.238575 -24.27223) (xy 44.261227 -24.321835) (xy 44.27659 -24.374158)
			(xy 44.28435 -24.428134) (xy 44.28435 -24.482666) (xy 44.27659 -24.536642) (xy 44.261227 -24.588965)
			(xy 44.238575 -24.63857) (xy 44.209095 -24.684446) (xy 44.173386 -24.725659) (xy 44.132176 -24.761372)
			(xy 44.086303 -24.790857) (xy 44.036701 -24.813514) (xy 43.98438 -24.828882) (xy 43.930404 -24.836647)
			(xy 43.903138 -24.837136) (xy 43.014138 -24.837136) (xy 42.986863 -24.836727) (xy 42.932869 -24.828969)
			(xy 42.880528 -24.813605) (xy 42.830907 -24.790948) (xy 42.785015 -24.761459) (xy 42.743788 -24.725739)
			(xy 42.708064 -24.684515) (xy 42.67857 -24.638627) (xy 42.655909 -24.589008) (xy 42.640539 -24.536668)
			(xy 42.632776 -24.482675) (xy 41.890649 -24.482675) (xy 41.88289 -24.536642) (xy 41.867528 -24.588964)
			(xy 41.844876 -24.638568) (xy 41.815396 -24.684444) (xy 41.779688 -24.725658) (xy 41.738478 -24.761371)
			(xy 41.692605 -24.790856) (xy 41.643004 -24.813513) (xy 41.590683 -24.828881) (xy 41.536708 -24.836647)
			(xy 41.509442 -24.837136) (xy 40.620442 -24.837136) (xy 40.593167 -24.836727) (xy 40.539172 -24.82897)
			(xy 40.486831 -24.813606) (xy 40.437209 -24.790949) (xy 40.391317 -24.761461) (xy 40.350089 -24.725741)
			(xy 40.314365 -24.684517) (xy 40.284871 -24.638628) (xy 40.262209 -24.589009) (xy 40.246839 -24.536669)
			(xy 40.239076 -24.482675) (xy 0.509016 -24.482675) (xy 0.509016 -26.898451) (xy 62.226946 -26.898451)
			(xy 62.226946 -26.843949) (xy 62.234702 -26.790001) (xy 62.250056 -26.737705) (xy 62.272695 -26.688127)
			(xy 62.302159 -26.642275) (xy 62.337849 -26.601083) (xy 62.379037 -26.565388) (xy 62.424885 -26.535918)
			(xy 62.47446 -26.513272) (xy 62.526754 -26.497912) (xy 62.580701 -26.490149) (xy 62.607952 -26.48966)
			(xy 63.496952 -26.48966) (xy 63.524205 -26.490184) (xy 63.578156 -26.497935) (xy 63.630456 -26.513285)
			(xy 63.680038 -26.535923) (xy 63.725893 -26.565387) (xy 63.767088 -26.601078) (xy 63.802784 -26.642269)
			(xy 63.832254 -26.68812) (xy 63.854898 -26.737699) (xy 63.870255 -26.789997) (xy 63.878013 -26.843947)
			(xy 63.878013 -26.898453) (xy 63.870255 -26.952403) (xy 63.863218 -26.976368) (xy 64.442847 -26.976368)
			(xy 64.442847 -26.921832) (xy 64.450609 -26.867852) (xy 64.465973 -26.815525) (xy 64.488628 -26.765918)
			(xy 64.518112 -26.72004) (xy 64.553826 -26.678824) (xy 64.595041 -26.643111) (xy 64.64092 -26.613627)
			(xy 64.690527 -26.590972) (xy 64.742854 -26.575608) (xy 64.796834 -26.567847) (xy 64.824102 -26.567384)
			(xy 65.713102 -26.567384) (xy 65.740375 -26.567779) (xy 65.794364 -26.575542) (xy 65.8467 -26.590909)
			(xy 65.896316 -26.613568) (xy 65.942202 -26.643057) (xy 65.983424 -26.678777) (xy 66.019144 -26.72)
			(xy 66.048633 -26.765886) (xy 66.071292 -26.815502) (xy 66.086659 -26.867838) (xy 66.094421 -26.921827)
			(xy 66.094421 -26.976373) (xy 66.086659 -27.030362) (xy 66.071292 -27.082698) (xy 66.048633 -27.132314)
			(xy 66.019144 -27.1782) (xy 65.983424 -27.219423) (xy 65.942202 -27.255143) (xy 65.896316 -27.284632)
			(xy 65.8467 -27.307291) (xy 65.794364 -27.322658) (xy 65.740375 -27.330421) (xy 65.713102 -27.330908)
			(xy 64.824102 -27.330908) (xy 64.796834 -27.330353) (xy 64.742854 -27.322592) (xy 64.690527 -27.307228)
			(xy 64.64092 -27.284573) (xy 64.595041 -27.255089) (xy 64.553826 -27.219376) (xy 64.518112 -27.17816)
			(xy 64.488628 -27.132282) (xy 64.465973 -27.082675) (xy 64.450609 -27.030348) (xy 64.442847 -26.976368)
			(xy 63.863218 -26.976368) (xy 63.854898 -27.004701) (xy 63.832254 -27.05428) (xy 63.802784 -27.100131)
			(xy 63.767088 -27.141322) (xy 63.725893 -27.177013) (xy 63.680038 -27.206477) (xy 63.630456 -27.229115)
			(xy 63.578156 -27.244465) (xy 63.524205 -27.252216) (xy 63.496952 -27.252676) (xy 62.607952 -27.252676)
			(xy 62.580701 -27.252251) (xy 62.526754 -27.244488) (xy 62.47446 -27.229128) (xy 62.424885 -27.206482)
			(xy 62.379037 -27.177012) (xy 62.337849 -27.141317) (xy 62.302159 -27.100125) (xy 62.272695 -27.054273)
			(xy 62.250056 -27.004695) (xy 62.234702 -26.952399) (xy 62.226946 -26.898451) (xy 0.509016 -26.898451)
			(xy 0.509016 -48.189134) (xy 23.749 -48.189134) (xy 23.749 -46.588934) (xy 23.749498 -46.511651)
			(xy 23.757454 -46.357291) (xy 23.773347 -46.203545) (xy 23.797133 -46.050821) (xy 23.82875 -45.899525)
			(xy 23.868113 -45.750056) (xy 23.915118 -45.602812) (xy 23.969642 -45.458182) (xy 24.031538 -45.316552)
			(xy 24.100643 -45.178295) (xy 24.176774 -45.04378) (xy 24.259728 -44.913361) (xy 24.349287 -44.787386)
			(xy 24.445211 -44.666189) (xy 24.547248 -44.55009) (xy 24.655125 -44.439398) (xy 24.768558 -44.334406)
			(xy 24.887246 -44.235393) (xy 25.010873 -44.14262) (xy 25.139112 -44.056335) (xy 25.271623 -43.976766)
			(xy 25.408055 -43.904124) (xy 25.548045 -43.838602) (xy 25.691222 -43.780373) (xy 25.837207 -43.729592)
			(xy 25.985613 -43.686393) (xy 26.136045 -43.650891) (xy 26.288106 -43.623181) (xy 26.441392 -43.603335)
			(xy 26.595496 -43.591406) (xy 26.75001 -43.587427) (xy 26.904524 -43.591406) (xy 27.058628 -43.603335)
			(xy 27.211914 -43.623181) (xy 27.363975 -43.650891) (xy 27.514407 -43.686393) (xy 27.662813 -43.729592)
			(xy 27.808798 -43.780373) (xy 27.951975 -43.838602) (xy 28.091965 -43.904124) (xy 28.228397 -43.976766)
			(xy 28.360908 -44.056335) (xy 28.489147 -44.14262) (xy 28.612774 -44.235393) (xy 28.731462 -44.334406)
			(xy 28.844895 -44.439398) (xy 28.952772 -44.55009) (xy 29.054809 -44.666189) (xy 29.150733 -44.787386)
			(xy 29.240292 -44.913361) (xy 29.252254 -44.932168) (xy 66.731138 -44.932168) (xy 66.731138 -44.877632)
			(xy 66.738899 -44.823652) (xy 66.754264 -44.771325) (xy 66.776918 -44.721717) (xy 66.806402 -44.675839)
			(xy 66.842114 -44.634623) (xy 66.883329 -44.598909) (xy 66.929207 -44.569424) (xy 66.978814 -44.546768)
			(xy 67.03114 -44.531402) (xy 67.08512 -44.523639) (xy 67.112388 -44.523152) (xy 68.001388 -44.523152)
			(xy 68.028661 -44.523587) (xy 68.082651 -44.531348) (xy 68.134987 -44.546714) (xy 68.184603 -44.569371)
			(xy 68.23049 -44.59886) (xy 68.271713 -44.634578) (xy 68.307433 -44.6758) (xy 68.336923 -44.721686)
			(xy 68.359582 -44.771302) (xy 68.37495 -44.823638) (xy 68.382712 -44.877627) (xy 68.382712 -44.932173)
			(xy 68.37495 -44.986162) (xy 68.359582 -45.038498) (xy 68.336923 -45.088114) (xy 68.307433 -45.134)
			(xy 68.271713 -45.175222) (xy 68.23049 -45.21094) (xy 68.184603 -45.240429) (xy 68.134987 -45.263086)
			(xy 68.082651 -45.278452) (xy 68.028661 -45.286213) (xy 68.001388 -45.286676) (xy 67.112388 -45.286676)
			(xy 67.08512 -45.286161) (xy 67.03114 -45.278398) (xy 66.978814 -45.263032) (xy 66.929207 -45.240376)
			(xy 66.883329 -45.210891) (xy 66.842114 -45.175177) (xy 66.806402 -45.133961) (xy 66.776918 -45.088083)
			(xy 66.754264 -45.038475) (xy 66.738899 -44.986148) (xy 66.731138 -44.932168) (xy 29.252254 -44.932168)
			(xy 29.323246 -45.04378) (xy 29.399377 -45.178295) (xy 29.468482 -45.316552) (xy 29.530378 -45.458182)
			(xy 29.584902 -45.602812) (xy 29.631907 -45.750056) (xy 29.67127 -45.899525) (xy 29.702887 -46.050821)
			(xy 29.726673 -46.203545) (xy 29.742566 -46.357291) (xy 29.750522 -46.511651) (xy 29.75102 -46.588934)
			(xy 29.75102 -48.189134) (xy 29.750522 -48.266417) (xy 29.742566 -48.420777) (xy 29.726673 -48.574523)
			(xy 29.702887 -48.727247) (xy 29.67127 -48.878543) (xy 29.631907 -49.028012) (xy 29.584902 -49.175256)
			(xy 29.530378 -49.319886) (xy 29.468482 -49.461516) (xy 29.399377 -49.599773) (xy 29.323246 -49.734288)
			(xy 29.240292 -49.864707) (xy 29.150733 -49.990682) (xy 29.054809 -50.111879) (xy 28.952772 -50.227978)
			(xy 28.844895 -50.33867) (xy 28.731462 -50.443662) (xy 28.612774 -50.542675) (xy 28.489147 -50.635448)
			(xy 28.360908 -50.721733) (xy 28.228397 -50.801302) (xy 28.091965 -50.873944) (xy 27.951975 -50.939466)
			(xy 27.808798 -50.997695) (xy 27.662813 -51.048476) (xy 27.514407 -51.091675) (xy 27.363975 -51.127177)
			(xy 27.211914 -51.154887) (xy 27.058628 -51.174733) (xy 26.904524 -51.186662) (xy 26.75001 -51.190642)
			(xy 26.595496 -51.186662) (xy 26.441392 -51.174733) (xy 26.288106 -51.154887) (xy 26.136045 -51.127177)
			(xy 25.985613 -51.091675) (xy 25.837207 -51.048476) (xy 25.691222 -50.997695) (xy 25.548045 -50.939466)
			(xy 25.408055 -50.873944) (xy 25.271623 -50.801302) (xy 25.139112 -50.721733) (xy 25.010873 -50.635448)
			(xy 24.887246 -50.542675) (xy 24.768558 -50.443662) (xy 24.655125 -50.33867) (xy 24.547248 -50.227978)
			(xy 24.445211 -50.111879) (xy 24.349287 -49.990682) (xy 24.259728 -49.864707) (xy 24.176774 -49.734288)
			(xy 24.100643 -49.599773) (xy 24.031538 -49.461516) (xy 23.969642 -49.319886) (xy 23.915118 -49.175256)
			(xy 23.868113 -49.028012) (xy 23.82875 -48.878543) (xy 23.797133 -48.727247) (xy 23.773347 -48.574523)
			(xy 23.757454 -48.420777) (xy 23.749498 -48.266417) (xy 23.749 -48.189134) (xy 0.509016 -48.189134)
			(xy 0.509016 -52.67175) (xy 66.314303 -52.67175) (xy 66.314303 -52.61725) (xy 66.32206 -52.563304)
			(xy 66.337415 -52.511011) (xy 66.360056 -52.461436) (xy 66.389522 -52.415587) (xy 66.425214 -52.374399)
			(xy 66.466403 -52.33871) (xy 66.512253 -52.309246) (xy 66.56183 -52.286608) (xy 66.614123 -52.271256)
			(xy 66.66807 -52.263502) (xy 66.69532 -52.26304) (xy 67.58432 -52.26304) (xy 67.611574 -52.263431)
			(xy 67.665526 -52.271191) (xy 67.717825 -52.28655) (xy 67.767406 -52.309195) (xy 67.81326 -52.338666)
			(xy 67.854453 -52.374362) (xy 67.890146 -52.415556) (xy 67.919615 -52.461412) (xy 67.942257 -52.510994)
			(xy 67.957613 -52.563293) (xy 67.96537 -52.617246) (xy 67.96537 -52.671754) (xy 67.957613 -52.725707)
			(xy 67.942257 -52.778006) (xy 67.919615 -52.827588) (xy 67.890146 -52.873444) (xy 67.854453 -52.914638)
			(xy 67.81326 -52.950334) (xy 67.767406 -52.979805) (xy 67.717825 -53.00245) (xy 67.665526 -53.017809)
			(xy 67.611574 -53.025569) (xy 67.58432 -53.026056) (xy 66.69532 -53.026056) (xy 66.66807 -53.025498)
			(xy 66.614123 -53.017744) (xy 66.56183 -53.002392) (xy 66.512253 -52.979754) (xy 66.466403 -52.95029)
			(xy 66.425214 -52.914601) (xy 66.389522 -52.873413) (xy 66.360056 -52.827564) (xy 66.337415 -52.777989)
			(xy 66.32206 -52.725696) (xy 66.314303 -52.67175) (xy 0.509016 -52.67175) (xy 0.509016 -54.53387)
			(xy 66.568023 -54.53387) (xy 66.568023 -54.47933) (xy 66.575786 -54.425344) (xy 66.591152 -54.373013)
			(xy 66.61381 -54.323401) (xy 66.643298 -54.277519) (xy 66.679015 -54.236301) (xy 66.720235 -54.200586)
			(xy 66.766119 -54.1711) (xy 66.815732 -54.148445) (xy 66.868064 -54.133081) (xy 66.92205 -54.125322)
			(xy 66.94932 -54.12486) (xy 67.83832 -54.12486) (xy 67.86559 -54.125304) (xy 67.919575 -54.133068)
			(xy 67.971905 -54.148436) (xy 68.021515 -54.171095) (xy 68.067396 -54.200583) (xy 68.108614 -54.2363)
			(xy 68.144329 -54.27752) (xy 68.173815 -54.323402) (xy 68.196471 -54.373014) (xy 68.211836 -54.425345)
			(xy 68.219598 -54.47933) (xy 68.219598 -54.53387) (xy 68.211836 -54.587855) (xy 68.196471 -54.640186)
			(xy 68.173815 -54.689798) (xy 68.144329 -54.73568) (xy 68.108614 -54.7769) (xy 68.067396 -54.812617)
			(xy 68.021515 -54.842105) (xy 67.971905 -54.864764) (xy 67.919575 -54.880132) (xy 67.86559 -54.887896)
			(xy 67.83832 -54.888384) (xy 66.94932 -54.888384) (xy 66.92205 -54.887878) (xy 66.868064 -54.880119)
			(xy 66.815732 -54.864755) (xy 66.766119 -54.8421) (xy 66.720235 -54.812614) (xy 66.679015 -54.776899)
			(xy 66.643298 -54.735681) (xy 66.61381 -54.689799) (xy 66.591152 -54.640187) (xy 66.575786 -54.587856)
			(xy 66.568023 -54.53387) (xy 0.509016 -54.53387) (xy 0.509016 -58.166508) (xy 60.959492 -58.166508)
			(xy 60.959492 -57.366662) (xy 60.959966 -57.340674) (xy 60.968103 -57.289338) (xy 60.984169 -57.239907)
			(xy 61.007769 -57.193597) (xy 61.038323 -57.15155) (xy 61.075078 -57.114799) (xy 61.11713 -57.08425)
			(xy 61.163442 -57.060654) (xy 61.212875 -57.044594) (xy 61.264212 -57.036464) (xy 61.2902 -57.035954)
			(xy 61.317668 -57.036479) (xy 61.371851 -57.04555) (xy 61.423791 -57.063444) (xy 61.472065 -57.089668)
			(xy 61.515345 -57.123503) (xy 61.534294 -57.143396) (xy 61.55212 -57.162087) (xy 61.582322 -57.203984)
			(xy 61.605643 -57.250068) (xy 61.621515 -57.299217) (xy 61.629551 -57.350236) (xy 61.630052 -57.37606)
			(xy 61.629773 -57.39555) (xy 61.625189 -57.43426) (xy 61.620908 -57.453276) (xy 61.620908 -58.166508)
			(xy 61.620398 -58.192491) (xy 63.359983 -58.192491) (xy 63.359983 -58.140509) (xy 63.368116 -58.089167)
			(xy 63.38418 -58.03973) (xy 63.407782 -57.993415) (xy 63.438338 -57.951362) (xy 63.475097 -57.914608)
			(xy 63.517154 -57.884058) (xy 63.563473 -57.860463) (xy 63.612912 -57.844405) (xy 63.664255 -57.83628)
			(xy 63.690246 -57.8358) (xy 64.490092 -57.8358) (xy 64.516082 -57.836267) (xy 64.567423 -57.844397)
			(xy 64.61686 -57.860459) (xy 64.663175 -57.884057) (xy 64.705229 -57.91461) (xy 64.741985 -57.951365)
			(xy 64.772539 -57.993418) (xy 64.796138 -58.039733) (xy 64.812201 -58.089169) (xy 64.820333 -58.14051)
			(xy 64.820333 -58.19249) (xy 64.812201 -58.243831) (xy 64.796138 -58.293267) (xy 64.772539 -58.339582)
			(xy 64.741985 -58.381635) (xy 64.705229 -58.41839) (xy 64.663175 -58.448943) (xy 64.61686 -58.472541)
			(xy 64.567423 -58.488603) (xy 64.516082 -58.496733) (xy 64.490092 -58.497216) (xy 63.690246 -58.497216)
			(xy 63.664255 -58.49672) (xy 63.612912 -58.488595) (xy 63.563473 -58.472537) (xy 63.517154 -58.448942)
			(xy 63.475097 -58.418392) (xy 63.438338 -58.381638) (xy 63.407782 -58.339585) (xy 63.38418 -58.29327)
			(xy 63.368116 -58.243833) (xy 63.359983 -58.192491) (xy 61.620398 -58.192491) (xy 61.620398 -58.192495)
			(xy 61.612268 -58.24383) (xy 61.596207 -58.29326) (xy 61.572611 -58.33957) (xy 61.542061 -58.381618)
			(xy 61.50531 -58.418369) (xy 61.463262 -58.448919) (xy 61.416952 -58.472515) (xy 61.367522 -58.488576)
			(xy 61.316187 -58.496706) (xy 61.264213 -58.496706) (xy 61.212878 -58.488576) (xy 61.163448 -58.472515)
			(xy 61.117138 -58.448919) (xy 61.07509 -58.418369) (xy 61.038339 -58.381618) (xy 61.007789 -58.33957)
			(xy 60.984193 -58.29326) (xy 60.968132 -58.24383) (xy 60.960002 -58.192495) (xy 60.959492 -58.166508)
			(xy 0.509016 -58.166508) (xy 0.509016 -58.992411) (xy 61.759802 -58.992411) (xy 61.759802 -58.940389)
			(xy 61.76794 -58.889008) (xy 61.784015 -58.839533) (xy 61.807633 -58.793181) (xy 61.83821 -58.751095)
			(xy 61.874995 -58.71431) (xy 61.917081 -58.683733) (xy 61.963433 -58.660115) (xy 62.012908 -58.64404)
			(xy 62.064289 -58.635902) (xy 62.0903 -58.635392) (xy 62.890146 -58.635392) (xy 62.916147 -58.635998)
			(xy 62.967508 -58.644139) (xy 63.016964 -58.660214) (xy 63.063296 -58.683827) (xy 63.105364 -58.714397)
			(xy 63.142133 -58.751171) (xy 63.172697 -58.793243) (xy 63.196303 -58.839579) (xy 63.212372 -58.889036)
			(xy 63.220506 -58.940399) (xy 63.220506 -58.992401) (xy 63.220505 -58.99241) (xy 64.159602 -58.99241)
			(xy 64.159602 -58.94039) (xy 64.16774 -58.889009) (xy 64.183815 -58.839535) (xy 64.207431 -58.793184)
			(xy 64.238008 -58.751098) (xy 64.274792 -58.714313) (xy 64.316877 -58.683735) (xy 64.363227 -58.660118)
			(xy 64.412702 -58.644042) (xy 64.464082 -58.635903) (xy 64.490092 -58.635392) (xy 65.289938 -58.635392)
			(xy 65.31594 -58.635997) (xy 65.367302 -58.644137) (xy 65.416758 -58.660212) (xy 65.463091 -58.683825)
			(xy 65.505161 -58.714394) (xy 65.541931 -58.751168) (xy 65.572495 -58.793241) (xy 65.596103 -58.839577)
			(xy 65.612171 -58.889035) (xy 65.620306 -58.940398) (xy 65.620306 -58.992402) (xy 65.612171 -59.043765)
			(xy 65.596103 -59.093223) (xy 65.572495 -59.139559) (xy 65.541931 -59.181632) (xy 65.505161 -59.218406)
			(xy 65.463091 -59.248975) (xy 65.416758 -59.272588) (xy 65.367302 -59.288663) (xy 65.31594 -59.296803)
			(xy 65.289938 -59.297316) (xy 64.490092 -59.297316) (xy 64.464082 -59.296897) (xy 64.412702 -59.288758)
			(xy 64.363227 -59.272682) (xy 64.316877 -59.249065) (xy 64.274792 -59.218487) (xy 64.238008 -59.181702)
			(xy 64.207431 -59.139616) (xy 64.183815 -59.093265) (xy 64.16774 -59.043791) (xy 64.159602 -58.99241)
			(xy 63.220505 -58.99241) (xy 63.212372 -59.043763) (xy 63.196303 -59.093221) (xy 63.172697 -59.139557)
			(xy 63.142133 -59.181629) (xy 63.105364 -59.218403) (xy 63.063296 -59.248973) (xy 63.016964 -59.272586)
			(xy 62.967508 -59.288661) (xy 62.916147 -59.296802) (xy 62.890146 -59.297316) (xy 62.0903 -59.297316)
			(xy 62.064289 -59.296898) (xy 62.012908 -59.28876) (xy 61.963433 -59.272685) (xy 61.917081 -59.249067)
			(xy 61.874995 -59.21849) (xy 61.83821 -59.181705) (xy 61.807633 -59.139619) (xy 61.784015 -59.093267)
			(xy 61.76794 -59.043792) (xy 61.759802 -58.992411) (xy 0.509016 -58.992411) (xy 0.509016 -59.792515)
			(xy 63.359676 -59.792515) (xy 63.359676 -59.740485) (xy 63.367816 -59.689095) (xy 63.383895 -59.639612)
			(xy 63.407519 -59.593254) (xy 63.438104 -59.551162) (xy 63.474897 -59.514374) (xy 63.516993 -59.483794)
			(xy 63.563355 -59.460178) (xy 63.61284 -59.444105) (xy 63.664231 -59.435972) (xy 63.690246 -59.435492)
			(xy 64.490092 -59.435492) (xy 64.516098 -59.436067) (xy 64.56747 -59.444202) (xy 64.616937 -59.460274)
			(xy 64.66328 -59.483886) (xy 64.705359 -59.514457) (xy 64.742138 -59.551235) (xy 64.77271 -59.593313)
			(xy 64.796323 -59.639656) (xy 64.812396 -59.689122) (xy 64.820533 -59.740494) (xy 64.820533 -59.792506)
			(xy 64.812396 -59.843878) (xy 64.796323 -59.893344) (xy 64.77271 -59.939687) (xy 64.742138 -59.981765)
			(xy 64.705359 -60.018543) (xy 64.66328 -60.049114) (xy 64.616937 -60.072726) (xy 64.56747 -60.088798)
			(xy 64.516098 -60.096933) (xy 64.490092 -60.097416) (xy 63.690246 -60.097416) (xy 63.664231 -60.097028)
			(xy 63.61284 -60.088895) (xy 63.563355 -60.072822) (xy 63.516993 -60.049206) (xy 63.474897 -60.018626)
			(xy 63.438104 -59.981838) (xy 63.407519 -59.939746) (xy 63.383895 -59.893388) (xy 63.367816 -59.843905)
			(xy 63.359676 -59.792515) (xy 0.509016 -59.792515) (xy 0.509016 -60.3494) (xy 60.569868 -60.3494)
			(xy 60.573857 -60.296174) (xy 60.585733 -60.244137) (xy 60.605233 -60.194451) (xy 60.631919 -60.148227)
			(xy 60.665197 -60.106496) (xy 60.704323 -60.07019) (xy 60.748422 -60.040121) (xy 60.796511 -60.016961)
			(xy 60.847514 -60.001226) (xy 60.900292 -59.993268) (xy 60.92698 -59.992768) (xy 60.949767 -59.993141)
			(xy 60.994967 -59.998968) (xy 61.03906 -60.010491) (xy 61.06033 -60.018676) (xy 61.555376 -60.018676)
			(xy 61.564012 -60.015374) (xy 61.594178 -60.00485) (xy 61.657039 -59.993478) (xy 61.68898 -59.992768)
			(xy 61.717333 -59.993267) (xy 61.773326 -60.002234) (xy 61.827196 -60.019945) (xy 61.877586 -60.045954)
			(xy 61.923227 -60.079606) (xy 61.943488 -60.099448) (xy 61.962622 -60.116719) (xy 61.995857 -60.156112)
			(xy 62.022581 -60.200183) (xy 62.042146 -60.247865) (xy 62.054078 -60.298005) (xy 62.058089 -60.34939)
			(xy 62.054081 -60.400774) (xy 62.042152 -60.450915) (xy 62.022591 -60.498599) (xy 61.99587 -60.542671)
			(xy 61.962636 -60.582066) (xy 61.943488 -60.59932) (xy 61.923242 -60.619175) (xy 61.877589 -60.652806)
			(xy 61.827194 -60.678797) (xy 61.773323 -60.696496) (xy 61.717332 -60.705456) (xy 61.68898 -60.706)
			(xy 61.657039 -60.705289) (xy 61.594177 -60.693921) (xy 61.564012 -60.683394) (xy 61.555376 -60.680092)
			(xy 61.06033 -60.680092) (xy 61.039069 -60.688303) (xy 60.994975 -60.699837) (xy 60.949769 -60.705644)
			(xy 60.92698 -60.706) (xy 60.900292 -60.705532) (xy 60.847514 -60.697574) (xy 60.796511 -60.681839)
			(xy 60.748422 -60.658679) (xy 60.704323 -60.62861) (xy 60.665197 -60.592304) (xy 60.631919 -60.550573)
			(xy 60.605233 -60.504349) (xy 60.585733 -60.454663) (xy 60.573857 -60.402626) (xy 60.569868 -60.3494)
			(xy 0.509016 -60.3494) (xy 0.509016 -61.539628) (xy 0.508 -61.540644) (xy 0.508 -62.988444) (xy 0.509016 -62.98946)
			(xy 0.509016 -75.635104) (xy 15.732516 -75.635104) (xy 15.736498 -75.545176) (xy 15.748412 -75.455952)
			(xy 15.768165 -75.36813) (xy 15.795602 -75.282397) (xy 15.830509 -75.199425) (xy 15.872613 -75.119862)
			(xy 15.921583 -75.044332) (xy 15.977038 -74.973426) (xy 16.038542 -74.907698) (xy 16.105614 -74.847663)
			(xy 16.17773 -74.793791) (xy 16.254325 -74.746503) (xy 16.334799 -74.70617) (xy 16.418523 -74.673107)
			(xy 16.504842 -74.647573) (xy 16.59308 -74.629768) (xy 16.682545 -74.61983) (xy 16.77254 -74.617839)
			(xy 16.862357 -74.623809) (xy 16.951296 -74.637694) (xy 17.03866 -74.659385) (xy 17.123765 -74.688712)
			(xy 17.205944 -74.725446) (xy 17.284556 -74.7693) (xy 17.358984 -74.819929) (xy 17.428646 -74.876939)
			(xy 17.492997 -74.939882) (xy 17.551534 -75.008266) (xy 17.603797 -75.081556) (xy 17.649379 -75.159178)
			(xy 17.687922 -75.240525) (xy 17.719125 -75.32496) (xy 17.742743 -75.411822) (xy 17.758592 -75.500432)
			(xy 17.766548 -75.590096) (xy 17.767046 -75.635104) (xy 35.491176 -75.635104) (xy 35.495155 -75.535091)
			(xy 35.507068 -75.43571) (xy 35.526839 -75.33759) (xy 35.554343 -75.241351) (xy 35.589406 -75.147602)
			(xy 35.631807 -75.056934) (xy 35.681278 -74.969922) (xy 35.737505 -74.887115) (xy 35.800133 -74.809038)
			(xy 35.868767 -74.736183) (xy 35.942972 -74.669011) (xy 36.02228 -74.607948) (xy 36.106188 -74.553378)
			(xy 36.194166 -74.505647) (xy 36.285659 -74.465057) (xy 36.380087 -74.431865) (xy 36.476854 -74.40628)
			(xy 36.575348 -74.388463) (xy 36.674946 -74.378529) (xy 36.775018 -74.376539) (xy 36.874932 -74.382506)
			(xy 36.974056 -74.396392) (xy 37.071764 -74.41811) (xy 37.167437 -74.447522) (xy 37.260471 -74.484443)
			(xy 37.350277 -74.528638) (xy 37.436289 -74.579828) (xy 37.517961 -74.637691) (xy 37.594778 -74.701859)
			(xy 37.666254 -74.771928) (xy 37.731937 -74.847454) (xy 37.791412 -74.92796) (xy 37.844303 -75.012936)
			(xy 37.890275 -75.101846) (xy 37.929037 -75.194128) (xy 37.960346 -75.289197) (xy 37.984002 -75.386454)
			(xy 37.999856 -75.485282) (xy 38.007809 -75.585058) (xy 38.008306 -75.635104) (xy 38.007809 -75.68515)
			(xy 37.999856 -75.784926) (xy 37.984002 -75.883754) (xy 37.960346 -75.981011) (xy 37.929037 -76.07608)
			(xy 37.890275 -76.168362) (xy 37.844303 -76.257272) (xy 37.791412 -76.342248) (xy 37.731937 -76.422754)
			(xy 37.666254 -76.49828) (xy 37.594778 -76.568349) (xy 37.517961 -76.632517) (xy 37.436289 -76.69038)
			(xy 37.350277 -76.74157) (xy 37.260471 -76.785765) (xy 37.167437 -76.822686) (xy 37.071764 -76.852098)
			(xy 36.974056 -76.873816) (xy 36.874932 -76.887702) (xy 36.775018 -76.893669) (xy 36.674946 -76.891679)
			(xy 36.575348 -76.881745) (xy 36.476854 -76.863928) (xy 36.380087 -76.838343) (xy 36.285659 -76.805151)
			(xy 36.194166 -76.764561) (xy 36.106188 -76.71683) (xy 36.02228 -76.66226) (xy 35.942972 -76.601197)
			(xy 35.868767 -76.534025) (xy 35.800133 -76.46117) (xy 35.737505 -76.383093) (xy 35.681278 -76.300286)
			(xy 35.631807 -76.213274) (xy 35.589406 -76.122606) (xy 35.554343 -76.028857) (xy 35.526839 -75.932618)
			(xy 35.507068 -75.834498) (xy 35.495155 -75.735117) (xy 35.491176 -75.635104) (xy 17.767046 -75.635104)
			(xy 17.766548 -75.680112) (xy 17.758592 -75.769776) (xy 17.742743 -75.858386) (xy 17.719125 -75.945248)
			(xy 17.687922 -76.029683) (xy 17.649379 -76.11103) (xy 17.603797 -76.188652) (xy 17.551534 -76.261942)
			(xy 17.492997 -76.330326) (xy 17.428646 -76.393269) (xy 17.358984 -76.450279) (xy 17.284556 -76.500908)
			(xy 17.205944 -76.544762) (xy 17.123765 -76.581496) (xy 17.03866 -76.610823) (xy 16.951296 -76.632514)
			(xy 16.862357 -76.646399) (xy 16.77254 -76.652369) (xy 16.682545 -76.650378) (xy 16.59308 -76.64044)
			(xy 16.504842 -76.622635) (xy 16.418523 -76.597101) (xy 16.334799 -76.564038) (xy 16.254325 -76.523705)
			(xy 16.17773 -76.476417) (xy 16.105614 -76.422545) (xy 16.038542 -76.36251) (xy 15.977038 -76.296782)
			(xy 15.921583 -76.225876) (xy 15.872613 -76.150346) (xy 15.830509 -76.070783) (xy 15.795602 -75.987811)
			(xy 15.768165 -75.902078) (xy 15.748412 -75.814256) (xy 15.736498 -75.725032) (xy 15.732516 -75.635104)
			(xy 0.509016 -75.635104) (xy 0.509016 -80.990948) (xy 2.249932 -80.990948) (xy 2.293971 -80.991429)
			(xy 2.381714 -80.999105) (xy 2.468454 -81.0144) (xy 2.553531 -81.037196) (xy 2.636297 -81.067321)
			(xy 2.716123 -81.104545) (xy 2.792401 -81.148584) (xy 2.86455 -81.199103) (xy 2.932022 -81.255719)
			(xy 2.994302 -81.318) (xy 3.050918 -81.385471) (xy 3.101437 -81.457621) (xy 3.145476 -81.533899)
			(xy 3.1827 -81.613725) (xy 3.212824 -81.696491) (xy 3.23562 -81.781568) (xy 3.250915 -81.868308)
			(xy 3.258592 -81.956051) (xy 3.259074 -82.00009) (xy 3.259074 -84.499958) (xy 3.258594 -84.543997)
			(xy 3.250917 -84.63174) (xy 3.235623 -84.718481) (xy 3.212827 -84.803558) (xy 3.182702 -84.886325)
			(xy 3.145479 -84.966151) (xy 3.10144 -85.042429) (xy 3.05092 -85.114579) (xy 2.994305 -85.182051)
			(xy 2.932024 -85.244332) (xy 2.864552 -85.300948) (xy 2.792403 -85.351468) (xy 2.716124 -85.395507)
			(xy 2.636298 -85.432731) (xy 2.553532 -85.462855) (xy 2.468455 -85.485652) (xy 2.381714 -85.500947)
			(xy 2.293971 -85.508623) (xy 2.249932 -85.5091) (xy 0.509016 -85.5091) (xy 0.509016 -97.978249) (xy 45.046914 -97.978249)
			(xy 45.046914 -97.923751) (xy 45.05467 -97.869809) (xy 45.070024 -97.817519) (xy 45.092663 -97.767947)
			(xy 45.122126 -97.722101) (xy 45.157814 -97.680914) (xy 45.199001 -97.645226) (xy 45.244847 -97.615763)
			(xy 45.294419 -97.593124) (xy 45.346709 -97.57777) (xy 45.400651 -97.570014) (xy 45.4279 -97.569528)
			(xy 46.3169 -97.569528) (xy 46.344154 -97.569942) (xy 46.398107 -97.577699) (xy 46.450406 -97.593056)
			(xy 46.499988 -97.615699) (xy 46.545843 -97.645168) (xy 46.587037 -97.680863) (xy 46.622732 -97.722057)
			(xy 46.652201 -97.767912) (xy 46.674844 -97.817494) (xy 46.690201 -97.869793) (xy 46.697958 -97.923746)
			(xy 46.697958 -97.978254) (xy 46.690201 -98.032207) (xy 46.674844 -98.084506) (xy 46.652201 -98.134088)
			(xy 46.622732 -98.179943) (xy 46.587037 -98.221137) (xy 46.545843 -98.256832) (xy 46.499988 -98.286301)
			(xy 46.450406 -98.308944) (xy 46.398107 -98.324301) (xy 46.344154 -98.332058) (xy 46.3169 -98.332544)
			(xy 45.4279 -98.332544) (xy 45.400651 -98.331986) (xy 45.346709 -98.32423) (xy 45.294419 -98.308876)
			(xy 45.244847 -98.286237) (xy 45.199001 -98.256774) (xy 45.157814 -98.221086) (xy 45.122126 -98.179899)
			(xy 45.092663 -98.134053) (xy 45.070024 -98.084481) (xy 45.05467 -98.032191) (xy 45.046914 -97.978249)
			(xy 0.509016 -97.978249) (xy 0.509016 -98.410049) (xy 40.017714 -98.410049) (xy 40.017714 -98.355551)
			(xy 40.02547 -98.301609) (xy 40.040824 -98.249319) (xy 40.063463 -98.199747) (xy 40.092926 -98.153901)
			(xy 40.128614 -98.112714) (xy 40.169801 -98.077026) (xy 40.215647 -98.047563) (xy 40.265219 -98.024924)
			(xy 40.317509 -98.00957) (xy 40.371451 -98.001814) (xy 40.3987 -98.001328) (xy 41.2877 -98.001328)
			(xy 41.314954 -98.001742) (xy 41.368907 -98.009499) (xy 41.421206 -98.024856) (xy 41.470788 -98.047499)
			(xy 41.516643 -98.076968) (xy 41.557837 -98.112663) (xy 41.593532 -98.153857) (xy 41.623001 -98.199712)
			(xy 41.645644 -98.249294) (xy 41.661001 -98.301593) (xy 41.668758 -98.355546) (xy 41.668758 -98.410054)
			(xy 41.661001 -98.464007) (xy 41.645644 -98.516306) (xy 41.623001 -98.565888) (xy 41.593532 -98.611743)
			(xy 41.557837 -98.652937) (xy 41.516643 -98.688632) (xy 41.470788 -98.718101) (xy 41.421206 -98.740744)
			(xy 41.368907 -98.756101) (xy 41.314954 -98.763858) (xy 41.2877 -98.764344) (xy 40.3987 -98.764344)
			(xy 40.371451 -98.763786) (xy 40.317509 -98.75603) (xy 40.265219 -98.740676) (xy 40.215647 -98.718037)
			(xy 40.169801 -98.688574) (xy 40.128614 -98.652886) (xy 40.092926 -98.611699) (xy 40.063463 -98.565853)
			(xy 40.040824 -98.516281) (xy 40.02547 -98.463991) (xy 40.017714 -98.410049) (xy 0.509016 -98.410049)
			(xy 0.509016 -104.205349) (xy 54.921178 -104.205349) (xy 54.921178 -104.150851) (xy 54.928933 -104.096908)
			(xy 54.944285 -104.044617) (xy 54.966923 -103.995043) (xy 54.996385 -103.949195) (xy 55.032071 -103.908006)
			(xy 55.073255 -103.872315) (xy 55.119099 -103.842847) (xy 55.16867 -103.820203) (xy 55.220959 -103.804843)
			(xy 55.274901 -103.797081) (xy 55.30215 -103.796592) (xy 56.19115 -103.796592) (xy 56.218405 -103.797052)
			(xy 56.272362 -103.804803) (xy 56.324665 -103.820155) (xy 56.374252 -103.842794) (xy 56.420111 -103.872261)
			(xy 56.46131 -103.907955) (xy 56.497009 -103.949149) (xy 56.526482 -103.995004) (xy 56.549128 -104.044588)
			(xy 56.564486 -104.09689) (xy 56.572245 -104.150845) (xy 56.572245 -104.205355) (xy 56.564486 -104.25931)
			(xy 56.549128 -104.311612) (xy 56.526482 -104.361196) (xy 56.497009 -104.407051) (xy 56.46131 -104.448245)
			(xy 56.420111 -104.483939) (xy 56.374252 -104.513406) (xy 56.324665 -104.536045) (xy 56.272362 -104.551397)
			(xy 56.218405 -104.559148) (xy 56.19115 -104.559608) (xy 55.30215 -104.559608) (xy 55.274901 -104.559119)
			(xy 55.220959 -104.551357) (xy 55.16867 -104.535997) (xy 55.119099 -104.513353) (xy 55.073255 -104.483885)
			(xy 55.032071 -104.448194) (xy 54.996385 -104.407005) (xy 54.966923 -104.361157) (xy 54.944285 -104.311583)
			(xy 54.928933 -104.259292) (xy 54.921178 -104.205349) (xy 0.509016 -104.205349) (xy 0.509016 -107.774051)
			(xy 13.017478 -107.774051) (xy 13.017478 -107.719549) (xy 13.025234 -107.665601) (xy 13.040589 -107.613306)
			(xy 13.063231 -107.563729) (xy 13.092697 -107.517879) (xy 13.128388 -107.476688) (xy 13.169579 -107.440997)
			(xy 13.215429 -107.411531) (xy 13.265006 -107.388889) (xy 13.317301 -107.373534) (xy 13.371249 -107.365778)
			(xy 13.3985 -107.365292) (xy 14.2875 -107.365292) (xy 14.314751 -107.365778) (xy 14.368699 -107.373534)
			(xy 14.420994 -107.388889) (xy 14.470571 -107.411531) (xy 14.516421 -107.440997) (xy 14.557612 -107.476688)
			(xy 14.593303 -107.517879) (xy 14.622769 -107.563729) (xy 14.645411 -107.613306) (xy 14.660766 -107.665601)
			(xy 14.668522 -107.719549) (xy 14.668522 -107.77382) (xy 17.94482 -107.77382) (xy 17.94482 -107.71928)
			(xy 17.952582 -107.665296) (xy 17.967948 -107.612966) (xy 17.990604 -107.563355) (xy 18.02009 -107.517474)
			(xy 18.055806 -107.476256) (xy 18.097024 -107.44054) (xy 18.142905 -107.411054) (xy 18.192516 -107.388398)
			(xy 18.244846 -107.373032) (xy 18.29883 -107.36527) (xy 18.3261 -107.364784) (xy 19.2151 -107.364784)
			(xy 19.242369 -107.365278) (xy 19.296352 -107.37304) (xy 19.348681 -107.388405) (xy 19.398291 -107.411061)
			(xy 19.444171 -107.440547) (xy 19.485388 -107.476262) (xy 19.521103 -107.517479) (xy 19.550589 -107.563359)
			(xy 19.573245 -107.612969) (xy 19.58861 -107.665298) (xy 19.596372 -107.719281) (xy 19.596372 -107.773819)
			(xy 19.58861 -107.827802) (xy 19.573245 -107.880131) (xy 19.550589 -107.929741) (xy 19.521103 -107.975621)
			(xy 19.485388 -108.016838) (xy 19.444171 -108.052553) (xy 19.398291 -108.082039) (xy 19.348681 -108.104695)
			(xy 19.296352 -108.12006) (xy 19.242369 -108.127822) (xy 19.2151 -108.128308) (xy 18.3261 -108.128308)
			(xy 18.29883 -108.12783) (xy 18.244846 -108.120068) (xy 18.192516 -108.104702) (xy 18.142905 -108.082046)
			(xy 18.097024 -108.05256) (xy 18.055806 -108.016844) (xy 18.02009 -107.975626) (xy 17.990604 -107.929745)
			(xy 17.967948 -107.880134) (xy 17.952582 -107.827804) (xy 17.94482 -107.77382) (xy 14.668522 -107.77382)
			(xy 14.668522 -107.774051) (xy 14.660766 -107.827999) (xy 14.645411 -107.880294) (xy 14.622769 -107.929871)
			(xy 14.593303 -107.975721) (xy 14.557612 -108.016912) (xy 14.516421 -108.052603) (xy 14.470571 -108.082069)
			(xy 14.420994 -108.104711) (xy 14.368699 -108.120066) (xy 14.314751 -108.127822) (xy 14.2875 -108.128308)
			(xy 13.3985 -108.128308) (xy 13.371249 -108.127822) (xy 13.317301 -108.120066) (xy 13.265006 -108.104711)
			(xy 13.215429 -108.082069) (xy 13.169579 -108.052603) (xy 13.128388 -108.016912) (xy 13.092697 -107.975721)
			(xy 13.063231 -107.929871) (xy 13.040589 -107.880294) (xy 13.025234 -107.827999) (xy 13.017478 -107.774051)
			(xy 0.509016 -107.774051) (xy 0.509016 -109.570609) (xy 15.016716 -109.570609) (xy 15.016716 -109.516071)
			(xy 15.024478 -109.462088) (xy 15.039843 -109.409759) (xy 15.062499 -109.360149) (xy 15.091985 -109.314268)
			(xy 15.127699 -109.273051) (xy 15.168917 -109.237336) (xy 15.214797 -109.20785) (xy 15.264407 -109.185194)
			(xy 15.316736 -109.169828) (xy 15.370719 -109.162067) (xy 15.397988 -109.16158) (xy 16.286988 -109.16158)
			(xy 16.314259 -109.162039) (xy 16.368247 -109.169801) (xy 16.42058 -109.185167) (xy 16.470193 -109.207825)
			(xy 16.516078 -109.237313) (xy 16.557298 -109.27303) (xy 16.593016 -109.314251) (xy 16.622504 -109.360135)
			(xy 16.645162 -109.409748) (xy 16.660528 -109.462081) (xy 16.668291 -109.516069) (xy 16.668291 -109.570611)
			(xy 16.660528 -109.624599) (xy 16.645162 -109.676932) (xy 16.622504 -109.726545) (xy 16.593016 -109.772429)
			(xy 16.557298 -109.81365) (xy 16.516078 -109.849367) (xy 16.470193 -109.878855) (xy 16.42058 -109.901513)
			(xy 16.368247 -109.916879) (xy 16.314259 -109.924641) (xy 16.286988 -109.925104) (xy 15.397988 -109.925104)
			(xy 15.370719 -109.924613) (xy 15.316736 -109.916852) (xy 15.264407 -109.901486) (xy 15.214797 -109.87883)
			(xy 15.168917 -109.849344) (xy 15.127699 -109.813629) (xy 15.091985 -109.772412) (xy 15.062499 -109.726531)
			(xy 15.039843 -109.676921) (xy 15.024478 -109.624592) (xy 15.016716 -109.570609) (xy 0.509016 -109.570609)
			(xy 0.509016 -109.998056) (xy 84.426541 -109.998056) (xy 84.426541 -109.868916) (xy 84.434491 -109.740021)
			(xy 84.450361 -109.611861) (xy 84.47409 -109.48492) (xy 84.505589 -109.359681) (xy 84.544738 -109.236618)
			(xy 84.591389 -109.116199) (xy 84.645364 -108.99888) (xy 84.706459 -108.885106) (xy 84.774442 -108.775309)
			(xy 84.849056 -108.669906) (xy 84.930017 -108.569296) (xy 85.017017 -108.473861) (xy 85.109728 -108.383962)
			(xy 85.207798 -108.299941) (xy 85.310853 -108.222117) (xy 85.418504 -108.150785) (xy 85.530343 -108.086215)
			(xy 85.645944 -108.028653) (xy 85.764869 -107.978316) (xy 85.886668 -107.935396) (xy 86.010878 -107.900055)
			(xy 86.137027 -107.872428) (xy 86.264639 -107.852619) (xy 86.393228 -107.840703) (xy 86.522306 -107.836727)
			(xy 86.651384 -107.840703) (xy 86.779973 -107.852619) (xy 86.907585 -107.872428) (xy 87.033734 -107.900055)
			(xy 87.157944 -107.935396) (xy 87.279743 -107.978316) (xy 87.398668 -108.028653) (xy 87.514269 -108.086215)
			(xy 87.626108 -108.150785) (xy 87.733759 -108.222117) (xy 87.836814 -108.299941) (xy 87.934884 -108.383962)
			(xy 88.027595 -108.473861) (xy 88.114595 -108.569296) (xy 88.195556 -108.669906) (xy 88.27017 -108.775309)
			(xy 88.338153 -108.885106) (xy 88.399248 -108.99888) (xy 88.453223 -109.116199) (xy 88.499874 -109.236618)
			(xy 88.539023 -109.359681) (xy 88.570522 -109.48492) (xy 88.594251 -109.611861) (xy 88.610121 -109.740021)
			(xy 88.618071 -109.868916) (xy 88.618568 -109.933486) (xy 88.618071 -109.998056) (xy 88.610121 -110.126951)
			(xy 88.594251 -110.255111) (xy 88.570522 -110.382052) (xy 88.539023 -110.507291) (xy 88.499874 -110.630354)
			(xy 88.453223 -110.750773) (xy 88.399248 -110.868092) (xy 88.338153 -110.981866) (xy 88.27017 -111.091663)
			(xy 88.195556 -111.197066) (xy 88.114595 -111.297676) (xy 88.027595 -111.393111) (xy 87.934884 -111.48301)
			(xy 87.836814 -111.567031) (xy 87.733759 -111.644855) (xy 87.626108 -111.716187) (xy 87.514269 -111.780757)
			(xy 87.398668 -111.838319) (xy 87.279743 -111.888656) (xy 87.157944 -111.931576) (xy 87.033734 -111.966917)
			(xy 86.907585 -111.994544) (xy 86.779973 -112.014353) (xy 86.651384 -112.026269) (xy 86.522306 -112.030246)
			(xy 86.393228 -112.026269) (xy 86.264639 -112.014353) (xy 86.137027 -111.994544) (xy 86.010878 -111.966917)
			(xy 85.886668 -111.931576) (xy 85.764869 -111.888656) (xy 85.645944 -111.838319) (xy 85.530343 -111.780757)
			(xy 85.418504 -111.716187) (xy 85.310853 -111.644855) (xy 85.207798 -111.567031) (xy 85.109728 -111.48301)
			(xy 85.017017 -111.393111) (xy 84.930017 -111.297676) (xy 84.849056 -111.197066) (xy 84.774442 -111.091663)
			(xy 84.706459 -110.981866) (xy 84.645364 -110.868092) (xy 84.591389 -110.750773) (xy 84.544738 -110.630354)
			(xy 84.505589 -110.507291) (xy 84.47409 -110.382052) (xy 84.450361 -110.255111) (xy 84.434491 -110.126951)
			(xy 84.426541 -109.998056) (xy 0.509016 -109.998056) (xy 0.509016 -112.300004) (xy 0.509494 -112.35115)
			(xy 53.778158 -112.35115) (xy 53.778158 -112.29665) (xy 53.785913 -112.242703) (xy 53.801267 -112.19041)
			(xy 53.823905 -112.140833) (xy 53.853369 -112.094983) (xy 53.889057 -112.053792) (xy 53.930243 -112.018099)
			(xy 53.976089 -111.988629) (xy 54.025663 -111.965984) (xy 54.077955 -111.950624) (xy 54.1319 -111.942861)
			(xy 54.15915 -111.942372) (xy 55.04815 -111.942372) (xy 55.075404 -111.942872) (xy 55.129357 -111.950623)
			(xy 55.181658 -111.965974) (xy 55.231242 -111.988612) (xy 55.277099 -112.018077) (xy 55.318296 -112.053769)
			(xy 55.353993 -112.094961) (xy 55.383464 -112.140814) (xy 55.406109 -112.190395) (xy 55.421467 -112.242694)
			(xy 55.429225 -112.296646) (xy 55.429225 -112.351154) (xy 55.421467 -112.405106) (xy 55.406109 -112.457405)
			(xy 55.383464 -112.506986) (xy 55.353993 -112.552839) (xy 55.318296 -112.594031) (xy 55.277099 -112.629723)
			(xy 55.231242 -112.659188) (xy 55.181658 -112.681826) (xy 55.129357 -112.697177) (xy 55.075404 -112.704928)
			(xy 55.04815 -112.705388) (xy 54.15915 -112.705388) (xy 54.1319 -112.704939) (xy 54.077955 -112.697176)
			(xy 54.025663 -112.681816) (xy 53.976089 -112.659171) (xy 53.930243 -112.629701) (xy 53.889057 -112.594008)
			(xy 53.853369 -112.552817) (xy 53.823905 -112.506967) (xy 53.801267 -112.45739) (xy 53.785913 -112.405097)
			(xy 53.778158 -112.35115) (xy 0.509494 -112.35115) (xy 0.509537 -112.355773) (xy 0.517873 -112.466999)
			(xy 0.534497 -112.577291) (xy 0.559316 -112.686033) (xy 0.592193 -112.792616) (xy 0.632942 -112.896444)
			(xy 0.681337 -112.996936) (xy 0.737106 -113.093531) (xy 0.796039 -113.17997) (xy 23.969706 -113.17997)
			(xy 23.969706 -113.12543) (xy 23.977468 -113.071446) (xy 23.992833 -113.019115) (xy 24.015489 -112.969504)
			(xy 24.044974 -112.923622) (xy 24.080689 -112.882403) (xy 24.121906 -112.846686) (xy 24.167787 -112.817198)
			(xy 24.217397 -112.79454) (xy 24.269726 -112.779172) (xy 24.32371 -112.771408) (xy 24.35098 -112.77092)
			(xy 25.23998 -112.77092) (xy 25.267251 -112.771418) (xy 25.321237 -112.779178) (xy 25.37357 -112.794541)
			(xy 25.423183 -112.817197) (xy 25.469067 -112.846682) (xy 25.510288 -112.882398) (xy 25.546006 -112.923617)
			(xy 25.575494 -112.969499) (xy 25.598152 -113.019111) (xy 25.613518 -113.071443) (xy 25.62128 -113.125429)
			(xy 25.62128 -113.179971) (xy 25.613518 -113.233957) (xy 25.598152 -113.286289) (xy 25.575494 -113.335901)
			(xy 25.546006 -113.381783) (xy 25.510288 -113.423002) (xy 25.469067 -113.458718) (xy 25.423183 -113.488203)
			(xy 25.37357 -113.510859) (xy 25.321237 -113.526222) (xy 25.267251 -113.533982) (xy 25.23998 -113.534444)
			(xy 24.35098 -113.534444) (xy 24.32371 -113.533992) (xy 24.269726 -113.526228) (xy 24.217397 -113.51086)
			(xy 24.167787 -113.488202) (xy 24.121906 -113.458714) (xy 24.080689 -113.422997) (xy 24.044974 -113.381778)
			(xy 24.015489 -113.335896) (xy 23.992833 -113.286285) (xy 23.977468 -113.233954) (xy 23.969706 -113.17997)
			(xy 0.796039 -113.17997) (xy 0.799937 -113.185688) (xy 0.86948 -113.272892) (xy 0.945345 -113.354655)
			(xy 1.027108 -113.43052) (xy 1.114312 -113.500063) (xy 1.206469 -113.562894) (xy 1.303064 -113.618663)
			(xy 1.403556 -113.667058) (xy 1.507384 -113.707807) (xy 1.613967 -113.740684) (xy 1.722709 -113.765503)
			(xy 1.833001 -113.782127) (xy 1.944227 -113.790463) (xy 1.999996 -113.790984) (xy 4.500118 -113.790984)
			(xy 4.544143 -113.791475) (xy 4.631856 -113.799169) (xy 4.718565 -113.814476) (xy 4.803611 -113.83728)
			(xy 4.886347 -113.867406) (xy 4.966143 -113.904627) (xy 5.042392 -113.948658) (xy 5.114516 -113.999166)
			(xy 5.181964 -114.055765) (xy 5.244225 -114.118026) (xy 5.300824 -114.185474) (xy 5.351332 -114.257598)
			(xy 5.395363 -114.333847) (xy 5.432584 -114.413643) (xy 5.46271 -114.496379) (xy 5.485514 -114.581425)
			(xy 5.500821 -114.668134) (xy 5.508515 -114.755847) (xy 5.509006 -114.799872) (xy 5.509006 -118.711726)
			(xy 5.621528 -118.824248) (xy 5.936488 -118.824248) (xy 6.040374 -118.720616) (xy 9.704578 -118.720616)
			(xy 9.862312 -118.878096) (xy 10.162286 -118.878096)
		)
		(stroke
			(width 0)
			(type solid)
		)
		(fill yes)
		(layer "In3.Cu")
		(net "GND")
	)
	(gr_poly
		(pts
			(xy 121.000012 -119.892064) (xy 121.055819 -119.891554) (xy 121.16712 -119.883212) (xy 121.277487 -119.866576)
			(xy 121.386302 -119.841739) (xy 121.492956 -119.808839) (xy 121.596854 -119.768061) (xy 121.697414 -119.719632)
			(xy 121.794073 -119.663824) (xy 121.886292 -119.600949) (xy 121.973554 -119.531358) (xy 122.055371 -119.45544)
			(xy 122.131287 -119.373621) (xy 122.200875 -119.286356) (xy 122.263748 -119.194136) (xy 122.319553 -119.097475)
			(xy 122.367978 -118.996914) (xy 122.408754 -118.893015) (xy 122.44165 -118.786359) (xy 122.466484 -118.677544)
			(xy 122.483117 -118.567176) (xy 122.491456 -118.455875) (xy 122.492008 -118.400068) (xy 122.492008 129.499868)
			(xy 122.4915 129.555676) (xy 122.483161 129.666981) (xy 122.466528 129.777352) (xy 122.441693 129.886171)
			(xy 122.408795 129.992829) (xy 122.368019 130.096731) (xy 122.319592 130.197295) (xy 122.263785 130.293959)
			(xy 122.200911 130.386183) (xy 122.13132 130.473449) (xy 122.055402 130.555271) (xy 121.973583 130.631191)
			(xy 121.886318 130.700784) (xy 121.794097 130.763662) (xy 121.697434 130.819471) (xy 121.596872 130.867901)
			(xy 121.492971 130.908681) (xy 121.386313 130.941581) (xy 121.277495 130.96642) (xy 121.167125 130.983056)
			(xy 121.05582 130.991398) (xy 121.000012 130.991864) (xy 94.000066 130.991864) (xy 93.94426 130.991341)
			(xy 93.832961 130.982998) (xy 93.722596 130.96636) (xy 93.613784 130.941522) (xy 93.507131 130.908622)
			(xy 93.403236 130.867843) (xy 93.302679 130.819414) (xy 93.206021 130.763606) (xy 93.113805 130.700731)
			(xy 93.026545 130.631141) (xy 92.94473 130.555224) (xy 92.868816 130.473405) (xy 92.79923 130.386142)
			(xy 92.736359 130.293923) (xy 92.680555 130.197263) (xy 92.632131 130.096703) (xy 92.591357 129.992806)
			(xy 92.558461 129.886153) (xy 92.533627 129.777339) (xy 92.516995 129.666973) (xy 92.508656 129.555674)
			(xy 92.50807 129.499868) (xy 92.50807 126.435304) (xy 115.904253 126.435304) (xy 115.904253 126.564444)
			(xy 115.912203 126.693339) (xy 115.928073 126.821499) (xy 115.951802 126.94844) (xy 115.983301 127.073679)
			(xy 116.02245 127.196742) (xy 116.069101 127.317161) (xy 116.123076 127.43448) (xy 116.184171 127.548254)
			(xy 116.252154 127.658051) (xy 116.326768 127.763454) (xy 116.407729 127.864064) (xy 116.494729 127.959499)
			(xy 116.58744 128.049398) (xy 116.68551 128.133419) (xy 116.788565 128.211243) (xy 116.896216 128.282575)
			(xy 117.008055 128.347145) (xy 117.123656 128.404707) (xy 117.242581 128.455044) (xy 117.36438 128.497964)
			(xy 117.48859 128.533305) (xy 117.614739 128.560932) (xy 117.742351 128.580741) (xy 117.87094 128.592657)
			(xy 118.000018 128.596634) (xy 118.129096 128.592657) (xy 118.257685 128.580741) (xy 118.385297 128.560932)
			(xy 118.511446 128.533305) (xy 118.635656 128.497964) (xy 118.757455 128.455044) (xy 118.87638 128.404707)
			(xy 118.991981 128.347145) (xy 119.10382 128.282575) (xy 119.211471 128.211243) (xy 119.314526 128.133419)
			(xy 119.412596 128.049398) (xy 119.505307 127.959499) (xy 119.592307 127.864064) (xy 119.673268 127.763454)
			(xy 119.747882 127.658051) (xy 119.815865 127.548254) (xy 119.87696 127.43448) (xy 119.930935 127.317161)
			(xy 119.977586 127.196742) (xy 120.016735 127.073679) (xy 120.048234 126.94844) (xy 120.071963 126.821499)
			(xy 120.087833 126.693339) (xy 120.095783 126.564444) (xy 120.09628 126.499874) (xy 120.095783 126.435304)
			(xy 120.087833 126.306409) (xy 120.071963 126.178249) (xy 120.048234 126.051308) (xy 120.016735 125.926069)
			(xy 119.977586 125.803006) (xy 119.930935 125.682587) (xy 119.87696 125.565268) (xy 119.815865 125.451494)
			(xy 119.747882 125.341697) (xy 119.673268 125.236294) (xy 119.592307 125.135684) (xy 119.505307 125.040249)
			(xy 119.412596 124.95035) (xy 119.314526 124.866329) (xy 119.211471 124.788505) (xy 119.10382 124.717173)
			(xy 118.991981 124.652603) (xy 118.87638 124.595041) (xy 118.757455 124.544704) (xy 118.635656 124.501784)
			(xy 118.511446 124.466443) (xy 118.385297 124.438816) (xy 118.257685 124.419007) (xy 118.129096 124.407091)
			(xy 118.000018 124.403115) (xy 117.87094 124.407091) (xy 117.742351 124.419007) (xy 117.614739 124.438816)
			(xy 117.48859 124.466443) (xy 117.36438 124.501784) (xy 117.242581 124.544704) (xy 117.123656 124.595041)
			(xy 117.008055 124.652603) (xy 116.896216 124.717173) (xy 116.788565 124.788505) (xy 116.68551 124.866329)
			(xy 116.58744 124.95035) (xy 116.494729 125.040249) (xy 116.407729 125.135684) (xy 116.326768 125.236294)
			(xy 116.252154 125.341697) (xy 116.184171 125.451494) (xy 116.123076 125.565268) (xy 116.069101 125.682587)
			(xy 116.02245 125.803006) (xy 115.983301 125.926069) (xy 115.951802 126.051308) (xy 115.928073 126.178249)
			(xy 115.912203 126.306409) (xy 115.904253 126.435304) (xy 92.50807 126.435304) (xy 92.50807 122.226375)
			(xy 99.070401 122.226375) (xy 99.070401 122.312125) (xy 99.078313 122.397508) (xy 99.094069 122.481798)
			(xy 99.117536 122.564274) (xy 99.148512 122.644233) (xy 99.186734 122.720993) (xy 99.231875 122.793899)
			(xy 99.283551 122.862328) (xy 99.34132 122.925698) (xy 99.40469 122.983467) (xy 99.473119 123.035143)
			(xy 99.546025 123.080284) (xy 99.622785 123.118506) (xy 99.702744 123.149482) (xy 99.78522 123.172949)
			(xy 99.86951 123.188705) (xy 99.954893 123.196617) (xy 100.040643 123.196617) (xy 100.126026 123.188705)
			(xy 100.210316 123.172949) (xy 100.292792 123.149482) (xy 100.372751 123.118506) (xy 100.449511 123.080284)
			(xy 100.522417 123.035143) (xy 100.590846 122.983467) (xy 100.654216 122.925698) (xy 100.711985 122.862328)
			(xy 100.763661 122.793899) (xy 100.808802 122.720993) (xy 100.847024 122.644233) (xy 100.878 122.564274)
			(xy 100.901467 122.481798) (xy 100.917223 122.397508) (xy 100.925135 122.312125) (xy 100.92563 122.26925)
			(xy 100.925135 122.226375) (xy 101.610401 122.226375) (xy 101.610401 122.312125) (xy 101.618313 122.397508)
			(xy 101.634069 122.481798) (xy 101.657536 122.564274) (xy 101.688512 122.644233) (xy 101.726734 122.720993)
			(xy 101.771875 122.793899) (xy 101.823551 122.862328) (xy 101.88132 122.925698) (xy 101.94469 122.983467)
			(xy 102.013119 123.035143) (xy 102.086025 123.080284) (xy 102.162785 123.118506) (xy 102.242744 123.149482)
			(xy 102.32522 123.172949) (xy 102.40951 123.188705) (xy 102.494893 123.196617) (xy 102.580643 123.196617)
			(xy 102.666026 123.188705) (xy 102.750316 123.172949) (xy 102.832792 123.149482) (xy 102.912751 123.118506)
			(xy 102.989511 123.080284) (xy 103.062417 123.035143) (xy 103.130846 122.983467) (xy 103.194216 122.925698)
			(xy 103.251985 122.862328) (xy 103.303661 122.793899) (xy 103.348802 122.720993) (xy 103.387024 122.644233)
			(xy 103.418 122.564274) (xy 103.441467 122.481798) (xy 103.457223 122.397508) (xy 103.465135 122.312125)
			(xy 103.46563 122.26925) (xy 103.465135 122.226375) (xy 103.457223 122.140992) (xy 103.441467 122.056702)
			(xy 103.418 121.974226) (xy 103.387024 121.894267) (xy 103.348802 121.817507) (xy 103.303661 121.744601)
			(xy 103.251985 121.676172) (xy 103.194216 121.612802) (xy 103.130846 121.555033) (xy 103.062417 121.503357)
			(xy 102.989511 121.458216) (xy 102.912751 121.419994) (xy 102.832792 121.389018) (xy 102.750316 121.365551)
			(xy 102.666026 121.349795) (xy 102.580643 121.341883) (xy 102.494893 121.341883) (xy 102.40951 121.349795)
			(xy 102.32522 121.365551) (xy 102.242744 121.389018) (xy 102.162785 121.419994) (xy 102.086025 121.458216)
			(xy 102.013119 121.503357) (xy 101.94469 121.555033) (xy 101.88132 121.612802) (xy 101.823551 121.676172)
			(xy 101.771875 121.744601) (xy 101.726734 121.817507) (xy 101.688512 121.894267) (xy 101.657536 121.974226)
			(xy 101.634069 122.056702) (xy 101.618313 122.140992) (xy 101.610401 122.226375) (xy 100.925135 122.226375)
			(xy 100.917223 122.140992) (xy 100.901467 122.056702) (xy 100.878 121.974226) (xy 100.847024 121.894267)
			(xy 100.808802 121.817507) (xy 100.763661 121.744601) (xy 100.711985 121.676172) (xy 100.654216 121.612802)
			(xy 100.590846 121.555033) (xy 100.522417 121.503357) (xy 100.449511 121.458216) (xy 100.372751 121.419994)
			(xy 100.292792 121.389018) (xy 100.210316 121.365551) (xy 100.126026 121.349795) (xy 100.040643 121.341883)
			(xy 99.954893 121.341883) (xy 99.86951 121.349795) (xy 99.78522 121.365551) (xy 99.702744 121.389018)
			(xy 99.622785 121.419994) (xy 99.546025 121.458216) (xy 99.473119 121.503357) (xy 99.40469 121.555033)
			(xy 99.34132 121.612802) (xy 99.283551 121.676172) (xy 99.231875 121.744601) (xy 99.186734 121.817507)
			(xy 99.148512 121.894267) (xy 99.117536 121.974226) (xy 99.094069 122.056702) (xy 99.078313 122.140992)
			(xy 99.070401 122.226375) (xy 92.50807 122.226375) (xy 92.50807 117.881334) (xy 100.454746 117.881334)
			(xy 100.454746 117.935866) (xy 100.462507 117.989844) (xy 100.47787 118.042168) (xy 100.500522 118.091773)
			(xy 100.530003 118.13765) (xy 100.565713 118.178864) (xy 100.606924 118.214578) (xy 100.652799 118.244063)
			(xy 100.702402 118.266719) (xy 100.754725 118.282087) (xy 100.808702 118.289851) (xy 100.835968 118.29034)
			(xy 101.699568 118.29034) (xy 101.726842 118.289923) (xy 101.780835 118.282164) (xy 101.833175 118.266799)
			(xy 101.882795 118.244142) (xy 101.928685 118.214654) (xy 101.969912 118.178934) (xy 102.005635 118.137711)
			(xy 102.035127 118.091823) (xy 102.057788 118.042205) (xy 102.073157 117.989867) (xy 102.08092 117.935874)
			(xy 102.08092 117.881326) (xy 102.073157 117.827333) (xy 102.057788 117.774995) (xy 102.035127 117.725377)
			(xy 102.005635 117.679489) (xy 101.969912 117.638266) (xy 101.928685 117.602546) (xy 101.882795 117.573058)
			(xy 101.833175 117.550401) (xy 101.780836 117.535036) (xy 101.726842 117.527277) (xy 101.699568 117.526816)
			(xy 100.835968 117.526816) (xy 100.808702 117.527349) (xy 100.754725 117.535113) (xy 100.702402 117.550481)
			(xy 100.652799 117.573137) (xy 100.606924 117.602622) (xy 100.565713 117.638336) (xy 100.530003 117.67955)
			(xy 100.500522 117.725427) (xy 100.47787 117.775032) (xy 100.462507 117.827356) (xy 100.454746 117.881334)
			(xy 92.50807 117.881334) (xy 92.50807 115.606627) (xy 93.714049 115.606627) (xy 93.714049 115.692377)
			(xy 93.721961 115.77776) (xy 93.737717 115.86205) (xy 93.761184 115.944526) (xy 93.79216 116.024485)
			(xy 93.830382 116.101245) (xy 93.875523 116.174151) (xy 93.927199 116.24258) (xy 93.984968 116.30595)
			(xy 94.048338 116.363719) (xy 94.116767 116.415395) (xy 94.189673 116.460536) (xy 94.266433 116.498758)
			(xy 94.346392 116.529734) (xy 94.428868 116.553201) (xy 94.513158 116.568957) (xy 94.598541 116.576869)
			(xy 94.684291 116.576869) (xy 94.769674 116.568957) (xy 94.853964 116.553201) (xy 94.93644 116.529734)
			(xy 95.016399 116.498758) (xy 95.093159 116.460536) (xy 95.166065 116.415395) (xy 95.234494 116.363719)
			(xy 95.297864 116.30595) (xy 95.355633 116.24258) (xy 95.407309 116.174151) (xy 95.45245 116.101245)
			(xy 95.490672 116.024485) (xy 95.521648 115.944526) (xy 95.545115 115.86205) (xy 95.560871 115.77776)
			(xy 95.568783 115.692377) (xy 95.569278 115.649502) (xy 95.568783 115.606627) (xy 96.254049 115.606627)
			(xy 96.254049 115.692377) (xy 96.261961 115.77776) (xy 96.277717 115.86205) (xy 96.301184 115.944526)
			(xy 96.33216 116.024485) (xy 96.370382 116.101245) (xy 96.415523 116.174151) (xy 96.467199 116.24258)
			(xy 96.524968 116.30595) (xy 96.588338 116.363719) (xy 96.656767 116.415395) (xy 96.729673 116.460536)
			(xy 96.806433 116.498758) (xy 96.886392 116.529734) (xy 96.968868 116.553201) (xy 97.053158 116.568957)
			(xy 97.138541 116.576869) (xy 97.224291 116.576869) (xy 97.309674 116.568957) (xy 97.393964 116.553201)
			(xy 97.47644 116.529734) (xy 97.556399 116.498758) (xy 97.633159 116.460536) (xy 97.706065 116.415395)
			(xy 97.774494 116.363719) (xy 97.837864 116.30595) (xy 97.895633 116.24258) (xy 97.947309 116.174151)
			(xy 97.99245 116.101245) (xy 98.030672 116.024485) (xy 98.061648 115.944526) (xy 98.081039 115.876375)
			(xy 99.070401 115.876375) (xy 99.070401 115.962125) (xy 99.078313 116.047508) (xy 99.094069 116.131798)
			(xy 99.117536 116.214274) (xy 99.148512 116.294233) (xy 99.186734 116.370993) (xy 99.231875 116.443899)
			(xy 99.283551 116.512328) (xy 99.34132 116.575698) (xy 99.40469 116.633467) (xy 99.473119 116.685143)
			(xy 99.546025 116.730284) (xy 99.622785 116.768506) (xy 99.702744 116.799482) (xy 99.78522 116.822949)
			(xy 99.86951 116.838705) (xy 99.954893 116.846617) (xy 100.040643 116.846617) (xy 100.126026 116.838705)
			(xy 100.210316 116.822949) (xy 100.292792 116.799482) (xy 100.372751 116.768506) (xy 100.449511 116.730284)
			(xy 100.522417 116.685143) (xy 100.590846 116.633467) (xy 100.654216 116.575698) (xy 100.711985 116.512328)
			(xy 100.763661 116.443899) (xy 100.808802 116.370993) (xy 100.847024 116.294233) (xy 100.878 116.214274)
			(xy 100.901467 116.131798) (xy 100.917223 116.047508) (xy 100.925135 115.962125) (xy 100.92563 115.91925)
			(xy 100.925135 115.876375) (xy 101.610401 115.876375) (xy 101.610401 115.962125) (xy 101.618313 116.047508)
			(xy 101.634069 116.131798) (xy 101.657536 116.214274) (xy 101.688512 116.294233) (xy 101.726734 116.370993)
			(xy 101.771875 116.443899) (xy 101.823551 116.512328) (xy 101.88132 116.575698) (xy 101.94469 116.633467)
			(xy 102.013119 116.685143) (xy 102.086025 116.730284) (xy 102.162785 116.768506) (xy 102.242744 116.799482)
			(xy 102.32522 116.822949) (xy 102.40951 116.838705) (xy 102.494893 116.846617) (xy 102.580643 116.846617)
			(xy 102.666026 116.838705) (xy 102.750316 116.822949) (xy 102.832792 116.799482) (xy 102.912751 116.768506)
			(xy 102.989511 116.730284) (xy 103.062417 116.685143) (xy 103.130846 116.633467) (xy 103.194216 116.575698)
			(xy 103.251985 116.512328) (xy 103.303661 116.443899) (xy 103.348802 116.370993) (xy 103.387024 116.294233)
			(xy 103.418 116.214274) (xy 103.441467 116.131798) (xy 103.457223 116.047508) (xy 103.465135 115.962125)
			(xy 103.46563 115.91925) (xy 103.465135 115.876375) (xy 103.457223 115.790992) (xy 103.441467 115.706702)
			(xy 103.418 115.624226) (xy 103.387024 115.544267) (xy 103.348802 115.467507) (xy 103.303661 115.394601)
			(xy 103.251985 115.326172) (xy 103.194216 115.262802) (xy 103.130846 115.205033) (xy 103.062417 115.153357)
			(xy 102.989511 115.108216) (xy 102.912751 115.069994) (xy 102.832792 115.039018) (xy 102.750316 115.015551)
			(xy 102.666026 114.999795) (xy 102.580643 114.991883) (xy 102.494893 114.991883) (xy 102.40951 114.999795)
			(xy 102.32522 115.015551) (xy 102.242744 115.039018) (xy 102.162785 115.069994) (xy 102.086025 115.108216)
			(xy 102.013119 115.153357) (xy 101.94469 115.205033) (xy 101.88132 115.262802) (xy 101.823551 115.326172)
			(xy 101.771875 115.394601) (xy 101.726734 115.467507) (xy 101.688512 115.544267) (xy 101.657536 115.624226)
			(xy 101.634069 115.706702) (xy 101.618313 115.790992) (xy 101.610401 115.876375) (xy 100.925135 115.876375)
			(xy 100.917223 115.790992) (xy 100.901467 115.706702) (xy 100.878 115.624226) (xy 100.847024 115.544267)
			(xy 100.808802 115.467507) (xy 100.763661 115.394601) (xy 100.711985 115.326172) (xy 100.654216 115.262802)
			(xy 100.590846 115.205033) (xy 100.522417 115.153357) (xy 100.449511 115.108216) (xy 100.372751 115.069994)
			(xy 100.292792 115.039018) (xy 100.210316 115.015551) (xy 100.126026 114.999795) (xy 100.040643 114.991883)
			(xy 99.954893 114.991883) (xy 99.86951 114.999795) (xy 99.78522 115.015551) (xy 99.702744 115.039018)
			(xy 99.622785 115.069994) (xy 99.546025 115.108216) (xy 99.473119 115.153357) (xy 99.40469 115.205033)
			(xy 99.34132 115.262802) (xy 99.283551 115.326172) (xy 99.231875 115.394601) (xy 99.186734 115.467507)
			(xy 99.148512 115.544267) (xy 99.117536 115.624226) (xy 99.094069 115.706702) (xy 99.078313 115.790992)
			(xy 99.070401 115.876375) (xy 98.081039 115.876375) (xy 98.085115 115.86205) (xy 98.100871 115.77776)
			(xy 98.108783 115.692377) (xy 98.109278 115.649502) (xy 98.108783 115.606627) (xy 98.100871 115.521244)
			(xy 98.085115 115.436954) (xy 98.061648 115.354478) (xy 98.030672 115.274519) (xy 97.99245 115.197759)
			(xy 97.947309 115.124853) (xy 97.895633 115.056424) (xy 97.837864 114.993054) (xy 97.774494 114.935285)
			(xy 97.706065 114.883609) (xy 97.633159 114.838468) (xy 97.556399 114.800246) (xy 97.47644 114.76927)
			(xy 97.393964 114.745803) (xy 97.309674 114.730047) (xy 97.224291 114.722135) (xy 97.138541 114.722135)
			(xy 97.053158 114.730047) (xy 96.968868 114.745803) (xy 96.886392 114.76927) (xy 96.806433 114.800246)
			(xy 96.729673 114.838468) (xy 96.656767 114.883609) (xy 96.588338 114.935285) (xy 96.524968 114.993054)
			(xy 96.467199 115.056424) (xy 96.415523 115.124853) (xy 96.370382 115.197759) (xy 96.33216 115.274519)
			(xy 96.301184 115.354478) (xy 96.277717 115.436954) (xy 96.261961 115.521244) (xy 96.254049 115.606627)
			(xy 95.568783 115.606627) (xy 95.560871 115.521244) (xy 95.545115 115.436954) (xy 95.521648 115.354478)
			(xy 95.490672 115.274519) (xy 95.45245 115.197759) (xy 95.407309 115.124853) (xy 95.355633 115.056424)
			(xy 95.297864 114.993054) (xy 95.234494 114.935285) (xy 95.166065 114.883609) (xy 95.093159 114.838468)
			(xy 95.016399 114.800246) (xy 94.93644 114.76927) (xy 94.853964 114.745803) (xy 94.769674 114.730047)
			(xy 94.684291 114.722135) (xy 94.598541 114.722135) (xy 94.513158 114.730047) (xy 94.428868 114.745803)
			(xy 94.346392 114.76927) (xy 94.266433 114.800246) (xy 94.189673 114.838468) (xy 94.116767 114.883609)
			(xy 94.048338 114.935285) (xy 93.984968 114.993054) (xy 93.927199 115.056424) (xy 93.875523 115.124853)
			(xy 93.830382 115.197759) (xy 93.79216 115.274519) (xy 93.761184 115.354478) (xy 93.737717 115.436954)
			(xy 93.721961 115.521244) (xy 93.714049 115.606627) (xy 92.50807 115.606627) (xy 92.50807 111.261526)
			(xy 95.098272 111.261526) (xy 95.098272 111.316074) (xy 95.106035 111.370066) (xy 95.121403 111.422404)
			(xy 95.144064 111.472023) (xy 95.173555 111.517911) (xy 95.209277 111.559134) (xy 95.250502 111.594855)
			(xy 95.296392 111.624344) (xy 95.346011 111.647003) (xy 95.398349 111.662369) (xy 95.452342 111.67013)
			(xy 95.479616 111.670592) (xy 96.343216 111.670592) (xy 96.370482 111.670045) (xy 96.42446 111.662282)
			(xy 96.476784 111.646916) (xy 96.526388 111.624261) (xy 96.572263 111.594777) (xy 96.613476 111.559064)
			(xy 96.649186 111.51785) (xy 96.678668 111.471974) (xy 96.701322 111.422369) (xy 96.716685 111.370044)
			(xy 96.724446 111.316067) (xy 96.724446 111.261534) (xy 96.716685 111.207556) (xy 96.701322 111.155231)
			(xy 96.678668 111.105626) (xy 96.649186 111.05975) (xy 96.613476 111.018536) (xy 96.572263 110.982823)
			(xy 96.526388 110.953339) (xy 96.476784 110.930684) (xy 96.42446 110.915318) (xy 96.370482 110.907555)
			(xy 96.343216 110.907068) (xy 95.479616 110.907068) (xy 95.452342 110.90747) (xy 95.398349 110.915231)
			(xy 95.346011 110.930597) (xy 95.296392 110.953256) (xy 95.250502 110.982745) (xy 95.209277 111.018466)
			(xy 95.173555 111.059689) (xy 95.144064 111.105577) (xy 95.121403 111.155196) (xy 95.106035 111.207534)
			(xy 95.098272 111.261526) (xy 92.50807 111.261526) (xy 92.50807 109.256627) (xy 93.714049 109.256627)
			(xy 93.714049 109.342377) (xy 93.721961 109.42776) (xy 93.737717 109.51205) (xy 93.761184 109.594526)
			(xy 93.79216 109.674485) (xy 93.830382 109.751245) (xy 93.875523 109.824151) (xy 93.927199 109.89258)
			(xy 93.984968 109.95595) (xy 94.048338 110.013719) (xy 94.116767 110.065395) (xy 94.189673 110.110536)
			(xy 94.266433 110.148758) (xy 94.346392 110.179734) (xy 94.428868 110.203201) (xy 94.513158 110.218957)
			(xy 94.598541 110.226869) (xy 94.684291 110.226869) (xy 94.769674 110.218957) (xy 94.853964 110.203201)
			(xy 94.93644 110.179734) (xy 95.016399 110.148758) (xy 95.093159 110.110536) (xy 95.166065 110.065395)
			(xy 95.234494 110.013719) (xy 95.297864 109.95595) (xy 95.355633 109.89258) (xy 95.407309 109.824151)
			(xy 95.45245 109.751245) (xy 95.490672 109.674485) (xy 95.521648 109.594526) (xy 95.545115 109.51205)
			(xy 95.560871 109.42776) (xy 95.568783 109.342377) (xy 95.569278 109.299502) (xy 95.568783 109.256627)
			(xy 96.254049 109.256627) (xy 96.254049 109.342377) (xy 96.261961 109.42776) (xy 96.277717 109.51205)
			(xy 96.301184 109.594526) (xy 96.33216 109.674485) (xy 96.370382 109.751245) (xy 96.415523 109.824151)
			(xy 96.467199 109.89258) (xy 96.524968 109.95595) (xy 96.588338 110.013719) (xy 96.656767 110.065395)
			(xy 96.729673 110.110536) (xy 96.806433 110.148758) (xy 96.886392 110.179734) (xy 96.968868 110.203201)
			(xy 97.053158 110.218957) (xy 97.138541 110.226869) (xy 97.224291 110.226869) (xy 97.309674 110.218957)
			(xy 97.393964 110.203201) (xy 97.47644 110.179734) (xy 97.556399 110.148758) (xy 97.633159 110.110536)
			(xy 97.706065 110.065395) (xy 97.774494 110.013719) (xy 97.837864 109.95595) (xy 97.895633 109.89258)
			(xy 97.947309 109.824151) (xy 97.99245 109.751245) (xy 98.030672 109.674485) (xy 98.061648 109.594526)
			(xy 98.085115 109.51205) (xy 98.100871 109.42776) (xy 98.108783 109.342377) (xy 98.109278 109.299502)
			(xy 98.108783 109.256627) (xy 98.100871 109.171244) (xy 98.085115 109.086954) (xy 98.061648 109.004478)
			(xy 98.030672 108.924519) (xy 97.99245 108.847759) (xy 97.947309 108.774853) (xy 97.895633 108.706424)
			(xy 97.837864 108.643054) (xy 97.774494 108.585285) (xy 97.706065 108.533609) (xy 97.633159 108.488468)
			(xy 97.556399 108.450246) (xy 97.47644 108.41927) (xy 97.393964 108.395803) (xy 97.309674 108.380047)
			(xy 97.224291 108.372135) (xy 97.138541 108.372135) (xy 97.053158 108.380047) (xy 96.968868 108.395803)
			(xy 96.886392 108.41927) (xy 96.806433 108.450246) (xy 96.729673 108.488468) (xy 96.656767 108.533609)
			(xy 96.588338 108.585285) (xy 96.524968 108.643054) (xy 96.467199 108.706424) (xy 96.415523 108.774853)
			(xy 96.370382 108.847759) (xy 96.33216 108.924519) (xy 96.301184 109.004478) (xy 96.277717 109.086954)
			(xy 96.261961 109.171244) (xy 96.254049 109.256627) (xy 95.568783 109.256627) (xy 95.560871 109.171244)
			(xy 95.545115 109.086954) (xy 95.521648 109.004478) (xy 95.490672 108.924519) (xy 95.45245 108.847759)
			(xy 95.407309 108.774853) (xy 95.355633 108.706424) (xy 95.297864 108.643054) (xy 95.234494 108.585285)
			(xy 95.166065 108.533609) (xy 95.093159 108.488468) (xy 95.016399 108.450246) (xy 94.93644 108.41927)
			(xy 94.853964 108.395803) (xy 94.769674 108.380047) (xy 94.684291 108.372135) (xy 94.598541 108.372135)
			(xy 94.513158 108.380047) (xy 94.428868 108.395803) (xy 94.346392 108.41927) (xy 94.266433 108.450246)
			(xy 94.189673 108.488468) (xy 94.116767 108.533609) (xy 94.048338 108.585285) (xy 93.984968 108.643054)
			(xy 93.927199 108.706424) (xy 93.875523 108.774853) (xy 93.830382 108.847759) (xy 93.79216 108.924519)
			(xy 93.761184 109.004478) (xy 93.737717 109.086954) (xy 93.721961 109.171244) (xy 93.714049 109.256627)
			(xy 92.50807 109.256627) (xy 92.50807 56.800039) (xy 93.729289 56.800039) (xy 93.729289 56.885789)
			(xy 93.737201 56.971172) (xy 93.752957 57.055462) (xy 93.776424 57.137938) (xy 93.8074 57.217897)
			(xy 93.845622 57.294657) (xy 93.890763 57.367563) (xy 93.942439 57.435992) (xy 94.000208 57.499362)
			(xy 94.063578 57.557131) (xy 94.132007 57.608807) (xy 94.204913 57.653948) (xy 94.281673 57.69217)
			(xy 94.361632 57.723146) (xy 94.444108 57.746613) (xy 94.528398 57.762369) (xy 94.613781 57.770281)
			(xy 94.699531 57.770281) (xy 94.784914 57.762369) (xy 94.869204 57.746613) (xy 94.95168 57.723146)
			(xy 95.031639 57.69217) (xy 95.108399 57.653948) (xy 95.181305 57.608807) (xy 95.249734 57.557131)
			(xy 95.313104 57.499362) (xy 95.370873 57.435992) (xy 95.422549 57.367563) (xy 95.46769 57.294657)
			(xy 95.505912 57.217897) (xy 95.536888 57.137938) (xy 95.560355 57.055462) (xy 95.576111 56.971172)
			(xy 95.584023 56.885789) (xy 95.584518 56.842914) (xy 95.584023 56.800039) (xy 96.269289 56.800039)
			(xy 96.269289 56.885789) (xy 96.277201 56.971172) (xy 96.292957 57.055462) (xy 96.316424 57.137938)
			(xy 96.3474 57.217897) (xy 96.385622 57.294657) (xy 96.430763 57.367563) (xy 96.482439 57.435992)
			(xy 96.540208 57.499362) (xy 96.603578 57.557131) (xy 96.672007 57.608807) (xy 96.744913 57.653948)
			(xy 96.821673 57.69217) (xy 96.901632 57.723146) (xy 96.984108 57.746613) (xy 97.068398 57.762369)
			(xy 97.153781 57.770281) (xy 97.239531 57.770281) (xy 97.324914 57.762369) (xy 97.409204 57.746613)
			(xy 97.49168 57.723146) (xy 97.571639 57.69217) (xy 97.648399 57.653948) (xy 97.721305 57.608807)
			(xy 97.789734 57.557131) (xy 97.853104 57.499362) (xy 97.910873 57.435992) (xy 97.962549 57.367563)
			(xy 98.00769 57.294657) (xy 98.045912 57.217897) (xy 98.076888 57.137938) (xy 98.100355 57.055462)
			(xy 98.116111 56.971172) (xy 98.124023 56.885789) (xy 98.124518 56.842914) (xy 98.124023 56.800039)
			(xy 98.116111 56.714656) (xy 98.100355 56.630366) (xy 98.076888 56.54789) (xy 98.045912 56.467931)
			(xy 98.00769 56.391171) (xy 97.962549 56.318265) (xy 97.910873 56.249836) (xy 97.853104 56.186466)
			(xy 97.789734 56.128697) (xy 97.721305 56.077021) (xy 97.648399 56.03188) (xy 97.571639 55.993658)
			(xy 97.49168 55.962682) (xy 97.409204 55.939215) (xy 97.324914 55.923459) (xy 97.239531 55.915547)
			(xy 97.153781 55.915547) (xy 97.068398 55.923459) (xy 96.984108 55.939215) (xy 96.901632 55.962682)
			(xy 96.821673 55.993658) (xy 96.744913 56.03188) (xy 96.672007 56.077021) (xy 96.603578 56.128697)
			(xy 96.540208 56.186466) (xy 96.482439 56.249836) (xy 96.430763 56.318265) (xy 96.385622 56.391171)
			(xy 96.3474 56.467931) (xy 96.316424 56.54789) (xy 96.292957 56.630366) (xy 96.277201 56.714656)
			(xy 96.269289 56.800039) (xy 95.584023 56.800039) (xy 95.576111 56.714656) (xy 95.560355 56.630366)
			(xy 95.536888 56.54789) (xy 95.505912 56.467931) (xy 95.46769 56.391171) (xy 95.422549 56.318265)
			(xy 95.370873 56.249836) (xy 95.313104 56.186466) (xy 95.249734 56.128697) (xy 95.181305 56.077021)
			(xy 95.108399 56.03188) (xy 95.031639 55.993658) (xy 94.95168 55.962682) (xy 94.869204 55.939215)
			(xy 94.784914 55.923459) (xy 94.699531 55.915547) (xy 94.613781 55.915547) (xy 94.528398 55.923459)
			(xy 94.444108 55.939215) (xy 94.361632 55.962682) (xy 94.281673 55.993658) (xy 94.204913 56.03188)
			(xy 94.132007 56.077021) (xy 94.063578 56.128697) (xy 94.000208 56.186466) (xy 93.942439 56.249836)
			(xy 93.890763 56.318265) (xy 93.845622 56.391171) (xy 93.8074 56.467931) (xy 93.776424 56.54789)
			(xy 93.752957 56.630366) (xy 93.737201 56.714656) (xy 93.729289 56.800039) (xy 92.50807 56.800039)
			(xy 92.50807 54.826334) (xy 95.113638 54.826334) (xy 95.113638 54.880866) (xy 95.121398 54.934844)
			(xy 95.136761 54.987168) (xy 95.159413 55.036774) (xy 95.188894 55.082651) (xy 95.224603 55.123866)
			(xy 95.265814 55.15958) (xy 95.311688 55.189066) (xy 95.36129 55.211724) (xy 95.413613 55.227092)
			(xy 95.46759 55.234859) (xy 95.494856 55.235348) (xy 96.358456 55.235348) (xy 96.38573 55.234915)
			(xy 96.439724 55.227158) (xy 96.492064 55.211795) (xy 96.541684 55.189139) (xy 96.587575 55.159652)
			(xy 96.628802 55.123933) (xy 96.664525 55.08271) (xy 96.694018 55.036823) (xy 96.71668 54.987205)
			(xy 96.732049 54.934867) (xy 96.739812 54.880874) (xy 96.739812 54.826326) (xy 96.732049 54.772333)
			(xy 96.71668 54.719995) (xy 96.694018 54.670377) (xy 96.664525 54.62449) (xy 96.628802 54.583267)
			(xy 96.587575 54.547548) (xy 96.541684 54.518061) (xy 96.492064 54.495405) (xy 96.439724 54.480042)
			(xy 96.38573 54.472285) (xy 96.358456 54.471824) (xy 95.494856 54.471824) (xy 95.46759 54.472341)
			(xy 95.413613 54.480108) (xy 95.36129 54.495476) (xy 95.311688 54.518134) (xy 95.265814 54.54762)
			(xy 95.224603 54.583334) (xy 95.188894 54.624549) (xy 95.159413 54.670426) (xy 95.136761 54.720032)
			(xy 95.121399 54.772356) (xy 95.113638 54.826334) (xy 92.50807 54.826334) (xy 92.50807 50.450039)
			(xy 93.729289 50.450039) (xy 93.729289 50.535789) (xy 93.737201 50.621172) (xy 93.752957 50.705462)
			(xy 93.776424 50.787938) (xy 93.8074 50.867897) (xy 93.845622 50.944657) (xy 93.890763 51.017563)
			(xy 93.942439 51.085992) (xy 94.000208 51.149362) (xy 94.063578 51.207131) (xy 94.132007 51.258807)
			(xy 94.204913 51.303948) (xy 94.281673 51.34217) (xy 94.361632 51.373146) (xy 94.444108 51.396613)
			(xy 94.528398 51.412369) (xy 94.613781 51.420281) (xy 94.699531 51.420281) (xy 94.784914 51.412369)
			(xy 94.869204 51.396613) (xy 94.95168 51.373146) (xy 95.031639 51.34217) (xy 95.108399 51.303948)
			(xy 95.181305 51.258807) (xy 95.249734 51.207131) (xy 95.313104 51.149362) (xy 95.370873 51.085992)
			(xy 95.422549 51.017563) (xy 95.46769 50.944657) (xy 95.505912 50.867897) (xy 95.536888 50.787938)
			(xy 95.560355 50.705462) (xy 95.576111 50.621172) (xy 95.584023 50.535789) (xy 95.584518 50.492914)
			(xy 95.584023 50.450039) (xy 96.269289 50.450039) (xy 96.269289 50.535789) (xy 96.277201 50.621172)
			(xy 96.292957 50.705462) (xy 96.316424 50.787938) (xy 96.3474 50.867897) (xy 96.385622 50.944657)
			(xy 96.430763 51.017563) (xy 96.482439 51.085992) (xy 96.540208 51.149362) (xy 96.603578 51.207131)
			(xy 96.672007 51.258807) (xy 96.744913 51.303948) (xy 96.821673 51.34217) (xy 96.901632 51.373146)
			(xy 96.984108 51.396613) (xy 97.068398 51.412369) (xy 97.153781 51.420281) (xy 97.239531 51.420281)
			(xy 97.324914 51.412369) (xy 97.409204 51.396613) (xy 97.49168 51.373146) (xy 97.571639 51.34217)
			(xy 97.648399 51.303948) (xy 97.721305 51.258807) (xy 97.789734 51.207131) (xy 97.853104 51.149362)
			(xy 97.910873 51.085992) (xy 97.962549 51.017563) (xy 98.00769 50.944657) (xy 98.045912 50.867897)
			(xy 98.076888 50.787938) (xy 98.100355 50.705462) (xy 98.116111 50.621172) (xy 98.124023 50.535789)
			(xy 98.124518 50.492914) (xy 98.124023 50.450039) (xy 98.116111 50.364656) (xy 98.100355 50.280366)
			(xy 98.076888 50.19789) (xy 98.045912 50.117931) (xy 98.00769 50.041171) (xy 97.962549 49.968265)
			(xy 97.910873 49.899836) (xy 97.853104 49.836466) (xy 97.789734 49.778697) (xy 97.721305 49.727021)
			(xy 97.648399 49.68188) (xy 97.571639 49.643658) (xy 97.49168 49.612682) (xy 97.409204 49.589215)
			(xy 97.324914 49.573459) (xy 97.239531 49.565547) (xy 97.153781 49.565547) (xy 97.068398 49.573459)
			(xy 96.984108 49.589215) (xy 96.901632 49.612682) (xy 96.821673 49.643658) (xy 96.744913 49.68188)
			(xy 96.672007 49.727021) (xy 96.603578 49.778697) (xy 96.540208 49.836466) (xy 96.482439 49.899836)
			(xy 96.430763 49.968265) (xy 96.385622 50.041171) (xy 96.3474 50.117931) (xy 96.316424 50.19789)
			(xy 96.292957 50.280366) (xy 96.277201 50.364656) (xy 96.269289 50.450039) (xy 95.584023 50.450039)
			(xy 95.576111 50.364656) (xy 95.560355 50.280366) (xy 95.536888 50.19789) (xy 95.505912 50.117931)
			(xy 95.46769 50.041171) (xy 95.422549 49.968265) (xy 95.370873 49.899836) (xy 95.313104 49.836466)
			(xy 95.249734 49.778697) (xy 95.181305 49.727021) (xy 95.108399 49.68188) (xy 95.031639 49.643658)
			(xy 94.95168 49.612682) (xy 94.869204 49.589215) (xy 94.784914 49.573459) (xy 94.699531 49.565547)
			(xy 94.613781 49.565547) (xy 94.528398 49.573459) (xy 94.444108 49.589215) (xy 94.361632 49.612682)
			(xy 94.281673 49.643658) (xy 94.204913 49.68188) (xy 94.132007 49.727021) (xy 94.063578 49.778697)
			(xy 94.000208 49.836466) (xy 93.942439 49.899836) (xy 93.890763 49.968265) (xy 93.845622 50.041171)
			(xy 93.8074 50.117931) (xy 93.776424 50.19789) (xy 93.752957 50.280366) (xy 93.737201 50.364656)
			(xy 93.729289 50.450039) (xy 92.50807 50.450039) (xy 92.50807 44.925539) (xy 93.706937 44.925539)
			(xy 93.706937 45.011289) (xy 93.714849 45.096672) (xy 93.730605 45.180962) (xy 93.754072 45.263438)
			(xy 93.785048 45.343397) (xy 93.82327 45.420157) (xy 93.868411 45.493063) (xy 93.920087 45.561492)
			(xy 93.977856 45.624862) (xy 94.041226 45.682631) (xy 94.109655 45.734307) (xy 94.182561 45.779448)
			(xy 94.259321 45.81767) (xy 94.33928 45.848646) (xy 94.421756 45.872113) (xy 94.506046 45.887869)
			(xy 94.591429 45.895781) (xy 94.677179 45.895781) (xy 94.762562 45.887869) (xy 94.846852 45.872113)
			(xy 94.929328 45.848646) (xy 95.009287 45.81767) (xy 95.086047 45.779448) (xy 95.158953 45.734307)
			(xy 95.227382 45.682631) (xy 95.290752 45.624862) (xy 95.348521 45.561492) (xy 95.400197 45.493063)
			(xy 95.445338 45.420157) (xy 95.48356 45.343397) (xy 95.514536 45.263438) (xy 95.538003 45.180962)
			(xy 95.553759 45.096672) (xy 95.561671 45.011289) (xy 95.562166 44.968414) (xy 95.561671 44.925539)
			(xy 96.246937 44.925539) (xy 96.246937 45.011289) (xy 96.254849 45.096672) (xy 96.270605 45.180962)
			(xy 96.294072 45.263438) (xy 96.325048 45.343397) (xy 96.36327 45.420157) (xy 96.408411 45.493063)
			(xy 96.460087 45.561492) (xy 96.517856 45.624862) (xy 96.581226 45.682631) (xy 96.649655 45.734307)
			(xy 96.722561 45.779448) (xy 96.799321 45.81767) (xy 96.87928 45.848646) (xy 96.961756 45.872113)
			(xy 97.046046 45.887869) (xy 97.131429 45.895781) (xy 97.217179 45.895781) (xy 97.302562 45.887869)
			(xy 97.386852 45.872113) (xy 97.469328 45.848646) (xy 97.549287 45.81767) (xy 97.626047 45.779448)
			(xy 97.698953 45.734307) (xy 97.767382 45.682631) (xy 97.830752 45.624862) (xy 97.888521 45.561492)
			(xy 97.940197 45.493063) (xy 97.985338 45.420157) (xy 98.02356 45.343397) (xy 98.054536 45.263438)
			(xy 98.078003 45.180962) (xy 98.093759 45.096672) (xy 98.101671 45.011289) (xy 98.102166 44.968414)
			(xy 98.101671 44.925539) (xy 98.093759 44.840156) (xy 98.078003 44.755866) (xy 98.054536 44.67339)
			(xy 98.02356 44.593431) (xy 97.985338 44.516671) (xy 97.940197 44.443765) (xy 97.888521 44.375336)
			(xy 97.830752 44.311966) (xy 97.767382 44.254197) (xy 97.698953 44.202521) (xy 97.626047 44.15738)
			(xy 97.549287 44.119158) (xy 97.469328 44.088182) (xy 97.386852 44.064715) (xy 97.302562 44.048959)
			(xy 97.217179 44.041047) (xy 97.131429 44.041047) (xy 97.046046 44.048959) (xy 96.961756 44.064715)
			(xy 96.87928 44.088182) (xy 96.799321 44.119158) (xy 96.722561 44.15738) (xy 96.649655 44.202521)
			(xy 96.581226 44.254197) (xy 96.517856 44.311966) (xy 96.460087 44.375336) (xy 96.408411 44.443765)
			(xy 96.36327 44.516671) (xy 96.325048 44.593431) (xy 96.294072 44.67339) (xy 96.270605 44.755866)
			(xy 96.254849 44.840156) (xy 96.246937 44.925539) (xy 95.561671 44.925539) (xy 95.553759 44.840156)
			(xy 95.538003 44.755866) (xy 95.514536 44.67339) (xy 95.48356 44.593431) (xy 95.445338 44.516671)
			(xy 95.400197 44.443765) (xy 95.348521 44.375336) (xy 95.290752 44.311966) (xy 95.227382 44.254197)
			(xy 95.158953 44.202521) (xy 95.086047 44.15738) (xy 95.009287 44.119158) (xy 94.929328 44.088182)
			(xy 94.846852 44.064715) (xy 94.762562 44.048959) (xy 94.677179 44.041047) (xy 94.591429 44.041047)
			(xy 94.506046 44.048959) (xy 94.421756 44.064715) (xy 94.33928 44.088182) (xy 94.259321 44.119158)
			(xy 94.182561 44.15738) (xy 94.109655 44.202521) (xy 94.041226 44.254197) (xy 93.977856 44.311966)
			(xy 93.920087 44.375336) (xy 93.868411 44.443765) (xy 93.82327 44.516671) (xy 93.785048 44.593431)
			(xy 93.754072 44.67339) (xy 93.730605 44.755866) (xy 93.714849 44.840156) (xy 93.706937 44.925539)
			(xy 92.50807 44.925539) (xy 92.50807 40.580426) (xy 95.09116 40.580426) (xy 95.09116 40.634974) (xy 95.098923 40.688967)
			(xy 95.114291 40.741306) (xy 95.136951 40.790925) (xy 95.166442 40.836814) (xy 95.202164 40.878039)
			(xy 95.243389 40.91376) (xy 95.289279 40.943251) (xy 95.338898 40.965911) (xy 95.391237 40.981278)
			(xy 95.44523 40.989041) (xy 95.472504 40.989504) (xy 96.336104 40.989504) (xy 96.36337 40.988933)
			(xy 96.417347 40.981172) (xy 96.469671 40.965808) (xy 96.519275 40.943154) (xy 96.56515 40.913671)
			(xy 96.606363 40.87796) (xy 96.642074 40.836747) (xy 96.671556 40.790871) (xy 96.69421 40.741267)
			(xy 96.709573 40.688944) (xy 96.717334 40.634966) (xy 96.717334 40.580434) (xy 96.709573 40.526456)
			(xy 96.69421 40.474133) (xy 96.671556 40.424529) (xy 96.642074 40.378653) (xy 96.606363 40.33744)
			(xy 96.56515 40.301729) (xy 96.519275 40.272246) (xy 96.469671 40.249592) (xy 96.417347 40.234228)
			(xy 96.36337 40.226467) (xy 96.336104 40.22598) (xy 95.472504 40.22598) (xy 95.44523 40.226359) (xy 95.391237 40.234122)
			(xy 95.338898 40.249489) (xy 95.289279 40.272149) (xy 95.243389 40.30164) (xy 95.202164 40.337361)
			(xy 95.166442 40.378586) (xy 95.136951 40.424475) (xy 95.114291 40.474094) (xy 95.098923 40.526433)
			(xy 95.09116 40.580426) (xy 92.50807 40.580426) (xy 92.50807 38.575539) (xy 93.706937 38.575539)
			(xy 93.706937 38.661289) (xy 93.714849 38.746672) (xy 93.730605 38.830962) (xy 93.754072 38.913438)
			(xy 93.785048 38.993397) (xy 93.82327 39.070157) (xy 93.868411 39.143063) (xy 93.920087 39.211492)
			(xy 93.977856 39.274862) (xy 94.041226 39.332631) (xy 94.109655 39.384307) (xy 94.182561 39.429448)
			(xy 94.259321 39.46767) (xy 94.33928 39.498646) (xy 94.421756 39.522113) (xy 94.506046 39.537869)
			(xy 94.591429 39.545781) (xy 94.677179 39.545781) (xy 94.762562 39.537869) (xy 94.846852 39.522113)
			(xy 94.929328 39.498646) (xy 95.009287 39.46767) (xy 95.086047 39.429448) (xy 95.158953 39.384307)
			(xy 95.227382 39.332631) (xy 95.290752 39.274862) (xy 95.348521 39.211492) (xy 95.400197 39.143063)
			(xy 95.445338 39.070157) (xy 95.48356 38.993397) (xy 95.514536 38.913438) (xy 95.538003 38.830962)
			(xy 95.553759 38.746672) (xy 95.561671 38.661289) (xy 95.562166 38.618414) (xy 95.561671 38.575539)
			(xy 96.246937 38.575539) (xy 96.246937 38.661289) (xy 96.254849 38.746672) (xy 96.270605 38.830962)
			(xy 96.294072 38.913438) (xy 96.325048 38.993397) (xy 96.36327 39.070157) (xy 96.408411 39.143063)
			(xy 96.460087 39.211492) (xy 96.517856 39.274862) (xy 96.581226 39.332631) (xy 96.649655 39.384307)
			(xy 96.722561 39.429448) (xy 96.799321 39.46767) (xy 96.87928 39.498646) (xy 96.961756 39.522113)
			(xy 97.046046 39.537869) (xy 97.131429 39.545781) (xy 97.217179 39.545781) (xy 97.302562 39.537869)
			(xy 97.386852 39.522113) (xy 97.469328 39.498646) (xy 97.549287 39.46767) (xy 97.626047 39.429448)
			(xy 97.698953 39.384307) (xy 97.767382 39.332631) (xy 97.830752 39.274862) (xy 97.888521 39.211492)
			(xy 97.940197 39.143063) (xy 97.985338 39.070157) (xy 98.02356 38.993397) (xy 98.054536 38.913438)
			(xy 98.078003 38.830962) (xy 98.093759 38.746672) (xy 98.101671 38.661289) (xy 98.102166 38.618414)
			(xy 98.101671 38.575539) (xy 98.093759 38.490156) (xy 98.078003 38.405866) (xy 98.054536 38.32339)
			(xy 98.02356 38.243431) (xy 97.985338 38.166671) (xy 97.940197 38.093765) (xy 97.888521 38.025336)
			(xy 97.830752 37.961966) (xy 97.767382 37.904197) (xy 97.698953 37.852521) (xy 97.626047 37.80738)
			(xy 97.549287 37.769158) (xy 97.469328 37.738182) (xy 97.386852 37.714715) (xy 97.302562 37.698959)
			(xy 97.217179 37.691047) (xy 97.131429 37.691047) (xy 97.046046 37.698959) (xy 96.961756 37.714715)
			(xy 96.87928 37.738182) (xy 96.799321 37.769158) (xy 96.722561 37.80738) (xy 96.649655 37.852521)
			(xy 96.581226 37.904197) (xy 96.517856 37.961966) (xy 96.460087 38.025336) (xy 96.408411 38.093765)
			(xy 96.36327 38.166671) (xy 96.325048 38.243431) (xy 96.294072 38.32339) (xy 96.270605 38.405866)
			(xy 96.254849 38.490156) (xy 96.246937 38.575539) (xy 95.561671 38.575539) (xy 95.553759 38.490156)
			(xy 95.538003 38.405866) (xy 95.514536 38.32339) (xy 95.48356 38.243431) (xy 95.445338 38.166671)
			(xy 95.400197 38.093765) (xy 95.348521 38.025336) (xy 95.290752 37.961966) (xy 95.227382 37.904197)
			(xy 95.158953 37.852521) (xy 95.086047 37.80738) (xy 95.009287 37.769158) (xy 94.929328 37.738182)
			(xy 94.846852 37.714715) (xy 94.762562 37.698959) (xy 94.677179 37.691047) (xy 94.591429 37.691047)
			(xy 94.506046 37.698959) (xy 94.421756 37.714715) (xy 94.33928 37.738182) (xy 94.259321 37.769158)
			(xy 94.182561 37.80738) (xy 94.109655 37.852521) (xy 94.041226 37.904197) (xy 93.977856 37.961966)
			(xy 93.920087 38.025336) (xy 93.868411 38.093765) (xy 93.82327 38.166671) (xy 93.785048 38.243431)
			(xy 93.754072 38.32339) (xy 93.730605 38.405866) (xy 93.714849 38.490156) (xy 93.706937 38.575539)
			(xy 92.50807 38.575539) (xy 92.50807 32.685787) (xy 99.092753 32.685787) (xy 99.092753 32.771537)
			(xy 99.100665 32.85692) (xy 99.116421 32.94121) (xy 99.139888 33.023686) (xy 99.170864 33.103645)
			(xy 99.209086 33.180405) (xy 99.254227 33.253311) (xy 99.305903 33.32174) (xy 99.363672 33.38511)
			(xy 99.427042 33.442879) (xy 99.495471 33.494555) (xy 99.568377 33.539696) (xy 99.645137 33.577918)
			(xy 99.725096 33.608894) (xy 99.807572 33.632361) (xy 99.891862 33.648117) (xy 99.977245 33.656029)
			(xy 100.062995 33.656029) (xy 100.148378 33.648117) (xy 100.232668 33.632361) (xy 100.315144 33.608894)
			(xy 100.395103 33.577918) (xy 100.471863 33.539696) (xy 100.544769 33.494555) (xy 100.613198 33.442879)
			(xy 100.676568 33.38511) (xy 100.734337 33.32174) (xy 100.786013 33.253311) (xy 100.831154 33.180405)
			(xy 100.869376 33.103645) (xy 100.900352 33.023686) (xy 100.923819 32.94121) (xy 100.939575 32.85692)
			(xy 100.947487 32.771537) (xy 100.947982 32.728662) (xy 100.947487 32.685787) (xy 101.632753 32.685787)
			(xy 101.632753 32.771537) (xy 101.640665 32.85692) (xy 101.656421 32.94121) (xy 101.679888 33.023686)
			(xy 101.710864 33.103645) (xy 101.749086 33.180405) (xy 101.794227 33.253311) (xy 101.845903 33.32174)
			(xy 101.903672 33.38511) (xy 101.967042 33.442879) (xy 102.035471 33.494555) (xy 102.108377 33.539696)
			(xy 102.185137 33.577918) (xy 102.265096 33.608894) (xy 102.347572 33.632361) (xy 102.431862 33.648117)
			(xy 102.517245 33.656029) (xy 102.602995 33.656029) (xy 102.688378 33.648117) (xy 102.772668 33.632361)
			(xy 102.855144 33.608894) (xy 102.935103 33.577918) (xy 103.011863 33.539696) (xy 103.084769 33.494555)
			(xy 103.153198 33.442879) (xy 103.216568 33.38511) (xy 103.274337 33.32174) (xy 103.326013 33.253311)
			(xy 103.371154 33.180405) (xy 103.409376 33.103645) (xy 103.440352 33.023686) (xy 103.463819 32.94121)
			(xy 103.479575 32.85692) (xy 103.487487 32.771537) (xy 103.487982 32.728662) (xy 103.487487 32.685787)
			(xy 103.479575 32.600404) (xy 103.463819 32.516114) (xy 103.440352 32.433638) (xy 103.409376 32.353679)
			(xy 103.371154 32.276919) (xy 103.326013 32.204013) (xy 103.274337 32.135584) (xy 103.216568 32.072214)
			(xy 103.153198 32.014445) (xy 103.084769 31.962769) (xy 103.011863 31.917628) (xy 102.935103 31.879406)
			(xy 102.855144 31.84843) (xy 102.772668 31.824963) (xy 102.688378 31.809207) (xy 102.602995 31.801295)
			(xy 102.517245 31.801295) (xy 102.431862 31.809207) (xy 102.347572 31.824963) (xy 102.265096 31.84843)
			(xy 102.185137 31.879406) (xy 102.108377 31.917628) (xy 102.035471 31.962769) (xy 101.967042 32.014445)
			(xy 101.903672 32.072214) (xy 101.845903 32.135584) (xy 101.794227 32.204013) (xy 101.749086 32.276919)
			(xy 101.710864 32.353679) (xy 101.679888 32.433638) (xy 101.656421 32.516114) (xy 101.640665 32.600404)
			(xy 101.632753 32.685787) (xy 100.947487 32.685787) (xy 100.939575 32.600404) (xy 100.923819 32.516114)
			(xy 100.900352 32.433638) (xy 100.869376 32.353679) (xy 100.831154 32.276919) (xy 100.786013 32.204013)
			(xy 100.734337 32.135584) (xy 100.676568 32.072214) (xy 100.613198 32.014445) (xy 100.544769 31.962769)
			(xy 100.471863 31.917628) (xy 100.395103 31.879406) (xy 100.315144 31.84843) (xy 100.232668 31.824963)
			(xy 100.148378 31.809207) (xy 100.062995 31.801295) (xy 99.977245 31.801295) (xy 99.891862 31.809207)
			(xy 99.807572 31.824963) (xy 99.725096 31.84843) (xy 99.645137 31.879406) (xy 99.568377 31.917628)
			(xy 99.495471 31.962769) (xy 99.427042 32.014445) (xy 99.363672 32.072214) (xy 99.305903 32.135584)
			(xy 99.254227 32.204013) (xy 99.209086 32.276919) (xy 99.170864 32.353679) (xy 99.139888 32.433638)
			(xy 99.116421 32.516114) (xy 99.100665 32.600404) (xy 99.092753 32.685787) (xy 92.50807 32.685787)
			(xy 92.50807 30.712026) (xy 100.476968 30.712026) (xy 100.476968 30.766574) (xy 100.484731 30.820568)
			(xy 100.5001 30.872907) (xy 100.522761 30.922526) (xy 100.552253 30.968414) (xy 100.587976 31.009639)
			(xy 100.629202 31.045359) (xy 100.675092 31.074849) (xy 100.724712 31.097507) (xy 100.777052 31.112873)
			(xy 100.831046 31.120634) (xy 100.85832 31.121096) (xy 101.72192 31.121096) (xy 101.749186 31.12054)
			(xy 101.803163 31.112777) (xy 101.855485 31.097411) (xy 101.905088 31.074756) (xy 101.950963 31.045272)
			(xy 101.992174 31.00956) (xy 102.027884 30.968347) (xy 102.057366 30.922471) (xy 102.080018 30.872866)
			(xy 102.095381 30.820543) (xy 102.103142 30.766566) (xy 102.103142 30.712034) (xy 102.095381 30.658057)
			(xy 102.080018 30.605734) (xy 102.057366 30.556129) (xy 102.027884 30.510253) (xy 101.992174 30.46904)
			(xy 101.950963 30.433328) (xy 101.905088 30.403844) (xy 101.855485 30.381189) (xy 101.803163 30.365823)
			(xy 101.749186 30.35806) (xy 101.72192 30.357572) (xy 100.85832 30.357572) (xy 100.831046 30.357966)
			(xy 100.777052 30.365727) (xy 100.724712 30.381093) (xy 100.675092 30.403751) (xy 100.629202 30.433241)
			(xy 100.587976 30.468961) (xy 100.552253 30.510186) (xy 100.522761 30.556074) (xy 100.5001 30.605693)
			(xy 100.484731 30.658032) (xy 100.476968 30.712026) (xy 92.50807 30.712026) (xy 92.50807 26.335787)
			(xy 99.092753 26.335787) (xy 99.092753 26.421537) (xy 99.100665 26.50692) (xy 99.116421 26.59121)
			(xy 99.139888 26.673686) (xy 99.170864 26.753645) (xy 99.209086 26.830405) (xy 99.254227 26.903311)
			(xy 99.305903 26.97174) (xy 99.363672 27.03511) (xy 99.427042 27.092879) (xy 99.495471 27.144555)
			(xy 99.568377 27.189696) (xy 99.645137 27.227918) (xy 99.725096 27.258894) (xy 99.807572 27.282361)
			(xy 99.891862 27.298117) (xy 99.977245 27.306029) (xy 100.062995 27.306029) (xy 100.148378 27.298117)
			(xy 100.232668 27.282361) (xy 100.315144 27.258894) (xy 100.395103 27.227918) (xy 100.471863 27.189696)
			(xy 100.544769 27.144555) (xy 100.613198 27.092879) (xy 100.676568 27.03511) (xy 100.734337 26.97174)
			(xy 100.786013 26.903311) (xy 100.831154 26.830405) (xy 100.869376 26.753645) (xy 100.900352 26.673686)
			(xy 100.923819 26.59121) (xy 100.939575 26.50692) (xy 100.947487 26.421537) (xy 100.947982 26.378662)
			(xy 100.947487 26.335787) (xy 101.632753 26.335787) (xy 101.632753 26.421537) (xy 101.640665 26.50692)
			(xy 101.656421 26.59121) (xy 101.679888 26.673686) (xy 101.710864 26.753645) (xy 101.749086 26.830405)
			(xy 101.794227 26.903311) (xy 101.845903 26.97174) (xy 101.903672 27.03511) (xy 101.967042 27.092879)
			(xy 102.035471 27.144555) (xy 102.108377 27.189696) (xy 102.185137 27.227918) (xy 102.265096 27.258894)
			(xy 102.347572 27.282361) (xy 102.431862 27.298117) (xy 102.517245 27.306029) (xy 102.602995 27.306029)
			(xy 102.688378 27.298117) (xy 102.772668 27.282361) (xy 102.855144 27.258894) (xy 102.935103 27.227918)
			(xy 103.011863 27.189696) (xy 103.084769 27.144555) (xy 103.153198 27.092879) (xy 103.216568 27.03511)
			(xy 103.274337 26.97174) (xy 103.326013 26.903311) (xy 103.371154 26.830405) (xy 103.409376 26.753645)
			(xy 103.440352 26.673686) (xy 103.463819 26.59121) (xy 103.479575 26.50692) (xy 103.487487 26.421537)
			(xy 103.487982 26.378662) (xy 103.487487 26.335787) (xy 103.479575 26.250404) (xy 103.463819 26.166114)
			(xy 103.440352 26.083638) (xy 103.409376 26.003679) (xy 103.371154 25.926919) (xy 103.326013 25.854013)
			(xy 103.274337 25.785584) (xy 103.216568 25.722214) (xy 103.153198 25.664445) (xy 103.084769 25.612769)
			(xy 103.011863 25.567628) (xy 102.935103 25.529406) (xy 102.855144 25.49843) (xy 102.772668 25.474963)
			(xy 102.688378 25.459207) (xy 102.602995 25.451295) (xy 102.517245 25.451295) (xy 102.431862 25.459207)
			(xy 102.347572 25.474963) (xy 102.265096 25.49843) (xy 102.185137 25.529406) (xy 102.108377 25.567628)
			(xy 102.035471 25.612769) (xy 101.967042 25.664445) (xy 101.903672 25.722214) (xy 101.845903 25.785584)
			(xy 101.794227 25.854013) (xy 101.749086 25.926919) (xy 101.710864 26.003679) (xy 101.679888 26.083638)
			(xy 101.656421 26.166114) (xy 101.640665 26.250404) (xy 101.632753 26.335787) (xy 100.947487 26.335787)
			(xy 100.939575 26.250404) (xy 100.923819 26.166114) (xy 100.900352 26.083638) (xy 100.869376 26.003679)
			(xy 100.831154 25.926919) (xy 100.786013 25.854013) (xy 100.734337 25.785584) (xy 100.676568 25.722214)
			(xy 100.613198 25.664445) (xy 100.544769 25.612769) (xy 100.471863 25.567628) (xy 100.395103 25.529406)
			(xy 100.315144 25.49843) (xy 100.232668 25.474963) (xy 100.148378 25.459207) (xy 100.062995 25.451295)
			(xy 99.977245 25.451295) (xy 99.891862 25.459207) (xy 99.807572 25.474963) (xy 99.725096 25.49843)
			(xy 99.645137 25.529406) (xy 99.568377 25.567628) (xy 99.495471 25.612769) (xy 99.427042 25.664445)
			(xy 99.363672 25.722214) (xy 99.305903 25.785584) (xy 99.254227 25.854013) (xy 99.209086 25.926919)
			(xy 99.170864 26.003679) (xy 99.139888 26.083638) (xy 99.116421 26.166114) (xy 99.100665 26.250404)
			(xy 99.092753 26.335787) (xy 92.50807 26.335787) (xy 92.50807 20.841513) (xy 99.085133 20.841513)
			(xy 99.085133 20.927263) (xy 99.093045 21.012646) (xy 99.108801 21.096936) (xy 99.132268 21.179412)
			(xy 99.163244 21.259371) (xy 99.201466 21.336131) (xy 99.246607 21.409037) (xy 99.298283 21.477466)
			(xy 99.356052 21.540836) (xy 99.419422 21.598605) (xy 99.487851 21.650281) (xy 99.560757 21.695422)
			(xy 99.637517 21.733644) (xy 99.717476 21.76462) (xy 99.799952 21.788087) (xy 99.884242 21.803843)
			(xy 99.969625 21.811755) (xy 100.055375 21.811755) (xy 100.140758 21.803843) (xy 100.225048 21.788087)
			(xy 100.307524 21.76462) (xy 100.387483 21.733644) (xy 100.464243 21.695422) (xy 100.537149 21.650281)
			(xy 100.605578 21.598605) (xy 100.668948 21.540836) (xy 100.726717 21.477466) (xy 100.778393 21.409037)
			(xy 100.823534 21.336131) (xy 100.861756 21.259371) (xy 100.892732 21.179412) (xy 100.916199 21.096936)
			(xy 100.931955 21.012646) (xy 100.939867 20.927263) (xy 100.940362 20.884388) (xy 100.939867 20.841513)
			(xy 101.625133 20.841513) (xy 101.625133 20.927263) (xy 101.633045 21.012646) (xy 101.648801 21.096936)
			(xy 101.672268 21.179412) (xy 101.703244 21.259371) (xy 101.741466 21.336131) (xy 101.786607 21.409037)
			(xy 101.838283 21.477466) (xy 101.896052 21.540836) (xy 101.959422 21.598605) (xy 102.027851 21.650281)
			(xy 102.100757 21.695422) (xy 102.177517 21.733644) (xy 102.257476 21.76462) (xy 102.339952 21.788087)
			(xy 102.424242 21.803843) (xy 102.509625 21.811755) (xy 102.595375 21.811755) (xy 102.680758 21.803843)
			(xy 102.765048 21.788087) (xy 102.847524 21.76462) (xy 102.927483 21.733644) (xy 103.004243 21.695422)
			(xy 103.077149 21.650281) (xy 103.145578 21.598605) (xy 103.208948 21.540836) (xy 103.266717 21.477466)
			(xy 103.318393 21.409037) (xy 103.363534 21.336131) (xy 103.401756 21.259371) (xy 103.432732 21.179412)
			(xy 103.456199 21.096936) (xy 103.471955 21.012646) (xy 103.479867 20.927263) (xy 103.480362 20.884388)
			(xy 103.479867 20.841513) (xy 104.165133 20.841513) (xy 104.165133 20.927263) (xy 104.173045 21.012646)
			(xy 104.188801 21.096936) (xy 104.212268 21.179412) (xy 104.243244 21.259371) (xy 104.281466 21.336131)
			(xy 104.326607 21.409037) (xy 104.378283 21.477466) (xy 104.436052 21.540836) (xy 104.499422 21.598605)
			(xy 104.567851 21.650281) (xy 104.640757 21.695422) (xy 104.717517 21.733644) (xy 104.797476 21.76462)
			(xy 104.879952 21.788087) (xy 104.964242 21.803843) (xy 105.049625 21.811755) (xy 105.135375 21.811755)
			(xy 105.220758 21.803843) (xy 105.305048 21.788087) (xy 105.387524 21.76462) (xy 105.467483 21.733644)
			(xy 105.544243 21.695422) (xy 105.617149 21.650281) (xy 105.685578 21.598605) (xy 105.748948 21.540836)
			(xy 105.806717 21.477466) (xy 105.858393 21.409037) (xy 105.903534 21.336131) (xy 105.941756 21.259371)
			(xy 105.972732 21.179412) (xy 105.996199 21.096936) (xy 106.011955 21.012646) (xy 106.019867 20.927263)
			(xy 106.020362 20.884388) (xy 106.019867 20.841513) (xy 106.011955 20.75613) (xy 105.996199 20.67184)
			(xy 105.972732 20.589364) (xy 105.941756 20.509405) (xy 105.903534 20.432645) (xy 105.858393 20.359739)
			(xy 105.806717 20.29131) (xy 105.748948 20.22794) (xy 105.685578 20.170171) (xy 105.617149 20.118495)
			(xy 105.544243 20.073354) (xy 105.467483 20.035132) (xy 105.387524 20.004156) (xy 105.305048 19.980689)
			(xy 105.220758 19.964933) (xy 105.135375 19.957021) (xy 105.049625 19.957021) (xy 104.964242 19.964933)
			(xy 104.879952 19.980689) (xy 104.797476 20.004156) (xy 104.717517 20.035132) (xy 104.640757 20.073354)
			(xy 104.567851 20.118495) (xy 104.499422 20.170171) (xy 104.436052 20.22794) (xy 104.378283 20.29131)
			(xy 104.326607 20.359739) (xy 104.281466 20.432645) (xy 104.243244 20.509405) (xy 104.212268 20.589364)
			(xy 104.188801 20.67184) (xy 104.173045 20.75613) (xy 104.165133 20.841513) (xy 103.479867 20.841513)
			(xy 103.471955 20.75613) (xy 103.456199 20.67184) (xy 103.432732 20.589364) (xy 103.401756 20.509405)
			(xy 103.363534 20.432645) (xy 103.318393 20.359739) (xy 103.266717 20.29131) (xy 103.208948 20.22794)
			(xy 103.145578 20.170171) (xy 103.077149 20.118495) (xy 103.004243 20.073354) (xy 102.927483 20.035132)
			(xy 102.847524 20.004156) (xy 102.765048 19.980689) (xy 102.680758 19.964933) (xy 102.595375 19.957021)
			(xy 102.509625 19.957021) (xy 102.424242 19.964933) (xy 102.339952 19.980689) (xy 102.257476 20.004156)
			(xy 102.177517 20.035132) (xy 102.100757 20.073354) (xy 102.027851 20.118495) (xy 101.959422 20.170171)
			(xy 101.896052 20.22794) (xy 101.838283 20.29131) (xy 101.786607 20.359739) (xy 101.741466 20.432645)
			(xy 101.703244 20.509405) (xy 101.672268 20.589364) (xy 101.648801 20.67184) (xy 101.633045 20.75613)
			(xy 101.625133 20.841513) (xy 100.939867 20.841513) (xy 100.931955 20.75613) (xy 100.916199 20.67184)
			(xy 100.892732 20.589364) (xy 100.861756 20.509405) (xy 100.823534 20.432645) (xy 100.778393 20.359739)
			(xy 100.726717 20.29131) (xy 100.668948 20.22794) (xy 100.605578 20.170171) (xy 100.537149 20.118495)
			(xy 100.464243 20.073354) (xy 100.387483 20.035132) (xy 100.307524 20.004156) (xy 100.225048 19.980689)
			(xy 100.140758 19.964933) (xy 100.055375 19.957021) (xy 99.969625 19.957021) (xy 99.884242 19.964933)
			(xy 99.799952 19.980689) (xy 99.717476 20.004156) (xy 99.637517 20.035132) (xy 99.560757 20.073354)
			(xy 99.487851 20.118495) (xy 99.419422 20.170171) (xy 99.356052 20.22794) (xy 99.298283 20.29131)
			(xy 99.246607 20.359739) (xy 99.201466 20.432645) (xy 99.163244 20.509405) (xy 99.132268 20.589364)
			(xy 99.108801 20.67184) (xy 99.093045 20.75613) (xy 99.085133 20.841513) (xy 92.50807 20.841513)
			(xy 92.50807 14.491513) (xy 99.085133 14.491513) (xy 99.085133 14.577263) (xy 99.093045 14.662646)
			(xy 99.108801 14.746936) (xy 99.132268 14.829412) (xy 99.163244 14.909371) (xy 99.201466 14.986131)
			(xy 99.246607 15.059037) (xy 99.298283 15.127466) (xy 99.356052 15.190836) (xy 99.419422 15.248605)
			(xy 99.487851 15.300281) (xy 99.560757 15.345422) (xy 99.637517 15.383644) (xy 99.717476 15.41462)
			(xy 99.799952 15.438087) (xy 99.884242 15.453843) (xy 99.969625 15.461755) (xy 100.055375 15.461755)
			(xy 100.140758 15.453843) (xy 100.225048 15.438087) (xy 100.307524 15.41462) (xy 100.387483 15.383644)
			(xy 100.464243 15.345422) (xy 100.537149 15.300281) (xy 100.605578 15.248605) (xy 100.668948 15.190836)
			(xy 100.726717 15.127466) (xy 100.778393 15.059037) (xy 100.823534 14.986131) (xy 100.861756 14.909371)
			(xy 100.892732 14.829412) (xy 100.916199 14.746936) (xy 100.931955 14.662646) (xy 100.939867 14.577263)
			(xy 100.940362 14.534388) (xy 100.939867 14.491513) (xy 101.625133 14.491513) (xy 101.625133 14.577263)
			(xy 101.633045 14.662646) (xy 101.648801 14.746936) (xy 101.672268 14.829412) (xy 101.703244 14.909371)
			(xy 101.741466 14.986131) (xy 101.786607 15.059037) (xy 101.838283 15.127466) (xy 101.896052 15.190836)
			(xy 101.959422 15.248605) (xy 102.027851 15.300281) (xy 102.100757 15.345422) (xy 102.177517 15.383644)
			(xy 102.257476 15.41462) (xy 102.339952 15.438087) (xy 102.424242 15.453843) (xy 102.509625 15.461755)
			(xy 102.595375 15.461755) (xy 102.680758 15.453843) (xy 102.765048 15.438087) (xy 102.847524 15.41462)
			(xy 102.927483 15.383644) (xy 103.004243 15.345422) (xy 103.077149 15.300281) (xy 103.145578 15.248605)
			(xy 103.208948 15.190836) (xy 103.266717 15.127466) (xy 103.318393 15.059037) (xy 103.363534 14.986131)
			(xy 103.401756 14.909371) (xy 103.432732 14.829412) (xy 103.456199 14.746936) (xy 103.471955 14.662646)
			(xy 103.479867 14.577263) (xy 103.480362 14.534388) (xy 103.479867 14.491513) (xy 104.165133 14.491513)
			(xy 104.165133 14.577263) (xy 104.173045 14.662646) (xy 104.188801 14.746936) (xy 104.212268 14.829412)
			(xy 104.243244 14.909371) (xy 104.281466 14.986131) (xy 104.326607 15.059037) (xy 104.378283 15.127466)
			(xy 104.436052 15.190836) (xy 104.499422 15.248605) (xy 104.567851 15.300281) (xy 104.640757 15.345422)
			(xy 104.717517 15.383644) (xy 104.797476 15.41462) (xy 104.879952 15.438087) (xy 104.964242 15.453843)
			(xy 105.049625 15.461755) (xy 105.135375 15.461755) (xy 105.220758 15.453843) (xy 105.305048 15.438087)
			(xy 105.387524 15.41462) (xy 105.467483 15.383644) (xy 105.544243 15.345422) (xy 105.617149 15.300281)
			(xy 105.685578 15.248605) (xy 105.748948 15.190836) (xy 105.806717 15.127466) (xy 105.858393 15.059037)
			(xy 105.903534 14.986131) (xy 105.941756 14.909371) (xy 105.972732 14.829412) (xy 105.996199 14.746936)
			(xy 106.011955 14.662646) (xy 106.019867 14.577263) (xy 106.020362 14.534388) (xy 106.019867 14.491513)
			(xy 106.011955 14.40613) (xy 105.996199 14.32184) (xy 105.972732 14.239364) (xy 105.941756 14.159405)
			(xy 105.903534 14.082645) (xy 105.858393 14.009739) (xy 105.806717 13.94131) (xy 105.748948 13.87794)
			(xy 105.685578 13.820171) (xy 105.617149 13.768495) (xy 105.544243 13.723354) (xy 105.467483 13.685132)
			(xy 105.387524 13.654156) (xy 105.305048 13.630689) (xy 105.220758 13.614933) (xy 105.135375 13.607021)
			(xy 105.049625 13.607021) (xy 104.964242 13.614933) (xy 104.879952 13.630689) (xy 104.797476 13.654156)
			(xy 104.717517 13.685132) (xy 104.640757 13.723354) (xy 104.567851 13.768495) (xy 104.499422 13.820171)
			(xy 104.436052 13.87794) (xy 104.378283 13.94131) (xy 104.326607 14.009739) (xy 104.281466 14.082645)
			(xy 104.243244 14.159405) (xy 104.212268 14.239364) (xy 104.188801 14.32184) (xy 104.173045 14.40613)
			(xy 104.165133 14.491513) (xy 103.479867 14.491513) (xy 103.471955 14.40613) (xy 103.456199 14.32184)
			(xy 103.432732 14.239364) (xy 103.401756 14.159405) (xy 103.363534 14.082645) (xy 103.318393 14.009739)
			(xy 103.266717 13.94131) (xy 103.208948 13.87794) (xy 103.145578 13.820171) (xy 103.077149 13.768495)
			(xy 103.004243 13.723354) (xy 102.927483 13.685132) (xy 102.847524 13.654156) (xy 102.765048 13.630689)
			(xy 102.680758 13.614933) (xy 102.595375 13.607021) (xy 102.509625 13.607021) (xy 102.424242 13.614933)
			(xy 102.339952 13.630689) (xy 102.257476 13.654156) (xy 102.177517 13.685132) (xy 102.100757 13.723354)
			(xy 102.027851 13.768495) (xy 101.959422 13.820171) (xy 101.896052 13.87794) (xy 101.838283 13.94131)
			(xy 101.786607 14.009739) (xy 101.741466 14.082645) (xy 101.703244 14.159405) (xy 101.672268 14.239364)
			(xy 101.648801 14.32184) (xy 101.633045 14.40613) (xy 101.625133 14.491513) (xy 100.939867 14.491513)
			(xy 100.931955 14.40613) (xy 100.916199 14.32184) (xy 100.892732 14.239364) (xy 100.861756 14.159405)
			(xy 100.823534 14.082645) (xy 100.778393 14.009739) (xy 100.726717 13.94131) (xy 100.668948 13.87794)
			(xy 100.605578 13.820171) (xy 100.537149 13.768495) (xy 100.464243 13.723354) (xy 100.387483 13.685132)
			(xy 100.307524 13.654156) (xy 100.225048 13.630689) (xy 100.140758 13.614933) (xy 100.055375 13.607021)
			(xy 99.969625 13.607021) (xy 99.884242 13.614933) (xy 99.799952 13.630689) (xy 99.717476 13.654156)
			(xy 99.637517 13.685132) (xy 99.560757 13.723354) (xy 99.487851 13.768495) (xy 99.419422 13.820171)
			(xy 99.356052 13.87794) (xy 99.298283 13.94131) (xy 99.246607 14.009739) (xy 99.201466 14.082645)
			(xy 99.163244 14.159405) (xy 99.132268 14.239364) (xy 99.108801 14.32184) (xy 99.093045 14.40613)
			(xy 99.085133 14.491513) (xy 92.50807 14.491513) (xy 92.50807 -1.181049) (xy 93.729289 -1.181049)
			(xy 93.729289 -1.095299) (xy 93.737201 -1.009916) (xy 93.752957 -0.925626) (xy 93.776424 -0.84315)
			(xy 93.8074 -0.763191) (xy 93.845622 -0.686431) (xy 93.890763 -0.613525) (xy 93.942439 -0.545096)
			(xy 94.000208 -0.481726) (xy 94.063578 -0.423957) (xy 94.132007 -0.372281) (xy 94.204913 -0.32714)
			(xy 94.281673 -0.288918) (xy 94.361632 -0.257942) (xy 94.444108 -0.234475) (xy 94.528398 -0.218719)
			(xy 94.613781 -0.210807) (xy 94.699531 -0.210807) (xy 94.784914 -0.218719) (xy 94.869204 -0.234475)
			(xy 94.95168 -0.257942) (xy 95.031639 -0.288918) (xy 95.108399 -0.32714) (xy 95.181305 -0.372281)
			(xy 95.249734 -0.423957) (xy 95.313104 -0.481726) (xy 95.370873 -0.545096) (xy 95.422549 -0.613525)
			(xy 95.46769 -0.686431) (xy 95.505912 -0.763191) (xy 95.536888 -0.84315) (xy 95.560355 -0.925626)
			(xy 95.576111 -1.009916) (xy 95.584023 -1.095299) (xy 95.584518 -1.138174) (xy 95.584023 -1.181049)
			(xy 96.269289 -1.181049) (xy 96.269289 -1.095299) (xy 96.277201 -1.009916) (xy 96.292957 -0.925626)
			(xy 96.316424 -0.84315) (xy 96.3474 -0.763191) (xy 96.385622 -0.686431) (xy 96.430763 -0.613525)
			(xy 96.482439 -0.545096) (xy 96.540208 -0.481726) (xy 96.603578 -0.423957) (xy 96.672007 -0.372281)
			(xy 96.744913 -0.32714) (xy 96.821673 -0.288918) (xy 96.901632 -0.257942) (xy 96.984108 -0.234475)
			(xy 97.068398 -0.218719) (xy 97.153781 -0.210807) (xy 97.239531 -0.210807) (xy 97.324914 -0.218719)
			(xy 97.409204 -0.234475) (xy 97.49168 -0.257942) (xy 97.571639 -0.288918) (xy 97.648399 -0.32714)
			(xy 97.721305 -0.372281) (xy 97.789734 -0.423957) (xy 97.853104 -0.481726) (xy 97.910873 -0.545096)
			(xy 97.962549 -0.613525) (xy 98.00769 -0.686431) (xy 98.045912 -0.763191) (xy 98.076888 -0.84315)
			(xy 98.100355 -0.925626) (xy 98.116111 -1.009916) (xy 98.124023 -1.095299) (xy 98.124518 -1.138174)
			(xy 98.124023 -1.181049) (xy 98.116111 -1.266432) (xy 98.100355 -1.350722) (xy 98.076888 -1.433198)
			(xy 98.045912 -1.513157) (xy 98.00769 -1.589917) (xy 97.962549 -1.662823) (xy 97.910873 -1.731252)
			(xy 97.853104 -1.794622) (xy 97.789734 -1.852391) (xy 97.721305 -1.904067) (xy 97.648399 -1.949208)
			(xy 97.571639 -1.98743) (xy 97.49168 -2.018406) (xy 97.409204 -2.041873) (xy 97.324914 -2.057629)
			(xy 97.239531 -2.065541) (xy 97.153781 -2.065541) (xy 97.068398 -2.057629) (xy 96.984108 -2.041873)
			(xy 96.901632 -2.018406) (xy 96.821673 -1.98743) (xy 96.744913 -1.949208) (xy 96.672007 -1.904067)
			(xy 96.603578 -1.852391) (xy 96.540208 -1.794622) (xy 96.482439 -1.731252) (xy 96.430763 -1.662823)
			(xy 96.385622 -1.589917) (xy 96.3474 -1.513157) (xy 96.316424 -1.433198) (xy 96.292957 -1.350722)
			(xy 96.277201 -1.266432) (xy 96.269289 -1.181049) (xy 95.584023 -1.181049) (xy 95.576111 -1.266432)
			(xy 95.560355 -1.350722) (xy 95.536888 -1.433198) (xy 95.505912 -1.513157) (xy 95.46769 -1.589917)
			(xy 95.422549 -1.662823) (xy 95.370873 -1.731252) (xy 95.313104 -1.794622) (xy 95.249734 -1.852391)
			(xy 95.181305 -1.904067) (xy 95.108399 -1.949208) (xy 95.031639 -1.98743) (xy 94.95168 -2.018406)
			(xy 94.869204 -2.041873) (xy 94.784914 -2.057629) (xy 94.699531 -2.065541) (xy 94.613781 -2.065541)
			(xy 94.528398 -2.057629) (xy 94.444108 -2.041873) (xy 94.361632 -2.018406) (xy 94.281673 -1.98743)
			(xy 94.204913 -1.949208) (xy 94.132007 -1.904067) (xy 94.063578 -1.852391) (xy 94.000208 -1.794622)
			(xy 93.942439 -1.731252) (xy 93.890763 -1.662823) (xy 93.845622 -1.589917) (xy 93.8074 -1.513157)
			(xy 93.776424 -1.433198) (xy 93.752957 -1.350722) (xy 93.737201 -1.266432) (xy 93.729289 -1.181049)
			(xy 92.50807 -1.181049) (xy 92.50807 -3.154767) (xy 95.113626 -3.154767) (xy 95.113626 -3.100233)
			(xy 95.121387 -3.046253) (xy 95.13675 -2.993928) (xy 95.159403 -2.944321) (xy 95.188884 -2.898442)
			(xy 95.224595 -2.857226) (xy 95.265807 -2.821511) (xy 95.311682 -2.792024) (xy 95.361286 -2.769365)
			(xy 95.41361 -2.753996) (xy 95.467589 -2.746229) (xy 95.494856 -2.74574) (xy 96.358456 -2.74574)
			(xy 96.385729 -2.746196) (xy 96.439721 -2.753954) (xy 96.492059 -2.769316) (xy 96.541678 -2.791971)
			(xy 96.587568 -2.821458) (xy 96.628793 -2.857176) (xy 96.664516 -2.898397) (xy 96.694008 -2.944283)
			(xy 96.716668 -2.993899) (xy 96.732037 -3.046236) (xy 96.7398 -3.100227) (xy 96.7398 -3.154773) (xy 96.732037 -3.208764)
			(xy 96.716668 -3.261101) (xy 96.694008 -3.310717) (xy 96.664516 -3.356603) (xy 96.628793 -3.397824)
			(xy 96.587568 -3.433542) (xy 96.541678 -3.463029) (xy 96.492059 -3.485684) (xy 96.439721 -3.501046)
			(xy 96.385729 -3.508804) (xy 96.358456 -3.509264) (xy 95.494856 -3.509264) (xy 95.467589 -3.508771)
			(xy 95.41361 -3.501004) (xy 95.361286 -3.485635) (xy 95.311682 -3.462976) (xy 95.265807 -3.433489)
			(xy 95.224595 -3.397774) (xy 95.188884 -3.356558) (xy 95.159403 -3.310679) (xy 95.13675 -3.261072)
			(xy 95.121387 -3.208747) (xy 95.113626 -3.154767) (xy 92.50807 -3.154767) (xy 92.50807 -7.531049)
			(xy 93.729289 -7.531049) (xy 93.729289 -7.445299) (xy 93.737201 -7.359916) (xy 93.752957 -7.275626)
			(xy 93.776424 -7.19315) (xy 93.8074 -7.113191) (xy 93.845622 -7.036431) (xy 93.890763 -6.963525)
			(xy 93.942439 -6.895096) (xy 94.000208 -6.831726) (xy 94.063578 -6.773957) (xy 94.132007 -6.722281)
			(xy 94.204913 -6.67714) (xy 94.281673 -6.638918) (xy 94.361632 -6.607942) (xy 94.444108 -6.584475)
			(xy 94.528398 -6.568719) (xy 94.613781 -6.560807) (xy 94.699531 -6.560807) (xy 94.784914 -6.568719)
			(xy 94.869204 -6.584475) (xy 94.95168 -6.607942) (xy 95.031639 -6.638918) (xy 95.108399 -6.67714)
			(xy 95.181305 -6.722281) (xy 95.249734 -6.773957) (xy 95.313104 -6.831726) (xy 95.370873 -6.895096)
			(xy 95.422549 -6.963525) (xy 95.46769 -7.036431) (xy 95.505912 -7.113191) (xy 95.536888 -7.19315)
			(xy 95.560355 -7.275626) (xy 95.576111 -7.359916) (xy 95.584023 -7.445299) (xy 95.584518 -7.488174)
			(xy 95.584023 -7.531049) (xy 96.269289 -7.531049) (xy 96.269289 -7.445299) (xy 96.277201 -7.359916)
			(xy 96.292957 -7.275626) (xy 96.316424 -7.19315) (xy 96.3474 -7.113191) (xy 96.385622 -7.036431)
			(xy 96.430763 -6.963525) (xy 96.482439 -6.895096) (xy 96.540208 -6.831726) (xy 96.603578 -6.773957)
			(xy 96.672007 -6.722281) (xy 96.744913 -6.67714) (xy 96.821673 -6.638918) (xy 96.901632 -6.607942)
			(xy 96.984108 -6.584475) (xy 97.068398 -6.568719) (xy 97.153781 -6.560807) (xy 97.239531 -6.560807)
			(xy 97.324914 -6.568719) (xy 97.409204 -6.584475) (xy 97.49168 -6.607942) (xy 97.571639 -6.638918)
			(xy 97.648399 -6.67714) (xy 97.721305 -6.722281) (xy 97.789734 -6.773957) (xy 97.853104 -6.831726)
			(xy 97.910873 -6.895096) (xy 97.962549 -6.963525) (xy 98.00769 -7.036431) (xy 98.045912 -7.113191)
			(xy 98.076888 -7.19315) (xy 98.100355 -7.275626) (xy 98.116111 -7.359916) (xy 98.124023 -7.445299)
			(xy 98.124518 -7.488174) (xy 98.124023 -7.531049) (xy 98.116111 -7.616432) (xy 98.100355 -7.700722)
			(xy 98.076888 -7.783198) (xy 98.045912 -7.863157) (xy 98.00769 -7.939917) (xy 97.962549 -8.012823)
			(xy 97.910873 -8.081252) (xy 97.853104 -8.144622) (xy 97.789734 -8.202391) (xy 97.721305 -8.254067)
			(xy 97.648399 -8.299208) (xy 97.571639 -8.33743) (xy 97.49168 -8.368406) (xy 97.409204 -8.391873)
			(xy 97.324914 -8.407629) (xy 97.239531 -8.415541) (xy 97.153781 -8.415541) (xy 97.068398 -8.407629)
			(xy 96.984108 -8.391873) (xy 96.901632 -8.368406) (xy 96.821673 -8.33743) (xy 96.744913 -8.299208)
			(xy 96.672007 -8.254067) (xy 96.603578 -8.202391) (xy 96.540208 -8.144622) (xy 96.482439 -8.081252)
			(xy 96.430763 -8.012823) (xy 96.385622 -7.939917) (xy 96.3474 -7.863157) (xy 96.316424 -7.783198)
			(xy 96.292957 -7.700722) (xy 96.277201 -7.616432) (xy 96.269289 -7.531049) (xy 95.584023 -7.531049)
			(xy 95.576111 -7.616432) (xy 95.560355 -7.700722) (xy 95.536888 -7.783198) (xy 95.505912 -7.863157)
			(xy 95.46769 -7.939917) (xy 95.422549 -8.012823) (xy 95.370873 -8.081252) (xy 95.313104 -8.144622)
			(xy 95.249734 -8.202391) (xy 95.181305 -8.254067) (xy 95.108399 -8.299208) (xy 95.031639 -8.33743)
			(xy 94.95168 -8.368406) (xy 94.869204 -8.391873) (xy 94.784914 -8.407629) (xy 94.699531 -8.415541)
			(xy 94.613781 -8.415541) (xy 94.528398 -8.407629) (xy 94.444108 -8.391873) (xy 94.361632 -8.368406)
			(xy 94.281673 -8.33743) (xy 94.204913 -8.299208) (xy 94.132007 -8.254067) (xy 94.063578 -8.202391)
			(xy 94.000208 -8.144622) (xy 93.942439 -8.081252) (xy 93.890763 -8.012823) (xy 93.845622 -7.939917)
			(xy 93.8074 -7.863157) (xy 93.776424 -7.783198) (xy 93.752957 -7.700722) (xy 93.737201 -7.616432)
			(xy 93.729289 -7.531049) (xy 92.50807 -7.531049) (xy 92.50807 -13.055549) (xy 93.714049 -13.055549)
			(xy 93.714049 -12.969799) (xy 93.721961 -12.884416) (xy 93.737717 -12.800126) (xy 93.761184 -12.71765)
			(xy 93.79216 -12.637691) (xy 93.830382 -12.560931) (xy 93.875523 -12.488025) (xy 93.927199 -12.419596)
			(xy 93.984968 -12.356226) (xy 94.048338 -12.298457) (xy 94.116767 -12.246781) (xy 94.189673 -12.20164)
			(xy 94.266433 -12.163418) (xy 94.346392 -12.132442) (xy 94.428868 -12.108975) (xy 94.513158 -12.093219)
			(xy 94.598541 -12.085307) (xy 94.684291 -12.085307) (xy 94.769674 -12.093219) (xy 94.853964 -12.108975)
			(xy 94.93644 -12.132442) (xy 95.016399 -12.163418) (xy 95.093159 -12.20164) (xy 95.166065 -12.246781)
			(xy 95.234494 -12.298457) (xy 95.297864 -12.356226) (xy 95.355633 -12.419596) (xy 95.407309 -12.488025)
			(xy 95.45245 -12.560931) (xy 95.490672 -12.637691) (xy 95.521648 -12.71765) (xy 95.545115 -12.800126)
			(xy 95.560871 -12.884416) (xy 95.568783 -12.969799) (xy 95.569278 -13.012674) (xy 95.568783 -13.055549)
			(xy 96.254049 -13.055549) (xy 96.254049 -12.969799) (xy 96.261961 -12.884416) (xy 96.277717 -12.800126)
			(xy 96.301184 -12.71765) (xy 96.33216 -12.637691) (xy 96.370382 -12.560931) (xy 96.415523 -12.488025)
			(xy 96.467199 -12.419596) (xy 96.524968 -12.356226) (xy 96.588338 -12.298457) (xy 96.656767 -12.246781)
			(xy 96.729673 -12.20164) (xy 96.806433 -12.163418) (xy 96.886392 -12.132442) (xy 96.968868 -12.108975)
			(xy 97.053158 -12.093219) (xy 97.138541 -12.085307) (xy 97.224291 -12.085307) (xy 97.309674 -12.093219)
			(xy 97.393964 -12.108975) (xy 97.47644 -12.132442) (xy 97.556399 -12.163418) (xy 97.633159 -12.20164)
			(xy 97.706065 -12.246781) (xy 97.774494 -12.298457) (xy 97.837864 -12.356226) (xy 97.895633 -12.419596)
			(xy 97.947309 -12.488025) (xy 97.99245 -12.560931) (xy 98.030672 -12.637691) (xy 98.061648 -12.71765)
			(xy 98.085115 -12.800126) (xy 98.100871 -12.884416) (xy 98.108783 -12.969799) (xy 98.109278 -13.012674)
			(xy 98.108783 -13.055549) (xy 98.100871 -13.140932) (xy 98.085115 -13.225222) (xy 98.061648 -13.307698)
			(xy 98.030672 -13.387657) (xy 97.99245 -13.464417) (xy 97.947309 -13.537323) (xy 97.895633 -13.605752)
			(xy 97.837864 -13.669122) (xy 97.774494 -13.726891) (xy 97.706065 -13.778567) (xy 97.633159 -13.823708)
			(xy 97.556399 -13.86193) (xy 97.47644 -13.892906) (xy 97.393964 -13.916373) (xy 97.309674 -13.932129)
			(xy 97.224291 -13.940041) (xy 97.138541 -13.940041) (xy 97.053158 -13.932129) (xy 96.968868 -13.916373)
			(xy 96.886392 -13.892906) (xy 96.806433 -13.86193) (xy 96.729673 -13.823708) (xy 96.656767 -13.778567)
			(xy 96.588338 -13.726891) (xy 96.524968 -13.669122) (xy 96.467199 -13.605752) (xy 96.415523 -13.537323)
			(xy 96.370382 -13.464417) (xy 96.33216 -13.387657) (xy 96.301184 -13.307698) (xy 96.277717 -13.225222)
			(xy 96.261961 -13.140932) (xy 96.254049 -13.055549) (xy 95.568783 -13.055549) (xy 95.560871 -13.140932)
			(xy 95.545115 -13.225222) (xy 95.521648 -13.307698) (xy 95.490672 -13.387657) (xy 95.45245 -13.464417)
			(xy 95.407309 -13.537323) (xy 95.355633 -13.605752) (xy 95.297864 -13.669122) (xy 95.234494 -13.726891)
			(xy 95.166065 -13.778567) (xy 95.093159 -13.823708) (xy 95.016399 -13.86193) (xy 94.93644 -13.892906)
			(xy 94.853964 -13.916373) (xy 94.769674 -13.932129) (xy 94.684291 -13.940041) (xy 94.598541 -13.940041)
			(xy 94.513158 -13.932129) (xy 94.428868 -13.916373) (xy 94.346392 -13.892906) (xy 94.266433 -13.86193)
			(xy 94.189673 -13.823708) (xy 94.116767 -13.778567) (xy 94.048338 -13.726891) (xy 93.984968 -13.669122)
			(xy 93.927199 -13.605752) (xy 93.875523 -13.537323) (xy 93.830382 -13.464417) (xy 93.79216 -13.387657)
			(xy 93.761184 -13.307698) (xy 93.737717 -13.225222) (xy 93.721961 -13.140932) (xy 93.714049 -13.055549)
			(xy 92.50807 -13.055549) (xy 92.50807 -17.400568) (xy 95.098347 -17.400568) (xy 95.098347 -17.346032)
			(xy 95.106109 -17.29205) (xy 95.121474 -17.239722) (xy 95.14413 -17.190114) (xy 95.173616 -17.144235)
			(xy 95.209331 -17.103019) (xy 95.250548 -17.067306) (xy 95.296428 -17.037823) (xy 95.346037 -17.015169)
			(xy 95.398365 -16.999806) (xy 95.452348 -16.992046) (xy 95.479616 -16.991584) (xy 96.343216 -16.991584)
			(xy 96.370488 -16.99198) (xy 96.424476 -16.999744) (xy 96.47681 -17.015113) (xy 96.526424 -17.037773)
			(xy 96.572309 -17.067262) (xy 96.613529 -17.102982) (xy 96.649247 -17.144204) (xy 96.678735 -17.19009)
			(xy 96.701393 -17.239705) (xy 96.716759 -17.292039) (xy 96.724522 -17.346028) (xy 96.724522 -17.400572)
			(xy 96.716759 -17.454561) (xy 96.701393 -17.506895) (xy 96.678735 -17.55651) (xy 96.649247 -17.602396)
			(xy 96.613529 -17.643618) (xy 96.572309 -17.679338) (xy 96.526424 -17.708827) (xy 96.47681 -17.731487)
			(xy 96.424476 -17.746856) (xy 96.370488 -17.75462) (xy 96.343216 -17.755108) (xy 95.479616 -17.755108)
			(xy 95.452348 -17.754554) (xy 95.398365 -17.746794) (xy 95.346037 -17.731431) (xy 95.296428 -17.708777)
			(xy 95.250548 -17.679294) (xy 95.209331 -17.643581) (xy 95.173616 -17.602365) (xy 95.14413 -17.556486)
			(xy 95.121474 -17.506878) (xy 95.106109 -17.45455) (xy 95.098347 -17.400568) (xy 92.50807 -17.400568)
			(xy 92.50807 -19.405549) (xy 93.714049 -19.405549) (xy 93.714049 -19.319799) (xy 93.721961 -19.234416)
			(xy 93.737717 -19.150126) (xy 93.761184 -19.06765) (xy 93.79216 -18.987691) (xy 93.830382 -18.910931)
			(xy 93.875523 -18.838025) (xy 93.927199 -18.769596) (xy 93.984968 -18.706226) (xy 94.048338 -18.648457)
			(xy 94.116767 -18.596781) (xy 94.189673 -18.55164) (xy 94.266433 -18.513418) (xy 94.346392 -18.482442)
			(xy 94.428868 -18.458975) (xy 94.513158 -18.443219) (xy 94.598541 -18.435307) (xy 94.684291 -18.435307)
			(xy 94.769674 -18.443219) (xy 94.853964 -18.458975) (xy 94.93644 -18.482442) (xy 95.016399 -18.513418)
			(xy 95.093159 -18.55164) (xy 95.166065 -18.596781) (xy 95.234494 -18.648457) (xy 95.297864 -18.706226)
			(xy 95.355633 -18.769596) (xy 95.407309 -18.838025) (xy 95.45245 -18.910931) (xy 95.490672 -18.987691)
			(xy 95.521648 -19.06765) (xy 95.545115 -19.150126) (xy 95.560871 -19.234416) (xy 95.568783 -19.319799)
			(xy 95.569278 -19.362674) (xy 95.568783 -19.405549) (xy 96.254049 -19.405549) (xy 96.254049 -19.319799)
			(xy 96.261961 -19.234416) (xy 96.277717 -19.150126) (xy 96.301184 -19.06765) (xy 96.33216 -18.987691)
			(xy 96.370382 -18.910931) (xy 96.415523 -18.838025) (xy 96.467199 -18.769596) (xy 96.524968 -18.706226)
			(xy 96.588338 -18.648457) (xy 96.656767 -18.596781) (xy 96.729673 -18.55164) (xy 96.806433 -18.513418)
			(xy 96.886392 -18.482442) (xy 96.968868 -18.458975) (xy 97.053158 -18.443219) (xy 97.138541 -18.435307)
			(xy 97.224291 -18.435307) (xy 97.309674 -18.443219) (xy 97.393964 -18.458975) (xy 97.47644 -18.482442)
			(xy 97.556399 -18.513418) (xy 97.633159 -18.55164) (xy 97.706065 -18.596781) (xy 97.774494 -18.648457)
			(xy 97.837864 -18.706226) (xy 97.895633 -18.769596) (xy 97.947309 -18.838025) (xy 97.99245 -18.910931)
			(xy 98.030672 -18.987691) (xy 98.061648 -19.06765) (xy 98.085115 -19.150126) (xy 98.100871 -19.234416)
			(xy 98.108783 -19.319799) (xy 98.109278 -19.362674) (xy 98.108783 -19.405549) (xy 98.100871 -19.490932)
			(xy 98.085115 -19.575222) (xy 98.061648 -19.657698) (xy 98.030672 -19.737657) (xy 97.99245 -19.814417)
			(xy 97.947309 -19.887323) (xy 97.895633 -19.955752) (xy 97.837864 -20.019122) (xy 97.774494 -20.076891)
			(xy 97.706065 -20.128567) (xy 97.633159 -20.173708) (xy 97.556399 -20.21193) (xy 97.47644 -20.242906)
			(xy 97.393964 -20.266373) (xy 97.309674 -20.282129) (xy 97.224291 -20.290041) (xy 97.138541 -20.290041)
			(xy 97.053158 -20.282129) (xy 96.968868 -20.266373) (xy 96.886392 -20.242906) (xy 96.806433 -20.21193)
			(xy 96.729673 -20.173708) (xy 96.656767 -20.128567) (xy 96.588338 -20.076891) (xy 96.524968 -20.019122)
			(xy 96.467199 -19.955752) (xy 96.415523 -19.887323) (xy 96.370382 -19.814417) (xy 96.33216 -19.737657)
			(xy 96.301184 -19.657698) (xy 96.277717 -19.575222) (xy 96.261961 -19.490932) (xy 96.254049 -19.405549)
			(xy 95.568783 -19.405549) (xy 95.560871 -19.490932) (xy 95.545115 -19.575222) (xy 95.521648 -19.657698)
			(xy 95.490672 -19.737657) (xy 95.45245 -19.814417) (xy 95.407309 -19.887323) (xy 95.355633 -19.955752)
			(xy 95.297864 -20.019122) (xy 95.234494 -20.076891) (xy 95.166065 -20.128567) (xy 95.093159 -20.173708)
			(xy 95.016399 -20.21193) (xy 94.93644 -20.242906) (xy 94.853964 -20.266373) (xy 94.769674 -20.282129)
			(xy 94.684291 -20.290041) (xy 94.598541 -20.290041) (xy 94.513158 -20.282129) (xy 94.428868 -20.266373)
			(xy 94.346392 -20.242906) (xy 94.266433 -20.21193) (xy 94.189673 -20.173708) (xy 94.116767 -20.128567)
			(xy 94.048338 -20.076891) (xy 93.984968 -20.019122) (xy 93.927199 -19.955752) (xy 93.875523 -19.887323)
			(xy 93.830382 -19.814417) (xy 93.79216 -19.737657) (xy 93.761184 -19.657698) (xy 93.737717 -19.575222)
			(xy 93.721961 -19.490932) (xy 93.714049 -19.405549) (xy 92.50807 -19.405549) (xy 92.50807 -50.979527)
			(xy 99.085133 -50.979527) (xy 99.085133 -50.893777) (xy 99.093045 -50.808394) (xy 99.108801 -50.724104)
			(xy 99.132268 -50.641628) (xy 99.163244 -50.561669) (xy 99.201466 -50.484909) (xy 99.246607 -50.412003)
			(xy 99.298283 -50.343574) (xy 99.356052 -50.280204) (xy 99.419422 -50.222435) (xy 99.487851 -50.170759)
			(xy 99.560757 -50.125618) (xy 99.637517 -50.087396) (xy 99.717476 -50.05642) (xy 99.799952 -50.032953)
			(xy 99.884242 -50.017197) (xy 99.969625 -50.009285) (xy 100.055375 -50.009285) (xy 100.140758 -50.017197)
			(xy 100.225048 -50.032953) (xy 100.307524 -50.05642) (xy 100.387483 -50.087396) (xy 100.464243 -50.125618)
			(xy 100.537149 -50.170759) (xy 100.605578 -50.222435) (xy 100.668948 -50.280204) (xy 100.726717 -50.343574)
			(xy 100.778393 -50.412003) (xy 100.823534 -50.484909) (xy 100.861756 -50.561669) (xy 100.892732 -50.641628)
			(xy 100.916199 -50.724104) (xy 100.931955 -50.808394) (xy 100.939867 -50.893777) (xy 100.940362 -50.936652)
			(xy 100.939867 -50.979527) (xy 101.625133 -50.979527) (xy 101.625133 -50.893777) (xy 101.633045 -50.808394)
			(xy 101.648801 -50.724104) (xy 101.672268 -50.641628) (xy 101.703244 -50.561669) (xy 101.741466 -50.484909)
			(xy 101.786607 -50.412003) (xy 101.838283 -50.343574) (xy 101.896052 -50.280204) (xy 101.959422 -50.222435)
			(xy 102.027851 -50.170759) (xy 102.100757 -50.125618) (xy 102.177517 -50.087396) (xy 102.257476 -50.05642)
			(xy 102.339952 -50.032953) (xy 102.424242 -50.017197) (xy 102.509625 -50.009285) (xy 102.595375 -50.009285)
			(xy 102.680758 -50.017197) (xy 102.765048 -50.032953) (xy 102.847524 -50.05642) (xy 102.927483 -50.087396)
			(xy 103.004243 -50.125618) (xy 103.077149 -50.170759) (xy 103.145578 -50.222435) (xy 103.208948 -50.280204)
			(xy 103.266717 -50.343574) (xy 103.318393 -50.412003) (xy 103.363534 -50.484909) (xy 103.401756 -50.561669)
			(xy 103.432732 -50.641628) (xy 103.456199 -50.724104) (xy 103.471955 -50.808394) (xy 103.479867 -50.893777)
			(xy 103.480362 -50.936652) (xy 103.479867 -50.979527) (xy 104.165133 -50.979527) (xy 104.165133 -50.893777)
			(xy 104.173045 -50.808394) (xy 104.188801 -50.724104) (xy 104.212268 -50.641628) (xy 104.243244 -50.561669)
			(xy 104.281466 -50.484909) (xy 104.326607 -50.412003) (xy 104.378283 -50.343574) (xy 104.436052 -50.280204)
			(xy 104.499422 -50.222435) (xy 104.567851 -50.170759) (xy 104.640757 -50.125618) (xy 104.717517 -50.087396)
			(xy 104.797476 -50.05642) (xy 104.879952 -50.032953) (xy 104.964242 -50.017197) (xy 105.049625 -50.009285)
			(xy 105.135375 -50.009285) (xy 105.220758 -50.017197) (xy 105.305048 -50.032953) (xy 105.387524 -50.05642)
			(xy 105.467483 -50.087396) (xy 105.544243 -50.125618) (xy 105.617149 -50.170759) (xy 105.685578 -50.222435)
			(xy 105.748948 -50.280204) (xy 105.806717 -50.343574) (xy 105.858393 -50.412003) (xy 105.903534 -50.484909)
			(xy 105.941756 -50.561669) (xy 105.972732 -50.641628) (xy 105.996199 -50.724104) (xy 106.011955 -50.808394)
			(xy 106.019867 -50.893777) (xy 106.020362 -50.936652) (xy 106.019867 -50.979527) (xy 106.011955 -51.06491)
			(xy 105.996199 -51.1492) (xy 105.972732 -51.231676) (xy 105.941756 -51.311635) (xy 105.903534 -51.388395)
			(xy 105.858393 -51.461301) (xy 105.806717 -51.52973) (xy 105.748948 -51.5931) (xy 105.685578 -51.650869)
			(xy 105.617149 -51.702545) (xy 105.544243 -51.747686) (xy 105.467483 -51.785908) (xy 105.387524 -51.816884)
			(xy 105.305048 -51.840351) (xy 105.220758 -51.856107) (xy 105.135375 -51.864019) (xy 105.049625 -51.864019)
			(xy 104.964242 -51.856107) (xy 104.879952 -51.840351) (xy 104.797476 -51.816884) (xy 104.717517 -51.785908)
			(xy 104.640757 -51.747686) (xy 104.567851 -51.702545) (xy 104.499422 -51.650869) (xy 104.436052 -51.5931)
			(xy 104.378283 -51.52973) (xy 104.326607 -51.461301) (xy 104.281466 -51.388395) (xy 104.243244 -51.311635)
			(xy 104.212268 -51.231676) (xy 104.188801 -51.1492) (xy 104.173045 -51.06491) (xy 104.165133 -50.979527)
			(xy 103.479867 -50.979527) (xy 103.471955 -51.06491) (xy 103.456199 -51.1492) (xy 103.432732 -51.231676)
			(xy 103.401756 -51.311635) (xy 103.363534 -51.388395) (xy 103.318393 -51.461301) (xy 103.266717 -51.52973)
			(xy 103.208948 -51.5931) (xy 103.145578 -51.650869) (xy 103.077149 -51.702545) (xy 103.004243 -51.747686)
			(xy 102.927483 -51.785908) (xy 102.847524 -51.816884) (xy 102.765048 -51.840351) (xy 102.680758 -51.856107)
			(xy 102.595375 -51.864019) (xy 102.509625 -51.864019) (xy 102.424242 -51.856107) (xy 102.339952 -51.840351)
			(xy 102.257476 -51.816884) (xy 102.177517 -51.785908) (xy 102.100757 -51.747686) (xy 102.027851 -51.702545)
			(xy 101.959422 -51.650869) (xy 101.896052 -51.5931) (xy 101.838283 -51.52973) (xy 101.786607 -51.461301)
			(xy 101.741466 -51.388395) (xy 101.703244 -51.311635) (xy 101.672268 -51.231676) (xy 101.648801 -51.1492)
			(xy 101.633045 -51.06491) (xy 101.625133 -50.979527) (xy 100.939867 -50.979527) (xy 100.931955 -51.06491)
			(xy 100.916199 -51.1492) (xy 100.892732 -51.231676) (xy 100.861756 -51.311635) (xy 100.823534 -51.388395)
			(xy 100.778393 -51.461301) (xy 100.726717 -51.52973) (xy 100.668948 -51.5931) (xy 100.605578 -51.650869)
			(xy 100.537149 -51.702545) (xy 100.464243 -51.747686) (xy 100.387483 -51.785908) (xy 100.307524 -51.816884)
			(xy 100.225048 -51.840351) (xy 100.140758 -51.856107) (xy 100.055375 -51.864019) (xy 99.969625 -51.864019)
			(xy 99.884242 -51.856107) (xy 99.799952 -51.840351) (xy 99.717476 -51.816884) (xy 99.637517 -51.785908)
			(xy 99.560757 -51.747686) (xy 99.487851 -51.702545) (xy 99.419422 -51.650869) (xy 99.356052 -51.5931)
			(xy 99.298283 -51.52973) (xy 99.246607 -51.461301) (xy 99.201466 -51.388395) (xy 99.163244 -51.311635)
			(xy 99.132268 -51.231676) (xy 99.108801 -51.1492) (xy 99.093045 -51.06491) (xy 99.085133 -50.979527)
			(xy 92.50807 -50.979527) (xy 92.50807 -57.329527) (xy 99.085133 -57.329527) (xy 99.085133 -57.243777)
			(xy 99.093045 -57.158394) (xy 99.108801 -57.074104) (xy 99.132268 -56.991628) (xy 99.163244 -56.911669)
			(xy 99.201466 -56.834909) (xy 99.246607 -56.762003) (xy 99.298283 -56.693574) (xy 99.356052 -56.630204)
			(xy 99.419422 -56.572435) (xy 99.487851 -56.520759) (xy 99.560757 -56.475618) (xy 99.637517 -56.437396)
			(xy 99.717476 -56.40642) (xy 99.799952 -56.382953) (xy 99.884242 -56.367197) (xy 99.969625 -56.359285)
			(xy 100.055375 -56.359285) (xy 100.140758 -56.367197) (xy 100.225048 -56.382953) (xy 100.307524 -56.40642)
			(xy 100.387483 -56.437396) (xy 100.464243 -56.475618) (xy 100.537149 -56.520759) (xy 100.605578 -56.572435)
			(xy 100.668948 -56.630204) (xy 100.726717 -56.693574) (xy 100.778393 -56.762003) (xy 100.823534 -56.834909)
			(xy 100.861756 -56.911669) (xy 100.892732 -56.991628) (xy 100.916199 -57.074104) (xy 100.931955 -57.158394)
			(xy 100.939867 -57.243777) (xy 100.940362 -57.286652) (xy 100.939867 -57.329527) (xy 101.625133 -57.329527)
			(xy 101.625133 -57.243777) (xy 101.633045 -57.158394) (xy 101.648801 -57.074104) (xy 101.672268 -56.991628)
			(xy 101.703244 -56.911669) (xy 101.741466 -56.834909) (xy 101.786607 -56.762003) (xy 101.838283 -56.693574)
			(xy 101.896052 -56.630204) (xy 101.959422 -56.572435) (xy 102.027851 -56.520759) (xy 102.100757 -56.475618)
			(xy 102.177517 -56.437396) (xy 102.257476 -56.40642) (xy 102.339952 -56.382953) (xy 102.424242 -56.367197)
			(xy 102.509625 -56.359285) (xy 102.595375 -56.359285) (xy 102.680758 -56.367197) (xy 102.765048 -56.382953)
			(xy 102.847524 -56.40642) (xy 102.927483 -56.437396) (xy 103.004243 -56.475618) (xy 103.077149 -56.520759)
			(xy 103.145578 -56.572435) (xy 103.208948 -56.630204) (xy 103.266717 -56.693574) (xy 103.318393 -56.762003)
			(xy 103.363534 -56.834909) (xy 103.401756 -56.911669) (xy 103.432732 -56.991628) (xy 103.456199 -57.074104)
			(xy 103.471955 -57.158394) (xy 103.479867 -57.243777) (xy 103.480362 -57.286652) (xy 103.479867 -57.329527)
			(xy 104.165133 -57.329527) (xy 104.165133 -57.243777) (xy 104.173045 -57.158394) (xy 104.188801 -57.074104)
			(xy 104.212268 -56.991628) (xy 104.243244 -56.911669) (xy 104.281466 -56.834909) (xy 104.326607 -56.762003)
			(xy 104.378283 -56.693574) (xy 104.436052 -56.630204) (xy 104.499422 -56.572435) (xy 104.567851 -56.520759)
			(xy 104.640757 -56.475618) (xy 104.717517 -56.437396) (xy 104.797476 -56.40642) (xy 104.879952 -56.382953)
			(xy 104.964242 -56.367197) (xy 105.049625 -56.359285) (xy 105.135375 -56.359285) (xy 105.220758 -56.367197)
			(xy 105.305048 -56.382953) (xy 105.387524 -56.40642) (xy 105.467483 -56.437396) (xy 105.544243 -56.475618)
			(xy 105.617149 -56.520759) (xy 105.685578 -56.572435) (xy 105.748948 -56.630204) (xy 105.806717 -56.693574)
			(xy 105.858393 -56.762003) (xy 105.903534 -56.834909) (xy 105.941756 -56.911669) (xy 105.972732 -56.991628)
			(xy 105.996199 -57.074104) (xy 106.011955 -57.158394) (xy 106.019867 -57.243777) (xy 106.020362 -57.286652)
			(xy 106.019867 -57.329527) (xy 106.011955 -57.41491) (xy 105.996199 -57.4992) (xy 105.972732 -57.581676)
			(xy 105.941756 -57.661635) (xy 105.903534 -57.738395) (xy 105.858393 -57.811301) (xy 105.806717 -57.87973)
			(xy 105.748948 -57.9431) (xy 105.685578 -58.000869) (xy 105.617149 -58.052545) (xy 105.544243 -58.097686)
			(xy 105.467483 -58.135908) (xy 105.387524 -58.166884) (xy 105.305048 -58.190351) (xy 105.220758 -58.206107)
			(xy 105.135375 -58.214019) (xy 105.049625 -58.214019) (xy 104.964242 -58.206107) (xy 104.879952 -58.190351)
			(xy 104.797476 -58.166884) (xy 104.717517 -58.135908) (xy 104.640757 -58.097686) (xy 104.567851 -58.052545)
			(xy 104.499422 -58.000869) (xy 104.436052 -57.9431) (xy 104.378283 -57.87973) (xy 104.326607 -57.811301)
			(xy 104.281466 -57.738395) (xy 104.243244 -57.661635) (xy 104.212268 -57.581676) (xy 104.188801 -57.4992)
			(xy 104.173045 -57.41491) (xy 104.165133 -57.329527) (xy 103.479867 -57.329527) (xy 103.471955 -57.41491)
			(xy 103.456199 -57.4992) (xy 103.432732 -57.581676) (xy 103.401756 -57.661635) (xy 103.363534 -57.738395)
			(xy 103.318393 -57.811301) (xy 103.266717 -57.87973) (xy 103.208948 -57.9431) (xy 103.145578 -58.000869)
			(xy 103.077149 -58.052545) (xy 103.004243 -58.097686) (xy 102.927483 -58.135908) (xy 102.847524 -58.166884)
			(xy 102.765048 -58.190351) (xy 102.680758 -58.206107) (xy 102.595375 -58.214019) (xy 102.509625 -58.214019)
			(xy 102.424242 -58.206107) (xy 102.339952 -58.190351) (xy 102.257476 -58.166884) (xy 102.177517 -58.135908)
			(xy 102.100757 -58.097686) (xy 102.027851 -58.052545) (xy 101.959422 -58.000869) (xy 101.896052 -57.9431)
			(xy 101.838283 -57.87973) (xy 101.786607 -57.811301) (xy 101.741466 -57.738395) (xy 101.703244 -57.661635)
			(xy 101.672268 -57.581676) (xy 101.648801 -57.4992) (xy 101.633045 -57.41491) (xy 101.625133 -57.329527)
			(xy 100.939867 -57.329527) (xy 100.931955 -57.41491) (xy 100.916199 -57.4992) (xy 100.892732 -57.581676)
			(xy 100.861756 -57.661635) (xy 100.823534 -57.738395) (xy 100.778393 -57.811301) (xy 100.726717 -57.87973)
			(xy 100.668948 -57.9431) (xy 100.605578 -58.000869) (xy 100.537149 -58.052545) (xy 100.464243 -58.097686)
			(xy 100.387483 -58.135908) (xy 100.307524 -58.166884) (xy 100.225048 -58.190351) (xy 100.140758 -58.206107)
			(xy 100.055375 -58.214019) (xy 99.969625 -58.214019) (xy 99.884242 -58.206107) (xy 99.799952 -58.190351)
			(xy 99.717476 -58.166884) (xy 99.637517 -58.135908) (xy 99.560757 -58.097686) (xy 99.487851 -58.052545)
			(xy 99.419422 -58.000869) (xy 99.356052 -57.9431) (xy 99.298283 -57.87973) (xy 99.246607 -57.811301)
			(xy 99.201466 -57.738395) (xy 99.163244 -57.661635) (xy 99.132268 -57.581676) (xy 99.108801 -57.4992)
			(xy 99.093045 -57.41491) (xy 99.085133 -57.329527) (xy 92.50807 -57.329527) (xy 92.50807 -62.793575)
			(xy 99.085133 -62.793575) (xy 99.085133 -62.707825) (xy 99.093045 -62.622442) (xy 99.108801 -62.538152)
			(xy 99.132268 -62.455676) (xy 99.163244 -62.375717) (xy 99.201466 -62.298957) (xy 99.246607 -62.226051)
			(xy 99.298283 -62.157622) (xy 99.356052 -62.094252) (xy 99.419422 -62.036483) (xy 99.487851 -61.984807)
			(xy 99.560757 -61.939666) (xy 99.637517 -61.901444) (xy 99.717476 -61.870468) (xy 99.799952 -61.847001)
			(xy 99.884242 -61.831245) (xy 99.969625 -61.823333) (xy 100.055375 -61.823333) (xy 100.140758 -61.831245)
			(xy 100.225048 -61.847001) (xy 100.307524 -61.870468) (xy 100.387483 -61.901444) (xy 100.464243 -61.939666)
			(xy 100.537149 -61.984807) (xy 100.605578 -62.036483) (xy 100.668948 -62.094252) (xy 100.726717 -62.157622)
			(xy 100.778393 -62.226051) (xy 100.823534 -62.298957) (xy 100.861756 -62.375717) (xy 100.892732 -62.455676)
			(xy 100.916199 -62.538152) (xy 100.931955 -62.622442) (xy 100.939867 -62.707825) (xy 100.940362 -62.7507)
			(xy 100.939867 -62.793575) (xy 101.625133 -62.793575) (xy 101.625133 -62.707825) (xy 101.633045 -62.622442)
			(xy 101.648801 -62.538152) (xy 101.672268 -62.455676) (xy 101.703244 -62.375717) (xy 101.741466 -62.298957)
			(xy 101.786607 -62.226051) (xy 101.838283 -62.157622) (xy 101.896052 -62.094252) (xy 101.959422 -62.036483)
			(xy 102.027851 -61.984807) (xy 102.100757 -61.939666) (xy 102.177517 -61.901444) (xy 102.257476 -61.870468)
			(xy 102.339952 -61.847001) (xy 102.424242 -61.831245) (xy 102.509625 -61.823333) (xy 102.595375 -61.823333)
			(xy 102.680758 -61.831245) (xy 102.765048 -61.847001) (xy 102.847524 -61.870468) (xy 102.927483 -61.901444)
			(xy 103.004243 -61.939666) (xy 103.077149 -61.984807) (xy 103.145578 -62.036483) (xy 103.208948 -62.094252)
			(xy 103.266717 -62.157622) (xy 103.318393 -62.226051) (xy 103.363534 -62.298957) (xy 103.401756 -62.375717)
			(xy 103.432732 -62.455676) (xy 103.456199 -62.538152) (xy 103.471955 -62.622442) (xy 103.479867 -62.707825)
			(xy 103.480362 -62.7507) (xy 103.479867 -62.793575) (xy 104.165133 -62.793575) (xy 104.165133 -62.707825)
			(xy 104.173045 -62.622442) (xy 104.188801 -62.538152) (xy 104.212268 -62.455676) (xy 104.243244 -62.375717)
			(xy 104.281466 -62.298957) (xy 104.326607 -62.226051) (xy 104.378283 -62.157622) (xy 104.436052 -62.094252)
			(xy 104.499422 -62.036483) (xy 104.567851 -61.984807) (xy 104.640757 -61.939666) (xy 104.717517 -61.901444)
			(xy 104.797476 -61.870468) (xy 104.879952 -61.847001) (xy 104.964242 -61.831245) (xy 105.049625 -61.823333)
			(xy 105.135375 -61.823333) (xy 105.220758 -61.831245) (xy 105.305048 -61.847001) (xy 105.387524 -61.870468)
			(xy 105.467483 -61.901444) (xy 105.544243 -61.939666) (xy 105.617149 -61.984807) (xy 105.685578 -62.036483)
			(xy 105.748948 -62.094252) (xy 105.806717 -62.157622) (xy 105.858393 -62.226051) (xy 105.903534 -62.298957)
			(xy 105.941756 -62.375717) (xy 105.972732 -62.455676) (xy 105.996199 -62.538152) (xy 106.011955 -62.622442)
			(xy 106.019867 -62.707825) (xy 106.020362 -62.7507) (xy 106.019867 -62.793575) (xy 106.011955 -62.878958)
			(xy 105.996199 -62.963248) (xy 105.972732 -63.045724) (xy 105.941756 -63.125683) (xy 105.903534 -63.202443)
			(xy 105.858393 -63.275349) (xy 105.806717 -63.343778) (xy 105.748948 -63.407148) (xy 105.685578 -63.464917)
			(xy 105.617149 -63.516593) (xy 105.544243 -63.561734) (xy 105.467483 -63.599956) (xy 105.387524 -63.630932)
			(xy 105.305048 -63.654399) (xy 105.220758 -63.670155) (xy 105.135375 -63.678067) (xy 105.049625 -63.678067)
			(xy 104.964242 -63.670155) (xy 104.879952 -63.654399) (xy 104.797476 -63.630932) (xy 104.717517 -63.599956)
			(xy 104.640757 -63.561734) (xy 104.567851 -63.516593) (xy 104.499422 -63.464917) (xy 104.436052 -63.407148)
			(xy 104.378283 -63.343778) (xy 104.326607 -63.275349) (xy 104.281466 -63.202443) (xy 104.243244 -63.125683)
			(xy 104.212268 -63.045724) (xy 104.188801 -62.963248) (xy 104.173045 -62.878958) (xy 104.165133 -62.793575)
			(xy 103.479867 -62.793575) (xy 103.471955 -62.878958) (xy 103.456199 -62.963248) (xy 103.432732 -63.045724)
			(xy 103.401756 -63.125683) (xy 103.363534 -63.202443) (xy 103.318393 -63.275349) (xy 103.266717 -63.343778)
			(xy 103.208948 -63.407148) (xy 103.145578 -63.464917) (xy 103.077149 -63.516593) (xy 103.004243 -63.561734)
			(xy 102.927483 -63.599956) (xy 102.847524 -63.630932) (xy 102.765048 -63.654399) (xy 102.680758 -63.670155)
			(xy 102.595375 -63.678067) (xy 102.509625 -63.678067) (xy 102.424242 -63.670155) (xy 102.339952 -63.654399)
			(xy 102.257476 -63.630932) (xy 102.177517 -63.599956) (xy 102.100757 -63.561734) (xy 102.027851 -63.516593)
			(xy 101.959422 -63.464917) (xy 101.896052 -63.407148) (xy 101.838283 -63.343778) (xy 101.786607 -63.275349)
			(xy 101.741466 -63.202443) (xy 101.703244 -63.125683) (xy 101.672268 -63.045724) (xy 101.648801 -62.963248)
			(xy 101.633045 -62.878958) (xy 101.625133 -62.793575) (xy 100.939867 -62.793575) (xy 100.931955 -62.878958)
			(xy 100.916199 -62.963248) (xy 100.892732 -63.045724) (xy 100.861756 -63.125683) (xy 100.823534 -63.202443)
			(xy 100.778393 -63.275349) (xy 100.726717 -63.343778) (xy 100.668948 -63.407148) (xy 100.605578 -63.464917)
			(xy 100.537149 -63.516593) (xy 100.464243 -63.561734) (xy 100.387483 -63.599956) (xy 100.307524 -63.630932)
			(xy 100.225048 -63.654399) (xy 100.140758 -63.670155) (xy 100.055375 -63.678067) (xy 99.969625 -63.678067)
			(xy 99.884242 -63.670155) (xy 99.799952 -63.654399) (xy 99.717476 -63.630932) (xy 99.637517 -63.599956)
			(xy 99.560757 -63.561734) (xy 99.487851 -63.516593) (xy 99.419422 -63.464917) (xy 99.356052 -63.407148)
			(xy 99.298283 -63.343778) (xy 99.246607 -63.275349) (xy 99.201466 -63.202443) (xy 99.163244 -63.125683)
			(xy 99.132268 -63.045724) (xy 99.108801 -62.963248) (xy 99.093045 -62.878958) (xy 99.085133 -62.793575)
			(xy 92.50807 -62.793575) (xy 92.50807 -69.143575) (xy 99.085133 -69.143575) (xy 99.085133 -69.057825)
			(xy 99.093045 -68.972442) (xy 99.108801 -68.888152) (xy 99.132268 -68.805676) (xy 99.163244 -68.725717)
			(xy 99.201466 -68.648957) (xy 99.246607 -68.576051) (xy 99.298283 -68.507622) (xy 99.356052 -68.444252)
			(xy 99.419422 -68.386483) (xy 99.487851 -68.334807) (xy 99.560757 -68.289666) (xy 99.637517 -68.251444)
			(xy 99.717476 -68.220468) (xy 99.799952 -68.197001) (xy 99.884242 -68.181245) (xy 99.969625 -68.173333)
			(xy 100.055375 -68.173333) (xy 100.140758 -68.181245) (xy 100.225048 -68.197001) (xy 100.307524 -68.220468)
			(xy 100.387483 -68.251444) (xy 100.464243 -68.289666) (xy 100.537149 -68.334807) (xy 100.605578 -68.386483)
			(xy 100.668948 -68.444252) (xy 100.726717 -68.507622) (xy 100.778393 -68.576051) (xy 100.823534 -68.648957)
			(xy 100.861756 -68.725717) (xy 100.892732 -68.805676) (xy 100.916199 -68.888152) (xy 100.931955 -68.972442)
			(xy 100.939867 -69.057825) (xy 100.940362 -69.1007) (xy 100.939867 -69.143575) (xy 101.625133 -69.143575)
			(xy 101.625133 -69.057825) (xy 101.633045 -68.972442) (xy 101.648801 -68.888152) (xy 101.672268 -68.805676)
			(xy 101.703244 -68.725717) (xy 101.741466 -68.648957) (xy 101.786607 -68.576051) (xy 101.838283 -68.507622)
			(xy 101.896052 -68.444252) (xy 101.959422 -68.386483) (xy 102.027851 -68.334807) (xy 102.100757 -68.289666)
			(xy 102.177517 -68.251444) (xy 102.257476 -68.220468) (xy 102.339952 -68.197001) (xy 102.424242 -68.181245)
			(xy 102.509625 -68.173333) (xy 102.595375 -68.173333) (xy 102.680758 -68.181245) (xy 102.765048 -68.197001)
			(xy 102.847524 -68.220468) (xy 102.927483 -68.251444) (xy 103.004243 -68.289666) (xy 103.077149 -68.334807)
			(xy 103.145578 -68.386483) (xy 103.208948 -68.444252) (xy 103.266717 -68.507622) (xy 103.318393 -68.576051)
			(xy 103.363534 -68.648957) (xy 103.401756 -68.725717) (xy 103.432732 -68.805676) (xy 103.456199 -68.888152)
			(xy 103.471955 -68.972442) (xy 103.479867 -69.057825) (xy 103.480362 -69.1007) (xy 103.479867 -69.143575)
			(xy 104.165133 -69.143575) (xy 104.165133 -69.057825) (xy 104.173045 -68.972442) (xy 104.188801 -68.888152)
			(xy 104.212268 -68.805676) (xy 104.243244 -68.725717) (xy 104.281466 -68.648957) (xy 104.326607 -68.576051)
			(xy 104.378283 -68.507622) (xy 104.436052 -68.444252) (xy 104.499422 -68.386483) (xy 104.567851 -68.334807)
			(xy 104.640757 -68.289666) (xy 104.717517 -68.251444) (xy 104.797476 -68.220468) (xy 104.879952 -68.197001)
			(xy 104.964242 -68.181245) (xy 105.049625 -68.173333) (xy 105.135375 -68.173333) (xy 105.220758 -68.181245)
			(xy 105.305048 -68.197001) (xy 105.387524 -68.220468) (xy 105.467483 -68.251444) (xy 105.544243 -68.289666)
			(xy 105.617149 -68.334807) (xy 105.685578 -68.386483) (xy 105.748948 -68.444252) (xy 105.806717 -68.507622)
			(xy 105.858393 -68.576051) (xy 105.903534 -68.648957) (xy 105.941756 -68.725717) (xy 105.972732 -68.805676)
			(xy 105.996199 -68.888152) (xy 106.011955 -68.972442) (xy 106.019867 -69.057825) (xy 106.020362 -69.1007)
			(xy 106.019867 -69.143575) (xy 106.011955 -69.228958) (xy 105.996199 -69.313248) (xy 105.972732 -69.395724)
			(xy 105.941756 -69.475683) (xy 105.903534 -69.552443) (xy 105.858393 -69.625349) (xy 105.806717 -69.693778)
			(xy 105.748948 -69.757148) (xy 105.685578 -69.814917) (xy 105.617149 -69.866593) (xy 105.544243 -69.911734)
			(xy 105.467483 -69.949956) (xy 105.387524 -69.980932) (xy 105.305048 -70.004399) (xy 105.220758 -70.020155)
			(xy 105.135375 -70.028067) (xy 105.049625 -70.028067) (xy 104.964242 -70.020155) (xy 104.879952 -70.004399)
			(xy 104.797476 -69.980932) (xy 104.717517 -69.949956) (xy 104.640757 -69.911734) (xy 104.567851 -69.866593)
			(xy 104.499422 -69.814917) (xy 104.436052 -69.757148) (xy 104.378283 -69.693778) (xy 104.326607 -69.625349)
			(xy 104.281466 -69.552443) (xy 104.243244 -69.475683) (xy 104.212268 -69.395724) (xy 104.188801 -69.313248)
			(xy 104.173045 -69.228958) (xy 104.165133 -69.143575) (xy 103.479867 -69.143575) (xy 103.471955 -69.228958)
			(xy 103.456199 -69.313248) (xy 103.432732 -69.395724) (xy 103.401756 -69.475683) (xy 103.363534 -69.552443)
			(xy 103.318393 -69.625349) (xy 103.266717 -69.693778) (xy 103.208948 -69.757148) (xy 103.145578 -69.814917)
			(xy 103.077149 -69.866593) (xy 103.004243 -69.911734) (xy 102.927483 -69.949956) (xy 102.847524 -69.980932)
			(xy 102.765048 -70.004399) (xy 102.680758 -70.020155) (xy 102.595375 -70.028067) (xy 102.509625 -70.028067)
			(xy 102.424242 -70.020155) (xy 102.339952 -70.004399) (xy 102.257476 -69.980932) (xy 102.177517 -69.949956)
			(xy 102.100757 -69.911734) (xy 102.027851 -69.866593) (xy 101.959422 -69.814917) (xy 101.896052 -69.757148)
			(xy 101.838283 -69.693778) (xy 101.786607 -69.625349) (xy 101.741466 -69.552443) (xy 101.703244 -69.475683)
			(xy 101.672268 -69.395724) (xy 101.648801 -69.313248) (xy 101.633045 -69.228958) (xy 101.625133 -69.143575)
			(xy 100.939867 -69.143575) (xy 100.931955 -69.228958) (xy 100.916199 -69.313248) (xy 100.892732 -69.395724)
			(xy 100.861756 -69.475683) (xy 100.823534 -69.552443) (xy 100.778393 -69.625349) (xy 100.726717 -69.693778)
			(xy 100.668948 -69.757148) (xy 100.605578 -69.814917) (xy 100.537149 -69.866593) (xy 100.464243 -69.911734)
			(xy 100.387483 -69.949956) (xy 100.307524 -69.980932) (xy 100.225048 -70.004399) (xy 100.140758 -70.020155)
			(xy 100.055375 -70.028067) (xy 99.969625 -70.028067) (xy 99.884242 -70.020155) (xy 99.799952 -70.004399)
			(xy 99.717476 -69.980932) (xy 99.637517 -69.949956) (xy 99.560757 -69.911734) (xy 99.487851 -69.866593)
			(xy 99.419422 -69.814917) (xy 99.356052 -69.757148) (xy 99.298283 -69.693778) (xy 99.246607 -69.625349)
			(xy 99.201466 -69.552443) (xy 99.163244 -69.475683) (xy 99.132268 -69.395724) (xy 99.108801 -69.313248)
			(xy 99.093045 -69.228958) (xy 99.085133 -69.143575) (xy 92.50807 -69.143575) (xy 92.50807 -94.976137)
			(xy 93.729289 -94.976137) (xy 93.729289 -94.890387) (xy 93.737201 -94.805004) (xy 93.752957 -94.720714)
			(xy 93.776424 -94.638238) (xy 93.8074 -94.558279) (xy 93.845622 -94.481519) (xy 93.890763 -94.408613)
			(xy 93.942439 -94.340184) (xy 94.000208 -94.276814) (xy 94.063578 -94.219045) (xy 94.132007 -94.167369)
			(xy 94.204913 -94.122228) (xy 94.281673 -94.084006) (xy 94.361632 -94.05303) (xy 94.444108 -94.029563)
			(xy 94.528398 -94.013807) (xy 94.613781 -94.005895) (xy 94.699531 -94.005895) (xy 94.784914 -94.013807)
			(xy 94.869204 -94.029563) (xy 94.95168 -94.05303) (xy 95.031639 -94.084006) (xy 95.108399 -94.122228)
			(xy 95.181305 -94.167369) (xy 95.249734 -94.219045) (xy 95.313104 -94.276814) (xy 95.370873 -94.340184)
			(xy 95.422549 -94.408613) (xy 95.46769 -94.481519) (xy 95.505912 -94.558279) (xy 95.536888 -94.638238)
			(xy 95.560355 -94.720714) (xy 95.576111 -94.805004) (xy 95.584023 -94.890387) (xy 95.584518 -94.933262)
			(xy 95.584023 -94.976137) (xy 96.269289 -94.976137) (xy 96.269289 -94.890387) (xy 96.277201 -94.805004)
			(xy 96.292957 -94.720714) (xy 96.316424 -94.638238) (xy 96.3474 -94.558279) (xy 96.385622 -94.481519)
			(xy 96.430763 -94.408613) (xy 96.482439 -94.340184) (xy 96.540208 -94.276814) (xy 96.603578 -94.219045)
			(xy 96.672007 -94.167369) (xy 96.744913 -94.122228) (xy 96.821673 -94.084006) (xy 96.901632 -94.05303)
			(xy 96.984108 -94.029563) (xy 97.068398 -94.013807) (xy 97.153781 -94.005895) (xy 97.239531 -94.005895)
			(xy 97.324914 -94.013807) (xy 97.409204 -94.029563) (xy 97.49168 -94.05303) (xy 97.571639 -94.084006)
			(xy 97.648399 -94.122228) (xy 97.721305 -94.167369) (xy 97.789734 -94.219045) (xy 97.853104 -94.276814)
			(xy 97.910873 -94.340184) (xy 97.962549 -94.408613) (xy 98.00769 -94.481519) (xy 98.045912 -94.558279)
			(xy 98.076888 -94.638238) (xy 98.100355 -94.720714) (xy 98.116111 -94.805004) (xy 98.124023 -94.890387)
			(xy 98.124518 -94.933262) (xy 98.124023 -94.976137) (xy 98.116111 -95.06152) (xy 98.100355 -95.14581)
			(xy 98.076888 -95.228286) (xy 98.045912 -95.308245) (xy 98.00769 -95.385005) (xy 97.962549 -95.457911)
			(xy 97.910873 -95.52634) (xy 97.853104 -95.58971) (xy 97.789734 -95.647479) (xy 97.721305 -95.699155)
			(xy 97.648399 -95.744296) (xy 97.571639 -95.782518) (xy 97.49168 -95.813494) (xy 97.409204 -95.836961)
			(xy 97.324914 -95.852717) (xy 97.239531 -95.860629) (xy 97.153781 -95.860629) (xy 97.068398 -95.852717)
			(xy 96.984108 -95.836961) (xy 96.901632 -95.813494) (xy 96.821673 -95.782518) (xy 96.744913 -95.744296)
			(xy 96.672007 -95.699155) (xy 96.603578 -95.647479) (xy 96.540208 -95.58971) (xy 96.482439 -95.52634)
			(xy 96.430763 -95.457911) (xy 96.385622 -95.385005) (xy 96.3474 -95.308245) (xy 96.316424 -95.228286)
			(xy 96.292957 -95.14581) (xy 96.277201 -95.06152) (xy 96.269289 -94.976137) (xy 95.584023 -94.976137)
			(xy 95.576111 -95.06152) (xy 95.560355 -95.14581) (xy 95.536888 -95.228286) (xy 95.505912 -95.308245)
			(xy 95.46769 -95.385005) (xy 95.422549 -95.457911) (xy 95.370873 -95.52634) (xy 95.313104 -95.58971)
			(xy 95.249734 -95.647479) (xy 95.181305 -95.699155) (xy 95.108399 -95.744296) (xy 95.031639 -95.782518)
			(xy 94.95168 -95.813494) (xy 94.869204 -95.836961) (xy 94.784914 -95.852717) (xy 94.699531 -95.860629)
			(xy 94.613781 -95.860629) (xy 94.528398 -95.852717) (xy 94.444108 -95.836961) (xy 94.361632 -95.813494)
			(xy 94.281673 -95.782518) (xy 94.204913 -95.744296) (xy 94.132007 -95.699155) (xy 94.063578 -95.647479)
			(xy 94.000208 -95.58971) (xy 93.942439 -95.52634) (xy 93.890763 -95.457911) (xy 93.845622 -95.385005)
			(xy 93.8074 -95.308245) (xy 93.776424 -95.228286) (xy 93.752957 -95.14581) (xy 93.737201 -95.06152)
			(xy 93.729289 -94.976137) (xy 92.50807 -94.976137) (xy 92.50807 -96.949868) (xy 95.113614 -96.949868)
			(xy 95.113614 -96.895332) (xy 95.121375 -96.841351) (xy 95.136739 -96.789023) (xy 95.159392 -96.739415)
			(xy 95.188875 -96.693535) (xy 95.224586 -96.652317) (xy 95.2658 -96.616601) (xy 95.311676 -96.587113)
			(xy 95.361282 -96.564454) (xy 95.413608 -96.549084) (xy 95.467588 -96.541317) (xy 95.494856 -96.540828)
			(xy 96.358456 -96.540828) (xy 96.385728 -96.541308) (xy 96.439719 -96.549065) (xy 96.492055 -96.564427)
			(xy 96.541673 -96.587082) (xy 96.587561 -96.616568) (xy 96.628785 -96.652284) (xy 96.664506 -96.693504)
			(xy 96.693997 -96.739389) (xy 96.716657 -96.789004) (xy 96.732025 -96.841338) (xy 96.739788 -96.895328)
			(xy 96.739788 -96.949872) (xy 96.732025 -97.003862) (xy 96.716657 -97.056196) (xy 96.693997 -97.105811)
			(xy 96.664506 -97.151696) (xy 96.628785 -97.192916) (xy 96.587561 -97.228632) (xy 96.541673 -97.258118)
			(xy 96.492055 -97.280773) (xy 96.439719 -97.296135) (xy 96.385728 -97.303892) (xy 96.358456 -97.304352)
			(xy 95.494856 -97.304352) (xy 95.467588 -97.303883) (xy 95.413608 -97.296116) (xy 95.361282 -97.280746)
			(xy 95.311676 -97.258087) (xy 95.2658 -97.228599) (xy 95.224586 -97.192883) (xy 95.188875 -97.151665)
			(xy 95.159392 -97.105785) (xy 95.136739 -97.056177) (xy 95.121375 -97.003849) (xy 95.113614 -96.949868)
			(xy 92.50807 -96.949868) (xy 92.50807 -101.326137) (xy 93.729289 -101.326137) (xy 93.729289 -101.240387)
			(xy 93.737201 -101.155004) (xy 93.752957 -101.070714) (xy 93.776424 -100.988238) (xy 93.8074 -100.908279)
			(xy 93.845622 -100.831519) (xy 93.890763 -100.758613) (xy 93.942439 -100.690184) (xy 94.000208 -100.626814)
			(xy 94.063578 -100.569045) (xy 94.132007 -100.517369) (xy 94.204913 -100.472228) (xy 94.281673 -100.434006)
			(xy 94.361632 -100.40303) (xy 94.444108 -100.379563) (xy 94.528398 -100.363807) (xy 94.613781 -100.355895)
			(xy 94.699531 -100.355895) (xy 94.784914 -100.363807) (xy 94.869204 -100.379563) (xy 94.95168 -100.40303)
			(xy 95.031639 -100.434006) (xy 95.108399 -100.472228) (xy 95.181305 -100.517369) (xy 95.249734 -100.569045)
			(xy 95.313104 -100.626814) (xy 95.370873 -100.690184) (xy 95.422549 -100.758613) (xy 95.46769 -100.831519)
			(xy 95.505912 -100.908279) (xy 95.536888 -100.988238) (xy 95.560355 -101.070714) (xy 95.576111 -101.155004)
			(xy 95.584023 -101.240387) (xy 95.584518 -101.283262) (xy 95.584023 -101.326137) (xy 96.269289 -101.326137)
			(xy 96.269289 -101.240387) (xy 96.277201 -101.155004) (xy 96.292957 -101.070714) (xy 96.316424 -100.988238)
			(xy 96.3474 -100.908279) (xy 96.385622 -100.831519) (xy 96.430763 -100.758613) (xy 96.482439 -100.690184)
			(xy 96.540208 -100.626814) (xy 96.603578 -100.569045) (xy 96.672007 -100.517369) (xy 96.744913 -100.472228)
			(xy 96.821673 -100.434006) (xy 96.901632 -100.40303) (xy 96.984108 -100.379563) (xy 97.068398 -100.363807)
			(xy 97.153781 -100.355895) (xy 97.239531 -100.355895) (xy 97.324914 -100.363807) (xy 97.409204 -100.379563)
			(xy 97.49168 -100.40303) (xy 97.571639 -100.434006) (xy 97.648399 -100.472228) (xy 97.721305 -100.517369)
			(xy 97.789734 -100.569045) (xy 97.853104 -100.626814) (xy 97.910873 -100.690184) (xy 97.962549 -100.758613)
			(xy 98.00769 -100.831519) (xy 98.045912 -100.908279) (xy 98.076888 -100.988238) (xy 98.100355 -101.070714)
			(xy 98.116111 -101.155004) (xy 98.124023 -101.240387) (xy 98.124518 -101.283262) (xy 98.124023 -101.326137)
			(xy 98.122681 -101.340615) (xy 99.085133 -101.340615) (xy 99.085133 -101.254865) (xy 99.093045 -101.169482)
			(xy 99.108801 -101.085192) (xy 99.132268 -101.002716) (xy 99.163244 -100.922757) (xy 99.201466 -100.845997)
			(xy 99.246607 -100.773091) (xy 99.298283 -100.704662) (xy 99.356052 -100.641292) (xy 99.419422 -100.583523)
			(xy 99.487851 -100.531847) (xy 99.560757 -100.486706) (xy 99.637517 -100.448484) (xy 99.717476 -100.417508)
			(xy 99.799952 -100.394041) (xy 99.884242 -100.378285) (xy 99.969625 -100.370373) (xy 100.055375 -100.370373)
			(xy 100.140758 -100.378285) (xy 100.225048 -100.394041) (xy 100.307524 -100.417508) (xy 100.387483 -100.448484)
			(xy 100.464243 -100.486706) (xy 100.537149 -100.531847) (xy 100.605578 -100.583523) (xy 100.668948 -100.641292)
			(xy 100.726717 -100.704662) (xy 100.778393 -100.773091) (xy 100.823534 -100.845997) (xy 100.861756 -100.922757)
			(xy 100.892732 -101.002716) (xy 100.916199 -101.085192) (xy 100.931955 -101.169482) (xy 100.939867 -101.254865)
			(xy 100.940362 -101.29774) (xy 100.939867 -101.340615) (xy 101.625133 -101.340615) (xy 101.625133 -101.254865)
			(xy 101.633045 -101.169482) (xy 101.648801 -101.085192) (xy 101.672268 -101.002716) (xy 101.703244 -100.922757)
			(xy 101.741466 -100.845997) (xy 101.786607 -100.773091) (xy 101.838283 -100.704662) (xy 101.896052 -100.641292)
			(xy 101.959422 -100.583523) (xy 102.027851 -100.531847) (xy 102.100757 -100.486706) (xy 102.177517 -100.448484)
			(xy 102.257476 -100.417508) (xy 102.339952 -100.394041) (xy 102.424242 -100.378285) (xy 102.509625 -100.370373)
			(xy 102.595375 -100.370373) (xy 102.680758 -100.378285) (xy 102.765048 -100.394041) (xy 102.847524 -100.417508)
			(xy 102.927483 -100.448484) (xy 103.004243 -100.486706) (xy 103.077149 -100.531847) (xy 103.145578 -100.583523)
			(xy 103.208948 -100.641292) (xy 103.266717 -100.704662) (xy 103.318393 -100.773091) (xy 103.363534 -100.845997)
			(xy 103.401756 -100.922757) (xy 103.432732 -101.002716) (xy 103.456199 -101.085192) (xy 103.471955 -101.169482)
			(xy 103.479867 -101.254865) (xy 103.480362 -101.29774) (xy 103.479867 -101.340615) (xy 104.165133 -101.340615)
			(xy 104.165133 -101.254865) (xy 104.173045 -101.169482) (xy 104.188801 -101.085192) (xy 104.212268 -101.002716)
			(xy 104.243244 -100.922757) (xy 104.281466 -100.845997) (xy 104.326607 -100.773091) (xy 104.378283 -100.704662)
			(xy 104.436052 -100.641292) (xy 104.499422 -100.583523) (xy 104.567851 -100.531847) (xy 104.640757 -100.486706)
			(xy 104.717517 -100.448484) (xy 104.797476 -100.417508) (xy 104.879952 -100.394041) (xy 104.964242 -100.378285)
			(xy 105.049625 -100.370373) (xy 105.135375 -100.370373) (xy 105.220758 -100.378285) (xy 105.305048 -100.394041)
			(xy 105.387524 -100.417508) (xy 105.467483 -100.448484) (xy 105.544243 -100.486706) (xy 105.617149 -100.531847)
			(xy 105.685578 -100.583523) (xy 105.748948 -100.641292) (xy 105.806717 -100.704662) (xy 105.858393 -100.773091)
			(xy 105.903534 -100.845997) (xy 105.941756 -100.922757) (xy 105.972732 -101.002716) (xy 105.996199 -101.085192)
			(xy 106.011955 -101.169482) (xy 106.019867 -101.254865) (xy 106.020362 -101.29774) (xy 106.019867 -101.340615)
			(xy 106.011955 -101.425998) (xy 105.996199 -101.510288) (xy 105.972732 -101.592764) (xy 105.941756 -101.672723)
			(xy 105.903534 -101.749483) (xy 105.858393 -101.822389) (xy 105.806717 -101.890818) (xy 105.748948 -101.954188)
			(xy 105.685578 -102.011957) (xy 105.617149 -102.063633) (xy 105.544243 -102.108774) (xy 105.467483 -102.146996)
			(xy 105.387524 -102.177972) (xy 105.305048 -102.201439) (xy 105.220758 -102.217195) (xy 105.135375 -102.225107)
			(xy 105.049625 -102.225107) (xy 104.964242 -102.217195) (xy 104.879952 -102.201439) (xy 104.797476 -102.177972)
			(xy 104.717517 -102.146996) (xy 104.640757 -102.108774) (xy 104.567851 -102.063633) (xy 104.499422 -102.011957)
			(xy 104.436052 -101.954188) (xy 104.378283 -101.890818) (xy 104.326607 -101.822389) (xy 104.281466 -101.749483)
			(xy 104.243244 -101.672723) (xy 104.212268 -101.592764) (xy 104.188801 -101.510288) (xy 104.173045 -101.425998)
			(xy 104.165133 -101.340615) (xy 103.479867 -101.340615) (xy 103.471955 -101.425998) (xy 103.456199 -101.510288)
			(xy 103.432732 -101.592764) (xy 103.401756 -101.672723) (xy 103.363534 -101.749483) (xy 103.318393 -101.822389)
			(xy 103.266717 -101.890818) (xy 103.208948 -101.954188) (xy 103.145578 -102.011957) (xy 103.077149 -102.063633)
			(xy 103.004243 -102.108774) (xy 102.927483 -102.146996) (xy 102.847524 -102.177972) (xy 102.765048 -102.201439)
			(xy 102.680758 -102.217195) (xy 102.595375 -102.225107) (xy 102.509625 -102.225107) (xy 102.424242 -102.217195)
			(xy 102.339952 -102.201439) (xy 102.257476 -102.177972) (xy 102.177517 -102.146996) (xy 102.100757 -102.108774)
			(xy 102.027851 -102.063633) (xy 101.959422 -102.011957) (xy 101.896052 -101.954188) (xy 101.838283 -101.890818)
			(xy 101.786607 -101.822389) (xy 101.741466 -101.749483) (xy 101.703244 -101.672723) (xy 101.672268 -101.592764)
			(xy 101.648801 -101.510288) (xy 101.633045 -101.425998) (xy 101.625133 -101.340615) (xy 100.939867 -101.340615)
			(xy 100.931955 -101.425998) (xy 100.916199 -101.510288) (xy 100.892732 -101.592764) (xy 100.861756 -101.672723)
			(xy 100.823534 -101.749483) (xy 100.778393 -101.822389) (xy 100.726717 -101.890818) (xy 100.668948 -101.954188)
			(xy 100.605578 -102.011957) (xy 100.537149 -102.063633) (xy 100.464243 -102.108774) (xy 100.387483 -102.146996)
			(xy 100.307524 -102.177972) (xy 100.225048 -102.201439) (xy 100.140758 -102.217195) (xy 100.055375 -102.225107)
			(xy 99.969625 -102.225107) (xy 99.884242 -102.217195) (xy 99.799952 -102.201439) (xy 99.717476 -102.177972)
			(xy 99.637517 -102.146996) (xy 99.560757 -102.108774) (xy 99.487851 -102.063633) (xy 99.419422 -102.011957)
			(xy 99.356052 -101.954188) (xy 99.298283 -101.890818) (xy 99.246607 -101.822389) (xy 99.201466 -101.749483)
			(xy 99.163244 -101.672723) (xy 99.132268 -101.592764) (xy 99.108801 -101.510288) (xy 99.093045 -101.425998)
			(xy 99.085133 -101.340615) (xy 98.122681 -101.340615) (xy 98.116111 -101.41152) (xy 98.100355 -101.49581)
			(xy 98.076888 -101.578286) (xy 98.045912 -101.658245) (xy 98.00769 -101.735005) (xy 97.962549 -101.807911)
			(xy 97.910873 -101.87634) (xy 97.853104 -101.93971) (xy 97.789734 -101.997479) (xy 97.721305 -102.049155)
			(xy 97.648399 -102.094296) (xy 97.571639 -102.132518) (xy 97.49168 -102.163494) (xy 97.409204 -102.186961)
			(xy 97.324914 -102.202717) (xy 97.239531 -102.210629) (xy 97.153781 -102.210629) (xy 97.068398 -102.202717)
			(xy 96.984108 -102.186961) (xy 96.901632 -102.163494) (xy 96.821673 -102.132518) (xy 96.744913 -102.094296)
			(xy 96.672007 -102.049155) (xy 96.603578 -101.997479) (xy 96.540208 -101.93971) (xy 96.482439 -101.87634)
			(xy 96.430763 -101.807911) (xy 96.385622 -101.735005) (xy 96.3474 -101.658245) (xy 96.316424 -101.578286)
			(xy 96.292957 -101.49581) (xy 96.277201 -101.41152) (xy 96.269289 -101.326137) (xy 95.584023 -101.326137)
			(xy 95.576111 -101.41152) (xy 95.560355 -101.49581) (xy 95.536888 -101.578286) (xy 95.505912 -101.658245)
			(xy 95.46769 -101.735005) (xy 95.422549 -101.807911) (xy 95.370873 -101.87634) (xy 95.313104 -101.93971)
			(xy 95.249734 -101.997479) (xy 95.181305 -102.049155) (xy 95.108399 -102.094296) (xy 95.031639 -102.132518)
			(xy 94.95168 -102.163494) (xy 94.869204 -102.186961) (xy 94.784914 -102.202717) (xy 94.699531 -102.210629)
			(xy 94.613781 -102.210629) (xy 94.528398 -102.202717) (xy 94.444108 -102.186961) (xy 94.361632 -102.163494)
			(xy 94.281673 -102.132518) (xy 94.204913 -102.094296) (xy 94.132007 -102.049155) (xy 94.063578 -101.997479)
			(xy 94.000208 -101.93971) (xy 93.942439 -101.87634) (xy 93.890763 -101.807911) (xy 93.845622 -101.735005)
			(xy 93.8074 -101.658245) (xy 93.776424 -101.578286) (xy 93.752957 -101.49581) (xy 93.737201 -101.41152)
			(xy 93.729289 -101.326137) (xy 92.50807 -101.326137) (xy 92.50807 -107.690615) (xy 99.085133 -107.690615)
			(xy 99.085133 -107.604865) (xy 99.093045 -107.519482) (xy 99.108801 -107.435192) (xy 99.132268 -107.352716)
			(xy 99.163244 -107.272757) (xy 99.201466 -107.195997) (xy 99.246607 -107.123091) (xy 99.298283 -107.054662)
			(xy 99.356052 -106.991292) (xy 99.419422 -106.933523) (xy 99.487851 -106.881847) (xy 99.560757 -106.836706)
			(xy 99.637517 -106.798484) (xy 99.717476 -106.767508) (xy 99.799952 -106.744041) (xy 99.884242 -106.728285)
			(xy 99.969625 -106.720373) (xy 100.055375 -106.720373) (xy 100.140758 -106.728285) (xy 100.225048 -106.744041)
			(xy 100.307524 -106.767508) (xy 100.387483 -106.798484) (xy 100.464243 -106.836706) (xy 100.537149 -106.881847)
			(xy 100.605578 -106.933523) (xy 100.668948 -106.991292) (xy 100.726717 -107.054662) (xy 100.778393 -107.123091)
			(xy 100.823534 -107.195997) (xy 100.861756 -107.272757) (xy 100.892732 -107.352716) (xy 100.916199 -107.435192)
			(xy 100.931955 -107.519482) (xy 100.939867 -107.604865) (xy 100.940362 -107.64774) (xy 100.939867 -107.690615)
			(xy 101.625133 -107.690615) (xy 101.625133 -107.604865) (xy 101.633045 -107.519482) (xy 101.648801 -107.435192)
			(xy 101.672268 -107.352716) (xy 101.703244 -107.272757) (xy 101.741466 -107.195997) (xy 101.786607 -107.123091)
			(xy 101.838283 -107.054662) (xy 101.896052 -106.991292) (xy 101.959422 -106.933523) (xy 102.027851 -106.881847)
			(xy 102.100757 -106.836706) (xy 102.177517 -106.798484) (xy 102.257476 -106.767508) (xy 102.339952 -106.744041)
			(xy 102.424242 -106.728285) (xy 102.509625 -106.720373) (xy 102.595375 -106.720373) (xy 102.680758 -106.728285)
			(xy 102.765048 -106.744041) (xy 102.847524 -106.767508) (xy 102.927483 -106.798484) (xy 103.004243 -106.836706)
			(xy 103.077149 -106.881847) (xy 103.145578 -106.933523) (xy 103.208948 -106.991292) (xy 103.266717 -107.054662)
			(xy 103.318393 -107.123091) (xy 103.363534 -107.195997) (xy 103.401756 -107.272757) (xy 103.432732 -107.352716)
			(xy 103.456199 -107.435192) (xy 103.471955 -107.519482) (xy 103.479867 -107.604865) (xy 103.480362 -107.64774)
			(xy 103.479867 -107.690615) (xy 104.165133 -107.690615) (xy 104.165133 -107.604865) (xy 104.173045 -107.519482)
			(xy 104.188801 -107.435192) (xy 104.212268 -107.352716) (xy 104.243244 -107.272757) (xy 104.281466 -107.195997)
			(xy 104.326607 -107.123091) (xy 104.378283 -107.054662) (xy 104.436052 -106.991292) (xy 104.499422 -106.933523)
			(xy 104.567851 -106.881847) (xy 104.640757 -106.836706) (xy 104.717517 -106.798484) (xy 104.797476 -106.767508)
			(xy 104.879952 -106.744041) (xy 104.964242 -106.728285) (xy 105.049625 -106.720373) (xy 105.135375 -106.720373)
			(xy 105.220758 -106.728285) (xy 105.305048 -106.744041) (xy 105.387524 -106.767508) (xy 105.467483 -106.798484)
			(xy 105.544243 -106.836706) (xy 105.617149 -106.881847) (xy 105.685578 -106.933523) (xy 105.748948 -106.991292)
			(xy 105.806717 -107.054662) (xy 105.858393 -107.123091) (xy 105.903534 -107.195997) (xy 105.941756 -107.272757)
			(xy 105.972732 -107.352716) (xy 105.996199 -107.435192) (xy 106.011955 -107.519482) (xy 106.019867 -107.604865)
			(xy 106.020362 -107.64774) (xy 106.019867 -107.690615) (xy 106.011955 -107.775998) (xy 105.996199 -107.860288)
			(xy 105.972732 -107.942764) (xy 105.941756 -108.022723) (xy 105.903534 -108.099483) (xy 105.858393 -108.172389)
			(xy 105.806717 -108.240818) (xy 105.748948 -108.304188) (xy 105.685578 -108.361957) (xy 105.617149 -108.413633)
			(xy 105.544243 -108.458774) (xy 105.467483 -108.496996) (xy 105.387524 -108.527972) (xy 105.305048 -108.551439)
			(xy 105.220758 -108.567195) (xy 105.135375 -108.575107) (xy 105.049625 -108.575107) (xy 104.964242 -108.567195)
			(xy 104.879952 -108.551439) (xy 104.797476 -108.527972) (xy 104.717517 -108.496996) (xy 104.640757 -108.458774)
			(xy 104.567851 -108.413633) (xy 104.499422 -108.361957) (xy 104.436052 -108.304188) (xy 104.378283 -108.240818)
			(xy 104.326607 -108.172389) (xy 104.281466 -108.099483) (xy 104.243244 -108.022723) (xy 104.212268 -107.942764)
			(xy 104.188801 -107.860288) (xy 104.173045 -107.775998) (xy 104.165133 -107.690615) (xy 103.479867 -107.690615)
			(xy 103.471955 -107.775998) (xy 103.456199 -107.860288) (xy 103.432732 -107.942764) (xy 103.401756 -108.022723)
			(xy 103.363534 -108.099483) (xy 103.318393 -108.172389) (xy 103.266717 -108.240818) (xy 103.208948 -108.304188)
			(xy 103.145578 -108.361957) (xy 103.077149 -108.413633) (xy 103.004243 -108.458774) (xy 102.927483 -108.496996)
			(xy 102.847524 -108.527972) (xy 102.765048 -108.551439) (xy 102.680758 -108.567195) (xy 102.595375 -108.575107)
			(xy 102.509625 -108.575107) (xy 102.424242 -108.567195) (xy 102.339952 -108.551439) (xy 102.257476 -108.527972)
			(xy 102.177517 -108.496996) (xy 102.100757 -108.458774) (xy 102.027851 -108.413633) (xy 101.959422 -108.361957)
			(xy 101.896052 -108.304188) (xy 101.838283 -108.240818) (xy 101.786607 -108.172389) (xy 101.741466 -108.099483)
			(xy 101.703244 -108.022723) (xy 101.672268 -107.942764) (xy 101.648801 -107.860288) (xy 101.633045 -107.775998)
			(xy 101.625133 -107.690615) (xy 100.939867 -107.690615) (xy 100.931955 -107.775998) (xy 100.916199 -107.860288)
			(xy 100.892732 -107.942764) (xy 100.861756 -108.022723) (xy 100.823534 -108.099483) (xy 100.778393 -108.172389)
			(xy 100.726717 -108.240818) (xy 100.668948 -108.304188) (xy 100.605578 -108.361957) (xy 100.537149 -108.413633)
			(xy 100.464243 -108.458774) (xy 100.387483 -108.496996) (xy 100.307524 -108.527972) (xy 100.225048 -108.551439)
			(xy 100.140758 -108.567195) (xy 100.055375 -108.575107) (xy 99.969625 -108.575107) (xy 99.884242 -108.567195)
			(xy 99.799952 -108.551439) (xy 99.717476 -108.527972) (xy 99.637517 -108.496996) (xy 99.560757 -108.458774)
			(xy 99.487851 -108.413633) (xy 99.419422 -108.361957) (xy 99.356052 -108.304188) (xy 99.298283 -108.240818)
			(xy 99.246607 -108.172389) (xy 99.201466 -108.099483) (xy 99.163244 -108.022723) (xy 99.132268 -107.942764)
			(xy 99.108801 -107.860288) (xy 99.093045 -107.775998) (xy 99.085133 -107.690615) (xy 92.50807 -107.690615)
			(xy 92.50807 -115.464644) (xy 115.904253 -115.464644) (xy 115.904253 -115.335504) (xy 115.912203 -115.206609)
			(xy 115.928073 -115.078449) (xy 115.951802 -114.951508) (xy 115.983301 -114.826269) (xy 116.02245 -114.703206)
			(xy 116.069101 -114.582787) (xy 116.123076 -114.465468) (xy 116.184171 -114.351694) (xy 116.252154 -114.241897)
			(xy 116.326768 -114.136494) (xy 116.407729 -114.035884) (xy 116.494729 -113.940449) (xy 116.58744 -113.85055)
			(xy 116.68551 -113.766529) (xy 116.788565 -113.688705) (xy 116.896216 -113.617373) (xy 117.008055 -113.552803)
			(xy 117.123656 -113.495241) (xy 117.242581 -113.444904) (xy 117.36438 -113.401984) (xy 117.48859 -113.366643)
			(xy 117.614739 -113.339016) (xy 117.742351 -113.319207) (xy 117.87094 -113.307291) (xy 118.000018 -113.303315)
			(xy 118.129096 -113.307291) (xy 118.257685 -113.319207) (xy 118.385297 -113.339016) (xy 118.511446 -113.366643)
			(xy 118.635656 -113.401984) (xy 118.757455 -113.444904) (xy 118.87638 -113.495241) (xy 118.991981 -113.552803)
			(xy 119.10382 -113.617373) (xy 119.211471 -113.688705) (xy 119.314526 -113.766529) (xy 119.412596 -113.85055)
			(xy 119.505307 -113.940449) (xy 119.592307 -114.035884) (xy 119.673268 -114.136494) (xy 119.747882 -114.241897)
			(xy 119.815865 -114.351694) (xy 119.87696 -114.465468) (xy 119.930935 -114.582787) (xy 119.977586 -114.703206)
			(xy 120.016735 -114.826269) (xy 120.048234 -114.951508) (xy 120.071963 -115.078449) (xy 120.087833 -115.206609)
			(xy 120.095783 -115.335504) (xy 120.09628 -115.400074) (xy 120.095783 -115.464644) (xy 120.087833 -115.593539)
			(xy 120.071963 -115.721699) (xy 120.048234 -115.84864) (xy 120.016735 -115.973879) (xy 119.977586 -116.096942)
			(xy 119.930935 -116.217361) (xy 119.87696 -116.33468) (xy 119.815865 -116.448454) (xy 119.747882 -116.558251)
			(xy 119.673268 -116.663654) (xy 119.592307 -116.764264) (xy 119.505307 -116.859699) (xy 119.412596 -116.949598)
			(xy 119.314526 -117.033619) (xy 119.211471 -117.111443) (xy 119.10382 -117.182775) (xy 118.991981 -117.247345)
			(xy 118.87638 -117.304907) (xy 118.757455 -117.355244) (xy 118.635656 -117.398164) (xy 118.511446 -117.433505)
			(xy 118.385297 -117.461132) (xy 118.257685 -117.480941) (xy 118.129096 -117.492857) (xy 118.000018 -117.496834)
			(xy 117.87094 -117.492857) (xy 117.742351 -117.480941) (xy 117.614739 -117.461132) (xy 117.48859 -117.433505)
			(xy 117.36438 -117.398164) (xy 117.242581 -117.355244) (xy 117.123656 -117.304907) (xy 117.008055 -117.247345)
			(xy 116.896216 -117.182775) (xy 116.788565 -117.111443) (xy 116.68551 -117.033619) (xy 116.58744 -116.949598)
			(xy 116.494729 -116.859699) (xy 116.407729 -116.764264) (xy 116.326768 -116.663654) (xy 116.252154 -116.558251)
			(xy 116.184171 -116.448454) (xy 116.123076 -116.33468) (xy 116.069101 -116.217361) (xy 116.02245 -116.096942)
			(xy 115.983301 -115.973879) (xy 115.951802 -115.84864) (xy 115.928073 -115.721699) (xy 115.912203 -115.593539)
			(xy 115.904253 -115.464644) (xy 92.50807 -115.464644) (xy 92.50807 -118.400068) (xy 92.508591 -118.455876)
			(xy 92.516929 -118.567181) (xy 92.533562 -118.677551) (xy 92.558397 -118.78637) (xy 92.591294 -118.893028)
			(xy 92.63207 -118.99693) (xy 92.680497 -119.097494) (xy 92.736303 -119.194158) (xy 92.799176 -119.286381)
			(xy 92.868766 -119.373648) (xy 92.944683 -119.45547) (xy 93.026502 -119.531391) (xy 93.113766 -119.600984)
			(xy 93.205986 -119.663862) (xy 93.302648 -119.719673) (xy 93.40321 -119.768103) (xy 93.50711 -119.808884)
			(xy 93.613767 -119.841786) (xy 93.722584 -119.866625) (xy 93.832954 -119.883263) (xy 93.944258 -119.891607)
			(xy 94.000066 -119.892064)
		)
		(stroke
			(width 0)
			(type solid)
		)
		(fill yes)
		(layer "In3.Cu")
		(net "GND_P1")
	)
	(gr_poly
		(pts
			(xy 22.70379 -79.435198) (xy 22.70379 -75.502516) (xy 22.612604 -75.41133) (xy 19.096228 -75.41133)
			(xy 18.927064 -75.580494) (xy 18.927064 -79.031592) (xy 19.408902 -79.51343) (xy 22.625558 -79.51343)
		)
		(stroke
			(width 0)
			(type solid)
		)
		(fill yes)
		(layer "In4.Cu")
		(net "GND")
	)
	(gr_poly
		(pts
			(xy 80.255364 -118.737634) (xy 80.255364 -115.252754) (xy 80.174338 -115.171728) (xy 79.865474 -115.171728)
			(xy 79.748126 -115.289076) (xy 79.748126 -118.718584) (xy 79.85379 -118.824248) (xy 80.16875 -118.824248)
		)
		(stroke
			(width 0)
			(type solid)
		)
		(fill yes)
		(layer "In4.Cu")
		(net "GND")
	)
	(gr_poly
		(pts
			(xy 76.221844 -117.139466) (xy 76.221844 -113.814098) (xy 76.859892 -113.17605) (xy 83.762342 -113.17605)
			(xy 84.430616 -112.507776)
			(arc
				(start 84.430616 -110.06836)
				(mid 84.427244 -110.00096)
				(end 84.426044 -109.933486)
			)
			(arc
				(start 84.426044 -109.933486)
				(mid 84.427245 -109.866012)
				(end 84.430616 -109.798612)
			)
			(xy 84.430616 -109.038136) (xy 85.68817 -107.780582) (xy 85.68817 -103.11257) (xy 85.5472 -102.9716)
			(xy 80.3656 -102.9716) (xy 79.7687 -103.5685) (xy 79.7687 -109.309662) (xy 78.227174 -110.851188)
			(xy 75.244706 -110.851188) (xy 74.866246 -111.229648) (xy 74.866246 -117.131846) (xy 74.977498 -117.243098)
			(xy 76.118212 -117.243098)
		)
		(stroke
			(width 0)
			(type solid)
		)
		(fill yes)
		(layer "In4.Cu")
		(net "P12V_AUX")
	)
	(gr_poly
		(pts
			(arc
				(start 37.05733 -108.2167)
				(mid 36.78809 -108.2167)
				(end 37.05733 -108.2167)
			)
		)
		(stroke
			(width 0)
			(type solid)
		)
		(fill yes)
		(layer "In4.Cu")
		(net "GND")
	)
	(gr_poly
		(pts
			(xy 37.445696 -57.043828) (xy 37.445696 -54.862984) (xy 37.28085 -54.698138)
			(arc
				(start 36.119816 -54.698138)
				(mid 36.099612 -54.723158)
				(end 36.077652 -54.746652)
			)
			(xy 35.828986 -54.995572) (xy 35.828986 -55.265828)
			(arc
				(start 35.849052 -55.286148)
				(mid 35.945588 -55.430391)
				(end 35.979608 -55.6006)
			)
			(arc
				(start 35.979608 -56.6674)
				(mid 35.945636 -56.837629)
				(end 35.849052 -56.981852)
			)
			(xy 35.828986 -57.002172) (xy 35.828986 -57.123584) (xy 35.938714 -57.233312) (xy 37.256212 -57.233312)
		)
		(stroke
			(width 0)
			(type solid)
		)
		(fill yes)
		(layer "In4.Cu")
		(net "GND")
	)
	(gr_poly
		(pts
			(xy 58.743088 -28.44165)
			(arc
				(start 58.707782 -28.43022)
				(mid 58.442896 -28.067)
				(end 58.707782 -27.70378)
			)
			(xy 58.743088 -27.69235) (xy 58.743088 -26.7589) (xy 55.359808 -26.7589) (xy 55.359808 -28.606496)
			(arc
				(start 55.36184 -28.613608)
				(mid 55.371661 -28.657323)
				(end 55.375048 -28.702)
			)
			(xy 55.375048 -29.311092) (xy 55.469028 -29.405326) (xy 58.743088 -29.405326)
		)
		(stroke
			(width 0)
			(type solid)
		)
		(fill yes)
		(layer "In4.Cu")
		(net "GND")
	)
	(gr_poly
		(pts
			(xy 10.257028 -118.783354)
			(arc
				(start 10.257028 -114.799872)
				(mid 10.552301 -114.087273)
				(end 11.2649 -113.792)
			)
			(xy 11.677904 -113.792) (xy 11.769344 -113.70056) (xy 11.769344 -113.376456) (xy 11.677396 -113.284508)
			(arc
				(start 11.2649 -113.284508)
				(mid 10.193376 -113.728348)
				(end 9.749536 -114.799872)
			)
			(xy 9.749536 -118.76532) (xy 9.862312 -118.878096) (xy 10.162286 -118.878096)
		)
		(stroke
			(width 0)
			(type solid)
		)
		(fill yes)
		(layer "In4.Cu")
		(net "GND")
	)
	(gr_poly
		(pts
			(arc
				(start 41.3893 -57.857644)
				(mid 41.457909 -57.837879)
				(end 41.529 -57.831228)
			)
			(arc
				(start 41.529 -57.831228)
				(mid 41.600094 -57.837862)
				(end 41.6687 -57.857644)
			)
			(xy 41.67759 -57.8612) (xy 42.0116 -57.8612)
			(arc
				(start 42.149014 -57.723786)
				(mid 42.176188 -57.630124)
				(end 42.11193 -57.556654)
			)
			(arc
				(start 42.11193 -57.556654)
				(mid 41.929719 -57.416965)
				(end 41.860724 -57.198006)
			)
			(arc
				(start 41.860724 -57.198006)
				(mid 41.920602 -56.992817)
				(end 42.08145 -56.852058)
			)
			(arc
				(start 42.08145 -56.852058)
				(mid 42.1345 -56.79306)
				(end 42.128948 -56.713882)
			)
			(arc
				(start 42.128948 -56.713882)
				(mid 42.097862 -56.629607)
				(end 42.087292 -56.5404)
			)
			(arc
				(start 42.087292 -56.5404)
				(mid 42.199033 -56.270633)
				(end 42.4688 -56.158892)
			)
			(arc
				(start 42.4688 -56.158892)
				(mid 42.497839 -56.159941)
				(end 42.526712 -56.16321)
			)
			(arc
				(start 42.526712 -56.16321)
				(mid 42.608103 -56.139838)
				(end 42.643552 -56.06288)
			)
			(xy 42.643552 -55.394352) (xy 42.4688 -55.2196) (xy 41.148 -55.2196) (xy 41.021508 -55.346092)
			(arc
				(start 41.021508 -55.752492)
				(mid 41.05707 -55.829703)
				(end 41.138856 -55.852822)
			)
			(arc
				(start 41.138856 -55.852822)
				(mid 41.168733 -55.849229)
				(end 41.1988 -55.847996)
			)
			(arc
				(start 41.1988 -55.847996)
				(mid 41.580308 -56.229504)
				(end 41.1988 -56.611012)
			)
			(arc
				(start 41.1988 -56.611012)
				(mid 40.992712 -56.550606)
				(end 40.851836 -56.388508)
			)
			(arc
				(start 40.851836 -56.388508)
				(mid 40.777537 -56.330691)
				(end 40.687752 -56.35879)
			)
			(xy 40.317928 -56.728868) (xy 40.317928 -57.818528) (xy 40.3606 -57.8612) (xy 41.38041 -57.8612)
		)
		(stroke
			(width 0)
			(type solid)
		)
		(fill yes)
		(layer "In4.Cu")
		(net "P3V3_AUX")
	)
	(gr_poly
		(pts
			(xy 21.407374 -38.155626) (xy 21.411184 -38.144196) (xy 21.420409 -38.11777) (xy 21.44412 -38.067067)
			(xy 21.473537 -38.019446) (xy 21.508266 -37.975549) (xy 21.52777 -37.955474) (xy 22.225 -37.258498)
			(xy 22.225 -34.036) (xy 23.9776 -32.2834) (xy 23.9776 -29.811726) (xy 23.977159 -29.797716) (xy 23.969543 -29.770751)
			(xy 23.954879 -29.746875) (xy 23.934273 -29.727888) (xy 23.909279 -29.715224) (xy 23.881782 -29.709836)
			(xy 23.853856 -29.712132) (xy 23.827608 -29.721939) (xy 23.805018 -29.738516) (xy 23.79599 -29.749242)
			(xy 23.777803 -29.771732) (xy 23.735789 -29.811481) (xy 23.688256 -29.844433) (xy 23.636294 -29.869831)
			(xy 23.581093 -29.887093) (xy 23.523919 -29.895825) (xy 23.495 -29.896308) (xy 23.467749 -29.895822)
			(xy 23.413801 -29.888066) (xy 23.361506 -29.872711) (xy 23.311929 -29.850069) (xy 23.266079 -29.820603)
			(xy 23.224888 -29.784912) (xy 23.189197 -29.743721) (xy 23.159731 -29.697871) (xy 23.137089 -29.648294)
			(xy 23.121734 -29.595999) (xy 23.113978 -29.542051) (xy 23.113978 -29.487549) (xy 23.121734 -29.433601)
			(xy 23.137089 -29.381306) (xy 23.159731 -29.331729) (xy 23.189197 -29.285879) (xy 23.224888 -29.244688)
			(xy 23.266079 -29.208997) (xy 23.311929 -29.179531) (xy 23.361506 -29.156889) (xy 23.413801 -29.141534)
			(xy 23.467749 -29.133778) (xy 23.495 -29.133292) (xy 23.523917 -29.133826) (xy 23.581088 -29.142553)
			(xy 23.636288 -29.159807) (xy 23.688252 -29.185192) (xy 23.735791 -29.218129) (xy 23.777815 -29.257861)
			(xy 23.79599 -29.280358) (xy 23.804966 -29.291118) (xy 23.827567 -29.307665) (xy 23.853814 -29.317445)
			(xy 23.881732 -29.319724) (xy 23.909218 -29.31433) (xy 23.934204 -29.301667) (xy 23.954807 -29.282691)
			(xy 23.969477 -29.25883) (xy 23.97711 -29.231879) (xy 23.9776 -29.217874) (xy 23.9776 -21.470112)
			(xy 23.932388 -21.4249) (xy 23.880826 -21.373084) (xy 23.574248 -21.373084) (xy 23.561802 -21.406104)
			(xy 23.552159 -21.430393) (xy 23.527177 -21.476296) (xy 23.496167 -21.518361) (xy 23.459707 -21.555802)
			(xy 23.439374 -21.57222) (xy 23.427577 -21.58212) (xy 23.410075 -21.607441) (xy 23.400911 -21.636827)
			(xy 23.400916 -21.667609) (xy 23.410091 -21.696992) (xy 23.427603 -21.722307) (xy 23.439374 -21.73224)
			(xy 23.460153 -21.748994) (xy 23.497277 -21.787348) (xy 23.528691 -21.830502) (xy 23.553784 -21.877614)
			(xy 23.572065 -21.927763) (xy 23.583178 -21.979971) (xy 23.586904 -22.033218) (xy 23.583172 -22.086465)
			(xy 23.572055 -22.138672) (xy 23.553769 -22.18882) (xy 23.528672 -22.235929) (xy 23.497253 -22.27908)
			(xy 23.460126 -22.31743) (xy 23.439374 -22.33422) (xy 23.427577 -22.34412) (xy 23.410075 -22.369441)
			(xy 23.400911 -22.398827) (xy 23.400916 -22.429609) (xy 23.410091 -22.458992) (xy 23.427603 -22.484307)
			(xy 23.439374 -22.49424) (xy 23.460153 -22.510994) (xy 23.497277 -22.549348) (xy 23.528691 -22.592502)
			(xy 23.553784 -22.639614) (xy 23.572065 -22.689763) (xy 23.583178 -22.741971) (xy 23.586904 -22.795218)
			(xy 23.583172 -22.848465) (xy 23.572055 -22.900672) (xy 23.553769 -22.95082) (xy 23.528672 -22.997929)
			(xy 23.497253 -23.04108) (xy 23.460126 -23.07943) (xy 23.439374 -23.09622) (xy 23.427577 -23.10612)
			(xy 23.410075 -23.131441) (xy 23.400911 -23.160827) (xy 23.400916 -23.191609) (xy 23.410091 -23.220992)
			(xy 23.427603 -23.246307) (xy 23.439374 -23.25624) (xy 23.461861 -23.274429) (xy 23.501604 -23.316445)
			(xy 23.534548 -23.363978) (xy 23.55994 -23.415941) (xy 23.577197 -23.47114) (xy 23.585923 -23.528313)
			(xy 23.58644 -23.55723) (xy 23.585954 -23.584481) (xy 23.578198 -23.638429) (xy 23.562843 -23.690724)
			(xy 23.540201 -23.740301) (xy 23.510735 -23.786151) (xy 23.475044 -23.827342) (xy 23.433853 -23.863033)
			(xy 23.388003 -23.892499) (xy 23.338426 -23.915141) (xy 23.286131 -23.930496) (xy 23.232183 -23.938252)
			(xy 23.177681 -23.938252) (xy 23.123733 -23.930496) (xy 23.071438 -23.915141) (xy 23.021861 -23.892499)
			(xy 22.976011 -23.863033) (xy 22.93482 -23.827342) (xy 22.899129 -23.786151) (xy 22.869663 -23.740301)
			(xy 22.847021 -23.690724) (xy 22.831666 -23.638429) (xy 22.82391 -23.584481) (xy 22.823424 -23.55723)
			(xy 22.823956 -23.528313) (xy 22.832679 -23.471139) (xy 22.849931 -23.415938) (xy 22.875316 -23.363971)
			(xy 22.908252 -23.316431) (xy 22.947985 -23.274406) (xy 22.97049 -23.25624) (xy 22.9823 -23.246342)
			(xy 22.999825 -23.221016) (xy 23.009008 -23.191618) (xy 23.009014 -23.160819) (xy 22.999842 -23.131417)
			(xy 22.982325 -23.106085) (xy 22.97049 -23.09622) (xy 22.949703 -23.079468) (xy 22.912566 -23.041115)
			(xy 22.881138 -22.99796) (xy 22.856033 -22.950844) (xy 22.837742 -22.900689) (xy 22.826621 -22.848474)
			(xy 22.822888 -22.795218) (xy 22.826616 -22.741962) (xy 22.837731 -22.689746) (xy 22.856018 -22.639589)
			(xy 22.881118 -22.592472) (xy 22.912542 -22.549313) (xy 22.949676 -22.510957) (xy 22.97049 -22.49424)
			(xy 22.9823 -22.484342) (xy 22.999825 -22.459016) (xy 23.009008 -22.429618) (xy 23.009014 -22.398819)
			(xy 22.999842 -22.369417) (xy 22.982325 -22.344085) (xy 22.97049 -22.33422) (xy 22.949703 -22.317468)
			(xy 22.912566 -22.279115) (xy 22.881138 -22.23596) (xy 22.856033 -22.188844) (xy 22.837742 -22.138689)
			(xy 22.826621 -22.086474) (xy 22.822888 -22.033218) (xy 22.826616 -21.979962) (xy 22.837731 -21.927746)
			(xy 22.856018 -21.877589) (xy 22.881118 -21.830472) (xy 22.912542 -21.787313) (xy 22.949676 -21.748957)
			(xy 22.97049 -21.73224) (xy 22.9823 -21.722342) (xy 22.999825 -21.697016) (xy 23.009008 -21.667618)
			(xy 23.009014 -21.636819) (xy 22.999842 -21.607417) (xy 22.982325 -21.582085) (xy 22.97049 -21.57222)
			(xy 22.950139 -21.555824) (xy 22.91368 -21.518379) (xy 22.882678 -21.476305) (xy 22.857711 -21.430392)
			(xy 22.848062 -21.406104) (xy 22.835616 -21.373084) (xy 19.357594 -21.373084) (xy 19.345148 -21.406104)
			(xy 19.335506 -21.430394) (xy 19.310526 -21.476299) (xy 19.279518 -21.518367) (xy 19.243061 -21.555811)
			(xy 19.22272 -21.57222) (xy 19.210919 -21.582117) (xy 19.193409 -21.607438) (xy 19.18424 -21.636826)
			(xy 19.184245 -21.667611) (xy 19.193425 -21.696996) (xy 19.210944 -21.72231) (xy 19.22272 -21.73224)
			(xy 19.243502 -21.748993) (xy 19.28063 -21.787345) (xy 19.312049 -21.830498) (xy 19.337145 -21.87761)
			(xy 19.355429 -21.92776) (xy 19.366543 -21.979969) (xy 19.37027 -22.033218) (xy 19.366538 -22.086467)
			(xy 19.355419 -22.138676) (xy 19.33713 -22.188824) (xy 19.312029 -22.235933) (xy 19.280606 -22.279084)
			(xy 19.243474 -22.317432) (xy 19.22272 -22.33422) (xy 19.210919 -22.344117) (xy 19.193409 -22.369438)
			(xy 19.18424 -22.398826) (xy 19.184245 -22.429611) (xy 19.193425 -22.458996) (xy 19.210944 -22.48431)
			(xy 19.22272 -22.49424) (xy 19.243502 -22.510993) (xy 19.28063 -22.549345) (xy 19.312049 -22.592498)
			(xy 19.337145 -22.63961) (xy 19.355429 -22.68976) (xy 19.366543 -22.741969) (xy 19.37027 -22.795218)
			(xy 19.366538 -22.848467) (xy 19.355419 -22.900676) (xy 19.33713 -22.950824) (xy 19.312029 -22.997933)
			(xy 19.280606 -23.041084) (xy 19.243474 -23.079432) (xy 19.22272 -23.09622) (xy 19.210919 -23.106117)
			(xy 19.193409 -23.131438) (xy 19.18424 -23.160826) (xy 19.184245 -23.191611) (xy 19.193425 -23.220996)
			(xy 19.210944 -23.24631) (xy 19.22272 -23.25624) (xy 19.245204 -23.274431) (xy 19.284943 -23.316448)
			(xy 19.317884 -23.363982) (xy 19.343272 -23.415944) (xy 19.360526 -23.471143) (xy 19.369251 -23.528314)
			(xy 19.369786 -23.55723) (xy 19.3693 -23.584481) (xy 19.361544 -23.638429) (xy 19.346189 -23.690724)
			(xy 19.323547 -23.740301) (xy 19.294081 -23.786151) (xy 19.25839 -23.827342) (xy 19.217199 -23.863033)
			(xy 19.171349 -23.892499) (xy 19.121772 -23.915141) (xy 19.069477 -23.930496) (xy 19.015529 -23.938252)
			(xy 18.961027 -23.938252) (xy 18.907079 -23.930496) (xy 18.854784 -23.915141) (xy 18.805207 -23.892499)
			(xy 18.759357 -23.863033) (xy 18.718166 -23.827342) (xy 18.682475 -23.786151) (xy 18.653009 -23.740301)
			(xy 18.630367 -23.690724) (xy 18.615012 -23.638429) (xy 18.607256 -23.584481) (xy 18.60677 -23.55723)
			(xy 18.607302 -23.528313) (xy 18.616026 -23.471141) (xy 18.633279 -23.41594) (xy 18.658666 -23.363976)
			(xy 18.691605 -23.316439) (xy 18.731341 -23.274418) (xy 18.753836 -23.25624) (xy 18.76565 -23.246345)
			(xy 18.783186 -23.22102) (xy 18.792374 -23.19162) (xy 18.792379 -23.160817) (xy 18.783202 -23.131413)
			(xy 18.765676 -23.106082) (xy 18.753836 -23.09622) (xy 18.733052 -23.079466) (xy 18.69592 -23.041111)
			(xy 18.664496 -22.997955) (xy 18.639395 -22.95084) (xy 18.621106 -22.900686) (xy 18.609987 -22.848472)
			(xy 18.606255 -22.795218) (xy 18.609982 -22.741964) (xy 18.621096 -22.68975) (xy 18.63938 -22.639594)
			(xy 18.664476 -22.592476) (xy 18.695896 -22.549317) (xy 18.733025 -22.510959) (xy 18.753836 -22.49424)
			(xy 18.765557 -22.484444) (xy 18.783005 -22.459388) (xy 18.792269 -22.430294) (xy 18.792519 -22.399762)
			(xy 18.783734 -22.37052) (xy 18.766698 -22.345181) (xy 18.755106 -22.335236) (xy 18.732437 -22.317053)
			(xy 18.692349 -22.274984) (xy 18.659107 -22.22732) (xy 18.633482 -22.175164) (xy 18.616064 -22.119725)
			(xy 18.607259 -22.062285) (xy 18.60677 -22.03323) (xy 18.606823 -22.023242) (xy 18.607842 -22.003293)
			(xy 18.608802 -21.993352) (xy 18.60931 -21.988526) (xy 18.613419 -21.958577) (xy 18.629878 -21.900413)
			(xy 18.655311 -21.845575) (xy 18.689082 -21.795441) (xy 18.730344 -21.751265) (xy 18.753836 -21.73224)
			(xy 18.76565 -21.722345) (xy 18.783186 -21.69702) (xy 18.792374 -21.66762) (xy 18.792379 -21.636817)
			(xy 18.783202 -21.607413) (xy 18.765676 -21.582082) (xy 18.753836 -21.57222) (xy 18.733483 -21.555825)
			(xy 18.697021 -21.518382) (xy 18.666014 -21.47631) (xy 18.641045 -21.430398) (xy 18.631408 -21.406104)
			(xy 18.618962 -21.373084) (xy 17.44472 -21.373084) (xy 17.153636 -21.664168) (xy 16.899128 -21.91893)
			(xy 16.899128 -29.061664) (xy 17.306804 -30.2514) (xy 21.639782 -30.2514) (xy 21.643853 -30.195778)
			(xy 21.655979 -30.141341) (xy 21.675902 -30.08925) (xy 21.703198 -30.040615) (xy 21.737284 -29.996472)
			(xy 21.777433 -29.957763) (xy 21.822791 -29.925312) (xy 21.872391 -29.899811) (xy 21.925175 -29.881804)
			(xy 21.980018 -29.871674) (xy 22.035752 -29.869637) (xy 22.091189 -29.875737) (xy 22.145146 -29.889843)
			(xy 22.196475 -29.911655) (xy 22.244081 -29.940709) (xy 22.286949 -29.976384) (xy 22.324166 -30.017921)
			(xy 22.354939 -30.064434) (xy 22.378611 -30.114931) (xy 22.394679 -30.168338) (xy 22.402799 -30.223514)
			(xy 22.403308 -30.2514) (xy 22.402799 -30.279286) (xy 22.394679 -30.334462) (xy 22.378611 -30.387869)
			(xy 22.354939 -30.438366) (xy 22.324166 -30.484879) (xy 22.286949 -30.526416) (xy 22.244081 -30.562091)
			(xy 22.196475 -30.591145) (xy 22.145146 -30.612957) (xy 22.091189 -30.627063) (xy 22.035752 -30.633163)
			(xy 21.980018 -30.631126) (xy 21.925175 -30.620996) (xy 21.872391 -30.602989) (xy 21.822791 -30.577488)
			(xy 21.777433 -30.545037) (xy 21.737284 -30.506328) (xy 21.703198 -30.462185) (xy 21.675902 -30.41355)
			(xy 21.655979 -30.361459) (xy 21.643853 -30.307022) (xy 21.639782 -30.2514) (xy 17.306804 -30.2514)
			(xy 17.431004 -30.613858) (xy 17.431004 -32.520128) (xy 17.431512 -32.5374) (xy 17.431004 -32.554672)
			(xy 17.431004 -34.790126) (xy 17.227296 -34.994088) (xy 17.227296 -39.223442) (xy 17.8816 -39.878)
			(xy 19.685 -39.878)
		)
		(stroke
			(width 0)
			(type solid)
		)
		(fill yes)
		(layer "In4.Cu")
		(net "GND")
	)
	(gr_poly
		(pts
			(xy 84.492084 -118.78056)
			(arc
				(start 84.492084 -114.799872)
				(mid 84.787357 -114.087273)
				(end 85.499956 -113.792)
			)
			(arc
				(start 88.000078 -113.792)
				(mid 89.055078 -113.355004)
				(end 89.492074 -112.300004)
			)
			(xy 89.492074 -85.508084)
			(arc
				(start 87.749888 -85.508084)
				(mid 87.037379 -85.212795)
				(end 86.742016 -84.500212)
			)
			(arc
				(start 86.742016 -81.999836)
				(mid 87.037289 -81.287237)
				(end 87.749888 -80.991964)
			)
			(xy 89.492074 -80.991964)
			(arc
				(start 89.492074 -1.999996)
				(mid 89.055078 -0.944996)
				(end 88.000078 -0.508)
			)
			(arc
				(start 1.999996 -0.508)
				(mid 0.944996 -0.944996)
				(end 0.508 -1.999996)
			)
			(xy 0.508 -80.991964)
			(arc
				(start 2.249932 -80.991964)
				(mid 2.962785 -81.287237)
				(end 3.258058 -82.00009)
			)
			(arc
				(start 3.258058 -84.499958)
				(mid 2.962785 -85.212811)
				(end 2.249932 -85.508084)
			)
			(xy 0.508 -85.508084)
			(arc
				(start 0.508 -112.300004)
				(mid 0.944996 -113.355004)
				(end 1.999996 -113.792)
			)
			(arc
				(start 4.500118 -113.792)
				(mid 5.212717 -114.087273)
				(end 5.50799 -114.799872)
			)
			(xy 5.50799 -118.71071) (xy 5.621528 -118.824248) (xy 5.936488 -118.824248) (xy 6.015228 -118.745508)
			(arc
				(start 6.015228 -114.799872)
				(mid 5.571478 -113.728438)
				(end 4.500118 -113.284508)
			)
			(arc
				(start 1.999996 -113.284508)
				(mid 1.303847 -112.996153)
				(end 1.015492 -112.300004)
			)
			(xy 1.015492 -86.015576)
			(arc
				(start 2.249932 -86.015576)
				(mid 2.819328 -85.90445)
				(end 3.305302 -85.587586)
			)
			(arc
				(start 3.337306 -85.555582)
				(mid 3.647708 -85.085234)
				(end 3.764788 -84.533994)
			)
			(arc
				(start 3.764788 -81.9658)
				(mid 3.309352 -80.916273)
				(end 2.249932 -80.484472)
			)
			(xy 1.015492 -80.484472) (xy 1.015492 -78.41615) (xy 1.014984 -78.401926) (xy 1.014984 -30.706568)
			(xy 1.015492 -30.692344)
			(arc
				(start 1.015492 -1.999996)
				(mid 1.303847 -1.303847)
				(end 1.999996 -1.015492)
			)
			(xy 63.713868 -1.015492) (xy 76.606908 -1.015492)
			(arc
				(start 88.000078 -1.015492)
				(mid 88.696317 -1.303831)
				(end 88.984836 -1.999996)
			)
			(xy 88.984836 -80.484472)
			(arc
				(start 87.749888 -80.484472)
				(mid 86.678438 -80.928386)
				(end 86.234524 -81.999836)
			)
			(arc
				(start 86.234524 -84.500212)
				(mid 86.678348 -85.571826)
				(end 87.749888 -86.015576)
			)
			(xy 88.984836 -86.015576)
			(arc
				(start 88.984836 -112.300004)
				(mid 88.696571 -112.996064)
				(end 88.000586 -113.284508)
			)
			(arc
				(start 85.499956 -113.284508)
				(mid 84.428432 -113.728348)
				(end 83.984592 -114.799872)
			)
			(xy 83.984592 -118.768114) (xy 84.094574 -118.878096) (xy 84.394548 -118.878096)
		)
		(stroke
			(width 0)
			(type solid)
		)
		(fill yes)
		(layer "In4.Cu")
		(net "GND")
	)
	(gr_poly
		(pts
			(xy 50.184812 -72.315832) (xy 50.184812 -69.088762) (xy 50.170334 -69.053456) (xy 49.623726 -68.506848)
			(xy 49.613672 -68.497427) (xy 49.58971 -68.483851) (xy 49.562992 -68.477171) (xy 49.535461 -68.477871)
			(xy 49.509117 -68.485901) (xy 49.485876 -68.500678) (xy 49.467427 -68.521126) (xy 49.460912 -68.533264)
			(xy 49.448678 -68.55662) (xy 49.418743 -68.600025) (xy 49.383119 -68.638896) (xy 49.342482 -68.672493)
			(xy 49.297608 -68.700176) (xy 49.249351 -68.721418) (xy 49.198628 -68.735815) (xy 49.146407 -68.743093)
			(xy 49.120044 -68.743576) (xy 49.09278 -68.743115) (xy 49.038806 -68.735357) (xy 48.986487 -68.719993)
			(xy 48.936889 -68.697337) (xy 48.891022 -68.667849) (xy 48.849821 -68.632131) (xy 48.814125 -68.59091)
			(xy 48.784663 -68.545027) (xy 48.762033 -68.495416) (xy 48.746698 -68.443088) (xy 48.73897 -68.38911)
			(xy 48.739006 -68.334582) (xy 48.746806 -68.280615) (xy 48.762211 -68.228308) (xy 48.784906 -68.178727)
			(xy 48.81443 -68.132883) (xy 48.850181 -68.09171) (xy 48.891429 -68.056047) (xy 48.937335 -68.02662)
			(xy 48.986964 -68.004029) (xy 49.039303 -67.988735) (xy 49.093287 -67.981049) (xy 49.120552 -67.98056)
			(xy 49.130635 -67.980177) (xy 49.149278 -67.972503) (xy 49.163528 -67.95824) (xy 49.171185 -67.939589)
			(xy 49.171606 -67.929506) (xy 49.171352 -67.92722) (xy 49.171352 -65.942972) (xy 48.985678 -65.757044)
			(xy 48.970438 -65.753996) (xy 48.944703 -65.748535) (xy 48.894936 -65.73148) (xy 48.847984 -65.70775)
			(xy 48.804735 -65.677797) (xy 48.766011 -65.642187) (xy 48.732545 -65.601595) (xy 48.704972 -65.556792)
			(xy 48.683814 -65.508626) (xy 48.669472 -65.45801) (xy 48.662219 -65.405904) (xy 48.661828 -65.3796)
			(xy 48.662397 -65.34942) (xy 48.671903 -65.289814) (xy 48.690695 -65.232454) (xy 48.703992 -65.205356)
			(xy 48.70958 -65.194434) (xy 48.70958 -60.443618) (xy 48.7092 -60.434084) (xy 48.702249 -60.416329)
			(xy 48.68927 -60.402361) (xy 48.672073 -60.394126) (xy 48.66259 -60.393072) (xy 48.636098 -60.39053)
			(xy 48.584239 -60.37858) (xy 48.534736 -60.359044) (xy 48.488693 -60.332357) (xy 48.447135 -60.299114)
			(xy 48.410988 -60.260055) (xy 48.381058 -60.216051) (xy 48.358011 -60.168082) (xy 48.342362 -60.117217)
			(xy 48.334458 -60.064589) (xy 48.333914 -60.03798) (xy 48.334436 -60.009996) (xy 48.343194 -59.954718)
			(xy 48.360492 -59.901491) (xy 48.385904 -59.851625) (xy 48.418803 -59.806349) (xy 48.458381 -59.766776)
			(xy 48.503661 -59.733882) (xy 48.55353 -59.708476) (xy 48.606759 -59.691185) (xy 48.662038 -59.682433)
			(xy 48.690022 -59.681872) (xy 48.715696 -59.682342) (xy 48.766508 -59.689753) (xy 48.815732 -59.704374)
			(xy 48.86235 -59.725904) (xy 48.905398 -59.753898) (xy 48.924972 -59.770518) (xy 49.28997 -59.40552)
			(xy 49.28997 -59.299856) (xy 49.247298 -59.292744) (xy 49.221766 -59.288143) (xy 49.172453 -59.272036)
			(xy 49.126264 -59.248418) (xy 49.084335 -59.21787) (xy 49.047698 -59.181142) (xy 49.017254 -59.139138)
			(xy 48.99375 -59.092891) (xy 48.977766 -59.043538) (xy 48.969694 -58.992293) (xy 48.969168 -58.966354)
			(xy 48.969681 -58.940368) (xy 48.977817 -58.889038) (xy 48.993882 -58.839612) (xy 49.01748 -58.793307)
			(xy 49.04803 -58.751264) (xy 49.08478 -58.714516) (xy 49.126826 -58.683968) (xy 49.173133 -58.660373)
			(xy 49.22256 -58.644312) (xy 49.27389 -58.636179) (xy 49.299876 -58.635646) (xy 49.325861 -58.636153)
			(xy 49.377192 -58.644278) (xy 49.426621 -58.66033) (xy 49.47293 -58.683916) (xy 49.514982 -58.714454)
			(xy 49.551739 -58.751193) (xy 49.582298 -58.793229) (xy 49.605907 -58.839527) (xy 49.621984 -58.888948)
			(xy 49.62652 -58.914538) (xy 49.62906 -58.930794) (xy 49.676558 -58.978546) (xy 49.782222 -58.872882)
			(xy 49.786032 -58.861452) (xy 49.794572 -58.837397) (xy 49.817999 -58.792048) (xy 49.848115 -58.750837)
			(xy 49.884206 -58.714742) (xy 49.925413 -58.68462) (xy 49.97076 -58.661187) (xy 49.99482 -58.652664)
			(xy 50.00625 -58.648854) (xy 50.111914 -58.54319) (xy 50.064162 -58.495692) (xy 50.047906 -58.493152)
			(xy 50.022321 -58.48858) (xy 49.972896 -58.472512) (xy 49.926592 -58.448912) (xy 49.88455 -58.41836)
			(xy 49.847804 -58.381607) (xy 49.817259 -58.33956) (xy 49.793666 -58.293252) (xy 49.777607 -58.243825)
			(xy 49.769477 -58.192494) (xy 49.769014 -58.166508) (xy 49.769497 -58.140519) (xy 49.777627 -58.089181)
			(xy 49.793689 -58.039747) (xy 49.817286 -57.993434) (xy 49.847839 -57.951383) (xy 49.884594 -57.91463)
			(xy 49.926646 -57.884079) (xy 49.972959 -57.860483) (xy 50.022394 -57.844424) (xy 50.073733 -57.836295)
			(xy 50.099722 -57.8358) (xy 50.110421 -57.835893) (xy 50.131774 -57.837288) (xy 50.142394 -57.838594)
			(xy 50.156754 -57.839943) (xy 50.185238 -57.835493) (xy 50.211341 -57.823254) (xy 50.232979 -57.804204)
			(xy 50.248426 -57.779862) (xy 50.25645 -57.752171) (xy 50.256948 -57.737756) (xy 50.256948 -57.197244)
			(xy 50.114962 -57.055258) (xy 49.678082 -57.055258) (xy 49.662978 -57.055809) (xy 49.634091 -57.064643)
			(xy 49.609048 -57.081535) (xy 49.590035 -57.105009) (xy 49.578714 -57.133015) (xy 49.576073 -57.163107)
			(xy 49.582342 -57.192657) (xy 49.589182 -57.206134) (xy 49.602188 -57.230826) (xy 49.620638 -57.283492)
			(xy 49.629996 -57.338506) (xy 49.630584 -57.366408) (xy 49.630074 -57.392395) (xy 49.621944 -57.44373)
			(xy 49.605883 -57.49316) (xy 49.582287 -57.53947) (xy 49.551737 -57.581518) (xy 49.514986 -57.618269)
			(xy 49.472938 -57.648819) (xy 49.426628 -57.672415) (xy 49.377198 -57.688476) (xy 49.325863 -57.696606)
			(xy 49.273889 -57.696606) (xy 49.222554 -57.688476) (xy 49.173124 -57.672415) (xy 49.126814 -57.648819)
			(xy 49.084766 -57.618269) (xy 49.048015 -57.581518) (xy 49.017465 -57.53947) (xy 48.993869 -57.49316)
			(xy 48.977808 -57.44373) (xy 48.969678 -57.392395) (xy 48.969168 -57.366408) (xy 48.969746 -57.338505)
			(xy 48.979105 -57.28349) (xy 48.997559 -57.230824) (xy 49.01057 -57.206134) (xy 49.017409 -57.192658)
			(xy 49.023682 -57.163112) (xy 49.021041 -57.133023) (xy 49.009719 -57.105021) (xy 48.990705 -57.081553)
			(xy 48.96566 -57.06467) (xy 48.936772 -57.055847) (xy 48.92167 -57.055258) (xy 48.316134 -57.055258)
			(xy 48.0568 -57.314592) (xy 48.0568 -58.192495) (xy 48.969678 -58.192495) (xy 48.969678 -58.140521)
			(xy 48.977808 -58.089186) (xy 48.993869 -58.039756) (xy 49.017465 -57.993446) (xy 49.048015 -57.951398)
			(xy 49.084766 -57.914647) (xy 49.126814 -57.884097) (xy 49.173124 -57.860501) (xy 49.222554 -57.84444)
			(xy 49.273889 -57.83631) (xy 49.325863 -57.83631) (xy 49.377198 -57.84444) (xy 49.426628 -57.860501)
			(xy 49.472938 -57.884097) (xy 49.514986 -57.914647) (xy 49.551737 -57.951398) (xy 49.582287 -57.993446)
			(xy 49.605883 -58.039756) (xy 49.621944 -58.089186) (xy 49.630074 -58.140521) (xy 49.630584 -58.166508)
			(xy 49.630074 -58.192495) (xy 49.621944 -58.24383) (xy 49.605883 -58.29326) (xy 49.582287 -58.33957)
			(xy 49.551737 -58.381618) (xy 49.514986 -58.418369) (xy 49.472938 -58.448919) (xy 49.426628 -58.472515)
			(xy 49.377198 -58.488576) (xy 49.325863 -58.496706) (xy 49.273889 -58.496706) (xy 49.222554 -58.488576)
			(xy 49.173124 -58.472515) (xy 49.126814 -58.448919) (xy 49.084766 -58.418369) (xy 49.048015 -58.381618)
			(xy 49.017465 -58.33957) (xy 48.993869 -58.29326) (xy 48.977808 -58.24383) (xy 48.969678 -58.192495)
			(xy 48.0568 -58.192495) (xy 48.0568 -58.35142) (xy 47.645828 -58.762392) (xy 47.645828 -59.26582)
			(xy 47.644558 -59.295538) (xy 47.643796 -59.304682) (xy 47.64256 -59.318012) (xy 47.638363 -59.344455)
			(xy 47.635414 -59.357514) (xy 47.633128 -59.367166) (xy 47.629237 -59.382653) (xy 47.61906 -59.412924)
			(xy 47.612808 -59.427618) (xy 47.607728 -59.439302) (xy 47.599042 -59.458579) (xy 47.577776 -59.495123)
			(xy 47.56531 -59.5122) (xy 47.552864 -59.52871) (xy 47.545256 -59.538601) (xy 47.528857 -59.557414)
			(xy 47.520098 -59.566302) (xy 46.535848 -60.550806) (xy 46.535848 -63.483744) (xy 46.83582 -63.483744)
			(xy 46.839891 -63.428122) (xy 46.852017 -63.373685) (xy 46.87194 -63.321594) (xy 46.899236 -63.272959)
			(xy 46.933322 -63.228816) (xy 46.973471 -63.190107) (xy 47.018829 -63.157656) (xy 47.068429 -63.132155)
			(xy 47.121213 -63.114148) (xy 47.176056 -63.104018) (xy 47.23179 -63.101981) (xy 47.287227 -63.108081)
			(xy 47.341184 -63.122187) (xy 47.392513 -63.143999) (xy 47.440119 -63.173053) (xy 47.482987 -63.208728)
			(xy 47.520204 -63.250265) (xy 47.550977 -63.296778) (xy 47.574649 -63.347275) (xy 47.590717 -63.400682)
			(xy 47.598837 -63.455858) (xy 47.599346 -63.483744) (xy 47.598837 -63.51163) (xy 47.590717 -63.566806)
			(xy 47.574649 -63.620213) (xy 47.550977 -63.67071) (xy 47.520204 -63.717223) (xy 47.482987 -63.75876)
			(xy 47.440119 -63.794435) (xy 47.392513 -63.823489) (xy 47.341184 -63.845301) (xy 47.287227 -63.859407)
			(xy 47.23179 -63.865507) (xy 47.176056 -63.86347) (xy 47.121213 -63.85334) (xy 47.068429 -63.835333)
			(xy 47.018829 -63.809832) (xy 46.973471 -63.777381) (xy 46.933322 -63.738672) (xy 46.899236 -63.694529)
			(xy 46.87194 -63.645894) (xy 46.852017 -63.593803) (xy 46.839891 -63.539366) (xy 46.83582 -63.483744)
			(xy 46.535848 -63.483744) (xy 46.535848 -63.784226) (xy 46.747684 -64.296544) (xy 46.755558 -64.317118)
			(xy 46.758352 -64.325246) (xy 46.762162 -64.337438) (xy 46.769274 -64.360806) (xy 46.77283 -64.372744)
			(xy 46.774862 -64.380364) (xy 46.779942 -64.40297) (xy 46.888254 -64.9478) (xy 47.217582 -64.9478)
			(xy 47.221653 -64.892178) (xy 47.233779 -64.837741) (xy 47.253702 -64.78565) (xy 47.280998 -64.737015)
			(xy 47.315084 -64.692872) (xy 47.355233 -64.654163) (xy 47.400591 -64.621712) (xy 47.450191 -64.596211)
			(xy 47.502975 -64.578204) (xy 47.557818 -64.568074) (xy 47.613552 -64.566037) (xy 47.668989 -64.572137)
			(xy 47.722946 -64.586243) (xy 47.774275 -64.608055) (xy 47.821881 -64.637109) (xy 47.864749 -64.672784)
			(xy 47.901966 -64.714321) (xy 47.932739 -64.760834) (xy 47.956411 -64.811331) (xy 47.972479 -64.864738)
			(xy 47.980599 -64.919914) (xy 47.981108 -64.9478) (xy 47.980599 -64.975686) (xy 47.972479 -65.030862)
			(xy 47.956411 -65.084269) (xy 47.932739 -65.134766) (xy 47.901966 -65.181279) (xy 47.864749 -65.222816)
			(xy 47.821881 -65.258491) (xy 47.774275 -65.287545) (xy 47.722946 -65.309357) (xy 47.668989 -65.323463)
			(xy 47.613552 -65.329563) (xy 47.557818 -65.327526) (xy 47.502975 -65.317396) (xy 47.450191 -65.299389)
			(xy 47.400591 -65.273888) (xy 47.355233 -65.241437) (xy 47.315084 -65.202728) (xy 47.280998 -65.158585)
			(xy 47.253702 -65.10995) (xy 47.233779 -65.057859) (xy 47.221653 -65.003422) (xy 47.217582 -64.9478)
			(xy 46.888254 -64.9478) (xy 47.007272 -65.546478) (xy 47.01032 -65.562734) (xy 47.01159 -65.571116)
			(xy 47.013368 -65.58661) (xy 47.015654 -65.607946) (xy 47.016924 -65.620392) (xy 47.017432 -65.627504)
			(xy 47.018448 -65.653158) (xy 47.018448 -66.16446) (xy 47.018196 -66.182946) (xy 47.014379 -66.219722)
			(xy 47.010828 -66.237866) (xy 47.00524 -66.264536) (xy 47.002073 -66.27898) (xy 46.993676 -66.307335)
			(xy 46.988476 -66.321178) (xy 46.986698 -66.32575) (xy 46.98365 -66.332608) (xy 46.964346 -66.379598)
			(xy 46.97095 -66.386202) (xy 48.280064 -66.386202) (xy 48.284135 -66.33058) (xy 48.296261 -66.276143)
			(xy 48.316184 -66.224052) (xy 48.34348 -66.175417) (xy 48.377566 -66.131274) (xy 48.417715 -66.092565)
			(xy 48.463073 -66.060114) (xy 48.512673 -66.034613) (xy 48.565457 -66.016606) (xy 48.6203 -66.006476)
			(xy 48.676034 -66.004439) (xy 48.731471 -66.010539) (xy 48.785428 -66.024645) (xy 48.836757 -66.046457)
			(xy 48.884363 -66.075511) (xy 48.927231 -66.111186) (xy 48.964448 -66.152723) (xy 48.995221 -66.199236)
			(xy 49.018893 -66.249733) (xy 49.034961 -66.30314) (xy 49.043081 -66.358316) (xy 49.04359 -66.386202)
			(xy 49.043081 -66.414088) (xy 49.034961 -66.469264) (xy 49.018893 -66.522671) (xy 48.995221 -66.573168)
			(xy 48.964448 -66.619681) (xy 48.927231 -66.661218) (xy 48.884363 -66.696893) (xy 48.836757 -66.725947)
			(xy 48.785428 -66.747759) (xy 48.731471 -66.761865) (xy 48.676034 -66.767965) (xy 48.6203 -66.765928)
			(xy 48.565457 -66.755798) (xy 48.512673 -66.737791) (xy 48.463073 -66.71229) (xy 48.417715 -66.679839)
			(xy 48.377566 -66.64113) (xy 48.34348 -66.596987) (xy 48.316184 -66.548352) (xy 48.296261 -66.496261)
			(xy 48.284135 -66.441824) (xy 48.280064 -66.386202) (xy 46.97095 -66.386202) (xy 47.230792 -66.646044)
			(xy 47.230792 -68.46189) (xy 47.252372 -68.480108) (xy 47.290442 -68.52182) (xy 47.321947 -68.568688)
			(xy 47.346198 -68.619689) (xy 47.362667 -68.673707) (xy 47.370992 -68.729563) (xy 47.370992 -68.786037)
			(xy 47.362667 -68.841893) (xy 47.346198 -68.895911) (xy 47.321947 -68.946912) (xy 47.290442 -68.99378)
			(xy 47.273995 -69.0118) (xy 48.106582 -69.0118) (xy 48.110653 -68.956178) (xy 48.122779 -68.901741)
			(xy 48.142702 -68.84965) (xy 48.169998 -68.801015) (xy 48.204084 -68.756872) (xy 48.244233 -68.718163)
			(xy 48.289591 -68.685712) (xy 48.339191 -68.660211) (xy 48.391975 -68.642204) (xy 48.446818 -68.632074)
			(xy 48.502552 -68.630037) (xy 48.557989 -68.636137) (xy 48.611946 -68.650243) (xy 48.663275 -68.672055)
			(xy 48.710881 -68.701109) (xy 48.753749 -68.736784) (xy 48.790966 -68.778321) (xy 48.821739 -68.824834)
			(xy 48.845411 -68.875331) (xy 48.861479 -68.928738) (xy 48.869599 -68.983914) (xy 48.870108 -69.0118)
			(xy 48.869599 -69.039686) (xy 48.861479 -69.094862) (xy 48.845411 -69.148269) (xy 48.821739 -69.198766)
			(xy 48.790966 -69.245279) (xy 48.753749 -69.286816) (xy 48.710881 -69.322491) (xy 48.663275 -69.351545)
			(xy 48.611946 -69.373357) (xy 48.557989 -69.387463) (xy 48.502552 -69.393563) (xy 48.446818 -69.391526)
			(xy 48.391975 -69.381396) (xy 48.339191 -69.363389) (xy 48.289591 -69.337888) (xy 48.244233 -69.305437)
			(xy 48.204084 -69.266728) (xy 48.169998 -69.222585) (xy 48.142702 -69.17395) (xy 48.122779 -69.121859)
			(xy 48.110653 -69.067422) (xy 48.106582 -69.0118) (xy 47.273995 -69.0118) (xy 47.252372 -69.035492)
			(xy 47.230792 -69.05371) (xy 47.230792 -69.417438) (xy 49.241962 -69.417438) (xy 49.246033 -69.361816)
			(xy 49.258159 -69.307379) (xy 49.278082 -69.255288) (xy 49.305378 -69.206653) (xy 49.339464 -69.16251)
			(xy 49.379613 -69.123801) (xy 49.424971 -69.09135) (xy 49.474571 -69.065849) (xy 49.527355 -69.047842)
			(xy 49.582198 -69.037712) (xy 49.637932 -69.035675) (xy 49.693369 -69.041775) (xy 49.747326 -69.055881)
			(xy 49.798655 -69.077693) (xy 49.846261 -69.106747) (xy 49.889129 -69.142422) (xy 49.926346 -69.183959)
			(xy 49.957119 -69.230472) (xy 49.980791 -69.280969) (xy 49.996859 -69.334376) (xy 50.004979 -69.389552)
			(xy 50.005488 -69.417438) (xy 50.004979 -69.445324) (xy 49.996859 -69.5005) (xy 49.980791 -69.553907)
			(xy 49.957119 -69.604404) (xy 49.926346 -69.650917) (xy 49.889129 -69.692454) (xy 49.846261 -69.728129)
			(xy 49.798655 -69.757183) (xy 49.747326 -69.778995) (xy 49.693369 -69.793101) (xy 49.637932 -69.799201)
			(xy 49.582198 -69.797164) (xy 49.527355 -69.787034) (xy 49.474571 -69.769027) (xy 49.424971 -69.743526)
			(xy 49.379613 -69.711075) (xy 49.339464 -69.672366) (xy 49.305378 -69.628223) (xy 49.278082 -69.579588)
			(xy 49.258159 -69.527497) (xy 49.246033 -69.47306) (xy 49.241962 -69.417438) (xy 47.230792 -69.417438)
			(xy 47.230792 -70.370954) (xy 47.449994 -70.590156) (xy 47.469515 -70.61047) (xy 47.502616 -70.656055)
			(xy 47.52818 -70.706256) (xy 47.545578 -70.759837) (xy 47.554382 -70.81548) (xy 47.554896 -70.843648)
			(xy 47.554896 -71.28637) (xy 47.681894 -71.28637) (xy 47.685965 -71.230748) (xy 47.698091 -71.176311)
			(xy 47.718014 -71.12422) (xy 47.74531 -71.075585) (xy 47.779396 -71.031442) (xy 47.819545 -70.992733)
			(xy 47.864903 -70.960282) (xy 47.914503 -70.934781) (xy 47.967287 -70.916774) (xy 48.02213 -70.906644)
			(xy 48.077864 -70.904607) (xy 48.133301 -70.910707) (xy 48.187258 -70.924813) (xy 48.238587 -70.946625)
			(xy 48.286193 -70.975679) (xy 48.329061 -71.011354) (xy 48.366278 -71.052891) (xy 48.397051 -71.099404)
			(xy 48.420723 -71.149901) (xy 48.436791 -71.203308) (xy 48.444911 -71.258484) (xy 48.44542 -71.28637)
			(xy 48.444911 -71.314256) (xy 48.436791 -71.369432) (xy 48.420723 -71.422839) (xy 48.397051 -71.473336)
			(xy 48.366278 -71.519849) (xy 48.329061 -71.561386) (xy 48.286193 -71.597061) (xy 48.238587 -71.626115)
			(xy 48.187258 -71.647927) (xy 48.133301 -71.662033) (xy 48.077864 -71.668133) (xy 48.02213 -71.666096)
			(xy 47.967287 -71.655966) (xy 47.914503 -71.637959) (xy 47.864903 -71.612458) (xy 47.819545 -71.580007)
			(xy 47.779396 -71.541298) (xy 47.74531 -71.497155) (xy 47.718014 -71.44852) (xy 47.698091 -71.396429)
			(xy 47.685965 -71.341992) (xy 47.681894 -71.28637) (xy 47.554896 -71.28637) (xy 47.554896 -72.194166)
			(xy 47.7266 -72.36587) (xy 50.135028 -72.36587)
		)
		(stroke
			(width 0)
			(type solid)
		)
		(fill yes)
		(layer "In4.Cu")
		(net "P1V8_SENSOR")
	)
	(gr_poly
		(pts
			(xy 50.700432 -67.295776) (xy 50.704173 -67.268284) (xy 50.71858 -67.214707) (xy 50.740597 -67.163782)
			(xy 50.769761 -67.116584) (xy 50.805456 -67.074111) (xy 50.846928 -67.037257) (xy 50.893302 -67.006802)
			(xy 50.9436 -66.983387) (xy 50.99676 -66.967507) (xy 51.051659 -66.959497) (xy 51.0794 -66.958972)
			(xy 51.108625 -66.959529) (xy 51.16639 -66.968442) (xy 51.222121 -66.986059) (xy 51.274514 -67.011968)
			(xy 51.322344 -67.045563) (xy 51.343814 -67.065398) (xy 51.379882 -67.099942) (xy 51.585114 -66.89471)
			(xy 51.669442 -66.691256) (xy 51.681665 -66.663619) (xy 51.71518 -66.613346) (xy 51.73599 -66.591434)
			(xy 51.883056 -66.444622) (xy 51.883056 -65.824862) (xy 51.86711 -65.800849) (xy 51.841863 -65.749032)
			(xy 51.824704 -65.694004) (xy 51.816026 -65.63702) (xy 51.816026 -65.57938) (xy 51.824704 -65.522396)
			(xy 51.841863 -65.467368) (xy 51.86711 -65.415551) (xy 51.883056 -65.391538) (xy 51.883056 -64.154812)
			(xy 51.311048 -63.583058) (xy 51.29427 -63.565633) (xy 51.265859 -63.526486) (xy 51.243934 -63.48337)
			(xy 51.229038 -63.437351) (xy 51.221538 -63.389566) (xy 51.221132 -63.36538) (xy 51.221132 -62.47511)
			(xy 51.221588 -62.450929) (xy 51.229112 -62.403156) (xy 51.244009 -62.357146) (xy 51.265913 -62.314029)
			(xy 51.294284 -62.274864) (xy 51.311048 -62.257432) (xy 51.3715 -62.197234) (xy 51.3715 -62.170056)
			(xy 51.883056 -61.6585) (xy 51.883056 -60.190888) (xy 51.882529 -60.175938) (xy 51.873875 -60.147319)
			(xy 51.857311 -60.122427) (xy 51.834253 -60.103393) (xy 51.806675 -60.091844) (xy 51.776934 -60.088768)
			(xy 51.762152 -60.091066) (xy 51.746686 -60.093898) (xy 51.71539 -60.096953) (xy 51.699668 -60.097162)
			(xy 51.673686 -60.09665) (xy 51.622363 -60.088516) (xy 51.572943 -60.072455) (xy 51.526645 -60.048861)
			(xy 51.484607 -60.018314) (xy 51.447865 -59.981569) (xy 51.417323 -59.939528) (xy 51.393733 -59.893227)
			(xy 51.377676 -59.843806) (xy 51.369548 -59.792482) (xy 51.369548 -59.740518) (xy 51.377676 -59.689194)
			(xy 51.393733 -59.639773) (xy 51.417323 -59.593472) (xy 51.447865 -59.551431) (xy 51.484607 -59.514686)
			(xy 51.526645 -59.484139) (xy 51.572943 -59.460545) (xy 51.622363 -59.444484) (xy 51.673686 -59.43635)
			(xy 51.699668 -59.435746) (xy 51.725429 -59.436235) (xy 51.776329 -59.444219) (xy 51.825376 -59.46)
			(xy 51.871382 -59.483194) (xy 51.913235 -59.513242) (xy 51.949923 -59.549416) (xy 51.965606 -59.569858)
			(xy 51.97467 -59.58128) (xy 51.99794 -59.598833) (xy 52.025215 -59.609114) (xy 52.054282 -59.611287)
			(xy 52.082782 -59.605177) (xy 52.108403 -59.591279) (xy 52.119022 -59.581288) (xy 52.314602 -59.385708)
			(xy 52.324595 -59.375072) (xy 52.338575 -59.349468) (xy 52.344735 -59.320953) (xy 52.342569 -59.291861)
			(xy 52.332255 -59.264572) (xy 52.314637 -59.241321) (xy 52.303172 -59.232292) (xy 52.282749 -59.216584)
			(xy 52.246569 -59.179905) (xy 52.216516 -59.138058) (xy 52.193317 -59.092056) (xy 52.177535 -59.043012)
			(xy 52.16955 -58.992114) (xy 52.16906 -58.966354) (xy 52.169573 -58.940368) (xy 52.177709 -58.889037)
			(xy 52.193774 -58.839611) (xy 52.217371 -58.793306) (xy 52.247921 -58.751261) (xy 52.284672 -58.714512)
			(xy 52.326718 -58.683964) (xy 52.373024 -58.660368) (xy 52.422451 -58.644306) (xy 52.473782 -58.636172)
			(xy 52.499768 -58.635646) (xy 52.531422 -58.636355) (xy 52.59358 -58.648367) (xy 52.623212 -58.659522)
			(xy 52.633386 -58.642802) (xy 52.657332 -58.611844) (xy 52.670964 -58.5978) (xy 52.78882 -58.480198)
			(xy 52.72278 -58.414412) (xy 52.687982 -58.438542) (xy 52.66712 -58.452389) (xy 52.622105 -58.474312)
			(xy 52.574303 -58.489209) (xy 52.524803 -58.496741) (xy 52.499768 -58.497216) (xy 52.473782 -58.496704)
			(xy 52.42245 -58.488569) (xy 52.373023 -58.472505) (xy 52.326716 -58.448907) (xy 52.284672 -58.418356)
			(xy 52.247923 -58.381604) (xy 52.217376 -58.339556) (xy 52.193783 -58.293248) (xy 52.177723 -58.243819)
			(xy 52.169593 -58.192486) (xy 52.169593 -58.140514) (xy 52.177723 -58.089181) (xy 52.193783 -58.039752)
			(xy 52.217376 -57.993444) (xy 52.247923 -57.951396) (xy 52.284672 -57.914644) (xy 52.326716 -57.884093)
			(xy 52.373023 -57.860495) (xy 52.42245 -57.844431) (xy 52.473782 -57.836296) (xy 52.499768 -57.8358)
			(xy 52.527077 -57.836367) (xy 52.58095 -57.845355) (xy 52.632613 -57.863076) (xy 52.680661 -57.889047)
			(xy 52.723786 -57.922563) (xy 52.760817 -57.962711) (xy 52.790745 -58.008399) (xy 52.802282 -58.033158)
			(xy 52.808412 -58.04587) (xy 52.826457 -58.067556) (xy 52.849746 -58.083478) (xy 52.876502 -58.092422)
			(xy 52.904684 -58.093707) (xy 52.932143 -58.087234) (xy 52.956784 -58.073496) (xy 52.967128 -58.063892)
			(xy 52.996338 -58.034936) (xy 53.000148 -58.026808) (xy 53.011254 -58.004104) (xy 53.03932 -57.962073)
			(xy 53.073458 -57.924804) (xy 53.112871 -57.893166) (xy 53.15664 -57.867896) (xy 53.203746 -57.849583)
			(xy 53.253091 -57.838654) (xy 53.278278 -57.836562) (xy 53.297328 -57.835292) (xy 53.384958 -57.747662)
			(xy 53.333396 -57.6961) (xy 53.311298 -57.696862) (xy 53.299868 -57.697116) (xy 53.273882 -57.696604)
			(xy 53.22255 -57.688469) (xy 53.173123 -57.672405) (xy 53.126816 -57.648807) (xy 53.084772 -57.618256)
			(xy 53.048023 -57.581504) (xy 53.017476 -57.539456) (xy 52.993883 -57.493148) (xy 52.977823 -57.443719)
			(xy 52.969693 -57.392386) (xy 52.969693 -57.340414) (xy 52.977823 -57.289081) (xy 52.993883 -57.239652)
			(xy 53.017476 -57.193344) (xy 53.048023 -57.151296) (xy 53.084772 -57.114544) (xy 53.126816 -57.083993)
			(xy 53.173123 -57.060395) (xy 53.22255 -57.044331) (xy 53.273882 -57.036196) (xy 53.299868 -57.0357)
			(xy 53.321458 -57.036462) (xy 53.33191 -57.036626) (xy 53.35156 -57.029563) (xy 53.366784 -57.01527)
			(xy 53.37507 -56.996103) (xy 53.37556 -56.985662) (xy 53.37556 -56.947308) (xy 53.375109 -56.936854)
			(xy 53.366861 -56.917649) (xy 53.351616 -56.903349) (xy 53.331923 -56.896345) (xy 53.321458 -56.896508)
			(xy 53.299868 -56.89727) (xy 53.273881 -56.896784) (xy 53.222549 -56.888649) (xy 53.173121 -56.872583)
			(xy 53.126815 -56.848983) (xy 53.084771 -56.81843) (xy 53.048025 -56.781676) (xy 53.01748 -56.739625)
			(xy 52.99389 -56.693314) (xy 52.977835 -56.643883) (xy 52.96971 -56.592549) (xy 52.96916 -56.566562)
			(xy 52.969267 -56.55599) (xy 52.970663 -56.534891) (xy 52.971954 -56.524398) (xy 52.972208 -56.521096)
			(xy 52.972208 -56.467248) (xy 52.827428 -56.467248) (xy 52.827428 -56.521096) (xy 52.827682 -56.524398)
			(xy 52.82897 -56.534892) (xy 52.830366 -56.55599) (xy 52.830476 -56.566562) (xy 52.829996 -56.592552)
			(xy 52.821869 -56.643894) (xy 52.80581 -56.693331) (xy 52.782213 -56.739647) (xy 52.751661 -56.781701)
			(xy 52.714906 -56.818457) (xy 52.672852 -56.84901) (xy 52.626537 -56.872607) (xy 52.577099 -56.888668)
			(xy 52.525758 -56.896795) (xy 52.499768 -56.89727) (xy 52.47386 -56.896764) (xy 52.422678 -56.888676)
			(xy 52.373384 -56.872704) (xy 52.327185 -56.849239) (xy 52.285211 -56.818855) (xy 52.248491 -56.782296)
			(xy 52.217922 -56.740456) (xy 52.194254 -56.69436) (xy 52.178066 -56.645137) (xy 52.169754 -56.593992)
			(xy 52.16906 -56.568086) (xy 52.16854 -56.554832) (xy 52.161525 -56.529261) (xy 52.148157 -56.506361)
			(xy 52.129338 -56.487682) (xy 52.10634 -56.474484) (xy 52.080718 -56.46766) (xy 52.06746 -56.467248)
			(xy 51.378104 -56.467248) (xy 51.378104 -56.743092) (xy 51.375564 -56.745886) (xy 51.375564 -56.749696)
			(xy 51.134772 -56.98998) (xy 51.125673 -56.999688) (xy 51.11236 -57.022714) (xy 51.105442 -57.048396)
			(xy 51.105388 -57.074993) (xy 51.112201 -57.100703) (xy 51.125421 -57.123782) (xy 51.134518 -57.13349)
			(xy 51.152389 -57.152189) (xy 51.182679 -57.194112) (xy 51.206064 -57.240244) (xy 51.221973 -57.289456)
			(xy 51.230018 -57.340548) (xy 51.23053 -57.366408) (xy 51.23002 -57.392395) (xy 51.36947 -57.392395)
			(xy 51.36947 -57.340421) (xy 51.3776 -57.289086) (xy 51.393661 -57.239656) (xy 51.417257 -57.193346)
			(xy 51.447807 -57.151298) (xy 51.484558 -57.114547) (xy 51.526606 -57.083997) (xy 51.572916 -57.060401)
			(xy 51.622346 -57.04434) (xy 51.673681 -57.03621) (xy 51.725655 -57.03621) (xy 51.77699 -57.04434)
			(xy 51.82642 -57.060401) (xy 51.87273 -57.083997) (xy 51.914778 -57.114547) (xy 51.951529 -57.151298)
			(xy 51.982079 -57.193346) (xy 52.005675 -57.239656) (xy 52.021736 -57.289086) (xy 52.029866 -57.340421)
			(xy 52.030376 -57.366408) (xy 52.029866 -57.392395) (xy 52.16957 -57.392395) (xy 52.16957 -57.340421)
			(xy 52.1777 -57.289086) (xy 52.193761 -57.239656) (xy 52.217357 -57.193346) (xy 52.247907 -57.151298)
			(xy 52.284658 -57.114547) (xy 52.326706 -57.083997) (xy 52.373016 -57.060401) (xy 52.422446 -57.04434)
			(xy 52.473781 -57.03621) (xy 52.525755 -57.03621) (xy 52.57709 -57.04434) (xy 52.62652 -57.060401)
			(xy 52.67283 -57.083997) (xy 52.714878 -57.114547) (xy 52.751629 -57.151298) (xy 52.782179 -57.193346)
			(xy 52.805775 -57.239656) (xy 52.821836 -57.289086) (xy 52.829966 -57.340421) (xy 52.830476 -57.366408)
			(xy 52.829966 -57.392395) (xy 52.821836 -57.44373) (xy 52.805775 -57.49316) (xy 52.782179 -57.53947)
			(xy 52.751629 -57.581518) (xy 52.714878 -57.618269) (xy 52.67283 -57.648819) (xy 52.62652 -57.672415)
			(xy 52.57709 -57.688476) (xy 52.525755 -57.696606) (xy 52.473781 -57.696606) (xy 52.422446 -57.688476)
			(xy 52.373016 -57.672415) (xy 52.326706 -57.648819) (xy 52.284658 -57.618269) (xy 52.247907 -57.581518)
			(xy 52.217357 -57.53947) (xy 52.193761 -57.49316) (xy 52.1777 -57.44373) (xy 52.16957 -57.392395)
			(xy 52.029866 -57.392395) (xy 52.021736 -57.44373) (xy 52.005675 -57.49316) (xy 51.982079 -57.53947)
			(xy 51.951529 -57.581518) (xy 51.914778 -57.618269) (xy 51.87273 -57.648819) (xy 51.82642 -57.672415)
			(xy 51.77699 -57.688476) (xy 51.725655 -57.696606) (xy 51.673681 -57.696606) (xy 51.622346 -57.688476)
			(xy 51.572916 -57.672415) (xy 51.526606 -57.648819) (xy 51.484558 -57.618269) (xy 51.447807 -57.581518)
			(xy 51.417257 -57.53947) (xy 51.393661 -57.49316) (xy 51.3776 -57.44373) (xy 51.36947 -57.392395)
			(xy 51.23002 -57.392395) (xy 51.221888 -57.44373) (xy 51.205827 -57.493161) (xy 51.182231 -57.539471)
			(xy 51.151682 -57.58152) (xy 51.114931 -57.618272) (xy 51.072883 -57.648824) (xy 51.026574 -57.672422)
			(xy 50.977144 -57.688485) (xy 50.925809 -57.696619) (xy 50.899822 -57.697116) (xy 50.875813 -57.696689)
			(xy 50.828301 -57.689748) (xy 50.782291 -57.676009) (xy 50.738752 -57.655761) (xy 50.698599 -57.629429)
			(xy 50.680366 -57.613804) (xy 50.669108 -57.604488) (xy 50.642643 -57.592128) (xy 50.613761 -57.587764)
			(xy 50.584826 -57.591754) (xy 50.558203 -57.60377) (xy 50.536069 -57.62283) (xy 50.520236 -57.647375)
			(xy 50.511997 -57.675399) (xy 50.511456 -57.690004) (xy 50.511456 -57.842912) (xy 50.511932 -57.857516)
			(xy 50.520196 -57.885531) (xy 50.536046 -57.910065) (xy 50.558186 -57.929115) (xy 50.584811 -57.941126)
			(xy 50.613745 -57.945116) (xy 50.642627 -57.94076) (xy 50.669098 -57.928415) (xy 50.680366 -57.919112)
			(xy 50.698611 -57.903502) (xy 50.738761 -57.877171) (xy 50.782297 -57.856923) (xy 50.828304 -57.843184)
			(xy 50.875815 -57.836243) (xy 50.899822 -57.8358) (xy 50.925807 -57.836311) (xy 50.977138 -57.844444)
			(xy 51.026564 -57.860507) (xy 51.07287 -57.884103) (xy 51.114914 -57.914653) (xy 51.151662 -57.951403)
			(xy 51.182208 -57.993449) (xy 51.205802 -58.039756) (xy 51.221861 -58.089183) (xy 51.229991 -58.140515)
			(xy 51.229991 -58.192485) (xy 51.229989 -58.192495) (xy 51.36947 -58.192495) (xy 51.36947 -58.140521)
			(xy 51.3776 -58.089186) (xy 51.393661 -58.039756) (xy 51.417257 -57.993446) (xy 51.447807 -57.951398)
			(xy 51.484558 -57.914647) (xy 51.526606 -57.884097) (xy 51.572916 -57.860501) (xy 51.622346 -57.84444)
			(xy 51.673681 -57.83631) (xy 51.725655 -57.83631) (xy 51.77699 -57.84444) (xy 51.82642 -57.860501)
			(xy 51.87273 -57.884097) (xy 51.914778 -57.914647) (xy 51.951529 -57.951398) (xy 51.982079 -57.993446)
			(xy 52.005675 -58.039756) (xy 52.021736 -58.089186) (xy 52.029866 -58.140521) (xy 52.030376 -58.166508)
			(xy 52.029866 -58.192495) (xy 52.021736 -58.24383) (xy 52.005675 -58.29326) (xy 51.982079 -58.33957)
			(xy 51.951529 -58.381618) (xy 51.914778 -58.418369) (xy 51.87273 -58.448919) (xy 51.82642 -58.472515)
			(xy 51.77699 -58.488576) (xy 51.725655 -58.496706) (xy 51.673681 -58.496706) (xy 51.622346 -58.488576)
			(xy 51.572916 -58.472515) (xy 51.526606 -58.448919) (xy 51.484558 -58.418369) (xy 51.447807 -58.381618)
			(xy 51.417257 -58.33957) (xy 51.393661 -58.29326) (xy 51.3776 -58.24383) (xy 51.36947 -58.192495)
			(xy 51.229989 -58.192495) (xy 51.221861 -58.243817) (xy 51.205802 -58.293244) (xy 51.182208 -58.339551)
			(xy 51.151662 -58.381597) (xy 51.114914 -58.418347) (xy 51.07287 -58.448897) (xy 51.026564 -58.472493)
			(xy 50.977138 -58.488556) (xy 50.925807 -58.496689) (xy 50.899822 -58.497216) (xy 50.875813 -58.496789)
			(xy 50.828301 -58.489848) (xy 50.782291 -58.476109) (xy 50.738752 -58.455861) (xy 50.698599 -58.429529)
			(xy 50.680366 -58.413904) (xy 50.669108 -58.404588) (xy 50.642643 -58.392228) (xy 50.613761 -58.387864)
			(xy 50.584826 -58.391854) (xy 50.558203 -58.40387) (xy 50.536069 -58.42293) (xy 50.520236 -58.447475)
			(xy 50.511997 -58.475499) (xy 50.511456 -58.490104) (xy 50.511456 -58.555128) (xy 50.33391 -58.732674)
			(xy 50.35187 -58.751418) (xy 50.382317 -58.793461) (xy 50.405828 -58.839741) (xy 50.421827 -58.889124)
			(xy 50.429921 -58.940399) (xy 50.43043 -58.966354) (xy 50.42995 -58.992341) (xy 50.569624 -58.992341)
			(xy 50.569624 -58.940367) (xy 50.577754 -58.889032) (xy 50.593815 -58.839602) (xy 50.617411 -58.793292)
			(xy 50.647961 -58.751244) (xy 50.684712 -58.714493) (xy 50.72676 -58.683943) (xy 50.77307 -58.660347)
			(xy 50.8225 -58.644286) (xy 50.873835 -58.636156) (xy 50.925809 -58.636156) (xy 50.977144 -58.644286)
			(xy 51.026574 -58.660347) (xy 51.072884 -58.683943) (xy 51.114932 -58.714493) (xy 51.151683 -58.751244)
			(xy 51.182233 -58.793292) (xy 51.205829 -58.839602) (xy 51.22189 -58.889032) (xy 51.23002 -58.940367)
			(xy 51.23053 -58.966354) (xy 51.23002 -58.992341) (xy 51.36947 -58.992341) (xy 51.36947 -58.940367)
			(xy 51.3776 -58.889032) (xy 51.393661 -58.839602) (xy 51.417257 -58.793292) (xy 51.447807 -58.751244)
			(xy 51.484558 -58.714493) (xy 51.526606 -58.683943) (xy 51.572916 -58.660347) (xy 51.622346 -58.644286)
			(xy 51.673681 -58.636156) (xy 51.725655 -58.636156) (xy 51.77699 -58.644286) (xy 51.82642 -58.660347)
			(xy 51.87273 -58.683943) (xy 51.914778 -58.714493) (xy 51.951529 -58.751244) (xy 51.982079 -58.793292)
			(xy 52.005675 -58.839602) (xy 52.021736 -58.889032) (xy 52.029866 -58.940367) (xy 52.030376 -58.966354)
			(xy 52.029866 -58.992341) (xy 52.021736 -59.043676) (xy 52.005675 -59.093106) (xy 51.982079 -59.139416)
			(xy 51.951529 -59.181464) (xy 51.914778 -59.218215) (xy 51.87273 -59.248765) (xy 51.82642 -59.272361)
			(xy 51.77699 -59.288422) (xy 51.725655 -59.296552) (xy 51.673681 -59.296552) (xy 51.622346 -59.288422)
			(xy 51.572916 -59.272361) (xy 51.526606 -59.248765) (xy 51.484558 -59.218215) (xy 51.447807 -59.181464)
			(xy 51.417257 -59.139416) (xy 51.393661 -59.093106) (xy 51.3776 -59.043676) (xy 51.36947 -58.992341)
			(xy 51.23002 -58.992341) (xy 51.22189 -59.043676) (xy 51.205829 -59.093106) (xy 51.182233 -59.139416)
			(xy 51.151683 -59.181464) (xy 51.114932 -59.218215) (xy 51.072884 -59.248765) (xy 51.026574 -59.272361)
			(xy 50.977144 -59.288422) (xy 50.925809 -59.296552) (xy 50.873835 -59.296552) (xy 50.8225 -59.288422)
			(xy 50.77307 -59.272361) (xy 50.72676 -59.248765) (xy 50.684712 -59.218215) (xy 50.647961 -59.181464)
			(xy 50.617411 -59.139416) (xy 50.593815 -59.093106) (xy 50.577754 -59.043676) (xy 50.569624 -58.992341)
			(xy 50.42995 -58.992341) (xy 50.42995 -58.992346) (xy 50.421825 -59.043692) (xy 50.405767 -59.093134)
			(xy 50.382172 -59.139455) (xy 50.351621 -59.181515) (xy 50.314866 -59.218277) (xy 50.272813 -59.248836)
			(xy 50.226497 -59.272441) (xy 50.177058 -59.288509) (xy 50.125714 -59.296645) (xy 50.099722 -59.297062)
			(xy 50.07333 -59.296571) (xy 50.021211 -59.288232) (xy 49.971079 -59.271714) (xy 49.924211 -59.247437)
			(xy 49.881798 -59.216019) (xy 49.862994 -59.197494) (xy 49.268047 -59.792441) (xy 49.769524 -59.792441)
			(xy 49.769524 -59.740467) (xy 49.777654 -59.689132) (xy 49.793715 -59.639702) (xy 49.817311 -59.593392)
			(xy 49.847861 -59.551344) (xy 49.884612 -59.514593) (xy 49.92666 -59.484043) (xy 49.97297 -59.460447)
			(xy 50.0224 -59.444386) (xy 50.073735 -59.436256) (xy 50.125709 -59.436256) (xy 50.177044 -59.444386)
			(xy 50.226474 -59.460447) (xy 50.272784 -59.484043) (xy 50.314832 -59.514593) (xy 50.351583 -59.551344)
			(xy 50.382133 -59.593392) (xy 50.405729 -59.639702) (xy 50.42179 -59.689132) (xy 50.42992 -59.740467)
			(xy 50.43043 -59.766454) (xy 50.42992 -59.792441) (xy 50.42179 -59.843776) (xy 50.405729 -59.893206)
			(xy 50.382133 -59.939516) (xy 50.351583 -59.981564) (xy 50.314832 -60.018315) (xy 50.272784 -60.048865)
			(xy 50.226474 -60.072461) (xy 50.177044 -60.088522) (xy 50.125709 -60.096652) (xy 50.073735 -60.096652)
			(xy 50.0224 -60.088522) (xy 49.97297 -60.072461) (xy 49.92666 -60.048865) (xy 49.884612 -60.018315)
			(xy 49.847861 -59.981564) (xy 49.817311 -59.939516) (xy 49.793715 -59.893206) (xy 49.777654 -59.843776)
			(xy 49.769524 -59.792441) (xy 49.268047 -59.792441) (xy 49.045876 -60.014612) (xy 49.04613 -60.035694)
			(xy 49.04613 -60.03798) (xy 49.045589 -60.06624) (xy 49.036659 -60.122051) (xy 49.019022 -60.175749)
			(xy 48.99312 -60.225985) (xy 48.976788 -60.249054) (xy 48.976788 -61.048646) (xy 49.61204 -61.048646)
			(xy 49.616111 -60.993024) (xy 49.628237 -60.938587) (xy 49.64816 -60.886496) (xy 49.675456 -60.837861)
			(xy 49.709542 -60.793718) (xy 49.749691 -60.755009) (xy 49.795049 -60.722558) (xy 49.844649 -60.697057)
			(xy 49.897433 -60.67905) (xy 49.952276 -60.66892) (xy 50.00801 -60.666883) (xy 50.063447 -60.672983)
			(xy 50.117404 -60.687089) (xy 50.168733 -60.708901) (xy 50.216339 -60.737955) (xy 50.259207 -60.77363)
			(xy 50.296424 -60.815167) (xy 50.327197 -60.86168) (xy 50.350869 -60.912177) (xy 50.366937 -60.965584)
			(xy 50.375057 -61.02076) (xy 50.375566 -61.048646) (xy 50.375057 -61.076532) (xy 50.366937 -61.131708)
			(xy 50.350869 -61.185115) (xy 50.327197 -61.235612) (xy 50.296424 -61.282125) (xy 50.259207 -61.323662)
			(xy 50.216339 -61.359337) (xy 50.168733 -61.388391) (xy 50.117404 -61.410203) (xy 50.063447 -61.424309)
			(xy 50.00801 -61.430409) (xy 49.952276 -61.428372) (xy 49.897433 -61.418242) (xy 49.844649 -61.400235)
			(xy 49.795049 -61.374734) (xy 49.749691 -61.342283) (xy 49.709542 -61.303574) (xy 49.675456 -61.259431)
			(xy 49.64816 -61.210796) (xy 49.628237 -61.158705) (xy 49.616111 -61.104268) (xy 49.61204 -61.048646)
			(xy 48.976788 -61.048646) (xy 48.976788 -62.943994) (xy 50.161442 -62.943994) (xy 50.165513 -62.888372)
			(xy 50.177639 -62.833935) (xy 50.197562 -62.781844) (xy 50.224858 -62.733209) (xy 50.258944 -62.689066)
			(xy 50.299093 -62.650357) (xy 50.344451 -62.617906) (xy 50.394051 -62.592405) (xy 50.446835 -62.574398)
			(xy 50.501678 -62.564268) (xy 50.557412 -62.562231) (xy 50.612849 -62.568331) (xy 50.666806 -62.582437)
			(xy 50.718135 -62.604249) (xy 50.765741 -62.633303) (xy 50.808609 -62.668978) (xy 50.845826 -62.710515)
			(xy 50.876599 -62.757028) (xy 50.900271 -62.807525) (xy 50.916339 -62.860932) (xy 50.924459 -62.916108)
			(xy 50.924968 -62.943994) (xy 50.924459 -62.97188) (xy 50.916339 -63.027056) (xy 50.900271 -63.080463)
			(xy 50.876599 -63.13096) (xy 50.845826 -63.177473) (xy 50.808609 -63.21901) (xy 50.765741 -63.254685)
			(xy 50.718135 -63.283739) (xy 50.666806 -63.305551) (xy 50.612849 -63.319657) (xy 50.557412 -63.325757)
			(xy 50.501678 -63.32372) (xy 50.446835 -63.31359) (xy 50.394051 -63.295583) (xy 50.344451 -63.270082)
			(xy 50.299093 -63.237631) (xy 50.258944 -63.198922) (xy 50.224858 -63.154779) (xy 50.197562 -63.106144)
			(xy 50.177639 -63.054053) (xy 50.165513 -62.999616) (xy 50.161442 -62.943994) (xy 48.976788 -62.943994)
			(xy 48.976788 -64.115188) (xy 49.332388 -64.470788) (xy 49.358296 -64.466724) (xy 49.374044 -64.464438)
			(xy 49.388494 -64.462206) (xy 49.415328 -64.450622) (xy 49.437789 -64.431919) (xy 49.45404 -64.407627)
			(xy 49.462756 -64.379729) (xy 49.463452 -64.365124) (xy 49.464348 -64.338158) (xy 49.4728 -64.284869)
			(xy 49.488676 -64.233303) (xy 49.511658 -64.184488) (xy 49.541289 -64.139399) (xy 49.576978 -64.098933)
			(xy 49.618012 -64.0639) (xy 49.663572 -64.034998) (xy 49.71275 -64.012804) (xy 49.764565 -63.99776)
			(xy 49.817983 -63.990166) (xy 49.84496 -63.989712) (xy 49.872214 -63.990173) (xy 49.926168 -63.997925)
			(xy 49.97847 -64.013278) (xy 50.028054 -64.035918) (xy 50.07391 -64.065386) (xy 50.115106 -64.10108)
			(xy 50.150802 -64.142273) (xy 50.180272 -64.188129) (xy 50.202915 -64.237711) (xy 50.218271 -64.290012)
			(xy 50.226026 -64.343966) (xy 50.226468 -64.37122) (xy 50.226011 -64.398135) (xy 50.218453 -64.451431)
			(xy 50.203476 -64.503134) (xy 50.181377 -64.552218) (xy 50.152595 -64.597706) (xy 50.117704 -64.638696)
			(xy 50.077395 -64.674372) (xy 50.03247 -64.704025) (xy 49.983821 -64.727066) (xy 49.958244 -64.735456)
			(xy 49.944112 -64.740378) (xy 49.919319 -64.757108) (xy 49.900427 -64.780295) (xy 49.889052 -64.807958)
			(xy 49.886167 -64.837728) (xy 49.892019 -64.86706) (xy 49.906108 -64.893444) (xy 49.916334 -64.904366)
			(xy 50.154078 -65.141856) (xy 50.170852 -65.159295) (xy 50.199298 -65.198434) (xy 50.221271 -65.241541)
			(xy 50.236232 -65.287555) (xy 50.24381 -65.335342) (xy 50.244248 -65.359534) (xy 50.244248 -65.41516)
			(xy 50.590702 -65.41516) (xy 50.594773 -65.359538) (xy 50.606899 -65.305101) (xy 50.626822 -65.25301)
			(xy 50.654118 -65.204375) (xy 50.688204 -65.160232) (xy 50.728353 -65.121523) (xy 50.773711 -65.089072)
			(xy 50.823311 -65.063571) (xy 50.876095 -65.045564) (xy 50.930938 -65.035434) (xy 50.986672 -65.033397)
			(xy 51.042109 -65.039497) (xy 51.096066 -65.053603) (xy 51.147395 -65.075415) (xy 51.195001 -65.104469)
			(xy 51.237869 -65.140144) (xy 51.275086 -65.181681) (xy 51.305859 -65.228194) (xy 51.329531 -65.278691)
			(xy 51.345599 -65.332098) (xy 51.353719 -65.387274) (xy 51.354228 -65.41516) (xy 51.353719 -65.443046)
			(xy 51.345599 -65.498222) (xy 51.329531 -65.551629) (xy 51.305859 -65.602126) (xy 51.275086 -65.648639)
			(xy 51.237869 -65.690176) (xy 51.195001 -65.725851) (xy 51.147395 -65.754905) (xy 51.096066 -65.776717)
			(xy 51.042109 -65.790823) (xy 50.986672 -65.796923) (xy 50.930938 -65.794886) (xy 50.876095 -65.784756)
			(xy 50.823311 -65.766749) (xy 50.773711 -65.741248) (xy 50.728353 -65.708797) (xy 50.688204 -65.670088)
			(xy 50.654118 -65.625945) (xy 50.626822 -65.57731) (xy 50.606899 -65.525219) (xy 50.594773 -65.470782)
			(xy 50.590702 -65.41516) (xy 50.244248 -65.41516) (xy 50.244248 -66.962528) (xy 50.6222 -67.340734)
			(xy 50.695352 -67.340734)
		)
		(stroke
			(width 0)
			(type solid)
		)
		(fill yes)
		(layer "In4.Cu")
		(net "P1V0_SENSOR")
	)
	(gr_poly
		(pts
			(xy 19.429222 -104.2416) (xy 19.444112 -104.241093) (xy 19.47263 -104.23252) (xy 19.49746 -104.216081)
			(xy 19.516489 -104.193175) (xy 19.528097 -104.165752) (xy 19.531296 -104.136146) (xy 19.525815 -104.106876)
			(xy 19.512118 -104.080434) (xy 19.50212 -104.069388) (xy 19.482117 -104.047924) (xy 19.448276 -103.999996)
			(xy 19.422175 -103.947451) (xy 19.40443 -103.891528) (xy 19.395458 -103.833547) (xy 19.394932 -103.804212)
			(xy 19.395395 -103.77696) (xy 19.40315 -103.72301) (xy 19.418506 -103.670713) (xy 19.441148 -103.621133)
			(xy 19.470616 -103.575282) (xy 19.506311 -103.534091) (xy 19.547504 -103.4984) (xy 19.593358 -103.468935)
			(xy 19.642939 -103.446296) (xy 19.695237 -103.430944) (xy 19.749188 -103.423193) (xy 19.77644 -103.422704)
			(xy 19.805519 -103.423257) (xy 19.863006 -103.43208) (xy 19.918494 -103.449503) (xy 19.944842 -103.46182)
			(xy 19.958284 -103.4679) (xy 19.987355 -103.472852) (xy 20.01663 -103.469296) (xy 20.04367 -103.457528)
			(xy 20.066223 -103.438528) (xy 20.082411 -103.413878) (xy 20.090885 -103.385632) (xy 20.0914 -103.370888)
			(xy 20.0914 -102.7684) (xy 21.0566 -101.8032) (xy 23.4696 -101.8032) (xy 25.0444 -100.2284) (xy 25.0444 -98.704654)
			(xy 25.043927 -98.690024) (xy 25.035641 -98.661962) (xy 25.019735 -98.637404) (xy 24.997515 -98.618367)
			(xy 24.970808 -98.606416) (xy 24.941807 -98.602533) (xy 24.912897 -98.607036) (xy 24.886451 -98.619556)
			(xy 24.875236 -98.628962) (xy 24.856936 -98.644705) (xy 24.816632 -98.671271) (xy 24.772898 -98.691703)
			(xy 24.726661 -98.705568) (xy 24.6789 -98.712573) (xy 24.654764 -98.713036) (xy 24.628776 -98.712524)
			(xy 24.577442 -98.704388) (xy 24.528012 -98.688322) (xy 24.481704 -98.664723) (xy 24.439657 -98.63417)
			(xy 24.402907 -98.597416) (xy 24.372358 -98.555366) (xy 24.348764 -98.509055) (xy 24.332704 -98.459623)
			(xy 24.324573 -98.408288) (xy 24.324573 -98.356312) (xy 24.332704 -98.304977) (xy 24.348764 -98.255545)
			(xy 24.372358 -98.209234) (xy 24.402907 -98.167184) (xy 24.439657 -98.13043) (xy 24.481704 -98.099877)
			(xy 24.528012 -98.076278) (xy 24.577442 -98.060212) (xy 24.628776 -98.052076) (xy 24.654764 -98.05162)
			(xy 24.678905 -98.052015) (xy 24.72668 -98.058998) (xy 24.772928 -98.072864) (xy 24.816663 -98.093317)
			(xy 24.856954 -98.119922) (xy 24.875236 -98.135694) (xy 24.886463 -98.145062) (xy 24.912897 -98.157533)
			(xy 24.941781 -98.162005) (xy 24.970749 -98.15811) (xy 24.997427 -98.146169) (xy 25.019629 -98.127159)
			(xy 25.035535 -98.102638) (xy 25.043844 -98.074616) (xy 25.0444 -98.060002) (xy 25.0444 -97.5614)
			(xy 24.7904 -97.3074) (xy 24.25065 -97.3074) (xy 24.236244 -97.307895) (xy 24.20858 -97.315944) (xy 24.184274 -97.331413)
			(xy 24.165267 -97.353066) (xy 24.15308 -97.379172) (xy 24.148685 -97.407646) (xy 24.152434 -97.436213)
			(xy 24.157686 -97.44964) (xy 24.166464 -97.470628) (xy 24.178815 -97.514413) (xy 24.185027 -97.559481)
			(xy 24.185372 -97.582228) (xy 24.184862 -97.608215) (xy 24.176732 -97.65955) (xy 24.160671 -97.70898)
			(xy 24.137075 -97.75529) (xy 24.106525 -97.797338) (xy 24.069774 -97.834089) (xy 24.027726 -97.864639)
			(xy 23.981416 -97.888235) (xy 23.931986 -97.904296) (xy 23.880651 -97.912426) (xy 23.828677 -97.912426)
			(xy 23.777342 -97.904296) (xy 23.727912 -97.888235) (xy 23.681602 -97.864639) (xy 23.639554 -97.834089)
			(xy 23.602803 -97.797338) (xy 23.572253 -97.75529) (xy 23.548657 -97.70898) (xy 23.532596 -97.65955)
			(xy 23.524466 -97.608215) (xy 23.523956 -97.582228) (xy 23.524341 -97.559485) (xy 23.530576 -97.514427)
			(xy 23.542904 -97.470642) (xy 23.551642 -97.44964) (xy 23.556945 -97.436241) (xy 23.560636 -97.407676)
			(xy 23.556206 -97.379216) (xy 23.544007 -97.353124) (xy 23.525009 -97.331475) (xy 23.500722 -97.31599)
			(xy 23.473079 -97.307901) (xy 23.458678 -97.3074) (xy 23.4188 -97.3074) (xy 23.330408 -97.395792)
			(xy 23.34768 -97.429066) (xy 23.359512 -97.452846) (xy 23.376272 -97.503243) (xy 23.384759 -97.555672)
			(xy 23.385272 -97.582228) (xy 23.384762 -97.608215) (xy 23.376632 -97.65955) (xy 23.360571 -97.70898)
			(xy 23.336975 -97.75529) (xy 23.306425 -97.797338) (xy 23.269674 -97.834089) (xy 23.227626 -97.864639)
			(xy 23.181316 -97.888235) (xy 23.131886 -97.904296) (xy 23.080551 -97.912426) (xy 23.028577 -97.912426)
			(xy 22.977242 -97.904296) (xy 22.927812 -97.888235) (xy 22.881502 -97.864639) (xy 22.839454 -97.834089)
			(xy 22.802703 -97.797338) (xy 22.772153 -97.75529) (xy 22.748557 -97.70898) (xy 22.732496 -97.65955)
			(xy 22.724366 -97.608215) (xy 22.723856 -97.582228) (xy 22.724364 -97.564194) (xy 22.724364 -97.5106)
			(xy 22.584918 -97.5106) (xy 22.584918 -97.564194) (xy 22.585426 -97.582228) (xy 22.584914 -97.608214)
			(xy 22.57678 -97.659546) (xy 22.560717 -97.708974) (xy 22.53712 -97.755281) (xy 22.50657 -97.797327)
			(xy 22.469819 -97.834077) (xy 22.427773 -97.864625) (xy 22.381465 -97.888221) (xy 22.332037 -97.904283)
			(xy 22.280704 -97.912415) (xy 22.254718 -97.912936) (xy 22.229873 -97.912491) (xy 22.180743 -97.90506)
			(xy 22.133277 -97.890363) (xy 22.088543 -97.868731) (xy 22.047549 -97.840651) (xy 22.011217 -97.806754)
			(xy 21.980365 -97.767803) (xy 21.955686 -97.724675) (xy 21.937738 -97.678341) (xy 21.926922 -97.629843)
			(xy 21.924772 -97.605088) (xy 21.923188 -97.589876) (xy 21.912129 -97.561375) (xy 21.893139 -97.537417)
			(xy 21.867915 -97.520143) (xy 21.838712 -97.511098) (xy 21.823426 -97.5106) (xy 21.095462 -97.5106)
			(xy 21.080181 -97.511121) (xy 21.050987 -97.520166) (xy 21.025772 -97.537437) (xy 21.006788 -97.561389)
			(xy 20.995733 -97.589882) (xy 20.994116 -97.605088) (xy 20.991813 -97.631145) (xy 20.980029 -97.682109)
			(xy 20.960369 -97.730583) (xy 20.933324 -97.775358) (xy 20.899569 -97.815317) (xy 20.859944 -97.849465)
			(xy 20.815438 -97.87695) (xy 20.767161 -97.897087) (xy 20.716315 -97.909373) (xy 20.66417 -97.913503)
			(xy 20.612025 -97.909373) (xy 20.561179 -97.897087) (xy 20.512902 -97.87695) (xy 20.468396 -97.849465)
			(xy 20.428771 -97.815317) (xy 20.395016 -97.775358) (xy 20.367971 -97.730583) (xy 20.348311 -97.682109)
			(xy 20.336527 -97.631145) (xy 20.334224 -97.605088) (xy 20.332639 -97.589879) (xy 20.321578 -97.561384)
			(xy 20.302587 -97.537434) (xy 20.277362 -97.520172) (xy 20.248161 -97.511139) (xy 20.232878 -97.5106)
			(xy 19.1262 -97.5106) (xy 18.8468 -97.2312) (xy 17.9324 -97.2312) (xy 17.78 -97.3836) (xy 17.78 -97.483422)
			(xy 17.782032 -97.490534) (xy 17.78809 -97.512971) (xy 17.794588 -97.55899) (xy 17.794584 -97.605464)
			(xy 17.788079 -97.651481) (xy 17.782032 -97.673922) (xy 17.78 -97.681034) (xy 17.78 -98.408315) (xy 17.933926 -98.408315)
			(xy 17.933926 -98.356341) (xy 17.942056 -98.305006) (xy 17.958117 -98.255576) (xy 17.981713 -98.209266)
			(xy 18.012263 -98.167218) (xy 18.049014 -98.130467) (xy 18.091062 -98.099917) (xy 18.137372 -98.076321)
			(xy 18.186802 -98.06026) (xy 18.238137 -98.05213) (xy 18.290111 -98.05213) (xy 18.341446 -98.06026)
			(xy 18.390876 -98.076321) (xy 18.437186 -98.099917) (xy 18.479234 -98.130467) (xy 18.515985 -98.167218)
			(xy 18.546535 -98.209266) (xy 18.570131 -98.255576) (xy 18.586192 -98.305006) (xy 18.594322 -98.356341)
			(xy 18.594832 -98.382328) (xy 18.594322 -98.408315) (xy 20.333972 -98.408315) (xy 20.333972 -98.356341)
			(xy 20.342102 -98.305006) (xy 20.358163 -98.255576) (xy 20.381759 -98.209266) (xy 20.412309 -98.167218)
			(xy 20.44906 -98.130467) (xy 20.491108 -98.099917) (xy 20.537418 -98.076321) (xy 20.586848 -98.06026)
			(xy 20.638183 -98.05213) (xy 20.690157 -98.05213) (xy 20.741492 -98.06026) (xy 20.790922 -98.076321)
			(xy 20.837232 -98.099917) (xy 20.87928 -98.130467) (xy 20.916031 -98.167218) (xy 20.946581 -98.209266)
			(xy 20.970177 -98.255576) (xy 20.986238 -98.305006) (xy 20.994368 -98.356341) (xy 20.994878 -98.382328)
			(xy 20.994368 -98.408315) (xy 21.92452 -98.408315) (xy 21.92452 -98.356341) (xy 21.93265 -98.305006)
			(xy 21.948711 -98.255576) (xy 21.972307 -98.209266) (xy 22.002857 -98.167218) (xy 22.039608 -98.130467)
			(xy 22.081656 -98.099917) (xy 22.127966 -98.076321) (xy 22.177396 -98.06026) (xy 22.228731 -98.05213)
			(xy 22.280705 -98.05213) (xy 22.33204 -98.06026) (xy 22.38147 -98.076321) (xy 22.42778 -98.099917)
			(xy 22.469828 -98.130467) (xy 22.506579 -98.167218) (xy 22.537129 -98.209266) (xy 22.560725 -98.255576)
			(xy 22.576786 -98.305006) (xy 22.584916 -98.356341) (xy 22.585426 -98.382328) (xy 22.584916 -98.408315)
			(xy 22.724366 -98.408315) (xy 22.724366 -98.356341) (xy 22.732496 -98.305006) (xy 22.748557 -98.255576)
			(xy 22.772153 -98.209266) (xy 22.802703 -98.167218) (xy 22.839454 -98.130467) (xy 22.881502 -98.099917)
			(xy 22.927812 -98.076321) (xy 22.977242 -98.06026) (xy 23.028577 -98.05213) (xy 23.080551 -98.05213)
			(xy 23.131886 -98.06026) (xy 23.181316 -98.076321) (xy 23.227626 -98.099917) (xy 23.269674 -98.130467)
			(xy 23.306425 -98.167218) (xy 23.336975 -98.209266) (xy 23.360571 -98.255576) (xy 23.376632 -98.305006)
			(xy 23.384762 -98.356341) (xy 23.385272 -98.382328) (xy 23.384762 -98.408315) (xy 23.524466 -98.408315)
			(xy 23.524466 -98.356341) (xy 23.532596 -98.305006) (xy 23.548657 -98.255576) (xy 23.572253 -98.209266)
			(xy 23.602803 -98.167218) (xy 23.639554 -98.130467) (xy 23.681602 -98.099917) (xy 23.727912 -98.076321)
			(xy 23.777342 -98.06026) (xy 23.828677 -98.05213) (xy 23.880651 -98.05213) (xy 23.931986 -98.06026)
			(xy 23.981416 -98.076321) (xy 24.027726 -98.099917) (xy 24.069774 -98.130467) (xy 24.106525 -98.167218)
			(xy 24.137075 -98.209266) (xy 24.160671 -98.255576) (xy 24.176732 -98.305006) (xy 24.184862 -98.356341)
			(xy 24.185372 -98.382328) (xy 24.184862 -98.408315) (xy 24.176732 -98.45965) (xy 24.160671 -98.50908)
			(xy 24.137075 -98.55539) (xy 24.106525 -98.597438) (xy 24.069774 -98.634189) (xy 24.027726 -98.664739)
			(xy 23.981416 -98.688335) (xy 23.931986 -98.704396) (xy 23.880651 -98.712526) (xy 23.828677 -98.712526)
			(xy 23.777342 -98.704396) (xy 23.727912 -98.688335) (xy 23.681602 -98.664739) (xy 23.639554 -98.634189)
			(xy 23.602803 -98.597438) (xy 23.572253 -98.55539) (xy 23.548657 -98.50908) (xy 23.532596 -98.45965)
			(xy 23.524466 -98.408315) (xy 23.384762 -98.408315) (xy 23.376632 -98.45965) (xy 23.360571 -98.50908)
			(xy 23.336975 -98.55539) (xy 23.306425 -98.597438) (xy 23.269674 -98.634189) (xy 23.227626 -98.664739)
			(xy 23.181316 -98.688335) (xy 23.131886 -98.704396) (xy 23.080551 -98.712526) (xy 23.028577 -98.712526)
			(xy 22.977242 -98.704396) (xy 22.927812 -98.688335) (xy 22.881502 -98.664739) (xy 22.839454 -98.634189)
			(xy 22.802703 -98.597438) (xy 22.772153 -98.55539) (xy 22.748557 -98.50908) (xy 22.732496 -98.45965)
			(xy 22.724366 -98.408315) (xy 22.584916 -98.408315) (xy 22.576786 -98.45965) (xy 22.560725 -98.50908)
			(xy 22.537129 -98.55539) (xy 22.506579 -98.597438) (xy 22.469828 -98.634189) (xy 22.42778 -98.664739)
			(xy 22.38147 -98.688335) (xy 22.33204 -98.704396) (xy 22.280705 -98.712526) (xy 22.228731 -98.712526)
			(xy 22.177396 -98.704396) (xy 22.127966 -98.688335) (xy 22.081656 -98.664739) (xy 22.039608 -98.634189)
			(xy 22.002857 -98.597438) (xy 21.972307 -98.55539) (xy 21.948711 -98.50908) (xy 21.93265 -98.45965)
			(xy 21.92452 -98.408315) (xy 20.994368 -98.408315) (xy 20.986238 -98.45965) (xy 20.970177 -98.50908)
			(xy 20.946581 -98.55539) (xy 20.916031 -98.597438) (xy 20.87928 -98.634189) (xy 20.837232 -98.664739)
			(xy 20.790922 -98.688335) (xy 20.741492 -98.704396) (xy 20.690157 -98.712526) (xy 20.638183 -98.712526)
			(xy 20.586848 -98.704396) (xy 20.537418 -98.688335) (xy 20.491108 -98.664739) (xy 20.44906 -98.634189)
			(xy 20.412309 -98.597438) (xy 20.381759 -98.55539) (xy 20.358163 -98.50908) (xy 20.342102 -98.45965)
			(xy 20.333972 -98.408315) (xy 18.594322 -98.408315) (xy 18.586192 -98.45965) (xy 18.570131 -98.50908)
			(xy 18.546535 -98.55539) (xy 18.515985 -98.597438) (xy 18.479234 -98.634189) (xy 18.437186 -98.664739)
			(xy 18.390876 -98.688335) (xy 18.341446 -98.704396) (xy 18.290111 -98.712526) (xy 18.238137 -98.712526)
			(xy 18.186802 -98.704396) (xy 18.137372 -98.688335) (xy 18.091062 -98.664739) (xy 18.049014 -98.634189)
			(xy 18.012263 -98.597438) (xy 17.981713 -98.55539) (xy 17.958117 -98.50908) (xy 17.942056 -98.45965)
			(xy 17.933926 -98.408315) (xy 17.78 -98.408315) (xy 17.78 -99.208161) (xy 21.92452 -99.208161) (xy 21.92452 -99.156187)
			(xy 21.93265 -99.104852) (xy 21.948711 -99.055422) (xy 21.972307 -99.009112) (xy 22.002857 -98.967064)
			(xy 22.039608 -98.930313) (xy 22.081656 -98.899763) (xy 22.127966 -98.876167) (xy 22.177396 -98.860106)
			(xy 22.228731 -98.851976) (xy 22.280705 -98.851976) (xy 22.33204 -98.860106) (xy 22.38147 -98.876167)
			(xy 22.42778 -98.899763) (xy 22.469828 -98.930313) (xy 22.506579 -98.967064) (xy 22.537129 -99.009112)
			(xy 22.560725 -99.055422) (xy 22.576786 -99.104852) (xy 22.584916 -99.156187) (xy 22.585426 -99.182174)
			(xy 22.584916 -99.208161) (xy 22.724366 -99.208161) (xy 22.724366 -99.156187) (xy 22.732496 -99.104852)
			(xy 22.748557 -99.055422) (xy 22.772153 -99.009112) (xy 22.802703 -98.967064) (xy 22.839454 -98.930313)
			(xy 22.881502 -98.899763) (xy 22.927812 -98.876167) (xy 22.977242 -98.860106) (xy 23.028577 -98.851976)
			(xy 23.080551 -98.851976) (xy 23.131886 -98.860106) (xy 23.181316 -98.876167) (xy 23.227626 -98.899763)
			(xy 23.269674 -98.930313) (xy 23.306425 -98.967064) (xy 23.336975 -99.009112) (xy 23.360571 -99.055422)
			(xy 23.376632 -99.104852) (xy 23.384762 -99.156187) (xy 23.385272 -99.182174) (xy 23.384762 -99.208161)
			(xy 23.376632 -99.259496) (xy 23.360571 -99.308926) (xy 23.336975 -99.355236) (xy 23.306425 -99.397284)
			(xy 23.269674 -99.434035) (xy 23.227626 -99.464585) (xy 23.181316 -99.488181) (xy 23.131886 -99.504242)
			(xy 23.080551 -99.512372) (xy 23.028577 -99.512372) (xy 22.977242 -99.504242) (xy 22.927812 -99.488181)
			(xy 22.881502 -99.464585) (xy 22.839454 -99.434035) (xy 22.802703 -99.397284) (xy 22.772153 -99.355236)
			(xy 22.748557 -99.308926) (xy 22.732496 -99.259496) (xy 22.724366 -99.208161) (xy 22.584916 -99.208161)
			(xy 22.576786 -99.259496) (xy 22.560725 -99.308926) (xy 22.537129 -99.355236) (xy 22.506579 -99.397284)
			(xy 22.469828 -99.434035) (xy 22.42778 -99.464585) (xy 22.38147 -99.488181) (xy 22.33204 -99.504242)
			(xy 22.280705 -99.512372) (xy 22.228731 -99.512372) (xy 22.177396 -99.504242) (xy 22.127966 -99.488181)
			(xy 22.081656 -99.464585) (xy 22.039608 -99.434035) (xy 22.002857 -99.397284) (xy 21.972307 -99.355236)
			(xy 21.948711 -99.308926) (xy 21.93265 -99.259496) (xy 21.92452 -99.208161) (xy 17.78 -99.208161)
			(xy 17.78 -99.746054) (xy 17.780466 -99.759934) (xy 17.78794 -99.78667) (xy 17.802348 -99.810398)
			(xy 17.822621 -99.829362) (xy 17.847258 -99.842156) (xy 17.874432 -99.847832) (xy 17.902129 -99.845969)
			(xy 17.915382 -99.841812) (xy 17.944119 -99.832345) (xy 18.00375 -99.822128) (xy 18.034 -99.821492)
			(xy 18.060649 -99.82199) (xy 18.113353 -99.829933) (xy 18.164283 -99.845643) (xy 18.212304 -99.868769)
			(xy 18.256341 -99.898793) (xy 18.295412 -99.935045) (xy 18.328643 -99.976716) (xy 18.355292 -100.022874)
			(xy 18.374764 -100.072488) (xy 18.386624 -100.12445) (xy 18.390608 -100.1776) (xy 18.386624 -100.23075)
			(xy 18.374764 -100.282712) (xy 18.355292 -100.332326) (xy 18.328643 -100.378484) (xy 18.295412 -100.420155)
			(xy 18.256341 -100.456407) (xy 18.216384 -100.483649) (xy 19.71039 -100.483649) (xy 19.71039 -100.430351)
			(xy 19.718333 -100.377647) (xy 19.734043 -100.326717) (xy 19.757169 -100.278696) (xy 19.787193 -100.234659)
			(xy 19.823445 -100.195588) (xy 19.865116 -100.162357) (xy 19.911274 -100.135708) (xy 19.960888 -100.116236)
			(xy 20.01285 -100.104376) (xy 20.066 -100.100393) (xy 20.11915 -100.104376) (xy 20.171112 -100.116236)
			(xy 20.220726 -100.135708) (xy 20.239309 -100.146437) (xy 22.329142 -100.146437) (xy 22.329142 -100.094463)
			(xy 22.337272 -100.043128) (xy 22.353333 -99.993698) (xy 22.376929 -99.947388) (xy 22.407479 -99.90534)
			(xy 22.44423 -99.868589) (xy 22.486278 -99.838039) (xy 22.532588 -99.814443) (xy 22.582018 -99.798382)
			(xy 22.633353 -99.790252) (xy 22.685327 -99.790252) (xy 22.736662 -99.798382) (xy 22.786092 -99.814443)
			(xy 22.832402 -99.838039) (xy 22.87445 -99.868589) (xy 22.911201 -99.90534) (xy 22.941751 -99.947388)
			(xy 22.965347 -99.993698) (xy 22.981408 -100.043128) (xy 22.989538 -100.094463) (xy 22.990048 -100.12045)
			(xy 22.989538 -100.146437) (xy 23.129242 -100.146437) (xy 23.129242 -100.094463) (xy 23.137372 -100.043128)
			(xy 23.153433 -99.993698) (xy 23.177029 -99.947388) (xy 23.207579 -99.90534) (xy 23.24433 -99.868589)
			(xy 23.286378 -99.838039) (xy 23.332688 -99.814443) (xy 23.382118 -99.798382) (xy 23.433453 -99.790252)
			(xy 23.485427 -99.790252) (xy 23.536762 -99.798382) (xy 23.586192 -99.814443) (xy 23.632502 -99.838039)
			(xy 23.67455 -99.868589) (xy 23.711301 -99.90534) (xy 23.741851 -99.947388) (xy 23.765447 -99.993698)
			(xy 23.781508 -100.043128) (xy 23.789638 -100.094463) (xy 23.790148 -100.12045) (xy 23.789638 -100.146437)
			(xy 23.781508 -100.197772) (xy 23.765447 -100.247202) (xy 23.741851 -100.293512) (xy 23.711301 -100.33556)
			(xy 23.67455 -100.372311) (xy 23.632502 -100.402861) (xy 23.586192 -100.426457) (xy 23.536762 -100.442518)
			(xy 23.485427 -100.450648) (xy 23.433453 -100.450648) (xy 23.382118 -100.442518) (xy 23.332688 -100.426457)
			(xy 23.286378 -100.402861) (xy 23.24433 -100.372311) (xy 23.207579 -100.33556) (xy 23.177029 -100.293512)
			(xy 23.153433 -100.247202) (xy 23.137372 -100.197772) (xy 23.129242 -100.146437) (xy 22.989538 -100.146437)
			(xy 22.981408 -100.197772) (xy 22.965347 -100.247202) (xy 22.941751 -100.293512) (xy 22.911201 -100.33556)
			(xy 22.87445 -100.372311) (xy 22.832402 -100.402861) (xy 22.786092 -100.426457) (xy 22.736662 -100.442518)
			(xy 22.685327 -100.450648) (xy 22.633353 -100.450648) (xy 22.582018 -100.442518) (xy 22.532588 -100.426457)
			(xy 22.486278 -100.402861) (xy 22.44423 -100.372311) (xy 22.407479 -100.33556) (xy 22.376929 -100.293512)
			(xy 22.353333 -100.247202) (xy 22.337272 -100.197772) (xy 22.329142 -100.146437) (xy 20.239309 -100.146437)
			(xy 20.266884 -100.162357) (xy 20.308555 -100.195588) (xy 20.344807 -100.234659) (xy 20.374831 -100.278696)
			(xy 20.397957 -100.326717) (xy 20.413667 -100.377647) (xy 20.42161 -100.430351) (xy 20.422108 -100.457)
			(xy 20.42161 -100.483649) (xy 20.413667 -100.536353) (xy 20.397957 -100.587283) (xy 20.374831 -100.635304)
			(xy 20.344807 -100.679341) (xy 20.308555 -100.718412) (xy 20.266884 -100.751643) (xy 20.220726 -100.778292)
			(xy 20.171112 -100.797764) (xy 20.11915 -100.809624) (xy 20.066 -100.813608) (xy 20.01285 -100.809624)
			(xy 19.960888 -100.797764) (xy 19.911274 -100.778292) (xy 19.865116 -100.751643) (xy 19.823445 -100.718412)
			(xy 19.787193 -100.679341) (xy 19.757169 -100.635304) (xy 19.734043 -100.587283) (xy 19.718333 -100.536353)
			(xy 19.71039 -100.483649) (xy 18.216384 -100.483649) (xy 18.212304 -100.486431) (xy 18.164283 -100.509557)
			(xy 18.113353 -100.525267) (xy 18.060649 -100.53321) (xy 18.034 -100.533708) (xy 18.00375 -100.533069)
			(xy 17.944119 -100.522855) (xy 17.915382 -100.513388) (xy 17.902139 -100.509217) (xy 17.874446 -100.50738)
			(xy 17.847282 -100.513071) (xy 17.822656 -100.525869) (xy 17.802387 -100.544828) (xy 17.787975 -100.568546)
			(xy 17.780484 -100.59527) (xy 17.78 -100.609146) (xy 17.78 -100.9904) (xy 20.572982 -100.9904) (xy 20.577053 -100.934778)
			(xy 20.589179 -100.880341) (xy 20.609102 -100.82825) (xy 20.636398 -100.779615) (xy 20.670484 -100.735472)
			(xy 20.710633 -100.696763) (xy 20.755991 -100.664312) (xy 20.805591 -100.638811) (xy 20.858375 -100.620804)
			(xy 20.913218 -100.610674) (xy 20.968952 -100.608637) (xy 21.024389 -100.614737) (xy 21.078346 -100.628843)
			(xy 21.129675 -100.650655) (xy 21.177281 -100.679709) (xy 21.220149 -100.715384) (xy 21.257366 -100.756921)
			(xy 21.288139 -100.803434) (xy 21.311811 -100.853931) (xy 21.327879 -100.907338) (xy 21.335999 -100.962514)
			(xy 21.336508 -100.9904) (xy 21.538182 -100.9904) (xy 21.542253 -100.934778) (xy 21.554379 -100.880341)
			(xy 21.574302 -100.82825) (xy 21.601598 -100.779615) (xy 21.635684 -100.735472) (xy 21.675833 -100.696763)
			(xy 21.721191 -100.664312) (xy 21.770791 -100.638811) (xy 21.823575 -100.620804) (xy 21.878418 -100.610674)
			(xy 21.934152 -100.608637) (xy 21.989589 -100.614737) (xy 22.043546 -100.628843) (xy 22.094875 -100.650655)
			(xy 22.142481 -100.679709) (xy 22.185349 -100.715384) (xy 22.222566 -100.756921) (xy 22.253339 -100.803434)
			(xy 22.277011 -100.853931) (xy 22.293079 -100.907338) (xy 22.301199 -100.962514) (xy 22.301708 -100.9904)
			(xy 22.604982 -100.9904) (xy 22.609053 -100.934778) (xy 22.621179 -100.880341) (xy 22.641102 -100.82825)
			(xy 22.668398 -100.779615) (xy 22.702484 -100.735472) (xy 22.742633 -100.696763) (xy 22.787991 -100.664312)
			(xy 22.837591 -100.638811) (xy 22.890375 -100.620804) (xy 22.945218 -100.610674) (xy 23.000952 -100.608637)
			(xy 23.056389 -100.614737) (xy 23.110346 -100.628843) (xy 23.161675 -100.650655) (xy 23.209281 -100.679709)
			(xy 23.252149 -100.715384) (xy 23.289366 -100.756921) (xy 23.320139 -100.803434) (xy 23.343811 -100.853931)
			(xy 23.359879 -100.907338) (xy 23.367999 -100.962514) (xy 23.368508 -100.9904) (xy 23.367999 -101.018286)
			(xy 23.359879 -101.073462) (xy 23.343811 -101.126869) (xy 23.320139 -101.177366) (xy 23.289366 -101.223879)
			(xy 23.252149 -101.265416) (xy 23.209281 -101.301091) (xy 23.161675 -101.330145) (xy 23.110346 -101.351957)
			(xy 23.056389 -101.366063) (xy 23.000952 -101.372163) (xy 22.945218 -101.370126) (xy 22.890375 -101.359996)
			(xy 22.837591 -101.341989) (xy 22.787991 -101.316488) (xy 22.742633 -101.284037) (xy 22.702484 -101.245328)
			(xy 22.668398 -101.201185) (xy 22.641102 -101.15255) (xy 22.621179 -101.100459) (xy 22.609053 -101.046022)
			(xy 22.604982 -100.9904) (xy 22.301708 -100.9904) (xy 22.301199 -101.018286) (xy 22.293079 -101.073462)
			(xy 22.277011 -101.126869) (xy 22.253339 -101.177366) (xy 22.222566 -101.223879) (xy 22.185349 -101.265416)
			(xy 22.142481 -101.301091) (xy 22.094875 -101.330145) (xy 22.043546 -101.351957) (xy 21.989589 -101.366063)
			(xy 21.934152 -101.372163) (xy 21.878418 -101.370126) (xy 21.823575 -101.359996) (xy 21.770791 -101.341989)
			(xy 21.721191 -101.316488) (xy 21.675833 -101.284037) (xy 21.635684 -101.245328) (xy 21.601598 -101.201185)
			(xy 21.574302 -101.15255) (xy 21.554379 -101.100459) (xy 21.542253 -101.046022) (xy 21.538182 -100.9904)
			(xy 21.336508 -100.9904) (xy 21.335999 -101.018286) (xy 21.327879 -101.073462) (xy 21.311811 -101.126869)
			(xy 21.288139 -101.177366) (xy 21.257366 -101.223879) (xy 21.220149 -101.265416) (xy 21.177281 -101.301091)
			(xy 21.129675 -101.330145) (xy 21.078346 -101.351957) (xy 21.024389 -101.366063) (xy 20.968952 -101.372163)
			(xy 20.913218 -101.370126) (xy 20.858375 -101.359996) (xy 20.805591 -101.341989) (xy 20.755991 -101.316488)
			(xy 20.710633 -101.284037) (xy 20.670484 -101.245328) (xy 20.636398 -101.201185) (xy 20.609102 -101.15255)
			(xy 20.589179 -101.100459) (xy 20.577053 -101.046022) (xy 20.572982 -100.9904) (xy 17.78 -100.9904)
			(xy 17.78 -103.459534) (xy 17.815814 -103.470456) (xy 17.841482 -103.478824) (xy 17.890344 -103.501783)
			(xy 17.93548 -103.531402) (xy 17.975988 -103.567089) (xy 18.01106 -103.608132) (xy 18.039995 -103.653711)
			(xy 18.062213 -103.702913) (xy 18.077272 -103.754757) (xy 18.08487 -103.808207) (xy 18.085308 -103.8352)
			(xy 18.084546 -103.861108) (xy 18.082768 -103.883968) (xy 18.4404 -104.2416)
		)
		(stroke
			(width 0)
			(type solid)
		)
		(fill yes)
		(layer "In4.Cu")
		(net "VCCIO2")
	)
	(gr_poly
		(pts
			(xy 73.961752 -63.481458) (xy 73.961752 -61.008006) (xy 72.8726 -59.9186) (xy 72.8726 -59.885072)
			(xy 72.863202 -59.871864) (xy 72.846492 -59.847479) (xy 72.820003 -59.794635) (xy 72.801984 -59.738336)
			(xy 72.792868 -59.679932) (xy 72.792336 -59.650376) (xy 72.792744 -59.625155) (xy 72.79939 -59.575153)
			(xy 72.812563 -59.526461) (xy 72.832033 -59.479929) (xy 72.857463 -59.436366) (xy 72.8726 -59.416188)
			(xy 72.8726 -56.642) (xy 71.228204 -54.997604) (xy 71.228204 -53.917596) (xy 69.342 -52.031138) (xy 63.88862 -52.031138)
			(xy 63.867006 -52.04666) (xy 63.81986 -52.071327) (xy 63.769375 -52.088134) (xy 63.716851 -52.096647)
			(xy 63.663641 -52.096647) (xy 63.611117 -52.088134) (xy 63.560632 -52.071327) (xy 63.513486 -52.04666)
			(xy 63.491872 -52.031138) (xy 63.08852 -52.031138) (xy 63.066906 -52.04666) (xy 63.01976 -52.071327)
			(xy 62.969275 -52.088134) (xy 62.916751 -52.096647) (xy 62.863541 -52.096647) (xy 62.811017 -52.088134)
			(xy 62.760532 -52.071327) (xy 62.713386 -52.04666) (xy 62.691772 -52.031138) (xy 62.288674 -52.031138)
			(xy 62.26706 -52.04666) (xy 62.219914 -52.071327) (xy 62.169429 -52.088134) (xy 62.116905 -52.096647)
			(xy 62.063695 -52.096647) (xy 62.011171 -52.088134) (xy 61.960686 -52.071327) (xy 61.91354 -52.04666)
			(xy 61.891926 -52.031138) (xy 59.888628 -52.031138) (xy 59.867013 -52.046656) (xy 59.819865 -52.071316)
			(xy 59.76938 -52.088115) (xy 59.716858 -52.09662) (xy 59.690254 -52.097178) (xy 59.676536 -52.097022)
			(xy 59.649197 -52.094731) (xy 59.635644 -52.092606) (xy 59.609736 -52.088288) (xy 59.491118 -52.206906)
			(xy 59.549538 -52.26558) (xy 59.579764 -52.254912) (xy 59.606514 -52.246012) (xy 59.662068 -52.236442)
			(xy 59.690254 -52.235862) (xy 59.716246 -52.236342) (xy 59.767592 -52.244467) (xy 59.817035 -52.260525)
			(xy 59.863357 -52.28412) (xy 59.905417 -52.314671) (xy 59.94218 -52.351425) (xy 59.972741 -52.393478)
			(xy 59.996346 -52.439795) (xy 60.012415 -52.489234) (xy 60.020552 -52.540578) (xy 60.020962 -52.56657)
			(xy 60.020463 -52.592459) (xy 60.020448 -52.592557) (xy 62.559948 -52.592557) (xy 62.559948 -52.540583)
			(xy 62.568078 -52.489248) (xy 62.584139 -52.439818) (xy 62.607735 -52.393508) (xy 62.638285 -52.35146)
			(xy 62.675036 -52.314709) (xy 62.717084 -52.284159) (xy 62.763394 -52.260563) (xy 62.812824 -52.244502)
			(xy 62.864159 -52.236372) (xy 62.916133 -52.236372) (xy 62.967468 -52.244502) (xy 63.016898 -52.260563)
			(xy 63.063208 -52.284159) (xy 63.105256 -52.314709) (xy 63.142007 -52.35146) (xy 63.172557 -52.393508)
			(xy 63.196153 -52.439818) (xy 63.212214 -52.489248) (xy 63.220344 -52.540583) (xy 63.220854 -52.56657)
			(xy 63.220344 -52.592557) (xy 63.360048 -52.592557) (xy 63.360048 -52.540583) (xy 63.368178 -52.489248)
			(xy 63.384239 -52.439818) (xy 63.407835 -52.393508) (xy 63.438385 -52.35146) (xy 63.475136 -52.314709)
			(xy 63.517184 -52.284159) (xy 63.563494 -52.260563) (xy 63.612924 -52.244502) (xy 63.664259 -52.236372)
			(xy 63.716233 -52.236372) (xy 63.767568 -52.244502) (xy 63.816998 -52.260563) (xy 63.863308 -52.284159)
			(xy 63.905356 -52.314709) (xy 63.942107 -52.35146) (xy 63.972657 -52.393508) (xy 63.996253 -52.439818)
			(xy 64.012314 -52.489248) (xy 64.020444 -52.540583) (xy 64.020954 -52.56657) (xy 64.020444 -52.592557)
			(xy 64.159894 -52.592557) (xy 64.159894 -52.540583) (xy 64.168024 -52.489248) (xy 64.184085 -52.439818)
			(xy 64.207681 -52.393508) (xy 64.238231 -52.35146) (xy 64.274982 -52.314709) (xy 64.31703 -52.284159)
			(xy 64.36334 -52.260563) (xy 64.41277 -52.244502) (xy 64.464105 -52.236372) (xy 64.516079 -52.236372)
			(xy 64.567414 -52.244502) (xy 64.616844 -52.260563) (xy 64.663154 -52.284159) (xy 64.705202 -52.314709)
			(xy 64.741953 -52.35146) (xy 64.772503 -52.393508) (xy 64.796099 -52.439818) (xy 64.81216 -52.489248)
			(xy 64.82029 -52.540583) (xy 64.8208 -52.56657) (xy 64.82029 -52.592557) (xy 64.959994 -52.592557)
			(xy 64.959994 -52.540583) (xy 64.968124 -52.489248) (xy 64.984185 -52.439818) (xy 65.007781 -52.393508)
			(xy 65.038331 -52.35146) (xy 65.075082 -52.314709) (xy 65.11713 -52.284159) (xy 65.16344 -52.260563)
			(xy 65.21287 -52.244502) (xy 65.264205 -52.236372) (xy 65.316179 -52.236372) (xy 65.367514 -52.244502)
			(xy 65.416944 -52.260563) (xy 65.463254 -52.284159) (xy 65.505302 -52.314709) (xy 65.542053 -52.35146)
			(xy 65.572603 -52.393508) (xy 65.596199 -52.439818) (xy 65.61226 -52.489248) (xy 65.62039 -52.540583)
			(xy 65.6209 -52.56657) (xy 65.62039 -52.592557) (xy 65.61226 -52.643892) (xy 65.604134 -52.6689)
			(xy 65.7517 -52.6689) (xy 65.755683 -52.615749) (xy 65.767544 -52.563786) (xy 65.787018 -52.51417)
			(xy 65.813669 -52.468012) (xy 65.846902 -52.426341) (xy 65.885975 -52.39009) (xy 65.930015 -52.360067)
			(xy 65.978038 -52.336943) (xy 66.028971 -52.321236) (xy 66.081676 -52.313295) (xy 66.108326 -52.312824)
			(xy 66.133358 -52.313249) (xy 66.182929 -52.320253) (xy 66.23103 -52.334134) (xy 66.276712 -52.354618)
			(xy 66.319073 -52.3813) (xy 66.33845 -52.397152) (xy 66.346268 -52.4032) (xy 66.365074 -52.409242)
			(xy 66.384771 -52.407745) (xy 66.402448 -52.39893) (xy 66.409316 -52.391818) (xy 66.427494 -52.371916)
			(xy 66.468526 -52.336964) (xy 66.514072 -52.308138) (xy 66.563222 -52.286012) (xy 66.614999 -52.271028)
			(xy 66.668369 -52.263483) (xy 66.69532 -52.26304) (xy 67.58432 -52.26304) (xy 67.609929 -52.263464)
			(xy 67.660685 -52.270325) (xy 67.710069 -52.283906) (xy 67.757195 -52.303966) (xy 67.801217 -52.330143)
			(xy 67.841347 -52.361968) (xy 67.859402 -52.380134) (xy 67.866596 -52.386932) (xy 67.884678 -52.394931)
			(xy 67.904443 -52.395497) (xy 67.922954 -52.388544) (xy 67.930522 -52.382166) (xy 67.950324 -52.364616)
			(xy 67.99418 -52.335014) (xy 68.041931 -52.312223) (xy 68.092528 -52.296745) (xy 68.144858 -52.288922)
			(xy 68.171314 -52.28844) (xy 68.197966 -52.288843) (xy 68.250675 -52.296789) (xy 68.301611 -52.312503)
			(xy 68.349636 -52.335632) (xy 68.393677 -52.36566) (xy 68.432752 -52.401918) (xy 68.465986 -52.443593)
			(xy 68.492637 -52.489757) (xy 68.512111 -52.539376) (xy 68.523972 -52.591345) (xy 68.527956 -52.6445)
			(xy 68.523972 -52.697655) (xy 68.512111 -52.749624) (xy 68.492637 -52.799243) (xy 68.465986 -52.845407)
			(xy 68.432752 -52.887082) (xy 68.393677 -52.92334) (xy 68.349636 -52.953368) (xy 68.301611 -52.976497)
			(xy 68.250675 -52.992211) (xy 68.197966 -53.000157) (xy 68.171314 -53.000656) (xy 68.144859 -53.00016)
			(xy 68.09253 -52.992345) (xy 68.041934 -52.976869) (xy 67.994186 -52.954074) (xy 67.95034 -52.924462)
			(xy 67.930522 -52.90693) (xy 67.922949 -52.900563) (xy 67.90444 -52.893625) (xy 67.884682 -52.89419)
			(xy 67.866599 -52.902173) (xy 67.859402 -52.908962) (xy 67.841369 -52.927153) (xy 67.801243 -52.958991)
			(xy 67.757219 -52.985175) (xy 67.710087 -53.005233) (xy 67.660695 -53.018806) (xy 67.609931 -53.025648)
			(xy 67.58432 -53.026056) (xy 66.69532 -53.026056) (xy 66.666131 -53.02551) (xy 66.608434 -53.016612)
			(xy 66.552765 -52.999037) (xy 66.500418 -52.973193) (xy 66.452616 -52.939682) (xy 66.43116 -52.919884)
			(xy 66.423725 -52.913349) (xy 66.405341 -52.906053) (xy 66.385564 -52.906269) (xy 66.367344 -52.913963)
			(xy 66.36004 -52.920646) (xy 66.339869 -52.940039) (xy 66.294608 -52.972935) (xy 66.244763 -52.998355)
			(xy 66.191559 -53.015674) (xy 66.136302 -53.024468) (xy 66.108326 -53.02504) (xy 66.081676 -53.024505)
			(xy 66.028971 -53.016564) (xy 65.978038 -53.000857) (xy 65.930015 -52.977733) (xy 65.885975 -52.94771)
			(xy 65.846902 -52.911459) (xy 65.813669 -52.869788) (xy 65.787018 -52.82363) (xy 65.767544 -52.774014)
			(xy 65.755683 -52.722051) (xy 65.7517 -52.6689) (xy 65.604134 -52.6689) (xy 65.596199 -52.693322)
			(xy 65.572603 -52.739632) (xy 65.542053 -52.78168) (xy 65.505302 -52.818431) (xy 65.463254 -52.848981)
			(xy 65.416944 -52.872577) (xy 65.367514 -52.888638) (xy 65.316179 -52.896768) (xy 65.264205 -52.896768)
			(xy 65.21287 -52.888638) (xy 65.16344 -52.872577) (xy 65.11713 -52.848981) (xy 65.075082 -52.818431)
			(xy 65.038331 -52.78168) (xy 65.007781 -52.739632) (xy 64.984185 -52.693322) (xy 64.968124 -52.643892)
			(xy 64.959994 -52.592557) (xy 64.82029 -52.592557) (xy 64.81216 -52.643892) (xy 64.796099 -52.693322)
			(xy 64.772503 -52.739632) (xy 64.741953 -52.78168) (xy 64.705202 -52.818431) (xy 64.663154 -52.848981)
			(xy 64.616844 -52.872577) (xy 64.567414 -52.888638) (xy 64.516079 -52.896768) (xy 64.464105 -52.896768)
			(xy 64.41277 -52.888638) (xy 64.36334 -52.872577) (xy 64.31703 -52.848981) (xy 64.274982 -52.818431)
			(xy 64.238231 -52.78168) (xy 64.207681 -52.739632) (xy 64.184085 -52.693322) (xy 64.168024 -52.643892)
			(xy 64.159894 -52.592557) (xy 64.020444 -52.592557) (xy 64.012314 -52.643892) (xy 63.996253 -52.693322)
			(xy 63.972657 -52.739632) (xy 63.942107 -52.78168) (xy 63.905356 -52.818431) (xy 63.863308 -52.848981)
			(xy 63.816998 -52.872577) (xy 63.767568 -52.888638) (xy 63.716233 -52.896768) (xy 63.664259 -52.896768)
			(xy 63.612924 -52.888638) (xy 63.563494 -52.872577) (xy 63.517184 -52.848981) (xy 63.475136 -52.818431)
			(xy 63.438385 -52.78168) (xy 63.407835 -52.739632) (xy 63.384239 -52.693322) (xy 63.368178 -52.643892)
			(xy 63.360048 -52.592557) (xy 63.220344 -52.592557) (xy 63.212214 -52.643892) (xy 63.196153 -52.693322)
			(xy 63.172557 -52.739632) (xy 63.142007 -52.78168) (xy 63.105256 -52.818431) (xy 63.063208 -52.848981)
			(xy 63.016898 -52.872577) (xy 62.967468 -52.888638) (xy 62.916133 -52.896768) (xy 62.864159 -52.896768)
			(xy 62.812824 -52.888638) (xy 62.763394 -52.872577) (xy 62.717084 -52.848981) (xy 62.675036 -52.818431)
			(xy 62.638285 -52.78168) (xy 62.607735 -52.739632) (xy 62.584139 -52.693322) (xy 62.568078 -52.643892)
			(xy 62.559948 -52.592557) (xy 60.020448 -52.592557) (xy 60.012399 -52.643605) (xy 59.996465 -52.692869)
			(xy 59.973049 -52.739049) (xy 59.942723 -52.781016) (xy 59.906228 -52.817746) (xy 59.864456 -52.848339)
			(xy 59.818426 -52.872051) (xy 59.769265 -52.8883) (xy 59.718172 -52.89669) (xy 59.692286 -52.897278)
			(xy 59.679029 -52.897798) (xy 59.653451 -52.904811) (xy 59.630544 -52.918178) (xy 59.611854 -52.936995)
			(xy 59.598644 -52.959993) (xy 59.591805 -52.985617) (xy 59.591448 -52.998878) (xy 59.591448 -53.392403)
			(xy 60.960002 -53.392403) (xy 60.960002 -53.340429) (xy 60.968132 -53.289094) (xy 60.984193 -53.239664)
			(xy 61.007789 -53.193354) (xy 61.038339 -53.151306) (xy 61.07509 -53.114555) (xy 61.117138 -53.084005)
			(xy 61.163448 -53.060409) (xy 61.212878 -53.044348) (xy 61.264213 -53.036218) (xy 61.316187 -53.036218)
			(xy 61.367522 -53.044348) (xy 61.416952 -53.060409) (xy 61.463262 -53.084005) (xy 61.50531 -53.114555)
			(xy 61.542061 -53.151306) (xy 61.572611 -53.193354) (xy 61.596207 -53.239664) (xy 61.612268 -53.289094)
			(xy 61.620398 -53.340429) (xy 61.620908 -53.366416) (xy 61.620398 -53.392403) (xy 62.559948 -53.392403)
			(xy 62.559948 -53.340429) (xy 62.568078 -53.289094) (xy 62.584139 -53.239664) (xy 62.607735 -53.193354)
			(xy 62.638285 -53.151306) (xy 62.675036 -53.114555) (xy 62.717084 -53.084005) (xy 62.763394 -53.060409)
			(xy 62.812824 -53.044348) (xy 62.864159 -53.036218) (xy 62.916133 -53.036218) (xy 62.967468 -53.044348)
			(xy 63.016898 -53.060409) (xy 63.063208 -53.084005) (xy 63.105256 -53.114555) (xy 63.142007 -53.151306)
			(xy 63.172557 -53.193354) (xy 63.196153 -53.239664) (xy 63.212214 -53.289094) (xy 63.220344 -53.340429)
			(xy 63.220854 -53.366416) (xy 63.220344 -53.392403) (xy 63.360048 -53.392403) (xy 63.360048 -53.340429)
			(xy 63.368178 -53.289094) (xy 63.384239 -53.239664) (xy 63.407835 -53.193354) (xy 63.438385 -53.151306)
			(xy 63.475136 -53.114555) (xy 63.517184 -53.084005) (xy 63.563494 -53.060409) (xy 63.612924 -53.044348)
			(xy 63.664259 -53.036218) (xy 63.716233 -53.036218) (xy 63.767568 -53.044348) (xy 63.816998 -53.060409)
			(xy 63.863308 -53.084005) (xy 63.905356 -53.114555) (xy 63.942107 -53.151306) (xy 63.972657 -53.193354)
			(xy 63.996253 -53.239664) (xy 64.012314 -53.289094) (xy 64.020444 -53.340429) (xy 64.020954 -53.366416)
			(xy 64.020444 -53.392403) (xy 64.012314 -53.443738) (xy 63.996253 -53.493168) (xy 63.972657 -53.539478)
			(xy 63.942107 -53.581526) (xy 63.905356 -53.618277) (xy 63.863308 -53.648827) (xy 63.816998 -53.672423)
			(xy 63.767568 -53.688484) (xy 63.716233 -53.696614) (xy 63.664259 -53.696614) (xy 63.612924 -53.688484)
			(xy 63.563494 -53.672423) (xy 63.517184 -53.648827) (xy 63.475136 -53.618277) (xy 63.438385 -53.581526)
			(xy 63.407835 -53.539478) (xy 63.384239 -53.493168) (xy 63.368178 -53.443738) (xy 63.360048 -53.392403)
			(xy 63.220344 -53.392403) (xy 63.212214 -53.443738) (xy 63.196153 -53.493168) (xy 63.172557 -53.539478)
			(xy 63.142007 -53.581526) (xy 63.105256 -53.618277) (xy 63.063208 -53.648827) (xy 63.016898 -53.672423)
			(xy 62.967468 -53.688484) (xy 62.916133 -53.696614) (xy 62.864159 -53.696614) (xy 62.812824 -53.688484)
			(xy 62.763394 -53.672423) (xy 62.717084 -53.648827) (xy 62.675036 -53.618277) (xy 62.638285 -53.581526)
			(xy 62.607735 -53.539478) (xy 62.584139 -53.493168) (xy 62.568078 -53.443738) (xy 62.559948 -53.392403)
			(xy 61.620398 -53.392403) (xy 61.612268 -53.443738) (xy 61.596207 -53.493168) (xy 61.572611 -53.539478)
			(xy 61.542061 -53.581526) (xy 61.50531 -53.618277) (xy 61.463262 -53.648827) (xy 61.416952 -53.672423)
			(xy 61.367522 -53.688484) (xy 61.316187 -53.696614) (xy 61.264213 -53.696614) (xy 61.212878 -53.688484)
			(xy 61.163448 -53.672423) (xy 61.117138 -53.648827) (xy 61.07509 -53.618277) (xy 61.038339 -53.581526)
			(xy 61.007789 -53.539478) (xy 60.984193 -53.493168) (xy 60.968132 -53.443738) (xy 60.960002 -53.392403)
			(xy 59.591448 -53.392403) (xy 59.591448 -53.844952) (xy 60.6425 -53.844952) (xy 60.667601 -53.845489)
			(xy 60.717126 -53.853715) (xy 60.76466 -53.869868) (xy 60.787026 -53.881274) (xy 60.798202 -53.887116)
			(xy 61.113162 -53.887116) (xy 61.133108 -53.874947) (xy 61.1757 -53.855739) (xy 61.220576 -53.842731)
			(xy 61.266838 -53.836183) (xy 61.2902 -53.835808) (xy 61.313559 -53.836215) (xy 61.359812 -53.842788)
			(xy 61.404684 -53.85579) (xy 61.447285 -53.874963) (xy 61.467238 -53.887116) (xy 62.713108 -53.887116)
			(xy 62.733055 -53.874949) (xy 62.775648 -53.855748) (xy 62.820524 -53.842746) (xy 62.866785 -53.836204)
			(xy 62.890146 -53.835808) (xy 62.913504 -53.836218) (xy 62.959754 -53.842797) (xy 63.004623 -53.855804)
			(xy 63.047221 -53.874982) (xy 63.067184 -53.887116) (xy 63.513208 -53.887116) (xy 63.533155 -53.874949)
			(xy 63.575748 -53.855748) (xy 63.620624 -53.842746) (xy 63.666885 -53.836204) (xy 63.690246 -53.835808)
			(xy 63.713604 -53.836218) (xy 63.759854 -53.842797) (xy 63.804723 -53.855804) (xy 63.847321 -53.874982)
			(xy 63.867284 -53.887116) (xy 64.313054 -53.887116) (xy 64.333 -53.874946) (xy 64.375592 -53.855737)
			(xy 64.420468 -53.842728) (xy 64.46673 -53.836179) (xy 64.490092 -53.835808) (xy 64.513451 -53.836214)
			(xy 64.559704 -53.842786) (xy 64.604577 -53.855787) (xy 64.647179 -53.87496) (xy 64.66713 -53.887116)
			(xy 65.113154 -53.887116) (xy 65.1331 -53.874946) (xy 65.175692 -53.855737) (xy 65.220568 -53.842728)
			(xy 65.26683 -53.836179) (xy 65.290192 -53.835808) (xy 65.31674 -53.836327) (xy 65.369157 -53.844791)
			(xy 65.419549 -53.861519) (xy 65.466622 -53.886082) (xy 65.509167 -53.917849) (xy 65.546091 -53.956004)
			(xy 65.576446 -53.999567) (xy 65.599453 -54.04742) (xy 65.614521 -54.098333) (xy 65.61836 -54.124606)
			(xy 65.620392 -54.141878) (xy 65.876932 -54.398418) (xy 65.887066 -54.407952) (xy 65.911308 -54.421593)
			(xy 65.938331 -54.428186) (xy 65.96613 -54.427243) (xy 65.992644 -54.418833) (xy 66.015905 -54.403582)
			(xy 66.034188 -54.382619) (xy 66.040508 -54.370224) (xy 66.051678 -54.347727) (xy 66.079397 -54.305841)
			(xy 66.11272 -54.268259) (xy 66.150987 -54.235727) (xy 66.193442 -54.208887) (xy 66.239244 -54.188272)
			(xy 66.287486 -54.174289) (xy 66.337213 -54.167215) (xy 66.362326 -54.16677) (xy 66.387827 -54.167208)
			(xy 66.438306 -54.174485) (xy 66.487232 -54.188887) (xy 66.533603 -54.210119) (xy 66.576473 -54.237747)
			(xy 66.596006 -54.254146) (xy 66.603751 -54.260239) (xy 66.622395 -54.266567) (xy 66.64205 -54.265428)
			(xy 66.659837 -54.256987) (xy 66.666872 -54.250082) (xy 66.685031 -54.230753) (xy 66.725766 -54.196793)
			(xy 66.770809 -54.168798) (xy 66.819293 -54.147306) (xy 66.870285 -54.132731) (xy 66.922803 -54.125352)
			(xy 66.94932 -54.12486) (xy 67.83832 -54.12486) (xy 67.863939 -54.125289) (xy 67.914713 -54.132174)
			(xy 67.96411 -54.145791) (xy 68.01124 -54.165894) (xy 68.055257 -54.192123) (xy 68.095368 -54.224006)
			(xy 68.113402 -54.242208) (xy 68.120602 -54.24899) (xy 68.138684 -54.256961) (xy 68.158437 -54.257525)
			(xy 68.176944 -54.250597) (xy 68.184522 -54.24424) (xy 68.20434 -54.22671) (xy 68.248188 -54.1971)
			(xy 68.295935 -54.174307) (xy 68.346531 -54.158832) (xy 68.398859 -54.151017) (xy 68.425314 -54.150514)
			(xy 68.451961 -54.151013) (xy 68.504659 -54.158958) (xy 68.555585 -54.174668) (xy 68.603601 -54.197793)
			(xy 68.647633 -54.227816) (xy 68.6867 -54.264065) (xy 68.719927 -54.305733) (xy 68.746574 -54.351887)
			(xy 68.766044 -54.401497) (xy 68.777902 -54.453455) (xy 68.781885 -54.5066) (xy 68.777902 -54.559745)
			(xy 68.766044 -54.611703) (xy 68.746574 -54.661313) (xy 68.719927 -54.707467) (xy 68.6867 -54.749135)
			(xy 68.647633 -54.785384) (xy 68.603601 -54.815407) (xy 68.555585 -54.838532) (xy 68.504659 -54.854242)
			(xy 68.451961 -54.862187) (xy 68.425314 -54.86273) (xy 68.398858 -54.862248) (xy 68.346529 -54.854424)
			(xy 68.295933 -54.838945) (xy 68.248182 -54.816153) (xy 68.204328 -54.786549) (xy 68.184522 -54.769004)
			(xy 68.176953 -54.762629) (xy 68.158442 -54.75568) (xy 68.138679 -54.756245) (xy 68.120596 -54.76424)
			(xy 68.113402 -54.771036) (xy 68.095358 -54.789225) (xy 68.055243 -54.821098) (xy 68.011227 -54.847321)
			(xy 67.964099 -54.867423) (xy 67.914707 -54.881043) (xy 67.863937 -54.887936) (xy 67.83832 -54.888384)
			(xy 66.94932 -54.888384) (xy 66.919617 -54.887803) (xy 66.860932 -54.878564) (xy 66.80439 -54.860337)
			(xy 66.751357 -54.833563) (xy 66.703118 -54.79889) (xy 66.681604 -54.778402) (xy 66.674221 -54.77182)
			(xy 66.655924 -54.764355) (xy 66.636164 -54.764355) (xy 66.617867 -54.77182) (xy 66.610484 -54.778402)
			(xy 66.589168 -54.798254) (xy 66.5413 -54.83144) (xy 66.515234 -54.844442) (xy 66.502809 -54.85078)
			(xy 66.481742 -54.869048) (xy 66.466398 -54.89233) (xy 66.457918 -54.918892) (xy 66.456933 -54.946759)
			(xy 66.463518 -54.973854) (xy 66.477181 -54.99816) (xy 66.486786 -55.008272) (xy 66.737484 -55.258716)
			(xy 66.737484 -56.420004) (xy 67.776088 -56.420004) (xy 67.780159 -56.364382) (xy 67.792285 -56.309945)
			(xy 67.812208 -56.257854) (xy 67.839504 -56.209219) (xy 67.87359 -56.165076) (xy 67.913739 -56.126367)
			(xy 67.959097 -56.093916) (xy 68.008697 -56.068415) (xy 68.061481 -56.050408) (xy 68.116324 -56.040278)
			(xy 68.172058 -56.038241) (xy 68.227495 -56.044341) (xy 68.281452 -56.058447) (xy 68.332781 -56.080259)
			(xy 68.380387 -56.109313) (xy 68.423255 -56.144988) (xy 68.460472 -56.186525) (xy 68.491245 -56.233038)
			(xy 68.514917 -56.283535) (xy 68.530985 -56.336942) (xy 68.539105 -56.392118) (xy 68.539614 -56.420004)
			(xy 68.539105 -56.44789) (xy 68.530985 -56.503066) (xy 68.514917 -56.556473) (xy 68.491245 -56.60697)
			(xy 68.460472 -56.653483) (xy 68.423255 -56.69502) (xy 68.380387 -56.730695) (xy 68.332781 -56.759749)
			(xy 68.281452 -56.781561) (xy 68.227495 -56.795667) (xy 68.172058 -56.801767) (xy 68.116324 -56.79973)
			(xy 68.061481 -56.7896) (xy 68.008697 -56.771593) (xy 67.959097 -56.746092) (xy 67.913739 -56.713641)
			(xy 67.87359 -56.674932) (xy 67.839504 -56.630789) (xy 67.812208 -56.582154) (xy 67.792285 -56.530063)
			(xy 67.780159 -56.475626) (xy 67.776088 -56.420004) (xy 66.737484 -56.420004) (xy 66.737484 -59.723782)
			(xy 66.795474 -59.781749) (xy 70.734694 -59.781749) (xy 70.734694 -59.727251) (xy 70.74245 -59.673307)
			(xy 70.757803 -59.621016) (xy 70.780442 -59.571442) (xy 70.809906 -59.525594) (xy 70.845594 -59.484406)
			(xy 70.88678 -59.448716) (xy 70.932626 -59.419251) (xy 70.982199 -59.39661) (xy 71.034489 -59.381254)
			(xy 71.088433 -59.373495) (xy 71.115682 -59.373008) (xy 71.143052 -59.373483) (xy 71.197231 -59.381298)
			(xy 71.249734 -59.396785) (xy 71.299481 -59.419625) (xy 71.345448 -59.449348) (xy 71.36638 -59.466988)
			(xy 71.377708 -59.476224) (xy 71.404265 -59.4884) (xy 71.433182 -59.492573) (xy 71.462099 -59.4884)
			(xy 71.488656 -59.476224) (xy 71.499984 -59.466988) (xy 71.52091 -59.449341) (xy 71.566884 -59.419631)
			(xy 71.616634 -59.396797) (xy 71.669136 -59.381307) (xy 71.723312 -59.373481) (xy 71.750682 -59.373008)
			(xy 71.777937 -59.373438) (xy 71.831892 -59.381193) (xy 71.884194 -59.396548) (xy 71.933779 -59.41919)
			(xy 71.979636 -59.448659) (xy 72.020833 -59.484354) (xy 72.05653 -59.525549) (xy 72.086001 -59.571405)
			(xy 72.108646 -59.620989) (xy 72.124003 -59.67329) (xy 72.131761 -59.727245) (xy 72.131761 -59.781755)
			(xy 72.124003 -59.83571) (xy 72.108646 -59.888011) (xy 72.086001 -59.937595) (xy 72.05653 -59.983451)
			(xy 72.020833 -60.024646) (xy 71.979636 -60.060341) (xy 71.933779 -60.08981) (xy 71.884194 -60.112452)
			(xy 71.831892 -60.127807) (xy 71.777937 -60.135562) (xy 71.750682 -60.136024) (xy 71.723311 -60.135587)
			(xy 71.669129 -60.127765) (xy 71.616625 -60.11227) (xy 71.566879 -60.089421) (xy 71.520914 -60.059689)
			(xy 71.499984 -60.042044) (xy 71.488656 -60.032808) (xy 71.462099 -60.020632) (xy 71.433182 -60.016459)
			(xy 71.404265 -60.020632) (xy 71.377708 -60.032808) (xy 71.36638 -60.042044) (xy 71.345435 -60.059666)
			(xy 71.299465 -60.089379) (xy 71.249721 -60.112218) (xy 71.197223 -60.127713) (xy 71.14305 -60.135547)
			(xy 71.115682 -60.136024) (xy 71.088433 -60.135505) (xy 71.034489 -60.127746) (xy 70.982199 -60.11239)
			(xy 70.932626 -60.089749) (xy 70.88678 -60.060284) (xy 70.845594 -60.024594) (xy 70.809906 -59.983406)
			(xy 70.780442 -59.937558) (xy 70.757803 -59.887984) (xy 70.74245 -59.835693) (xy 70.734694 -59.781749)
			(xy 66.795474 -59.781749) (xy 67.365372 -60.351416) (xy 67.386186 -60.373325) (xy 67.419698 -60.4236)
			(xy 67.43192 -60.451238) (xy 67.46494 -60.53074) (xy 68.4276 -61.4934) (xy 72.261982 -61.4934) (xy 72.266053 -61.437778)
			(xy 72.278179 -61.383341) (xy 72.298102 -61.33125) (xy 72.325398 -61.282615) (xy 72.359484 -61.238472)
			(xy 72.399633 -61.199763) (xy 72.444991 -61.167312) (xy 72.494591 -61.141811) (xy 72.547375 -61.123804)
			(xy 72.602218 -61.113674) (xy 72.657952 -61.111637) (xy 72.713389 -61.117737) (xy 72.767346 -61.131843)
			(xy 72.818675 -61.153655) (xy 72.866281 -61.182709) (xy 72.909149 -61.218384) (xy 72.946366 -61.259921)
			(xy 72.977139 -61.306434) (xy 73.000811 -61.356931) (xy 73.016879 -61.410338) (xy 73.024999 -61.465514)
			(xy 73.025508 -61.4934) (xy 73.024999 -61.521286) (xy 73.016879 -61.576462) (xy 73.000811 -61.629869)
			(xy 72.977139 -61.680366) (xy 72.946366 -61.726879) (xy 72.909149 -61.768416) (xy 72.866281 -61.804091)
			(xy 72.818675 -61.833145) (xy 72.767346 -61.854957) (xy 72.713389 -61.869063) (xy 72.657952 -61.875163)
			(xy 72.602218 -61.873126) (xy 72.547375 -61.862996) (xy 72.494591 -61.844989) (xy 72.444991 -61.819488)
			(xy 72.399633 -61.787037) (xy 72.359484 -61.748328) (xy 72.325398 -61.704185) (xy 72.298102 -61.65555)
			(xy 72.278179 -61.603459) (xy 72.266053 -61.549022) (xy 72.261982 -61.4934) (xy 68.4276 -61.4934)
			(xy 70.1294 -63.1952) (xy 71.078344 -63.1952) (xy 71.997316 -64.114172) (xy 73.329292 -64.114172)
		)
		(stroke
			(width 0)
			(type solid)
		)
		(fill yes)
		(layer "In4.Cu")
		(net "P1V8_STBY_DP_VCC18A")
	)
	(gr_poly
		(pts
			(xy 76.33589 -34.35477) (xy 76.346716 -34.32822) (xy 76.375177 -34.278445) (xy 76.410768 -34.233492)
			(xy 76.452687 -34.194373) (xy 76.499988 -34.161969) (xy 76.551608 -34.13701) (xy 76.606382 -34.120059)
			(xy 76.663075 -34.111498) (xy 76.691744 -34.11093) (xy 76.72066 -34.111469) (xy 76.777829 -34.120207)
			(xy 76.833022 -34.137477) (xy 76.884976 -34.162883) (xy 76.932498 -34.195841) (xy 76.953872 -34.215324)
			(xy 76.964816 -34.225041) (xy 76.990881 -34.238323) (xy 77.019644 -34.243664) (xy 77.04874 -34.240624)
			(xy 77.075779 -34.229455) (xy 77.087476 -34.220658) (xy 77.1079 -34.204771) (xy 77.152222 -34.178073)
			(xy 77.199747 -34.157613) (xy 77.249603 -34.143767) (xy 77.300873 -34.13679) (xy 77.326744 -34.13633)
			(xy 77.353883 -34.136812) (xy 77.407611 -34.144514) (xy 77.459705 -34.159755) (xy 77.509112 -34.182229)
			(xy 77.554833 -34.211481) (xy 77.595944 -34.246919) (xy 77.631616 -34.287829) (xy 77.661128 -34.333383)
			(xy 77.672946 -34.357818) (xy 77.686662 -34.387282) (xy 80.394302 -34.387282) (xy 80.934814 -33.84677)
			(xy 80.934814 -30.248098) (xy 80.934316 -30.233685) (xy 80.926268 -30.206004) (xy 80.910814 -30.18167)
			(xy 80.889181 -30.162617) (xy 80.863089 -30.15036) (xy 80.834613 -30.145874) (xy 80.82026 -30.14726)
			(xy 80.808246 -30.148685) (xy 80.784098 -30.15021) (xy 80.772 -30.150308) (xy 80.743807 -30.149809)
			(xy 80.688033 -30.141524) (xy 80.634086 -30.12512) (xy 80.58314 -30.100955) (xy 80.536307 -30.069554)
			(xy 80.494606 -30.031602) (xy 80.458944 -29.987925) (xy 80.4301 -29.939475) (xy 80.41894 -29.91358)
			(xy 80.412574 -29.899475) (xy 80.392816 -29.875677) (xy 80.366835 -29.858894) (xy 80.337019 -29.850666)
			(xy 80.306107 -29.851751) (xy 80.276941 -29.862048) (xy 80.264254 -29.870908) (xy 80.239319 -29.888815)
			(xy 80.184929 -29.917274) (xy 80.126687 -29.936665) (xy 80.066093 -29.946486) (xy 80.0354 -29.947108)
			(xy 80.008149 -29.946622) (xy 79.954201 -29.938866) (xy 79.901906 -29.923511) (xy 79.852329 -29.900869)
			(xy 79.806479 -29.871403) (xy 79.765288 -29.835712) (xy 79.729597 -29.794521) (xy 79.700131 -29.748671)
			(xy 79.677489 -29.699094) (xy 79.662134 -29.646799) (xy 79.654378 -29.592851) (xy 79.654378 -29.538349)
			(xy 79.662134 -29.484401) (xy 79.677489 -29.432106) (xy 79.700131 -29.382529) (xy 79.729597 -29.336679)
			(xy 79.765288 -29.295488) (xy 79.806479 -29.259797) (xy 79.852329 -29.230331) (xy 79.901906 -29.207689)
			(xy 79.954201 -29.192334) (xy 80.008149 -29.184578) (xy 80.0354 -29.184092) (xy 80.063593 -29.184591)
			(xy 80.119367 -29.192876) (xy 80.173314 -29.20928) (xy 80.22426 -29.233445) (xy 80.271093 -29.264846)
			(xy 80.312794 -29.302798) (xy 80.348456 -29.346475) (xy 80.3773 -29.394925) (xy 80.38846 -29.42082)
			(xy 80.394826 -29.434925) (xy 80.414584 -29.458723) (xy 80.440565 -29.475506) (xy 80.470381 -29.483734)
			(xy 80.501293 -29.482649) (xy 80.530459 -29.472352) (xy 80.543146 -29.463492) (xy 80.568081 -29.445585)
			(xy 80.622471 -29.417126) (xy 80.680713 -29.397735) (xy 80.741307 -29.387914) (xy 80.772 -29.387292)
			(xy 80.784099 -29.387376) (xy 80.808247 -29.388899) (xy 80.82026 -29.39034) (xy 80.834617 -29.39168)
			(xy 80.863089 -29.387216) (xy 80.88918 -29.374973) (xy 80.910809 -29.355926) (xy 80.926253 -29.331593)
			(xy 80.934281 -29.303913) (xy 80.934814 -29.289502) (xy 80.934814 -27.391106) (xy 79.521812 -25.978104)
			(xy 76.749148 -25.978104) (xy 76.733973 -25.978669) (xy 76.704964 -25.987591) (xy 76.67985 -26.004634)
			(xy 76.660844 -26.028297) (xy 76.64962 -26.056496) (xy 76.647166 -26.086747) (xy 76.653697 -26.116386)
			(xy 76.66864 -26.142803) (xy 76.679298 -26.153618) (xy 76.697838 -26.171699) (xy 76.730355 -26.212004)
			(xy 76.757116 -26.25634) (xy 76.777626 -26.303891) (xy 76.79151 -26.353782) (xy 76.79851 -26.405093)
			(xy 76.798932 -26.430986) (xy 76.798446 -26.458237) (xy 76.79069 -26.512185) (xy 76.775335 -26.56448)
			(xy 76.752693 -26.614057) (xy 76.723227 -26.659907) (xy 76.687536 -26.701098) (xy 76.646345 -26.736789)
			(xy 76.600495 -26.766255) (xy 76.550918 -26.788897) (xy 76.498623 -26.804252) (xy 76.444675 -26.812008)
			(xy 76.390173 -26.812008) (xy 76.336225 -26.804252) (xy 76.28393 -26.788897) (xy 76.234353 -26.766255)
			(xy 76.188503 -26.736789) (xy 76.147312 -26.701098) (xy 76.111621 -26.659907) (xy 76.082155 -26.614057)
			(xy 76.059513 -26.56448) (xy 76.044158 -26.512185) (xy 76.036402 -26.458237) (xy 76.035916 -26.430986)
			(xy 76.036074 -26.41587) (xy 76.03849 -26.385736) (xy 76.040742 -26.370788) (xy 76.042511 -26.356765)
			(xy 76.039142 -26.328713) (xy 76.028217 -26.302658) (xy 76.01057 -26.280593) (xy 75.987554 -26.264207)
			(xy 75.960928 -26.254754) (xy 75.932732 -26.252958) (xy 75.918822 -26.255472) (xy 75.898876 -26.259526)
			(xy 75.858402 -26.263856) (xy 75.83805 -26.264108) (xy 75.808814 -26.263545) (xy 75.751029 -26.254613)
			(xy 75.695285 -26.236966) (xy 75.642887 -26.211017) (xy 75.595063 -26.177375) (xy 75.552935 -26.136828)
			(xy 75.517488 -26.090326) (xy 75.489555 -26.038958) (xy 75.479148 -26.011632) (xy 75.466956 -25.978104)
			(xy 74.478896 -25.978104) (xy 73.3044 -27.1526) (xy 74.446382 -27.1526) (xy 74.450453 -27.096978)
			(xy 74.462579 -27.042541) (xy 74.482502 -26.99045) (xy 74.509798 -26.941815) (xy 74.543884 -26.897672)
			(xy 74.584033 -26.858963) (xy 74.629391 -26.826512) (xy 74.678991 -26.801011) (xy 74.731775 -26.783004)
			(xy 74.786618 -26.772874) (xy 74.842352 -26.770837) (xy 74.897789 -26.776937) (xy 74.951746 -26.791043)
			(xy 75.003075 -26.812855) (xy 75.050681 -26.841909) (xy 75.093549 -26.877584) (xy 75.130766 -26.919121)
			(xy 75.161539 -26.965634) (xy 75.185211 -27.016131) (xy 75.201279 -27.069538) (xy 75.209399 -27.124714)
			(xy 75.209908 -27.1526) (xy 75.209399 -27.180486) (xy 75.201279 -27.235662) (xy 75.185211 -27.289069)
			(xy 75.161539 -27.339566) (xy 75.130766 -27.386079) (xy 75.093549 -27.427616) (xy 75.050681 -27.463291)
			(xy 75.003075 -27.492345) (xy 74.951746 -27.514157) (xy 74.897789 -27.528263) (xy 74.842352 -27.534363)
			(xy 74.786618 -27.532326) (xy 74.731775 -27.522196) (xy 74.678991 -27.504189) (xy 74.629391 -27.478688)
			(xy 74.584033 -27.446237) (xy 74.543884 -27.407528) (xy 74.509798 -27.363385) (xy 74.482502 -27.31475)
			(xy 74.462579 -27.262659) (xy 74.450453 -27.208222) (xy 74.446382 -27.1526) (xy 73.3044 -27.1526)
			(xy 72.860154 -27.596846) (xy 76.110336 -27.596846) (xy 76.114407 -27.541224) (xy 76.126533 -27.486787)
			(xy 76.146456 -27.434696) (xy 76.173752 -27.386061) (xy 76.207838 -27.341918) (xy 76.247987 -27.303209)
			(xy 76.293345 -27.270758) (xy 76.342945 -27.245257) (xy 76.395729 -27.22725) (xy 76.450572 -27.21712)
			(xy 76.506306 -27.215083) (xy 76.561743 -27.221183) (xy 76.6157 -27.235289) (xy 76.667029 -27.257101)
			(xy 76.714635 -27.286155) (xy 76.757503 -27.32183) (xy 76.79472 -27.363367) (xy 76.825493 -27.40988)
			(xy 76.849165 -27.460377) (xy 76.865233 -27.513784) (xy 76.873353 -27.56896) (xy 76.873862 -27.596846)
			(xy 76.873353 -27.624732) (xy 76.865233 -27.679908) (xy 76.849165 -27.733315) (xy 76.825493 -27.783812)
			(xy 76.79472 -27.830325) (xy 76.757503 -27.871862) (xy 76.714635 -27.907537) (xy 76.667029 -27.936591)
			(xy 76.6157 -27.958403) (xy 76.561743 -27.972509) (xy 76.506306 -27.978609) (xy 76.450572 -27.976572)
			(xy 76.395729 -27.966442) (xy 76.342945 -27.948435) (xy 76.293345 -27.922934) (xy 76.247987 -27.890483)
			(xy 76.207838 -27.851774) (xy 76.173752 -27.807631) (xy 76.146456 -27.758996) (xy 76.126533 -27.706905)
			(xy 76.114407 -27.652468) (xy 76.110336 -27.596846) (xy 72.860154 -27.596846) (xy 72.0598 -28.3972)
			(xy 74.497182 -28.3972) (xy 74.501253 -28.341578) (xy 74.513379 -28.287141) (xy 74.533302 -28.23505)
			(xy 74.560598 -28.186415) (xy 74.594684 -28.142272) (xy 74.634833 -28.103563) (xy 74.680191 -28.071112)
			(xy 74.729791 -28.045611) (xy 74.782575 -28.027604) (xy 74.837418 -28.017474) (xy 74.893152 -28.015437)
			(xy 74.948589 -28.021537) (xy 75.002546 -28.035643) (xy 75.053875 -28.057455) (xy 75.101481 -28.086509)
			(xy 75.144349 -28.122184) (xy 75.181566 -28.163721) (xy 75.212339 -28.210234) (xy 75.236011 -28.260731)
			(xy 75.252079 -28.314138) (xy 75.260199 -28.369314) (xy 75.260708 -28.3972) (xy 75.260199 -28.425086)
			(xy 75.252079 -28.480262) (xy 75.236011 -28.533669) (xy 75.212339 -28.584166) (xy 75.181566 -28.630679)
			(xy 75.144349 -28.672216) (xy 75.101481 -28.707891) (xy 75.053875 -28.736945) (xy 75.002546 -28.758757)
			(xy 74.948589 -28.772863) (xy 74.893152 -28.778963) (xy 74.837418 -28.776926) (xy 74.782575 -28.766796)
			(xy 74.729791 -28.748789) (xy 74.680191 -28.723288) (xy 74.634833 -28.690837) (xy 74.594684 -28.652128)
			(xy 74.560598 -28.607985) (xy 74.533302 -28.55935) (xy 74.513379 -28.507259) (xy 74.501253 -28.452822)
			(xy 74.497182 -28.3972) (xy 72.0598 -28.3972) (xy 71.67626 -28.78074) (xy 71.67626 -29.7815) (xy 72.071482 -29.7815)
			(xy 72.075553 -29.725878) (xy 72.087679 -29.671441) (xy 72.107602 -29.61935) (xy 72.134898 -29.570715)
			(xy 72.168984 -29.526572) (xy 72.209133 -29.487863) (xy 72.254491 -29.455412) (xy 72.304091 -29.429911)
			(xy 72.356875 -29.411904) (xy 72.411718 -29.401774) (xy 72.467452 -29.399737) (xy 72.522889 -29.405837)
			(xy 72.576846 -29.419943) (xy 72.628175 -29.441755) (xy 72.675781 -29.470809) (xy 72.718649 -29.506484)
			(xy 72.755866 -29.548021) (xy 72.784301 -29.591) (xy 76.833982 -29.591) (xy 76.838053 -29.535378)
			(xy 76.850179 -29.480941) (xy 76.870102 -29.42885) (xy 76.897398 -29.380215) (xy 76.931484 -29.336072)
			(xy 76.971633 -29.297363) (xy 77.016991 -29.264912) (xy 77.066591 -29.239411) (xy 77.119375 -29.221404)
			(xy 77.174218 -29.211274) (xy 77.229952 -29.209237) (xy 77.285389 -29.215337) (xy 77.339346 -29.229443)
			(xy 77.390675 -29.251255) (xy 77.438281 -29.280309) (xy 77.481149 -29.315984) (xy 77.518366 -29.357521)
			(xy 77.549139 -29.404034) (xy 77.572811 -29.454531) (xy 77.588879 -29.507938) (xy 77.596999 -29.563114)
			(xy 77.597508 -29.591) (xy 77.596999 -29.618886) (xy 77.588879 -29.674062) (xy 77.572811 -29.727469)
			(xy 77.549139 -29.777966) (xy 77.518366 -29.824479) (xy 77.481149 -29.866016) (xy 77.438281 -29.901691)
			(xy 77.390675 -29.930745) (xy 77.339346 -29.952557) (xy 77.285389 -29.966663) (xy 77.229952 -29.972763)
			(xy 77.174218 -29.970726) (xy 77.119375 -29.960596) (xy 77.066591 -29.942589) (xy 77.016991 -29.917088)
			(xy 76.971633 -29.884637) (xy 76.931484 -29.845928) (xy 76.897398 -29.801785) (xy 76.870102 -29.75315)
			(xy 76.850179 -29.701059) (xy 76.838053 -29.646622) (xy 76.833982 -29.591) (xy 72.784301 -29.591)
			(xy 72.786639 -29.594534) (xy 72.810311 -29.645031) (xy 72.826379 -29.698438) (xy 72.834499 -29.753614)
			(xy 72.835008 -29.7815) (xy 72.834499 -29.809386) (xy 72.826379 -29.864562) (xy 72.810311 -29.917969)
			(xy 72.786639 -29.968466) (xy 72.755866 -30.014979) (xy 72.718649 -30.056516) (xy 72.675781 -30.092191)
			(xy 72.628175 -30.121245) (xy 72.576846 -30.143057) (xy 72.522889 -30.157163) (xy 72.467452 -30.163263)
			(xy 72.411718 -30.161226) (xy 72.356875 -30.151096) (xy 72.304091 -30.133089) (xy 72.254491 -30.107588)
			(xy 72.209133 -30.075137) (xy 72.168984 -30.036428) (xy 72.134898 -29.992285) (xy 72.107602 -29.94365)
			(xy 72.087679 -29.891559) (xy 72.075553 -29.837122) (xy 72.071482 -29.7815) (xy 71.67626 -29.7815)
			(xy 71.67626 -30.557724) (xy 72.799446 -30.557724) (xy 72.803517 -30.502102) (xy 72.815643 -30.447665)
			(xy 72.835566 -30.395574) (xy 72.862862 -30.346939) (xy 72.896948 -30.302796) (xy 72.937097 -30.264087)
			(xy 72.982455 -30.231636) (xy 73.032055 -30.206135) (xy 73.084839 -30.188128) (xy 73.139682 -30.177998)
			(xy 73.195416 -30.175961) (xy 73.250853 -30.182061) (xy 73.30481 -30.196167) (xy 73.356139 -30.217979)
			(xy 73.403745 -30.247033) (xy 73.408992 -30.2514) (xy 74.567032 -30.2514) (xy 74.571103 -30.195778)
			(xy 74.583229 -30.141341) (xy 74.603152 -30.08925) (xy 74.630448 -30.040615) (xy 74.664534 -29.996472)
			(xy 74.704683 -29.957763) (xy 74.750041 -29.925312) (xy 74.799641 -29.899811) (xy 74.852425 -29.881804)
			(xy 74.907268 -29.871674) (xy 74.963002 -29.869637) (xy 75.018439 -29.875737) (xy 75.072396 -29.889843)
			(xy 75.123725 -29.911655) (xy 75.171331 -29.940709) (xy 75.214199 -29.976384) (xy 75.251416 -30.017921)
			(xy 75.282189 -30.064434) (xy 75.305861 -30.114931) (xy 75.321929 -30.168338) (xy 75.32267 -30.173376)
			(xy 75.558503 -30.173376) (xy 75.566256 -30.119416) (xy 75.581611 -30.067108) (xy 75.604253 -30.017519)
			(xy 75.633722 -29.971656) (xy 75.669419 -29.930454) (xy 75.710616 -29.894753) (xy 75.756475 -29.865277)
			(xy 75.806062 -29.842628) (xy 75.858367 -29.827267) (xy 75.912326 -29.819506) (xy 75.966841 -29.819504)
			(xy 76.0208 -29.82726) (xy 76.073107 -29.842617) (xy 76.122696 -29.865261) (xy 76.168557 -29.894732)
			(xy 76.209757 -29.930431) (xy 76.245457 -29.971629) (xy 76.274931 -30.017489) (xy 76.297578 -30.067077)
			(xy 76.312937 -30.119383) (xy 76.320695 -30.173343) (xy 76.321158 -30.2006) (xy 76.321081 -30.211611)
			(xy 76.31981 -30.233596) (xy 76.318618 -30.244542) (xy 76.317428 -30.259423) (xy 76.322664 -30.288797)
			(xy 76.336175 -30.3154) (xy 76.356805 -30.336956) (xy 76.382789 -30.351621) (xy 76.411905 -30.358141)
			(xy 76.426822 -30.357572) (xy 76.454 -30.356556) (xy 76.481253 -30.357055) (xy 76.535205 -30.364813)
			(xy 76.587504 -30.380169) (xy 76.637085 -30.402813) (xy 76.682939 -30.432282) (xy 76.724132 -30.467977)
			(xy 76.759825 -30.509171) (xy 76.789293 -30.555025) (xy 76.811935 -30.604607) (xy 76.82729 -30.656906)
			(xy 76.835045 -30.710859) (xy 76.835044 -30.765365) (xy 76.827285 -30.819317) (xy 76.811927 -30.871615)
			(xy 76.789282 -30.921196) (xy 76.759811 -30.967048) (xy 76.724115 -31.00824) (xy 76.68292 -31.043933)
			(xy 76.65138 -31.0642) (xy 77.698092 -31.0642) (xy 77.698578 -31.036949) (xy 77.706334 -30.983001)
			(xy 77.721689 -30.930706) (xy 77.744331 -30.881129) (xy 77.773797 -30.835279) (xy 77.809488 -30.794088)
			(xy 77.850679 -30.758397) (xy 77.896529 -30.728931) (xy 77.946106 -30.706289) (xy 77.998401 -30.690934)
			(xy 78.052349 -30.683178) (xy 78.106851 -30.683178) (xy 78.160799 -30.690934) (xy 78.213094 -30.706289)
			(xy 78.262671 -30.728931) (xy 78.308521 -30.758397) (xy 78.349712 -30.794088) (xy 78.385403 -30.835279)
			(xy 78.414869 -30.881129) (xy 78.437511 -30.930706) (xy 78.452866 -30.983001) (xy 78.460622 -31.036949)
			(xy 78.461108 -31.0642) (xy 78.460602 -31.092542) (xy 78.452216 -31.148602) (xy 78.435627 -31.202804)
			(xy 78.411201 -31.253954) (xy 78.379476 -31.300929) (xy 78.34115 -31.342692) (xy 78.297067 -31.378325)
			(xy 78.272894 -31.39313) (xy 78.26131 -31.400338) (xy 78.242241 -31.419842) (xy 78.229019 -31.4437)
			(xy 78.222589 -31.470207) (xy 78.223408 -31.497472) (xy 78.23142 -31.523545) (xy 78.246051 -31.546566)
			(xy 78.266257 -31.564889) (xy 78.278228 -31.571438) (xy 78.279668 -31.5722) (xy 79.323182 -31.5722)
			(xy 79.327253 -31.516578) (xy 79.339379 -31.462141) (xy 79.359302 -31.41005) (xy 79.386598 -31.361415)
			(xy 79.420684 -31.317272) (xy 79.460833 -31.278563) (xy 79.506191 -31.246112) (xy 79.555791 -31.220611)
			(xy 79.608575 -31.202604) (xy 79.663418 -31.192474) (xy 79.719152 -31.190437) (xy 79.774589 -31.196537)
			(xy 79.828546 -31.210643) (xy 79.879875 -31.232455) (xy 79.927481 -31.261509) (xy 79.970349 -31.297184)
			(xy 80.007566 -31.338721) (xy 80.038339 -31.385234) (xy 80.062011 -31.435731) (xy 80.078079 -31.489138)
			(xy 80.086199 -31.544314) (xy 80.086708 -31.5722) (xy 80.086199 -31.600086) (xy 80.078079 -31.655262)
			(xy 80.062011 -31.708669) (xy 80.038339 -31.759166) (xy 80.007566 -31.805679) (xy 79.970349 -31.847216)
			(xy 79.927481 -31.882891) (xy 79.879875 -31.911945) (xy 79.828546 -31.933757) (xy 79.774589 -31.947863)
			(xy 79.719152 -31.953963) (xy 79.663418 -31.951926) (xy 79.608575 -31.941796) (xy 79.555791 -31.923789)
			(xy 79.506191 -31.898288) (xy 79.460833 -31.865837) (xy 79.420684 -31.827128) (xy 79.386598 -31.782985)
			(xy 79.359302 -31.73435) (xy 79.339379 -31.682259) (xy 79.327253 -31.627822) (xy 79.323182 -31.5722)
			(xy 78.279668 -31.5722) (xy 78.301412 -31.583706) (xy 78.344448 -31.613692) (xy 78.382969 -31.649293)
			(xy 78.416246 -31.689838) (xy 78.443652 -31.734561) (xy 78.464669 -31.782619) (xy 78.478901 -31.833104)
			(xy 78.486078 -31.885064) (xy 78.486508 -31.91129) (xy 78.486083 -31.937771) (xy 78.478769 -31.990225)
			(xy 78.464267 -32.041162) (xy 78.442855 -32.089602) (xy 78.414946 -32.134613) (xy 78.381077 -32.17533)
			(xy 78.361794 -32.193484) (xy 78.351456 -32.203605) (xy 78.336413 -32.2283) (xy 78.328902 -32.256224)
			(xy 78.329526 -32.285133) (xy 78.338234 -32.312707) (xy 78.354328 -32.33673) (xy 78.365096 -32.346392)
			(xy 78.3861 -32.364611) (xy 78.423101 -32.406114) (xy 78.453687 -32.452547) (xy 78.477212 -32.502926)
			(xy 78.493178 -32.556186) (xy 78.501246 -32.611199) (xy 78.501748 -32.639) (xy 78.501262 -32.666251)
			(xy 78.493506 -32.720199) (xy 78.478151 -32.772494) (xy 78.455509 -32.822071) (xy 78.426043 -32.867921)
			(xy 78.390352 -32.909112) (xy 78.349161 -32.944803) (xy 78.303311 -32.974269) (xy 78.253734 -32.996911)
			(xy 78.201439 -33.012266) (xy 78.147491 -33.020022) (xy 78.092989 -33.020022) (xy 78.039041 -33.012266)
			(xy 77.986746 -32.996911) (xy 77.937169 -32.974269) (xy 77.891319 -32.944803) (xy 77.850128 -32.909112)
			(xy 77.814437 -32.867921) (xy 77.784971 -32.822071) (xy 77.762329 -32.772494) (xy 77.746974 -32.720199)
			(xy 77.739218 -32.666251) (xy 77.738732 -32.639) (xy 77.73917 -32.61252) (xy 77.746484 -32.560067)
			(xy 77.760985 -32.509131) (xy 77.782394 -32.460691) (xy 77.8103 -32.41568) (xy 77.844165 -32.374962)
			(xy 77.863446 -32.356806) (xy 77.873789 -32.346692) (xy 77.888826 -32.321993) (xy 77.896332 -32.294069)
			(xy 77.895707 -32.26516) (xy 77.887 -32.237587) (xy 77.87091 -32.213562) (xy 77.860144 -32.203898)
			(xy 77.839123 -32.185698) (xy 77.802126 -32.144189) (xy 77.771544 -32.097752) (xy 77.748022 -32.047369)
			(xy 77.732059 -31.994107) (xy 77.723993 -31.939092) (xy 77.723492 -31.91129) (xy 77.72399 -31.882948)
			(xy 77.732378 -31.826888) (xy 77.748968 -31.772686) (xy 77.773395 -31.721535) (xy 77.805121 -31.674561)
			(xy 77.843448 -31.632798) (xy 77.887533 -31.597165) (xy 77.911706 -31.58236) (xy 77.9233 -31.575166)
			(xy 77.942369 -31.555659) (xy 77.955591 -31.531799) (xy 77.962021 -31.505289) (xy 77.9612 -31.478022)
			(xy 77.953186 -31.451947) (xy 77.938553 -31.428925) (xy 77.918344 -31.410601) (xy 77.906372 -31.404052)
			(xy 77.883184 -31.391791) (xy 77.840147 -31.361805) (xy 77.801627 -31.326203) (xy 77.76835 -31.285657)
			(xy 77.740944 -31.240932) (xy 77.719928 -31.192873) (xy 77.705698 -31.142387) (xy 77.698522 -31.090427)
			(xy 77.698092 -31.0642) (xy 76.65138 -31.0642) (xy 76.637064 -31.073399) (xy 76.587482 -31.096039)
			(xy 76.535182 -31.111392) (xy 76.481229 -31.119146) (xy 76.426723 -31.119143) (xy 76.372771 -31.111382)
			(xy 76.320473 -31.096022) (xy 76.270894 -31.073376) (xy 76.225042 -31.043904) (xy 76.183851 -31.008206)
			(xy 76.14816 -30.96701) (xy 76.118695 -30.921153) (xy 76.096057 -30.87157) (xy 76.080705 -30.81927)
			(xy 76.072953 -30.765317) (xy 76.072492 -30.738064) (xy 76.072574 -30.727053) (xy 76.073842 -30.705068)
			(xy 76.075032 -30.694122) (xy 76.076311 -30.679244) (xy 76.071063 -30.649857) (xy 76.057536 -30.623246)
			(xy 76.036888 -30.601688) (xy 76.010885 -30.587026) (xy 75.981752 -30.580516) (xy 75.966828 -30.581092)
			(xy 75.93965 -30.582108) (xy 75.912393 -30.581699) (xy 75.858432 -30.573947) (xy 75.806124 -30.558595)
			(xy 75.756533 -30.535955) (xy 75.71067 -30.506488) (xy 75.669466 -30.470793) (xy 75.633763 -30.429597)
			(xy 75.604285 -30.38374) (xy 75.581634 -30.334154) (xy 75.566271 -30.281849) (xy 75.558507 -30.227891)
			(xy 75.558503 -30.173376) (xy 75.32267 -30.173376) (xy 75.330049 -30.223514) (xy 75.330558 -30.2514)
			(xy 75.330049 -30.279286) (xy 75.321929 -30.334462) (xy 75.305861 -30.387869) (xy 75.282189 -30.438366)
			(xy 75.251416 -30.484879) (xy 75.214199 -30.526416) (xy 75.171331 -30.562091) (xy 75.123725 -30.591145)
			(xy 75.072396 -30.612957) (xy 75.018439 -30.627063) (xy 74.963002 -30.633163) (xy 74.907268 -30.631126)
			(xy 74.852425 -30.620996) (xy 74.799641 -30.602989) (xy 74.750041 -30.577488) (xy 74.704683 -30.545037)
			(xy 74.664534 -30.506328) (xy 74.630448 -30.462185) (xy 74.603152 -30.41355) (xy 74.583229 -30.361459)
			(xy 74.571103 -30.307022) (xy 74.567032 -30.2514) (xy 73.408992 -30.2514) (xy 73.446613 -30.282708)
			(xy 73.48383 -30.324245) (xy 73.514603 -30.370758) (xy 73.538275 -30.421255) (xy 73.554343 -30.474662)
			(xy 73.562463 -30.529838) (xy 73.562972 -30.557724) (xy 73.562463 -30.58561) (xy 73.554343 -30.640786)
			(xy 73.538275 -30.694193) (xy 73.514603 -30.74469) (xy 73.48383 -30.791203) (xy 73.446613 -30.83274)
			(xy 73.403745 -30.868415) (xy 73.356139 -30.897469) (xy 73.30481 -30.919281) (xy 73.250853 -30.933387)
			(xy 73.195416 -30.939487) (xy 73.139682 -30.93745) (xy 73.084839 -30.92732) (xy 73.032055 -30.909313)
			(xy 72.982455 -30.883812) (xy 72.937097 -30.851361) (xy 72.896948 -30.812652) (xy 72.862862 -30.768509)
			(xy 72.835566 -30.719874) (xy 72.815643 -30.667783) (xy 72.803517 -30.613346) (xy 72.799446 -30.557724)
			(xy 71.67626 -30.557724) (xy 71.67626 -32.057848) (xy 72.841102 -32.057848) (xy 72.845173 -32.002226)
			(xy 72.857299 -31.947789) (xy 72.877222 -31.895698) (xy 72.904518 -31.847063) (xy 72.938604 -31.80292)
			(xy 72.978753 -31.764211) (xy 73.024111 -31.73176) (xy 73.073711 -31.706259) (xy 73.126495 -31.688252)
			(xy 73.181338 -31.678122) (xy 73.237072 -31.676085) (xy 73.292509 -31.682185) (xy 73.346466 -31.696291)
			(xy 73.397795 -31.718103) (xy 73.445401 -31.747157) (xy 73.448817 -31.75) (xy 75.944982 -31.75) (xy 75.949053 -31.694378)
			(xy 75.961179 -31.639941) (xy 75.981102 -31.58785) (xy 76.008398 -31.539215) (xy 76.042484 -31.495072)
			(xy 76.082633 -31.456363) (xy 76.127991 -31.423912) (xy 76.177591 -31.398411) (xy 76.230375 -31.380404)
			(xy 76.285218 -31.370274) (xy 76.340952 -31.368237) (xy 76.396389 -31.374337) (xy 76.450346 -31.388443)
			(xy 76.501675 -31.410255) (xy 76.549281 -31.439309) (xy 76.592149 -31.474984) (xy 76.629366 -31.516521)
			(xy 76.660139 -31.563034) (xy 76.683811 -31.613531) (xy 76.699879 -31.666938) (xy 76.707999 -31.722114)
			(xy 76.708508 -31.75) (xy 76.707999 -31.777886) (xy 76.699879 -31.833062) (xy 76.683811 -31.886469)
			(xy 76.660139 -31.936966) (xy 76.629366 -31.983479) (xy 76.592149 -32.025016) (xy 76.549281 -32.060691)
			(xy 76.501675 -32.089745) (xy 76.450346 -32.111557) (xy 76.396389 -32.125663) (xy 76.340952 -32.131763)
			(xy 76.285218 -32.129726) (xy 76.230375 -32.119596) (xy 76.177591 -32.101589) (xy 76.127991 -32.076088)
			(xy 76.082633 -32.043637) (xy 76.042484 -32.004928) (xy 76.008398 -31.960785) (xy 75.981102 -31.91215)
			(xy 75.961179 -31.860059) (xy 75.949053 -31.805622) (xy 75.944982 -31.75) (xy 73.448817 -31.75) (xy 73.488269 -31.782832)
			(xy 73.525486 -31.824369) (xy 73.556259 -31.870882) (xy 73.579931 -31.921379) (xy 73.595999 -31.974786)
			(xy 73.604119 -32.029962) (xy 73.604628 -32.057848) (xy 73.604119 -32.085734) (xy 73.595999 -32.14091)
			(xy 73.579931 -32.194317) (xy 73.556259 -32.244814) (xy 73.525486 -32.291327) (xy 73.488269 -32.332864)
			(xy 73.445401 -32.368539) (xy 73.397795 -32.397593) (xy 73.346466 -32.419405) (xy 73.292509 -32.433511)
			(xy 73.237072 -32.439611) (xy 73.181338 -32.437574) (xy 73.126495 -32.427444) (xy 73.073711 -32.409437)
			(xy 73.024111 -32.383936) (xy 72.978753 -32.351485) (xy 72.938604 -32.312776) (xy 72.904518 -32.268633)
			(xy 72.877222 -32.219998) (xy 72.857299 -32.167907) (xy 72.845173 -32.11347) (xy 72.841102 -32.057848)
			(xy 71.67626 -32.057848) (xy 71.67626 -33.384466) (xy 72.719121 -33.384466) (xy 72.726876 -33.330509)
			(xy 72.742231 -33.278206) (xy 72.764873 -33.22862) (xy 72.794341 -33.182761) (xy 72.830036 -33.141563)
			(xy 72.871231 -33.105864) (xy 72.917087 -33.076391) (xy 72.966671 -33.053744) (xy 73.018973 -33.038384)
			(xy 73.072929 -33.030624) (xy 73.100184 -33.03016) (xy 73.1263 -33.03061) (xy 73.178043 -33.037754)
			(xy 73.203308 -33.044384) (xy 73.217107 -33.047851) (xy 73.245552 -33.047646) (xy 73.272838 -33.039604)
			(xy 73.296848 -33.02435) (xy 73.31572 -33.003065) (xy 73.327991 -32.977402) (xy 73.332709 -32.94935)
			(xy 73.331578 -32.935164) (xy 73.330497 -32.924657) (xy 73.329351 -32.903563) (xy 73.329292 -32.893)
			(xy 73.329778 -32.865749) (xy 73.337534 -32.811801) (xy 73.352889 -32.759506) (xy 73.375531 -32.709929)
			(xy 73.404997 -32.664079) (xy 73.440688 -32.622888) (xy 73.481879 -32.587197) (xy 73.527729 -32.557731)
			(xy 73.577306 -32.535089) (xy 73.629601 -32.519734) (xy 73.683549 -32.511978) (xy 73.738051 -32.511978)
			(xy 73.791999 -32.519734) (xy 73.844294 -32.535089) (xy 73.893871 -32.557731) (xy 73.939721 -32.587197)
			(xy 73.980912 -32.622888) (xy 74.016603 -32.664079) (xy 74.046069 -32.709929) (xy 74.048476 -32.7152)
			(xy 74.344782 -32.7152) (xy 74.348853 -32.659578) (xy 74.360979 -32.605141) (xy 74.380902 -32.55305)
			(xy 74.408198 -32.504415) (xy 74.442284 -32.460272) (xy 74.482433 -32.421563) (xy 74.527791 -32.389112)
			(xy 74.577391 -32.363611) (xy 74.630175 -32.345604) (xy 74.685018 -32.335474) (xy 74.740752 -32.333437)
			(xy 74.796189 -32.339537) (xy 74.850146 -32.353643) (xy 74.901475 -32.375455) (xy 74.949081 -32.404509)
			(xy 74.991949 -32.440184) (xy 75.029166 -32.481721) (xy 75.059939 -32.528234) (xy 75.083611 -32.578731)
			(xy 75.099679 -32.632138) (xy 75.107799 -32.687314) (xy 75.108308 -32.7152) (xy 75.107799 -32.743086)
			(xy 75.099679 -32.798262) (xy 75.083611 -32.851669) (xy 75.059939 -32.902166) (xy 75.029166 -32.948679)
			(xy 74.991949 -32.990216) (xy 74.986681 -32.9946) (xy 76.071982 -32.9946) (xy 76.076053 -32.938978)
			(xy 76.088179 -32.884541) (xy 76.108102 -32.83245) (xy 76.135398 -32.783815) (xy 76.169484 -32.739672)
			(xy 76.209633 -32.700963) (xy 76.254991 -32.668512) (xy 76.304591 -32.643011) (xy 76.357375 -32.625004)
			(xy 76.412218 -32.614874) (xy 76.467952 -32.612837) (xy 76.523389 -32.618937) (xy 76.577346 -32.633043)
			(xy 76.628675 -32.654855) (xy 76.676281 -32.683909) (xy 76.719149 -32.719584) (xy 76.756366 -32.761121)
			(xy 76.787139 -32.807634) (xy 76.810811 -32.858131) (xy 76.826879 -32.911538) (xy 76.834999 -32.966714)
			(xy 76.835508 -32.9946) (xy 76.834999 -33.022486) (xy 76.826879 -33.077662) (xy 76.810811 -33.131069)
			(xy 76.787139 -33.181566) (xy 76.756366 -33.228079) (xy 76.719149 -33.269616) (xy 76.676281 -33.305291)
			(xy 76.628675 -33.334345) (xy 76.577346 -33.356157) (xy 76.523389 -33.370263) (xy 76.467952 -33.376363)
			(xy 76.412218 -33.374326) (xy 76.357375 -33.364196) (xy 76.304591 -33.346189) (xy 76.254991 -33.320688)
			(xy 76.209633 -33.288237) (xy 76.169484 -33.249528) (xy 76.135398 -33.205385) (xy 76.108102 -33.15675)
			(xy 76.088179 -33.104659) (xy 76.076053 -33.050222) (xy 76.071982 -32.9946) (xy 74.986681 -32.9946)
			(xy 74.949081 -33.025891) (xy 74.901475 -33.054945) (xy 74.850146 -33.076757) (xy 74.796189 -33.090863)
			(xy 74.740752 -33.096963) (xy 74.685018 -33.094926) (xy 74.630175 -33.084796) (xy 74.577391 -33.066789)
			(xy 74.527791 -33.041288) (xy 74.482433 -33.008837) (xy 74.442284 -32.970128) (xy 74.408198 -32.925985)
			(xy 74.380902 -32.87735) (xy 74.360979 -32.825259) (xy 74.348853 -32.770822) (xy 74.344782 -32.7152)
			(xy 74.048476 -32.7152) (xy 74.068711 -32.759506) (xy 74.084066 -32.811801) (xy 74.091822 -32.865749)
			(xy 74.091822 -32.920251) (xy 74.084066 -32.974199) (xy 74.068711 -33.026494) (xy 74.046069 -33.076071)
			(xy 74.016603 -33.121921) (xy 73.980912 -33.163112) (xy 73.939721 -33.198803) (xy 73.893871 -33.228269)
			(xy 73.844294 -33.250911) (xy 73.791999 -33.266266) (xy 73.738051 -33.274022) (xy 73.7108 -33.274508)
			(xy 73.684684 -33.274038) (xy 73.632942 -33.266907) (xy 73.607676 -33.260284) (xy 73.59385 -33.256945)
			(xy 73.565422 -33.257132) (xy 73.538148 -33.265153) (xy 73.514145 -33.280386) (xy 73.495275 -33.301649)
			(xy 73.483002 -33.327293) (xy 73.478279 -33.355326) (xy 73.479406 -33.369504) (xy 73.480493 -33.380011)
			(xy 73.481635 -33.401105) (xy 73.481692 -33.411668) (xy 73.481279 -33.438923) (xy 73.473526 -33.49288)
			(xy 73.458173 -33.545184) (xy 73.435532 -33.594771) (xy 73.406065 -33.64063) (xy 73.370371 -33.68183)
			(xy 73.329177 -33.71753) (xy 73.283322 -33.747004) (xy 73.233739 -33.769652) (xy 73.181437 -33.785014)
			(xy 73.127482 -33.792775) (xy 73.072971 -33.792779) (xy 73.019015 -33.785025) (xy 72.966711 -33.769671)
			(xy 72.917125 -33.74703) (xy 72.871265 -33.717562) (xy 72.830066 -33.681867) (xy 72.794367 -33.640673)
			(xy 72.764893 -33.594818) (xy 72.742246 -33.545234) (xy 72.726885 -33.492932) (xy 72.719124 -33.438977)
			(xy 72.719121 -33.384466) (xy 71.67626 -33.384466) (xy 71.67626 -34.102802) (xy 71.96074 -34.387282)
			(xy 76.323444 -34.387282)
		)
		(stroke
			(width 0)
			(type solid)
		)
		(fill yes)
		(layer "In4.Cu")
		(net "P3V3_AUX")
	)
	(gr_poly
		(pts
			(xy 7.3152 -80.256888) (xy 7.328818 -80.256414) (xy 7.355067 -80.249139) (xy 7.378462 -80.235187)
			(xy 7.397338 -80.215549) (xy 7.410354 -80.191622) (xy 7.416585 -80.165105) (xy 7.416546 -80.151478)
			(xy 7.416292 -80.137) (xy 7.416778 -80.109749) (xy 7.424534 -80.055801) (xy 7.439889 -80.003506)
			(xy 7.462531 -79.953929) (xy 7.491997 -79.908079) (xy 7.527688 -79.866888) (xy 7.568879 -79.831197)
			(xy 7.614729 -79.801731) (xy 7.664306 -79.779089) (xy 7.716601 -79.763734) (xy 7.770549 -79.755978)
			(xy 7.825051 -79.755978) (xy 7.878999 -79.763734) (xy 7.931294 -79.779089) (xy 7.980871 -79.801731)
			(xy 8.026721 -79.831197) (xy 8.067912 -79.866888) (xy 8.103603 -79.908079) (xy 8.133069 -79.953929)
			(xy 8.155711 -80.003506) (xy 8.171066 -80.055801) (xy 8.178822 -80.109749) (xy 8.179308 -80.137)
			(xy 8.179054 -80.151478) (xy 8.178978 -80.165107) (xy 8.185195 -80.191632) (xy 8.198213 -80.215565)
			(xy 8.217102 -80.235198) (xy 8.240514 -80.24913) (xy 8.266779 -80.256368) (xy 8.2804 -80.256888)
			(xy 9.056624 -80.256888) (xy 9.477756 -79.835756) (xy 9.493727 -79.820339) (xy 9.529617 -79.79422)
			(xy 9.569155 -79.774044) (xy 9.611365 -79.76031) (xy 9.655206 -79.753358) (xy 9.6774 -79.752952)
			(xy 11.3538 -79.752952) (xy 11.37599 -79.753408) (xy 11.419818 -79.760384) (xy 11.46202 -79.774116)
			(xy 11.501561 -79.794269) (xy 11.53747 -79.820349) (xy 11.553444 -79.835756) (xy 11.705844 -79.988156)
			(xy 11.990832 -79.702914) (xy 11.990832 -79.645256) (xy 11.964211 -79.640619) (xy 11.912536 -79.624824)
			(xy 11.863606 -79.601895) (xy 11.818401 -79.572291) (xy 11.777826 -79.536606) (xy 11.742691 -79.495552)
			(xy 11.713701 -79.449951) (xy 11.691435 -79.400717) (xy 11.676339 -79.348833) (xy 11.668715 -79.295338)
			(xy 11.668715 -79.241302) (xy 11.676339 -79.187807) (xy 11.691435 -79.135923) (xy 11.713701 -79.086689)
			(xy 11.742691 -79.041088) (xy 11.777826 -79.000034) (xy 11.818401 -78.964349) (xy 11.863606 -78.934745)
			(xy 11.912536 -78.911816) (xy 11.964211 -78.896021) (xy 11.990832 -78.891384) (xy 11.990832 -78.78445)
			(xy 11.964211 -78.779813) (xy 11.912535 -78.764018) (xy 11.863605 -78.741089) (xy 11.818399 -78.711485)
			(xy 11.777823 -78.675799) (xy 11.742689 -78.634745) (xy 11.713698 -78.589144) (xy 11.691432 -78.539909)
			(xy 11.676335 -78.488024) (xy 11.668711 -78.434529) (xy 11.668711 -78.380493) (xy 11.676335 -78.326997)
			(xy 11.691431 -78.275113) (xy 11.713697 -78.225877) (xy 11.742688 -78.180276) (xy 11.777823 -78.139222)
			(xy 11.818398 -78.103536) (xy 11.863604 -78.073932) (xy 11.912534 -78.051003) (xy 11.964209 -78.035207)
			(xy 11.990832 -78.030578) (xy 11.990832 -77.652118) (xy 11.952986 -77.642212) (xy 11.926153 -77.634654)
			(xy 11.874859 -77.612823) (xy 11.82729 -77.583758) (xy 11.784457 -77.54808) (xy 11.747273 -77.506547)
			(xy 11.71653 -77.460044) (xy 11.692883 -77.409562) (xy 11.676836 -77.356176) (xy 11.668729 -77.301023)
			(xy 11.668252 -77.27315) (xy 11.668731 -77.245711) (xy 11.676599 -77.191399) (xy 11.692164 -77.138774)
			(xy 11.715107 -77.088922) (xy 11.744953 -77.042869) (xy 11.781088 -77.001566) (xy 11.801602 -76.983336)
			(xy 11.812379 -76.973446) (xy 11.828254 -76.948892) (xy 11.836535 -76.92085) (xy 11.836544 -76.891611)
			(xy 11.82828 -76.863564) (xy 11.812419 -76.839001) (xy 11.801602 -76.829158) (xy 11.781068 -76.810949)
			(xy 11.744927 -76.769648) (xy 11.71508 -76.723593) (xy 11.692143 -76.673734) (xy 11.676592 -76.621102)
			(xy 11.668746 -76.566785) (xy 11.668252 -76.539344) (xy 11.668763 -76.511476) (xy 11.676881 -76.456333)
			(xy 11.692935 -76.402958) (xy 11.716585 -76.352487) (xy 11.747326 -76.305994) (xy 11.784505 -76.264469)
			(xy 11.82733 -76.228794) (xy 11.87489 -76.199731) (xy 11.926172 -76.177896) (xy 11.952986 -76.170282)
			(xy 11.990832 -76.160376) (xy 11.990832 -70.860412) (xy 11.9904 -70.846718) (xy 11.983136 -70.820312)
			(xy 11.969103 -70.796795) (xy 11.949313 -70.777863) (xy 11.925197 -70.764885) (xy 11.898495 -70.758798)
			(xy 11.871137 -70.760041) (xy 11.85799 -70.763892) (xy 11.829257 -70.772679) (xy 11.769921 -70.782121)
			(xy 11.73988 -70.782688) (xy 11.712631 -70.7822) (xy 11.658688 -70.774442) (xy 11.606399 -70.759086)
			(xy 11.556827 -70.736445) (xy 11.510981 -70.70698) (xy 11.469796 -70.67129) (xy 11.434108 -70.630103)
			(xy 11.404646 -70.584256) (xy 11.382007 -70.534682) (xy 11.366654 -70.482392) (xy 11.358898 -70.428449)
			(xy 11.358898 -70.373951) (xy 11.366654 -70.320008) (xy 11.382007 -70.267718) (xy 11.404646 -70.218144)
			(xy 11.434108 -70.172297) (xy 11.469796 -70.13111) (xy 11.510981 -70.09542) (xy 11.556827 -70.065955)
			(xy 11.606399 -70.043314) (xy 11.658688 -70.027958) (xy 11.712631 -70.0202) (xy 11.73988 -70.019672)
			(xy 11.769917 -70.020289) (xy 11.829244 -70.029737) (xy 11.85799 -70.038468) (xy 11.871145 -70.042246)
			(xy 11.898477 -70.043432) (xy 11.925144 -70.037322) (xy 11.949234 -70.024353) (xy 11.969017 -70.005456)
			(xy 11.983075 -69.981986) (xy 11.990401 -69.955626) (xy 11.990832 -69.941948) (xy 11.990832 -67.362832)
			(xy 11.0744 -66.4464) (xy 11.0744 -59.0296) (xy 8.16356 -56.11876) (xy 8.16356 -51.58994) (xy 8.71728 -51.03622)
			(xy 9.64184 -51.03622) (xy 10.65784 -50.02022) (xy 10.65784 -48.598074) (xy 10.665968 -48.589946)
			(xy 10.668 -48.571912) (xy 10.671652 -48.540032) (xy 10.685278 -48.477325) (xy 10.70596 -48.416579)
			(xy 10.733427 -48.358585) (xy 10.767323 -48.304097) (xy 10.807205 -48.253826) (xy 10.829544 -48.23079)
			(xy 13.659612 -45.400722) (xy 13.659612 -33.291272) (xy 13.539216 -33.170876) (xy 13.503656 -33.198562)
			(xy 13.483433 -33.213925) (xy 13.439691 -33.239733) (xy 13.392913 -33.25951) (xy 13.343924 -33.272905)
			(xy 13.293591 -33.279683) (xy 13.268198 -33.280096) (xy 13.238052 -33.279525) (xy 13.17851 -33.270041)
			(xy 13.121201 -33.25131) (xy 13.067551 -33.223797) (xy 13.0429 -33.206436) (xy 13.030598 -33.19809)
			(xy 13.002571 -33.188218) (xy 12.972889 -33.186828) (xy 12.944062 -33.194037) (xy 12.918528 -33.209235)
			(xy 12.898448 -33.231138) (xy 12.885518 -33.257892) (xy 12.882626 -33.272476) (xy 12.877923 -33.299025)
			(xy 12.862024 -33.350543) (xy 12.839032 -33.399311) (xy 12.809404 -33.444357) (xy 12.77373 -33.484784)
			(xy 12.73272 -33.519786) (xy 12.687192 -33.548668) (xy 12.638052 -33.570853) (xy 12.586278 -33.5859)
			(xy 12.532902 -33.59351) (xy 12.505944 -33.59404) (xy 12.478688 -33.59358) (xy 12.424731 -33.585828)
			(xy 12.372426 -33.570477) (xy 12.322838 -33.547837) (xy 12.276977 -33.518371) (xy 12.235776 -33.482677)
			(xy 12.200075 -33.441484) (xy 12.170599 -33.395629) (xy 12.14795 -33.346046) (xy 12.132588 -33.293744)
			(xy 12.124825 -33.239788) (xy 12.124436 -33.212532) (xy 12.124968 -33.183615) (xy 12.133691 -33.126442)
			(xy 12.150943 -33.07124) (xy 12.176328 -33.019274) (xy 12.209265 -32.971734) (xy 12.248999 -32.92971)
			(xy 12.271502 -32.911542) (xy 12.283311 -32.901644) (xy 12.300835 -32.876317) (xy 12.310017 -32.846919)
			(xy 12.310023 -32.81612) (xy 12.300852 -32.786719) (xy 12.283338 -32.761385) (xy 12.271502 -32.751522)
			(xy 12.249019 -32.733331) (xy 12.209282 -32.691314) (xy 12.176344 -32.643779) (xy 12.150959 -32.591817)
			(xy 12.133709 -32.536618) (xy 12.124989 -32.479448) (xy 12.124436 -32.450532) (xy 12.124789 -32.427363)
			(xy 12.130433 -32.38137) (xy 12.141617 -32.336401) (xy 12.149582 -32.314642) (xy 12.154194 -32.30134)
			(xy 12.156704 -32.273308) (xy 12.151468 -32.245655) (xy 12.138884 -32.220482) (xy 12.119906 -32.1997)
			(xy 12.095976 -32.184886) (xy 12.068911 -32.177167) (xy 12.05484 -32.17672) (xy 10.798048 -32.17672)
			(xy 10.783994 -32.177217) (xy 10.756973 -32.184969) (xy 10.733086 -32.199789) (xy 10.71414 -32.220556)
			(xy 10.701569 -32.245699) (xy 10.696323 -32.273316) (xy 10.698799 -32.301318) (xy 10.703306 -32.314642)
			(xy 10.711254 -32.336407) (xy 10.722429 -32.381375) (xy 10.728086 -32.427364) (xy 10.728452 -32.450532)
			(xy 10.727915 -32.479447) (xy 10.719184 -32.536614) (xy 10.701925 -32.591809) (xy 10.676534 -32.643768)
			(xy 10.643593 -32.691299) (xy 10.603856 -32.733315) (xy 10.581386 -32.751522) (xy 10.569588 -32.761421)
			(xy 10.552085 -32.786742) (xy 10.54292 -32.816128) (xy 10.542926 -32.846911) (xy 10.552102 -32.876293)
			(xy 10.569616 -32.901608) (xy 10.581386 -32.911542) (xy 10.603872 -32.929731) (xy 10.643613 -32.971748)
			(xy 10.676557 -33.019282) (xy 10.701948 -33.071244) (xy 10.719203 -33.126443) (xy 10.727929 -33.183615)
			(xy 10.728452 -33.212532) (xy 10.727966 -33.239783) (xy 10.72021 -33.293731) (xy 10.704855 -33.346026)
			(xy 10.682213 -33.395603) (xy 10.652747 -33.441453) (xy 10.617056 -33.482644) (xy 10.575865 -33.518335)
			(xy 10.530015 -33.547801) (xy 10.480438 -33.570443) (xy 10.428143 -33.585798) (xy 10.374195 -33.593554)
			(xy 10.319693 -33.593554) (xy 10.265745 -33.585798) (xy 10.21345 -33.570443) (xy 10.163873 -33.547801)
			(xy 10.118023 -33.518335) (xy 10.076832 -33.482644) (xy 10.041141 -33.441453) (xy 10.011675 -33.395603)
			(xy 9.989033 -33.346026) (xy 9.973678 -33.293731) (xy 9.965922 -33.239783) (xy 9.965436 -33.212532)
			(xy 9.965968 -33.183615) (xy 9.974691 -33.126442) (xy 9.991943 -33.07124) (xy 10.017328 -33.019274)
			(xy 10.050265 -32.971734) (xy 10.089999 -32.92971) (xy 10.112502 -32.911542) (xy 10.124311 -32.901644)
			(xy 10.141835 -32.876317) (xy 10.151017 -32.846919) (xy 10.151023 -32.81612) (xy 10.141852 -32.786719)
			(xy 10.124338 -32.761385) (xy 10.112502 -32.751522) (xy 10.090019 -32.733331) (xy 10.050282 -32.691314)
			(xy 10.017344 -32.643779) (xy 9.991959 -32.591817) (xy 9.974709 -32.536618) (xy 9.965989 -32.479448)
			(xy 9.965436 -32.450532) (xy 9.965789 -32.427363) (xy 9.971433 -32.38137) (xy 9.982617 -32.336401)
			(xy 9.990582 -32.314642) (xy 9.995194 -32.30134) (xy 9.997704 -32.273308) (xy 9.992468 -32.245655)
			(xy 9.979884 -32.220482) (xy 9.960906 -32.1997) (xy 9.936976 -32.184886) (xy 9.909911 -32.177167)
			(xy 9.89584 -32.17672) (xy 8.639048 -32.17672) (xy 8.624994 -32.177217) (xy 8.597973 -32.184969)
			(xy 8.574086 -32.199789) (xy 8.55514 -32.220556) (xy 8.542569 -32.245699) (xy 8.537323 -32.273316)
			(xy 8.539799 -32.301318) (xy 8.544306 -32.314642) (xy 8.552254 -32.336407) (xy 8.563429 -32.381375)
			(xy 8.569086 -32.427364) (xy 8.569452 -32.450532) (xy 8.568915 -32.479447) (xy 8.560184 -32.536614)
			(xy 8.542925 -32.591809) (xy 8.517534 -32.643768) (xy 8.484593 -32.691299) (xy 8.444856 -32.733315)
			(xy 8.422386 -32.751522) (xy 8.410588 -32.761421) (xy 8.393085 -32.786742) (xy 8.38392 -32.816128)
			(xy 8.383926 -32.846911) (xy 8.393102 -32.876293) (xy 8.410616 -32.901608) (xy 8.422386 -32.911542)
			(xy 8.444872 -32.929731) (xy 8.484613 -32.971748) (xy 8.517557 -33.019282) (xy 8.542948 -33.071244)
			(xy 8.560203 -33.126443) (xy 8.568929 -33.183615) (xy 8.569452 -33.212532) (xy 8.568966 -33.239783)
			(xy 8.56121 -33.293731) (xy 8.545855 -33.346026) (xy 8.523213 -33.395603) (xy 8.493747 -33.441453)
			(xy 8.458056 -33.482644) (xy 8.416865 -33.518335) (xy 8.371015 -33.547801) (xy 8.321438 -33.570443)
			(xy 8.269143 -33.585798) (xy 8.215195 -33.593554) (xy 8.160693 -33.593554) (xy 8.106745 -33.585798)
			(xy 8.05445 -33.570443) (xy 8.004873 -33.547801) (xy 7.959023 -33.518335) (xy 7.917832 -33.482644)
			(xy 7.882141 -33.441453) (xy 7.852675 -33.395603) (xy 7.830033 -33.346026) (xy 7.814678 -33.293731)
			(xy 7.806922 -33.239783) (xy 7.806436 -33.212532) (xy 7.806968 -33.183615) (xy 7.815691 -33.126442)
			(xy 7.832943 -33.07124) (xy 7.858328 -33.019274) (xy 7.891265 -32.971734) (xy 7.930999 -32.92971)
			(xy 7.953502 -32.911542) (xy 7.965311 -32.901644) (xy 7.982835 -32.876317) (xy 7.992017 -32.846919)
			(xy 7.992023 -32.81612) (xy 7.982852 -32.786719) (xy 7.965338 -32.761385) (xy 7.953502 -32.751522)
			(xy 7.931019 -32.733331) (xy 7.891282 -32.691314) (xy 7.858344 -32.643779) (xy 7.832959 -32.591817)
			(xy 7.815709 -32.536618) (xy 7.806989 -32.479448) (xy 7.806436 -32.450532) (xy 7.806789 -32.427363)
			(xy 7.812433 -32.38137) (xy 7.823617 -32.336401) (xy 7.831582 -32.314642) (xy 7.836194 -32.30134)
			(xy 7.838704 -32.273308) (xy 7.833468 -32.245655) (xy 7.820884 -32.220482) (xy 7.801906 -32.1997)
			(xy 7.777976 -32.184886) (xy 7.750911 -32.177167) (xy 7.73684 -32.17672) (xy 6.480048 -32.17672)
			(xy 6.465994 -32.177217) (xy 6.438973 -32.184969) (xy 6.415086 -32.199789) (xy 6.39614 -32.220556)
			(xy 6.383569 -32.245699) (xy 6.378323 -32.273316) (xy 6.380799 -32.301318) (xy 6.385306 -32.314642)
			(xy 6.393254 -32.336407) (xy 6.404429 -32.381375) (xy 6.410086 -32.427364) (xy 6.410452 -32.450532)
			(xy 6.409915 -32.479447) (xy 6.401184 -32.536614) (xy 6.383925 -32.591809) (xy 6.358534 -32.643768)
			(xy 6.325593 -32.691299) (xy 6.285856 -32.733315) (xy 6.263386 -32.751522) (xy 6.251588 -32.761421)
			(xy 6.234085 -32.786742) (xy 6.22492 -32.816128) (xy 6.224926 -32.846911) (xy 6.234102 -32.876293)
			(xy 6.251616 -32.901608) (xy 6.263386 -32.911542) (xy 6.285872 -32.929731) (xy 6.325613 -32.971748)
			(xy 6.358557 -33.019282) (xy 6.383948 -33.071244) (xy 6.401203 -33.126443) (xy 6.409929 -33.183615)
			(xy 6.410452 -33.212532) (xy 6.409966 -33.239783) (xy 6.40221 -33.293731) (xy 6.386855 -33.346026)
			(xy 6.364213 -33.395603) (xy 6.334747 -33.441453) (xy 6.299056 -33.482644) (xy 6.257865 -33.518335)
			(xy 6.212015 -33.547801) (xy 6.162438 -33.570443) (xy 6.110143 -33.585798) (xy 6.056195 -33.593554)
			(xy 6.001693 -33.593554) (xy 5.947745 -33.585798) (xy 5.89545 -33.570443) (xy 5.845873 -33.547801)
			(xy 5.800023 -33.518335) (xy 5.758832 -33.482644) (xy 5.723141 -33.441453) (xy 5.693675 -33.395603)
			(xy 5.671033 -33.346026) (xy 5.655678 -33.293731) (xy 5.647922 -33.239783) (xy 5.647436 -33.212532)
			(xy 5.647971 -33.183616) (xy 5.656701 -33.126447) (xy 5.673958 -33.07125) (xy 5.699347 -33.019289)
			(xy 5.732286 -32.971755) (xy 5.772021 -32.929736) (xy 5.794502 -32.911542) (xy 5.806311 -32.901644)
			(xy 5.823835 -32.876317) (xy 5.833017 -32.846919) (xy 5.833023 -32.81612) (xy 5.823852 -32.786719)
			(xy 5.806338 -32.761385) (xy 5.794502 -32.751522) (xy 5.772019 -32.733331) (xy 5.732282 -32.691314)
			(xy 5.699344 -32.643779) (xy 5.673959 -32.591817) (xy 5.656709 -32.536618) (xy 5.647989 -32.479448)
			(xy 5.647436 -32.450532) (xy 5.647789 -32.427363) (xy 5.653433 -32.38137) (xy 5.664617 -32.336401)
			(xy 5.672582 -32.314642) (xy 5.677194 -32.30134) (xy 5.679704 -32.273308) (xy 5.674468 -32.245655)
			(xy 5.661884 -32.220482) (xy 5.642906 -32.1997) (xy 5.618976 -32.184886) (xy 5.591911 -32.177167)
			(xy 5.57784 -32.17672) (xy 5.176774 -32.17672) (xy 3.866134 -33.48736) (xy 3.866134 -47.60468) (xy 4.469382 -47.60468)
			(xy 4.473453 -47.549058) (xy 4.485579 -47.494621) (xy 4.505502 -47.44253) (xy 4.532798 -47.393895)
			(xy 4.566884 -47.349752) (xy 4.607033 -47.311043) (xy 4.652391 -47.278592) (xy 4.701991 -47.253091)
			(xy 4.754775 -47.235084) (xy 4.809618 -47.224954) (xy 4.865352 -47.222917) (xy 4.920789 -47.229017)
			(xy 4.974746 -47.243123) (xy 5.026075 -47.264935) (xy 5.073681 -47.293989) (xy 5.116549 -47.329664)
			(xy 5.153766 -47.371201) (xy 5.184539 -47.417714) (xy 5.208211 -47.468211) (xy 5.224279 -47.521618)
			(xy 5.232399 -47.576794) (xy 5.232908 -47.60468) (xy 5.232399 -47.632566) (xy 5.224279 -47.687742)
			(xy 5.208211 -47.741149) (xy 5.184539 -47.791646) (xy 5.153766 -47.838159) (xy 5.116549 -47.879696)
			(xy 5.073681 -47.915371) (xy 5.026075 -47.944425) (xy 4.974746 -47.966237) (xy 4.920789 -47.980343)
			(xy 4.865352 -47.986443) (xy 4.809618 -47.984406) (xy 4.754775 -47.974276) (xy 4.701991 -47.956269)
			(xy 4.652391 -47.930768) (xy 4.607033 -47.898317) (xy 4.566884 -47.859608) (xy 4.532798 -47.815465)
			(xy 4.505502 -47.76683) (xy 4.485579 -47.714739) (xy 4.473453 -47.660302) (xy 4.469382 -47.60468)
			(xy 3.866134 -47.60468) (xy 3.866134 -49.78146) (xy 9.627614 -49.78146) (xy 9.631685 -49.725838)
			(xy 9.643811 -49.671401) (xy 9.663734 -49.61931) (xy 9.69103 -49.570675) (xy 9.725116 -49.526532)
			(xy 9.765265 -49.487823) (xy 9.810623 -49.455372) (xy 9.860223 -49.429871) (xy 9.913007 -49.411864)
			(xy 9.96785 -49.401734) (xy 10.023584 -49.399697) (xy 10.079021 -49.405797) (xy 10.132978 -49.419903)
			(xy 10.184307 -49.441715) (xy 10.231913 -49.470769) (xy 10.274781 -49.506444) (xy 10.311998 -49.547981)
			(xy 10.342771 -49.594494) (xy 10.366443 -49.644991) (xy 10.382511 -49.698398) (xy 10.390631 -49.753574)
			(xy 10.39114 -49.78146) (xy 10.390631 -49.809346) (xy 10.382511 -49.864522) (xy 10.366443 -49.917929)
			(xy 10.342771 -49.968426) (xy 10.311998 -50.014939) (xy 10.274781 -50.056476) (xy 10.231913 -50.092151)
			(xy 10.184307 -50.121205) (xy 10.132978 -50.143017) (xy 10.079021 -50.157123) (xy 10.023584 -50.163223)
			(xy 9.96785 -50.161186) (xy 9.913007 -50.151056) (xy 9.860223 -50.133049) (xy 9.810623 -50.107548)
			(xy 9.765265 -50.075097) (xy 9.725116 -50.036388) (xy 9.69103 -49.992245) (xy 9.663734 -49.94361)
			(xy 9.643811 -49.891519) (xy 9.631685 -49.837082) (xy 9.627614 -49.78146) (xy 3.866134 -49.78146)
			(xy 3.866134 -56.164734) (xy 4.191 -56.4896) (xy 5.6134 -56.4896) (xy 5.8674 -56.7436) (xy 5.8674 -58.0136)
			(xy 5.5626 -58.3184) (xy 4.374134 -58.3184) (xy 3.866134 -58.8264) (xy 3.866134 -61.2648) (xy 8.660892 -61.2648)
			(xy 8.661375 -61.235881) (xy 8.670107 -61.178707) (xy 8.687369 -61.123506) (xy 8.712767 -61.071544)
			(xy 8.745719 -61.024011) (xy 8.785468 -60.981997) (xy 8.807958 -60.96381) (xy 8.819766 -60.953914)
			(xy 8.837288 -60.928591) (xy 8.846467 -60.899197) (xy 8.846467 -60.868403) (xy 8.837288 -60.839009)
			(xy 8.819766 -60.813686) (xy 8.807958 -60.80379) (xy 8.785461 -60.785615) (xy 8.745729 -60.743591)
			(xy 8.712792 -60.696052) (xy 8.687407 -60.644088) (xy 8.670153 -60.588888) (xy 8.661426 -60.531717)
			(xy 8.660892 -60.5028) (xy 8.661378 -60.475549) (xy 8.669134 -60.421601) (xy 8.684489 -60.369306)
			(xy 8.707131 -60.319729) (xy 8.736597 -60.273879) (xy 8.772288 -60.232688) (xy 8.813479 -60.196997)
			(xy 8.859329 -60.167531) (xy 8.908906 -60.144889) (xy 8.961201 -60.129534) (xy 9.015149 -60.121778)
			(xy 9.069651 -60.121778) (xy 9.123599 -60.129534) (xy 9.175894 -60.144889) (xy 9.225471 -60.167531)
			(xy 9.271321 -60.196997) (xy 9.312512 -60.232688) (xy 9.348203 -60.273879) (xy 9.377669 -60.319729)
			(xy 9.400311 -60.369306) (xy 9.415666 -60.421601) (xy 9.423422 -60.475549) (xy 9.423908 -60.5028)
			(xy 9.423425 -60.531719) (xy 9.414693 -60.588893) (xy 9.397431 -60.644094) (xy 9.372033 -60.696056)
			(xy 9.339081 -60.743589) (xy 9.299332 -60.785603) (xy 9.276842 -60.80379) (xy 9.265034 -60.813686)
			(xy 9.247512 -60.839009) (xy 9.238333 -60.868403) (xy 9.238333 -60.899197) (xy 9.247512 -60.928591)
			(xy 9.265034 -60.953914) (xy 9.276842 -60.96381) (xy 9.299339 -60.981985) (xy 9.339071 -61.024009)
			(xy 9.372008 -61.071548) (xy 9.397393 -61.123512) (xy 9.414647 -61.178712) (xy 9.423374 -61.235883)
			(xy 9.423908 -61.2648) (xy 9.423422 -61.292051) (xy 9.415666 -61.345999) (xy 9.400311 -61.398294)
			(xy 9.377669 -61.447871) (xy 9.348203 -61.493721) (xy 9.312512 -61.534912) (xy 9.271321 -61.570603)
			(xy 9.225471 -61.600069) (xy 9.175894 -61.622711) (xy 9.123599 -61.638066) (xy 9.069651 -61.645822)
			(xy 9.015149 -61.645822) (xy 8.961201 -61.638066) (xy 8.908906 -61.622711) (xy 8.859329 -61.600069)
			(xy 8.813479 -61.570603) (xy 8.772288 -61.534912) (xy 8.736597 -61.493721) (xy 8.707131 -61.447871)
			(xy 8.684489 -61.398294) (xy 8.669134 -61.345999) (xy 8.661378 -61.292051) (xy 8.660892 -61.2648)
			(xy 3.866134 -61.2648) (xy 3.866134 -63.2206) (xy 10.057382 -63.2206) (xy 10.061453 -63.164978) (xy 10.073579 -63.110541)
			(xy 10.093502 -63.05845) (xy 10.120798 -63.009815) (xy 10.154884 -62.965672) (xy 10.195033 -62.926963)
			(xy 10.240391 -62.894512) (xy 10.289991 -62.869011) (xy 10.342775 -62.851004) (xy 10.397618 -62.840874)
			(xy 10.453352 -62.838837) (xy 10.508789 -62.844937) (xy 10.562746 -62.859043) (xy 10.614075 -62.880855)
			(xy 10.661681 -62.909909) (xy 10.704549 -62.945584) (xy 10.741766 -62.987121) (xy 10.772539 -63.033634)
			(xy 10.796211 -63.084131) (xy 10.812279 -63.137538) (xy 10.820399 -63.192714) (xy 10.820908 -63.2206)
			(xy 10.820399 -63.248486) (xy 10.812279 -63.303662) (xy 10.796211 -63.357069) (xy 10.772539 -63.407566)
			(xy 10.741766 -63.454079) (xy 10.704549 -63.495616) (xy 10.661681 -63.531291) (xy 10.614075 -63.560345)
			(xy 10.562746 -63.582157) (xy 10.508789 -63.596263) (xy 10.453352 -63.602363) (xy 10.397618 -63.600326)
			(xy 10.342775 -63.590196) (xy 10.289991 -63.572189) (xy 10.240391 -63.546688) (xy 10.195033 -63.514237)
			(xy 10.154884 -63.475528) (xy 10.120798 -63.431385) (xy 10.093502 -63.38275) (xy 10.073579 -63.330659)
			(xy 10.061453 -63.276222) (xy 10.057382 -63.2206) (xy 3.866134 -63.2206) (xy 3.866134 -63.733934)
			(xy 4.75996 -64.62776) (xy 4.75996 -65.726818) (xy 5.893052 -65.726818) (xy 5.897123 -65.671196)
			(xy 5.909249 -65.616759) (xy 5.929172 -65.564668) (xy 5.956468 -65.516033) (xy 5.990554 -65.47189)
			(xy 6.030703 -65.433181) (xy 6.076061 -65.40073) (xy 6.125661 -65.375229) (xy 6.178445 -65.357222)
			(xy 6.233288 -65.347092) (xy 6.289022 -65.345055) (xy 6.344459 -65.351155) (xy 6.398416 -65.365261)
			(xy 6.449745 -65.387073) (xy 6.497351 -65.416127) (xy 6.540219 -65.451802) (xy 6.577436 -65.493339)
			(xy 6.608209 -65.539852) (xy 6.631881 -65.590349) (xy 6.647949 -65.643756) (xy 6.656069 -65.698932)
			(xy 6.656578 -65.726818) (xy 6.656393 -65.736978) (xy 9.139172 -65.736978) (xy 9.143243 -65.681356)
			(xy 9.155369 -65.626919) (xy 9.175292 -65.574828) (xy 9.202588 -65.526193) (xy 9.236674 -65.48205)
			(xy 9.276823 -65.443341) (xy 9.322181 -65.41089) (xy 9.371781 -65.385389) (xy 9.424565 -65.367382)
			(xy 9.479408 -65.357252) (xy 9.535142 -65.355215) (xy 9.590579 -65.361315) (xy 9.644536 -65.375421)
			(xy 9.695865 -65.397233) (xy 9.743471 -65.426287) (xy 9.786339 -65.461962) (xy 9.823556 -65.503499)
			(xy 9.854329 -65.550012) (xy 9.878001 -65.600509) (xy 9.894069 -65.653916) (xy 9.902189 -65.709092)
			(xy 9.902698 -65.736978) (xy 9.902189 -65.764864) (xy 9.894069 -65.82004) (xy 9.878001 -65.873447)
			(xy 9.854329 -65.923944) (xy 9.823556 -65.970457) (xy 9.786339 -66.011994) (xy 9.743471 -66.047669)
			(xy 9.695865 -66.076723) (xy 9.644536 -66.098535) (xy 9.590579 -66.112641) (xy 9.535142 -66.118741)
			(xy 9.479408 -66.116704) (xy 9.424565 -66.106574) (xy 9.371781 -66.088567) (xy 9.322181 -66.063066)
			(xy 9.276823 -66.030615) (xy 9.236674 -65.991906) (xy 9.202588 -65.947763) (xy 9.175292 -65.899128)
			(xy 9.155369 -65.847037) (xy 9.143243 -65.7926) (xy 9.139172 -65.736978) (xy 6.656393 -65.736978)
			(xy 6.656069 -65.754704) (xy 6.647949 -65.80988) (xy 6.631881 -65.863287) (xy 6.608209 -65.913784)
			(xy 6.577436 -65.960297) (xy 6.540219 -66.001834) (xy 6.497351 -66.037509) (xy 6.449745 -66.066563)
			(xy 6.398416 -66.088375) (xy 6.344459 -66.102481) (xy 6.289022 -66.108581) (xy 6.233288 -66.106544)
			(xy 6.178445 -66.096414) (xy 6.125661 -66.078407) (xy 6.076061 -66.052906) (xy 6.030703 -66.020455)
			(xy 5.990554 -65.981746) (xy 5.956468 -65.937603) (xy 5.929172 -65.888968) (xy 5.909249 -65.836877)
			(xy 5.897123 -65.78244) (xy 5.893052 -65.726818) (xy 4.75996 -65.726818) (xy 4.75996 -65.931034)
			(xy 3.866134 -66.82486) (xy 3.866134 -76.11491) (xy 3.866642 -76.118466) (xy 3.868432 -76.131856)
			(xy 3.870337 -76.158805) (xy 3.870452 -76.172314) (xy 3.870329 -76.185822) (xy 3.868419 -76.212771)
			(xy 3.866642 -76.226162) (xy 3.866134 -76.229718) (xy 3.866134 -76.975716) (xy 3.866642 -76.979272)
			(xy 3.868432 -76.992662) (xy 3.870336 -77.019612) (xy 3.870452 -77.03312) (xy 3.870333 -77.046628)
			(xy 3.868429 -77.073578) (xy 3.866642 -77.086968) (xy 3.866134 -77.090524) (xy 3.866134 -77.375004)
			(xy 5.26669 -77.375004) (xy 5.267155 -77.348782) (xy 5.274351 -77.296833) (xy 5.288592 -77.246359)
			(xy 5.309612 -77.198311) (xy 5.337014 -77.153595) (xy 5.370281 -77.113052) (xy 5.408787 -77.077447)
			(xy 5.451807 -77.047451) (xy 5.47497 -77.035152) (xy 5.487246 -77.028409) (xy 5.507814 -77.009413)
			(xy 5.52245 -76.985545) (xy 5.530054 -76.958599) (xy 5.530054 -76.930601) (xy 5.522451 -76.903656)
			(xy 5.507815 -76.879788) (xy 5.487247 -76.860792) (xy 5.47497 -76.85405) (xy 5.451797 -76.841763)
			(xy 5.408762 -76.811779) (xy 5.370242 -76.77618) (xy 5.336965 -76.735637) (xy 5.309558 -76.690917)
			(xy 5.288539 -76.642862) (xy 5.274304 -76.59238) (xy 5.267123 -76.540423) (xy 5.26669 -76.514198)
			(xy 5.267176 -76.486947) (xy 5.274932 -76.432999) (xy 5.290287 -76.380704) (xy 5.312929 -76.331127)
			(xy 5.342395 -76.285277) (xy 5.378086 -76.244086) (xy 5.419277 -76.208395) (xy 5.465127 -76.178929)
			(xy 5.514704 -76.156287) (xy 5.566999 -76.140932) (xy 5.620947 -76.133176) (xy 5.675449 -76.133176)
			(xy 5.729397 -76.140932) (xy 5.781692 -76.156287) (xy 5.831269 -76.178929) (xy 5.877119 -76.208395)
			(xy 5.91831 -76.244086) (xy 5.954001 -76.285277) (xy 5.983467 -76.331127) (xy 6.006109 -76.380704)
			(xy 6.021464 -76.432999) (xy 6.02922 -76.486947) (xy 6.029706 -76.514198) (xy 6.029244 -76.54042)
			(xy 6.022049 -76.592369) (xy 6.007807 -76.642843) (xy 5.986786 -76.690891) (xy 5.959384 -76.735608)
			(xy 5.926116 -76.776151) (xy 5.88761 -76.811756) (xy 5.84459 -76.841752) (xy 5.821426 -76.85405)
			(xy 5.809187 -76.86082) (xy 5.788698 -76.879844) (xy 5.774124 -76.903705) (xy 5.766554 -76.930621)
			(xy 5.766555 -76.95858) (xy 5.774124 -76.985496) (xy 5.788698 -77.009357) (xy 5.809188 -77.028381)
			(xy 5.821426 -77.035152) (xy 5.844599 -77.04744) (xy 5.887634 -77.077423) (xy 5.926154 -77.113022)
			(xy 5.959432 -77.153564) (xy 5.986839 -77.198285) (xy 6.007858 -77.24634) (xy 6.022092 -77.296822)
			(xy 6.029273 -77.348779) (xy 6.029605 -77.368908) (xy 7.400544 -77.368908) (xy 7.401038 -77.342687)
			(xy 7.408231 -77.290741) (xy 7.422471 -77.240269) (xy 7.443487 -77.192222) (xy 7.470885 -77.147506)
			(xy 7.504147 -77.106962) (xy 7.542649 -77.071356) (xy 7.585663 -77.041357) (xy 7.608824 -77.029056)
			(xy 7.621101 -77.02231) (xy 7.641677 -77.003319) (xy 7.656321 -76.979451) (xy 7.663929 -76.952503)
			(xy 7.663929 -76.924502) (xy 7.656322 -76.897553) (xy 7.64168 -76.873685) (xy 7.621104 -76.854693)
			(xy 7.608824 -76.847954) (xy 7.585654 -76.835662) (xy 7.542618 -76.805679) (xy 7.504098 -76.770081)
			(xy 7.470821 -76.729539) (xy 7.443414 -76.684819) (xy 7.422394 -76.636765) (xy 7.408159 -76.586283)
			(xy 7.400977 -76.534327) (xy 7.400544 -76.508102) (xy 7.40103 -76.480851) (xy 7.408786 -76.426903)
			(xy 7.424141 -76.374608) (xy 7.446783 -76.325031) (xy 7.476249 -76.279181) (xy 7.51194 -76.23799)
			(xy 7.553131 -76.202299) (xy 7.598981 -76.172833) (xy 7.648558 -76.150191) (xy 7.700853 -76.134836)
			(xy 7.754801 -76.12708) (xy 7.809303 -76.12708) (xy 7.863251 -76.134836) (xy 7.915546 -76.150191)
			(xy 7.965123 -76.172833) (xy 8.010973 -76.202299) (xy 8.052164 -76.23799) (xy 8.087855 -76.279181)
			(xy 8.117321 -76.325031) (xy 8.139963 -76.374608) (xy 8.155318 -76.426903) (xy 8.163074 -76.480851)
			(xy 8.16356 -76.508102) (xy 8.163072 -76.534323) (xy 8.155877 -76.58627) (xy 8.141637 -76.636742)
			(xy 8.12062 -76.684788) (xy 8.093221 -76.729505) (xy 8.059958 -76.770048) (xy 8.021456 -76.805654)
			(xy 7.978441 -76.835653) (xy 7.95528 -76.847954) (xy 7.943032 -76.854714) (xy 7.922532 -76.873736)
			(xy 7.90795 -76.897599) (xy 7.900376 -76.924519) (xy 7.900377 -76.952485) (xy 7.907952 -76.979405)
			(xy 7.922535 -77.003268) (xy 7.943036 -77.022288) (xy 7.95528 -77.029056) (xy 7.978451 -77.041346)
			(xy 8.021486 -77.07133) (xy 8.060006 -77.106928) (xy 8.093284 -77.14747) (xy 8.120691 -77.19219)
			(xy 8.14171 -77.240245) (xy 8.154785 -77.286612) (xy 9.534398 -77.286612) (xy 9.534894 -77.257996)
			(xy 9.543435 -77.201406) (xy 9.560341 -77.146729) (xy 9.585234 -77.095195) (xy 9.617552 -77.047962)
			(xy 9.656569 -77.006092) (xy 9.67867 -76.987908) (xy 9.690366 -76.978038) (xy 9.707665 -76.952806)
			(xy 9.716718 -76.923583) (xy 9.716714 -76.892991) (xy 9.707653 -76.863771) (xy 9.690348 -76.838543)
			(xy 9.67867 -76.82865) (xy 9.656589 -76.810445) (xy 9.617585 -76.768571) (xy 9.585275 -76.721339)
			(xy 9.560384 -76.66981) (xy 9.54347 -76.615141) (xy 9.534914 -76.558559) (xy 9.534398 -76.529946)
			(xy 9.534884 -76.502695) (xy 9.54264 -76.448747) (xy 9.557995 -76.396452) (xy 9.580637 -76.346875)
			(xy 9.610103 -76.301025) (xy 9.645794 -76.259834) (xy 9.686985 -76.224143) (xy 9.732835 -76.194677)
			(xy 9.782412 -76.172035) (xy 9.834707 -76.15668) (xy 9.888655 -76.148924) (xy 9.943157 -76.148924)
			(xy 9.997105 -76.15668) (xy 10.0494 -76.172035) (xy 10.098977 -76.194677) (xy 10.144827 -76.224143)
			(xy 10.186018 -76.259834) (xy 10.221709 -76.301025) (xy 10.251175 -76.346875) (xy 10.273817 -76.396452)
			(xy 10.289172 -76.448747) (xy 10.296928 -76.502695) (xy 10.297414 -76.529946) (xy 10.296883 -76.55856)
			(xy 10.288349 -76.615149) (xy 10.271449 -76.669825) (xy 10.246563 -76.721359) (xy 10.214251 -76.768593)
			(xy 10.17524 -76.810464) (xy 10.153142 -76.82865) (xy 10.141588 -76.838638) (xy 10.124398 -76.863859)
			(xy 10.115402 -76.893026) (xy 10.115398 -76.923548) (xy 10.124386 -76.952717) (xy 10.14157 -76.977943)
			(xy 10.153142 -76.987908) (xy 10.175205 -77.006133) (xy 10.21421 -77.048004) (xy 10.246522 -77.095231)
			(xy 10.271416 -77.146756) (xy 10.288334 -77.201421) (xy 10.296895 -77.258) (xy 10.297414 -77.286612)
			(xy 10.296928 -77.313863) (xy 10.289172 -77.367811) (xy 10.273817 -77.420106) (xy 10.251175 -77.469683)
			(xy 10.221709 -77.515533) (xy 10.186018 -77.556724) (xy 10.144827 -77.592415) (xy 10.098977 -77.621881)
			(xy 10.0494 -77.644523) (xy 9.997105 -77.659878) (xy 9.943157 -77.667634) (xy 9.888655 -77.667634)
			(xy 9.834707 -77.659878) (xy 9.782412 -77.644523) (xy 9.732835 -77.621881) (xy 9.686985 -77.592415)
			(xy 9.645794 -77.556724) (xy 9.610103 -77.515533) (xy 9.580637 -77.469683) (xy 9.557995 -77.420106)
			(xy 9.54264 -77.367811) (xy 9.534884 -77.313863) (xy 9.534398 -77.286612) (xy 8.154785 -77.286612)
			(xy 8.155945 -77.290726) (xy 8.163127 -77.342683) (xy 8.16356 -77.368908) (xy 8.163074 -77.396159)
			(xy 8.155318 -77.450107) (xy 8.139963 -77.502402) (xy 8.117321 -77.551979) (xy 8.087855 -77.597829)
			(xy 8.052164 -77.63902) (xy 8.010973 -77.674711) (xy 7.965123 -77.704177) (xy 7.915546 -77.726819)
			(xy 7.863251 -77.742174) (xy 7.809303 -77.74993) (xy 7.754801 -77.74993) (xy 7.700853 -77.742174)
			(xy 7.648558 -77.726819) (xy 7.598981 -77.704177) (xy 7.553131 -77.674711) (xy 7.51194 -77.63902)
			(xy 7.476249 -77.597829) (xy 7.446783 -77.551979) (xy 7.424141 -77.502402) (xy 7.408786 -77.450107)
			(xy 7.40103 -77.396159) (xy 7.400544 -77.368908) (xy 6.029605 -77.368908) (xy 6.029706 -77.375004)
			(xy 6.02922 -77.402255) (xy 6.021464 -77.456203) (xy 6.006109 -77.508498) (xy 5.983467 -77.558075)
			(xy 5.954001 -77.603925) (xy 5.91831 -77.645116) (xy 5.877119 -77.680807) (xy 5.831269 -77.710273)
			(xy 5.781692 -77.732915) (xy 5.729397 -77.74827) (xy 5.675449 -77.756026) (xy 5.620947 -77.756026)
			(xy 5.566999 -77.74827) (xy 5.514704 -77.732915) (xy 5.465127 -77.710273) (xy 5.419277 -77.680807)
			(xy 5.378086 -77.645116) (xy 5.342395 -77.603925) (xy 5.312929 -77.558075) (xy 5.290287 -77.508498)
			(xy 5.274932 -77.456203) (xy 5.267176 -77.402255) (xy 5.26669 -77.375004) (xy 3.866134 -77.375004)
			(xy 3.866134 -77.907134) (xy 6.199886 -80.240632) (xy 6.75894 -80.240632) (xy 6.782101 -80.241091)
			(xy 6.827889 -80.248109) (xy 6.850126 -80.254602) (xy 6.857492 -80.256888)
		)
		(stroke
			(width 0)
			(type solid)
		)
		(fill yes)
		(layer "In4.Cu")
		(net "GND")
	)
	(gr_poly
		(pts
			(xy 62.46241 -48.739552) (xy 62.476947 -48.739034) (xy 62.504843 -48.730842) (xy 62.529303 -48.715125)
			(xy 62.548345 -48.693154) (xy 62.560429 -48.66671) (xy 62.564574 -48.637933) (xy 62.562994 -48.623474)
			(xy 62.561365 -48.611666) (xy 62.559588 -48.587895) (xy 62.559438 -48.575976) (xy 62.559948 -48.549989)
			(xy 62.568078 -48.498654) (xy 62.584139 -48.449224) (xy 62.607735 -48.402914) (xy 62.638285 -48.360866)
			(xy 62.675036 -48.324115) (xy 62.717084 -48.293565) (xy 62.763394 -48.269969) (xy 62.812824 -48.253908)
			(xy 62.864159 -48.245778) (xy 62.916133 -48.245778) (xy 62.967468 -48.253908) (xy 63.016898 -48.269969)
			(xy 63.063208 -48.293565) (xy 63.105256 -48.324115) (xy 63.142007 -48.360866) (xy 63.172557 -48.402914)
			(xy 63.196153 -48.449224) (xy 63.212214 -48.498654) (xy 63.220344 -48.549989) (xy 63.220854 -48.575976)
			(xy 63.220722 -48.587895) (xy 63.218941 -48.611668) (xy 63.217298 -48.623474) (xy 63.215681 -48.637942)
			(xy 63.219807 -48.66675) (xy 63.231884 -48.693227) (xy 63.250933 -48.715229) (xy 63.27541 -48.73097)
			(xy 63.303331 -48.739176) (xy 63.317882 -48.739552) (xy 63.376556 -48.739552) (xy 63.376556 -48.681132)
			(xy 63.37427 -48.673766) (xy 63.367371 -48.64991) (xy 63.359969 -48.600806) (xy 63.359538 -48.575976)
			(xy 63.360048 -48.549989) (xy 63.368178 -48.498654) (xy 63.384239 -48.449224) (xy 63.407835 -48.402914)
			(xy 63.438385 -48.360866) (xy 63.475136 -48.324115) (xy 63.517184 -48.293565) (xy 63.563494 -48.269969)
			(xy 63.612924 -48.253908) (xy 63.664259 -48.245778) (xy 63.716233 -48.245778) (xy 63.767568 -48.253908)
			(xy 63.816998 -48.269969) (xy 63.863308 -48.293565) (xy 63.905356 -48.324115) (xy 63.942107 -48.360866)
			(xy 63.972657 -48.402914) (xy 63.996253 -48.449224) (xy 64.012314 -48.498654) (xy 64.020444 -48.549989)
			(xy 64.020954 -48.575976) (xy 64.020822 -48.587895) (xy 64.019041 -48.611668) (xy 64.017398 -48.623474)
			(xy 64.015781 -48.637942) (xy 64.019907 -48.66675) (xy 64.031984 -48.693227) (xy 64.051033 -48.715229)
			(xy 64.07551 -48.73097) (xy 64.103431 -48.739176) (xy 64.117982 -48.739552) (xy 64.176402 -48.739552)
			(xy 64.176402 -48.681132) (xy 64.174116 -48.673766) (xy 64.167218 -48.64991) (xy 64.159817 -48.600806)
			(xy 64.159384 -48.575976) (xy 64.159894 -48.549989) (xy 64.168024 -48.498654) (xy 64.184085 -48.449224)
			(xy 64.207681 -48.402914) (xy 64.238231 -48.360866) (xy 64.274982 -48.324115) (xy 64.31703 -48.293565)
			(xy 64.36334 -48.269969) (xy 64.41277 -48.253908) (xy 64.464105 -48.245778) (xy 64.516079 -48.245778)
			(xy 64.567414 -48.253908) (xy 64.616844 -48.269969) (xy 64.663154 -48.293565) (xy 64.705202 -48.324115)
			(xy 64.741953 -48.360866) (xy 64.772503 -48.402914) (xy 64.796099 -48.449224) (xy 64.81216 -48.498654)
			(xy 64.82029 -48.549989) (xy 64.8208 -48.575976) (xy 64.820668 -48.587895) (xy 64.818887 -48.611668)
			(xy 64.817244 -48.623474) (xy 64.815626 -48.63794) (xy 64.819753 -48.666744) (xy 64.831831 -48.693216)
			(xy 64.850881 -48.71521) (xy 64.875359 -48.730942) (xy 64.903279 -48.739137) (xy 64.917828 -48.739552)
			(xy 64.976502 -48.739552) (xy 64.976502 -48.681132) (xy 64.974216 -48.673766) (xy 64.967318 -48.64991)
			(xy 64.959917 -48.600806) (xy 64.959484 -48.575976) (xy 64.959994 -48.549989) (xy 64.968124 -48.498654)
			(xy 64.984185 -48.449224) (xy 65.007781 -48.402914) (xy 65.038331 -48.360866) (xy 65.075082 -48.324115)
			(xy 65.11713 -48.293565) (xy 65.16344 -48.269969) (xy 65.21287 -48.253908) (xy 65.264205 -48.245778)
			(xy 65.316179 -48.245778) (xy 65.367514 -48.253908) (xy 65.416944 -48.269969) (xy 65.463254 -48.293565)
			(xy 65.505302 -48.324115) (xy 65.542053 -48.360866) (xy 65.572603 -48.402914) (xy 65.596199 -48.449224)
			(xy 65.61226 -48.498654) (xy 65.62039 -48.549989) (xy 65.6209 -48.575976) (xy 65.620768 -48.587895)
			(xy 65.618987 -48.611668) (xy 65.617344 -48.623474) (xy 65.615726 -48.63794) (xy 65.619853 -48.666744)
			(xy 65.631931 -48.693216) (xy 65.650981 -48.71521) (xy 65.675459 -48.730942) (xy 65.703379 -48.739137)
			(xy 65.717928 -48.739552) (xy 66.363088 -48.739552) (xy 66.37274 -48.7299) (xy 66.37274 -45.02404)
			(xy 66.88074 -44.51604) (xy 68.15836 -44.51604) (xy 70.0278 -42.6466) (xy 70.0278 -36.57092) (xy 69.06006 -35.60318)
			(xy 68.166488 -35.60318) (xy 68.153538 -35.621802) (xy 68.124657 -35.656782) (xy 68.10883 -35.67303)
			(xy 67.589908 -36.191952) (xy 67.589908 -37.137848) (xy 67.890898 -37.438838) (xy 67.912919 -37.461555)
			(xy 67.951437 -37.511747) (xy 67.983072 -37.566539) (xy 68.007282 -37.624992) (xy 68.023654 -37.686106)
			(xy 68.031905 -37.748834) (xy 68.032376 -37.780468) (xy 68.032376 -37.822378) (xy 68.032842 -37.836577)
			(xy 68.040654 -37.863878) (xy 68.055681 -37.887974) (xy 68.07676 -37.907002) (xy 68.102264 -37.919491)
			(xy 68.13022 -37.924477) (xy 68.14439 -37.92347) (xy 68.154331 -37.922504) (xy 68.17428 -37.92149)
			(xy 68.184268 -37.921438) (xy 68.211521 -37.921899) (xy 68.265473 -37.929653) (xy 68.317772 -37.945006)
			(xy 68.367353 -37.967648) (xy 68.413207 -37.997116) (xy 68.4544 -38.03281) (xy 68.490093 -38.074004)
			(xy 68.519559 -38.119859) (xy 68.542198 -38.169441) (xy 68.55755 -38.221741) (xy 68.565302 -38.275693)
			(xy 68.565776 -38.302946) (xy 68.565301 -38.330315) (xy 68.557471 -38.384489) (xy 68.541978 -38.436989)
			(xy 68.51914 -38.486735) (xy 68.489427 -38.532706) (xy 68.471796 -38.553644) (xy 68.462566 -38.564971)
			(xy 68.450402 -38.591525) (xy 68.44624 -38.620435) (xy 68.450421 -38.649342) (xy 68.462604 -38.675888)
			(xy 68.471796 -38.687248) (xy 68.489435 -38.70818) (xy 68.519156 -38.754148) (xy 68.541993 -38.803895)
			(xy 68.557477 -38.856398) (xy 68.565289 -38.910576) (xy 68.565776 -38.937946) (xy 68.565287 -38.965194)
			(xy 68.557525 -39.019135) (xy 68.542165 -39.071423) (xy 68.519521 -39.120992) (xy 68.490053 -39.166834)
			(xy 68.454361 -39.208016) (xy 68.413172 -39.2437) (xy 68.367323 -39.273158) (xy 68.317749 -39.295792)
			(xy 68.265459 -39.311141) (xy 68.211516 -39.318892) (xy 68.184268 -39.319454) (xy 68.156899 -39.31898)
			(xy 68.102724 -39.311151) (xy 68.050224 -39.295659) (xy 68.000477 -39.272822) (xy 67.954506 -39.243108)
			(xy 67.93357 -39.225474) (xy 67.922242 -39.216238) (xy 67.895685 -39.204062) (xy 67.866768 -39.199889)
			(xy 67.837851 -39.204062) (xy 67.811294 -39.216238) (xy 67.799966 -39.225474) (xy 67.779035 -39.243115)
			(xy 67.733068 -39.272839) (xy 67.683321 -39.295679) (xy 67.630817 -39.311166) (xy 67.576638 -39.31898)
			(xy 67.549268 -39.319454) (xy 67.520839 -39.318926) (xy 67.464612 -39.310477) (xy 67.410263 -39.293772)
			(xy 67.358998 -39.26918) (xy 67.311953 -39.237247) (xy 67.290696 -39.218362) (xy 67.278766 -39.208161)
			(xy 67.250335 -39.194902) (xy 67.219223 -39.190876) (xy 67.188354 -39.196463) (xy 67.160626 -39.211136)
			(xy 67.149218 -39.221918) (xy 67.12754 -39.243202) (xy 67.078687 -39.279307) (xy 67.024729 -39.307215)
			(xy 66.967031 -39.32622) (xy 66.90705 -39.335843) (xy 66.876676 -39.336472) (xy 66.849425 -39.336007)
			(xy 66.795479 -39.328247) (xy 66.743186 -39.312889) (xy 66.693611 -39.290244) (xy 66.647764 -39.260775)
			(xy 66.606577 -39.225081) (xy 66.570889 -39.183888) (xy 66.541427 -39.138036) (xy 66.51879 -39.088458)
			(xy 66.50344 -39.036162) (xy 66.495689 -38.982215) (xy 66.495168 -38.954964) (xy 66.49576 -38.925168)
			(xy 66.505059 -38.866305) (xy 66.523395 -38.809604) (xy 66.550321 -38.756441) (xy 66.567304 -38.731952)
			(xy 66.575573 -38.719608) (xy 66.585272 -38.69154) (xy 66.586479 -38.661868) (xy 66.579092 -38.633104)
			(xy 66.563736 -38.607686) (xy 66.55308 -38.597332) (xy 66.533773 -38.579163) (xy 66.499861 -38.538412)
			(xy 66.471911 -38.493363) (xy 66.450461 -38.44488) (xy 66.435924 -38.393896) (xy 66.428579 -38.341392)
			(xy 66.428112 -38.314884) (xy 66.428618 -38.286264) (xy 66.43716 -38.229666) (xy 66.454063 -38.17498)
			(xy 66.478949 -38.123434) (xy 66.511258 -38.076186) (xy 66.550265 -38.034296) (xy 66.595094 -37.998706)
			(xy 66.644739 -37.970215) (xy 66.698083 -37.949463) (xy 66.75393 -37.936915) (xy 66.782442 -37.934392)
			(xy 66.796891 -37.932815) (xy 66.824095 -37.922621) (xy 66.847331 -37.905184) (xy 66.864721 -37.881912)
			(xy 66.874859 -37.854688) (xy 66.876927 -37.82571) (xy 66.870756 -37.797322) (xy 66.856847 -37.771817)
			(xy 66.846958 -37.761164) (xy 66.76517 -37.67963) (xy 66.763392 -37.677852) (xy 66.753705 -37.668643)
			(xy 66.730621 -37.655185) (xy 66.704838 -37.648167) (xy 66.678118 -37.648067) (xy 66.652284 -37.654893)
			(xy 66.629101 -37.668178) (xy 66.619374 -37.677344) (xy 66.243708 -38.053264) (xy 66.243708 -41.905428)
			(xy 66.985386 -41.905428) (xy 66.989457 -41.849806) (xy 67.001583 -41.795369) (xy 67.021506 -41.743278)
			(xy 67.048802 -41.694643) (xy 67.082888 -41.6505) (xy 67.123037 -41.611791) (xy 67.168395 -41.57934)
			(xy 67.217995 -41.553839) (xy 67.270779 -41.535832) (xy 67.325622 -41.525702) (xy 67.381356 -41.523665)
			(xy 67.436793 -41.529765) (xy 67.49075 -41.543871) (xy 67.542079 -41.565683) (xy 67.589685 -41.594737)
			(xy 67.632553 -41.630412) (xy 67.66977 -41.671949) (xy 67.700543 -41.718462) (xy 67.724215 -41.768959)
			(xy 67.740283 -41.822366) (xy 67.748403 -41.877542) (xy 67.748912 -41.905428) (xy 67.977764 -41.905428)
			(xy 67.981835 -41.849806) (xy 67.993961 -41.795369) (xy 68.013884 -41.743278) (xy 68.04118 -41.694643)
			(xy 68.075266 -41.6505) (xy 68.115415 -41.611791) (xy 68.160773 -41.57934) (xy 68.210373 -41.553839)
			(xy 68.263157 -41.535832) (xy 68.318 -41.525702) (xy 68.373734 -41.523665) (xy 68.429171 -41.529765)
			(xy 68.483128 -41.543871) (xy 68.534457 -41.565683) (xy 68.582063 -41.594737) (xy 68.624931 -41.630412)
			(xy 68.662148 -41.671949) (xy 68.692921 -41.718462) (xy 68.716593 -41.768959) (xy 68.732661 -41.822366)
			(xy 68.740781 -41.877542) (xy 68.74129 -41.905428) (xy 68.740781 -41.933314) (xy 68.732661 -41.98849)
			(xy 68.716593 -42.041897) (xy 68.692921 -42.092394) (xy 68.662148 -42.138907) (xy 68.624931 -42.180444)
			(xy 68.582063 -42.216119) (xy 68.534457 -42.245173) (xy 68.483128 -42.266985) (xy 68.429171 -42.281091)
			(xy 68.373734 -42.287191) (xy 68.318 -42.285154) (xy 68.263157 -42.275024) (xy 68.210373 -42.257017)
			(xy 68.160773 -42.231516) (xy 68.115415 -42.199065) (xy 68.075266 -42.160356) (xy 68.04118 -42.116213)
			(xy 68.013884 -42.067578) (xy 67.993961 -42.015487) (xy 67.981835 -41.96105) (xy 67.977764 -41.905428)
			(xy 67.748912 -41.905428) (xy 67.748403 -41.933314) (xy 67.740283 -41.98849) (xy 67.724215 -42.041897)
			(xy 67.700543 -42.092394) (xy 67.66977 -42.138907) (xy 67.632553 -42.180444) (xy 67.589685 -42.216119)
			(xy 67.542079 -42.245173) (xy 67.49075 -42.266985) (xy 67.436793 -42.281091) (xy 67.381356 -42.287191)
			(xy 67.325622 -42.285154) (xy 67.270779 -42.275024) (xy 67.217995 -42.257017) (xy 67.168395 -42.231516)
			(xy 67.123037 -42.199065) (xy 67.082888 -42.160356) (xy 67.048802 -42.116213) (xy 67.021506 -42.067578)
			(xy 67.001583 -42.015487) (xy 66.989457 -41.96105) (xy 66.985386 -41.905428) (xy 66.243708 -41.905428)
			(xy 66.243708 -43.7007) (xy 66.243258 -43.724892) (xy 66.235688 -43.772681) (xy 66.220734 -43.818698)
			(xy 66.198766 -43.861808) (xy 66.170323 -43.90095) (xy 66.153538 -43.918378) (xy 65.663318 -44.408598)
			(xy 65.645878 -44.425369) (xy 65.606737 -44.45381) (xy 65.56363 -44.475779) (xy 65.517617 -44.490734)
			(xy 65.469831 -44.498308) (xy 65.44564 -44.498768) (xy 64.921638 -44.498768) (xy 64.906232 -44.4993)
			(xy 64.876821 -44.508484) (xy 64.851491 -44.526026) (xy 64.83255 -44.550329) (xy 64.821725 -44.579176)
			(xy 64.820292 -44.594526) (xy 64.818426 -44.619521) (xy 64.808099 -44.668567) (xy 64.790489 -44.715492)
			(xy 64.766001 -44.759224) (xy 64.735193 -44.798758) (xy 64.698773 -44.833192) (xy 64.657573 -44.861735)
			(xy 64.612539 -44.883735) (xy 64.5647 -44.898687) (xy 64.515153 -44.906249) (xy 64.490092 -44.906692)
			(xy 64.464104 -44.906208) (xy 64.412767 -44.898076) (xy 64.363335 -44.882013) (xy 64.317024 -44.858414)
			(xy 64.274974 -44.827862) (xy 64.238223 -44.791107) (xy 64.207673 -44.749056) (xy 64.184078 -44.702743)
			(xy 64.168018 -44.65331) (xy 64.15989 -44.601972) (xy 64.159384 -44.575984) (xy 64.160146 -44.55287)
			(xy 64.1604 -44.551092) (xy 64.1604 -44.498768) (xy 64.019938 -44.498768) (xy 64.019938 -44.551092)
			(xy 64.020192 -44.55287) (xy 64.020954 -44.575984) (xy 64.020444 -44.601971) (xy 64.012314 -44.653306)
			(xy 63.996253 -44.702736) (xy 63.972657 -44.749046) (xy 63.942107 -44.791094) (xy 63.905356 -44.827845)
			(xy 63.863308 -44.858395) (xy 63.816998 -44.881991) (xy 63.767568 -44.898052) (xy 63.716233 -44.906182)
			(xy 63.664259 -44.906182) (xy 63.612924 -44.898052) (xy 63.563494 -44.881991) (xy 63.517184 -44.858395)
			(xy 63.475136 -44.827845) (xy 63.438385 -44.791094) (xy 63.407835 -44.749046) (xy 63.384239 -44.702736)
			(xy 63.368178 -44.653306) (xy 63.360048 -44.601971) (xy 63.359538 -44.575984) (xy 63.360049 -44.550216)
			(xy 63.368085 -44.499309) (xy 63.37554 -44.474638) (xy 63.351124 -44.463702) (xy 63.306173 -44.434703)
			(xy 63.286132 -44.41698) (xy 63.278771 -44.410798) (xy 63.260828 -44.403945) (xy 63.241621 -44.404164)
			(xy 63.223839 -44.411424) (xy 63.209968 -44.424711) (xy 63.201949 -44.442164) (xy 63.200903 -44.461344)
			(xy 63.203582 -44.470574) (xy 63.211641 -44.496178) (xy 63.220321 -44.549147) (xy 63.220854 -44.575984)
			(xy 63.220372 -44.601978) (xy 63.212241 -44.653326) (xy 63.196178 -44.70277) (xy 63.172577 -44.749092)
			(xy 63.142021 -44.791152) (xy 63.10526 -44.827913) (xy 63.063202 -44.858472) (xy 63.01688 -44.882074)
			(xy 62.967437 -44.898139) (xy 62.916089 -44.906271) (xy 62.864101 -44.90627) (xy 62.812754 -44.898137)
			(xy 62.763311 -44.88207) (xy 62.71699 -44.858467) (xy 62.674932 -44.827907) (xy 62.638173 -44.791145)
			(xy 62.607618 -44.749084) (xy 62.584018 -44.702761) (xy 62.567956 -44.653317) (xy 62.559827 -44.601969)
			(xy 62.559831 -44.549981) (xy 62.567968 -44.498634) (xy 62.584038 -44.449192) (xy 62.607644 -44.402873)
			(xy 62.638206 -44.360817) (xy 62.674971 -44.32406) (xy 62.717034 -44.293507) (xy 62.763358 -44.26991)
			(xy 62.812803 -44.253852) (xy 62.864152 -44.245726) (xy 62.890146 -44.245276) (xy 62.916984 -44.245798)
			(xy 62.969953 -44.254481) (xy 62.995556 -44.262548) (xy 63.00483 -44.265259) (xy 63.024111 -44.264273)
			(xy 63.041659 -44.256223) (xy 63.054984 -44.242252) (xy 63.062195 -44.224343) (xy 63.062267 -44.205037)
			(xy 63.055192 -44.187074) (xy 63.048896 -44.179744) (xy 63.035455 -44.164868) (xy 63.012146 -44.132248)
			(xy 63.002414 -44.11472) (xy 60.76188 -44.11472) (xy 60.5536 -44.323) (xy 60.5536 -44.601971) (xy 60.960002 -44.601971)
			(xy 60.960002 -44.549997) (xy 60.968132 -44.498662) (xy 60.984193 -44.449232) (xy 61.007789 -44.402922)
			(xy 61.038339 -44.360874) (xy 61.07509 -44.324123) (xy 61.117138 -44.293573) (xy 61.163448 -44.269977)
			(xy 61.212878 -44.253916) (xy 61.264213 -44.245786) (xy 61.316187 -44.245786) (xy 61.367522 -44.253916)
			(xy 61.416952 -44.269977) (xy 61.463262 -44.293573) (xy 61.50531 -44.324123) (xy 61.542061 -44.360874)
			(xy 61.572611 -44.402922) (xy 61.596207 -44.449232) (xy 61.612268 -44.498662) (xy 61.620398 -44.549997)
			(xy 61.620908 -44.575984) (xy 61.620398 -44.601971) (xy 61.760102 -44.601971) (xy 61.760102 -44.549997)
			(xy 61.768232 -44.498662) (xy 61.784293 -44.449232) (xy 61.807889 -44.402922) (xy 61.838439 -44.360874)
			(xy 61.87519 -44.324123) (xy 61.917238 -44.293573) (xy 61.963548 -44.269977) (xy 62.012978 -44.253916)
			(xy 62.064313 -44.245786) (xy 62.116287 -44.245786) (xy 62.167622 -44.253916) (xy 62.217052 -44.269977)
			(xy 62.263362 -44.293573) (xy 62.30541 -44.324123) (xy 62.342161 -44.360874) (xy 62.372711 -44.402922)
			(xy 62.396307 -44.449232) (xy 62.412368 -44.498662) (xy 62.420498 -44.549997) (xy 62.421008 -44.575984)
			(xy 62.420498 -44.601971) (xy 62.412368 -44.653306) (xy 62.396307 -44.702736) (xy 62.372711 -44.749046)
			(xy 62.342161 -44.791094) (xy 62.30541 -44.827845) (xy 62.263362 -44.858395) (xy 62.217052 -44.881991)
			(xy 62.167622 -44.898052) (xy 62.116287 -44.906182) (xy 62.064313 -44.906182) (xy 62.012978 -44.898052)
			(xy 61.963548 -44.881991) (xy 61.917238 -44.858395) (xy 61.87519 -44.827845) (xy 61.838439 -44.791094)
			(xy 61.807889 -44.749046) (xy 61.784293 -44.702736) (xy 61.768232 -44.653306) (xy 61.760102 -44.601971)
			(xy 61.620398 -44.601971) (xy 61.612268 -44.653306) (xy 61.596207 -44.702736) (xy 61.572611 -44.749046)
			(xy 61.542061 -44.791094) (xy 61.50531 -44.827845) (xy 61.463262 -44.858395) (xy 61.416952 -44.881991)
			(xy 61.367522 -44.898052) (xy 61.316187 -44.906182) (xy 61.264213 -44.906182) (xy 61.212878 -44.898052)
			(xy 61.163448 -44.881991) (xy 61.117138 -44.858395) (xy 61.07509 -44.827845) (xy 61.038339 -44.791094)
			(xy 61.007789 -44.749046) (xy 60.984193 -44.702736) (xy 60.968132 -44.653306) (xy 60.960002 -44.601971)
			(xy 60.5536 -44.601971) (xy 60.5536 -45.402071) (xy 60.960002 -45.402071) (xy 60.960002 -45.350097)
			(xy 60.968132 -45.298762) (xy 60.984193 -45.249332) (xy 61.007789 -45.203022) (xy 61.038339 -45.160974)
			(xy 61.07509 -45.124223) (xy 61.117138 -45.093673) (xy 61.163448 -45.070077) (xy 61.212878 -45.054016)
			(xy 61.264213 -45.045886) (xy 61.316187 -45.045886) (xy 61.367522 -45.054016) (xy 61.416952 -45.070077)
			(xy 61.463262 -45.093673) (xy 61.50531 -45.124223) (xy 61.542061 -45.160974) (xy 61.572611 -45.203022)
			(xy 61.596207 -45.249332) (xy 61.612268 -45.298762) (xy 61.620398 -45.350097) (xy 61.620908 -45.376084)
			(xy 61.620398 -45.402071) (xy 61.760102 -45.402071) (xy 61.760102 -45.350097) (xy 61.768232 -45.298762)
			(xy 61.784293 -45.249332) (xy 61.807889 -45.203022) (xy 61.838439 -45.160974) (xy 61.87519 -45.124223)
			(xy 61.917238 -45.093673) (xy 61.963548 -45.070077) (xy 62.012978 -45.054016) (xy 62.064313 -45.045886)
			(xy 62.116287 -45.045886) (xy 62.167622 -45.054016) (xy 62.217052 -45.070077) (xy 62.263362 -45.093673)
			(xy 62.30541 -45.124223) (xy 62.342161 -45.160974) (xy 62.372711 -45.203022) (xy 62.396307 -45.249332)
			(xy 62.412368 -45.298762) (xy 62.420498 -45.350097) (xy 62.421008 -45.376084) (xy 62.420498 -45.402071)
			(xy 62.559948 -45.402071) (xy 62.559948 -45.350097) (xy 62.568078 -45.298762) (xy 62.584139 -45.249332)
			(xy 62.607735 -45.203022) (xy 62.638285 -45.160974) (xy 62.675036 -45.124223) (xy 62.717084 -45.093673)
			(xy 62.763394 -45.070077) (xy 62.812824 -45.054016) (xy 62.864159 -45.045886) (xy 62.916133 -45.045886)
			(xy 62.967468 -45.054016) (xy 63.016898 -45.070077) (xy 63.063208 -45.093673) (xy 63.105256 -45.124223)
			(xy 63.142007 -45.160974) (xy 63.172557 -45.203022) (xy 63.196153 -45.249332) (xy 63.212214 -45.298762)
			(xy 63.220344 -45.350097) (xy 63.220854 -45.376084) (xy 63.220344 -45.402071) (xy 63.360048 -45.402071)
			(xy 63.360048 -45.350097) (xy 63.368178 -45.298762) (xy 63.384239 -45.249332) (xy 63.407835 -45.203022)
			(xy 63.438385 -45.160974) (xy 63.475136 -45.124223) (xy 63.517184 -45.093673) (xy 63.563494 -45.070077)
			(xy 63.612924 -45.054016) (xy 63.664259 -45.045886) (xy 63.716233 -45.045886) (xy 63.767568 -45.054016)
			(xy 63.816998 -45.070077) (xy 63.863308 -45.093673) (xy 63.905356 -45.124223) (xy 63.942107 -45.160974)
			(xy 63.972657 -45.203022) (xy 63.996253 -45.249332) (xy 64.012314 -45.298762) (xy 64.020444 -45.350097)
			(xy 64.020954 -45.376084) (xy 64.020444 -45.402071) (xy 64.159894 -45.402071) (xy 64.159894 -45.350097)
			(xy 64.168024 -45.298762) (xy 64.184085 -45.249332) (xy 64.207681 -45.203022) (xy 64.238231 -45.160974)
			(xy 64.274982 -45.124223) (xy 64.31703 -45.093673) (xy 64.36334 -45.070077) (xy 64.41277 -45.054016)
			(xy 64.464105 -45.045886) (xy 64.516079 -45.045886) (xy 64.567414 -45.054016) (xy 64.616844 -45.070077)
			(xy 64.663154 -45.093673) (xy 64.705202 -45.124223) (xy 64.741953 -45.160974) (xy 64.772503 -45.203022)
			(xy 64.796099 -45.249332) (xy 64.81216 -45.298762) (xy 64.82029 -45.350097) (xy 64.8208 -45.376084)
			(xy 64.82029 -45.402071) (xy 64.81216 -45.453406) (xy 64.796099 -45.502836) (xy 64.772503 -45.549146)
			(xy 64.741953 -45.591194) (xy 64.705202 -45.627945) (xy 64.663154 -45.658495) (xy 64.616844 -45.682091)
			(xy 64.567414 -45.698152) (xy 64.516079 -45.706282) (xy 64.464105 -45.706282) (xy 64.41277 -45.698152)
			(xy 64.36334 -45.682091) (xy 64.31703 -45.658495) (xy 64.274982 -45.627945) (xy 64.238231 -45.591194)
			(xy 64.207681 -45.549146) (xy 64.184085 -45.502836) (xy 64.168024 -45.453406) (xy 64.159894 -45.402071)
			(xy 64.020444 -45.402071) (xy 64.012314 -45.453406) (xy 63.996253 -45.502836) (xy 63.972657 -45.549146)
			(xy 63.942107 -45.591194) (xy 63.905356 -45.627945) (xy 63.863308 -45.658495) (xy 63.816998 -45.682091)
			(xy 63.767568 -45.698152) (xy 63.716233 -45.706282) (xy 63.664259 -45.706282) (xy 63.612924 -45.698152)
			(xy 63.563494 -45.682091) (xy 63.517184 -45.658495) (xy 63.475136 -45.627945) (xy 63.438385 -45.591194)
			(xy 63.407835 -45.549146) (xy 63.384239 -45.502836) (xy 63.368178 -45.453406) (xy 63.360048 -45.402071)
			(xy 63.220344 -45.402071) (xy 63.212214 -45.453406) (xy 63.196153 -45.502836) (xy 63.172557 -45.549146)
			(xy 63.142007 -45.591194) (xy 63.105256 -45.627945) (xy 63.063208 -45.658495) (xy 63.016898 -45.682091)
			(xy 62.967468 -45.698152) (xy 62.916133 -45.706282) (xy 62.864159 -45.706282) (xy 62.812824 -45.698152)
			(xy 62.763394 -45.682091) (xy 62.717084 -45.658495) (xy 62.675036 -45.627945) (xy 62.638285 -45.591194)
			(xy 62.607735 -45.549146) (xy 62.584139 -45.502836) (xy 62.568078 -45.453406) (xy 62.559948 -45.402071)
			(xy 62.420498 -45.402071) (xy 62.412368 -45.453406) (xy 62.396307 -45.502836) (xy 62.372711 -45.549146)
			(xy 62.342161 -45.591194) (xy 62.30541 -45.627945) (xy 62.263362 -45.658495) (xy 62.217052 -45.682091)
			(xy 62.167622 -45.698152) (xy 62.116287 -45.706282) (xy 62.064313 -45.706282) (xy 62.012978 -45.698152)
			(xy 61.963548 -45.682091) (xy 61.917238 -45.658495) (xy 61.87519 -45.627945) (xy 61.838439 -45.591194)
			(xy 61.807889 -45.549146) (xy 61.784293 -45.502836) (xy 61.768232 -45.453406) (xy 61.760102 -45.402071)
			(xy 61.620398 -45.402071) (xy 61.612268 -45.453406) (xy 61.596207 -45.502836) (xy 61.572611 -45.549146)
			(xy 61.542061 -45.591194) (xy 61.50531 -45.627945) (xy 61.463262 -45.658495) (xy 61.416952 -45.682091)
			(xy 61.367522 -45.698152) (xy 61.316187 -45.706282) (xy 61.264213 -45.706282) (xy 61.212878 -45.698152)
			(xy 61.163448 -45.682091) (xy 61.117138 -45.658495) (xy 61.07509 -45.627945) (xy 61.038339 -45.591194)
			(xy 61.007789 -45.549146) (xy 60.984193 -45.502836) (xy 60.968132 -45.453406) (xy 60.960002 -45.402071)
			(xy 60.5536 -45.402071) (xy 60.5536 -46.201917) (xy 61.760102 -46.201917) (xy 61.760102 -46.149943)
			(xy 61.768232 -46.098608) (xy 61.784293 -46.049178) (xy 61.807889 -46.002868) (xy 61.838439 -45.96082)
			(xy 61.87519 -45.924069) (xy 61.917238 -45.893519) (xy 61.963548 -45.869923) (xy 62.012978 -45.853862)
			(xy 62.064313 -45.845732) (xy 62.116287 -45.845732) (xy 62.167622 -45.853862) (xy 62.217052 -45.869923)
			(xy 62.263362 -45.893519) (xy 62.30541 -45.924069) (xy 62.342161 -45.96082) (xy 62.372711 -46.002868)
			(xy 62.396307 -46.049178) (xy 62.412368 -46.098608) (xy 62.420498 -46.149943) (xy 62.421008 -46.17593)
			(xy 62.420498 -46.201917) (xy 62.559948 -46.201917) (xy 62.559948 -46.149943) (xy 62.568078 -46.098608)
			(xy 62.584139 -46.049178) (xy 62.607735 -46.002868) (xy 62.638285 -45.96082) (xy 62.675036 -45.924069)
			(xy 62.717084 -45.893519) (xy 62.763394 -45.869923) (xy 62.812824 -45.853862) (xy 62.864159 -45.845732)
			(xy 62.916133 -45.845732) (xy 62.967468 -45.853862) (xy 63.016898 -45.869923) (xy 63.063208 -45.893519)
			(xy 63.105256 -45.924069) (xy 63.142007 -45.96082) (xy 63.172557 -46.002868) (xy 63.196153 -46.049178)
			(xy 63.212214 -46.098608) (xy 63.220344 -46.149943) (xy 63.220854 -46.17593) (xy 63.220344 -46.201917)
			(xy 63.360048 -46.201917) (xy 63.360048 -46.149943) (xy 63.368178 -46.098608) (xy 63.384239 -46.049178)
			(xy 63.407835 -46.002868) (xy 63.438385 -45.96082) (xy 63.475136 -45.924069) (xy 63.517184 -45.893519)
			(xy 63.563494 -45.869923) (xy 63.612924 -45.853862) (xy 63.664259 -45.845732) (xy 63.716233 -45.845732)
			(xy 63.767568 -45.853862) (xy 63.816998 -45.869923) (xy 63.863308 -45.893519) (xy 63.905356 -45.924069)
			(xy 63.942107 -45.96082) (xy 63.972657 -46.002868) (xy 63.996253 -46.049178) (xy 64.012314 -46.098608)
			(xy 64.020444 -46.149943) (xy 64.020954 -46.17593) (xy 64.020444 -46.201917) (xy 64.012314 -46.253252)
			(xy 63.996253 -46.302682) (xy 63.972657 -46.348992) (xy 63.942107 -46.39104) (xy 63.905356 -46.427791)
			(xy 63.863308 -46.458341) (xy 63.816998 -46.481937) (xy 63.767568 -46.497998) (xy 63.716233 -46.506128)
			(xy 63.664259 -46.506128) (xy 63.612924 -46.497998) (xy 63.563494 -46.481937) (xy 63.517184 -46.458341)
			(xy 63.475136 -46.427791) (xy 63.438385 -46.39104) (xy 63.407835 -46.348992) (xy 63.384239 -46.302682)
			(xy 63.368178 -46.253252) (xy 63.360048 -46.201917) (xy 63.220344 -46.201917) (xy 63.212214 -46.253252)
			(xy 63.196153 -46.302682) (xy 63.172557 -46.348992) (xy 63.142007 -46.39104) (xy 63.105256 -46.427791)
			(xy 63.063208 -46.458341) (xy 63.016898 -46.481937) (xy 62.967468 -46.497998) (xy 62.916133 -46.506128)
			(xy 62.864159 -46.506128) (xy 62.812824 -46.497998) (xy 62.763394 -46.481937) (xy 62.717084 -46.458341)
			(xy 62.675036 -46.427791) (xy 62.638285 -46.39104) (xy 62.607735 -46.348992) (xy 62.584139 -46.302682)
			(xy 62.568078 -46.253252) (xy 62.559948 -46.201917) (xy 62.420498 -46.201917) (xy 62.412368 -46.253252)
			(xy 62.396307 -46.302682) (xy 62.372711 -46.348992) (xy 62.342161 -46.39104) (xy 62.30541 -46.427791)
			(xy 62.263362 -46.458341) (xy 62.217052 -46.481937) (xy 62.167622 -46.497998) (xy 62.116287 -46.506128)
			(xy 62.064313 -46.506128) (xy 62.012978 -46.497998) (xy 61.963548 -46.481937) (xy 61.917238 -46.458341)
			(xy 61.87519 -46.427791) (xy 61.838439 -46.39104) (xy 61.807889 -46.348992) (xy 61.784293 -46.302682)
			(xy 61.768232 -46.253252) (xy 61.760102 -46.201917) (xy 60.5536 -46.201917) (xy 60.5536 -47.002017)
			(xy 60.960002 -47.002017) (xy 60.960002 -46.950043) (xy 60.968132 -46.898708) (xy 60.984193 -46.849278)
			(xy 61.007789 -46.802968) (xy 61.038339 -46.76092) (xy 61.07509 -46.724169) (xy 61.117138 -46.693619)
			(xy 61.163448 -46.670023) (xy 61.212878 -46.653962) (xy 61.264213 -46.645832) (xy 61.316187 -46.645832)
			(xy 61.367522 -46.653962) (xy 61.416952 -46.670023) (xy 61.463262 -46.693619) (xy 61.50531 -46.724169)
			(xy 61.542061 -46.76092) (xy 61.572611 -46.802968) (xy 61.596207 -46.849278) (xy 61.612268 -46.898708)
			(xy 61.620398 -46.950043) (xy 61.620908 -46.97603) (xy 61.620398 -47.002017) (xy 61.760102 -47.002017)
			(xy 61.760102 -46.950043) (xy 61.768232 -46.898708) (xy 61.784293 -46.849278) (xy 61.807889 -46.802968)
			(xy 61.838439 -46.76092) (xy 61.87519 -46.724169) (xy 61.917238 -46.693619) (xy 61.963548 -46.670023)
			(xy 62.012978 -46.653962) (xy 62.064313 -46.645832) (xy 62.116287 -46.645832) (xy 62.167622 -46.653962)
			(xy 62.217052 -46.670023) (xy 62.263362 -46.693619) (xy 62.30541 -46.724169) (xy 62.342161 -46.76092)
			(xy 62.372711 -46.802968) (xy 62.396307 -46.849278) (xy 62.412368 -46.898708) (xy 62.420498 -46.950043)
			(xy 62.421008 -46.97603) (xy 62.420498 -47.002017) (xy 62.559948 -47.002017) (xy 62.559948 -46.950043)
			(xy 62.568078 -46.898708) (xy 62.584139 -46.849278) (xy 62.607735 -46.802968) (xy 62.638285 -46.76092)
			(xy 62.675036 -46.724169) (xy 62.717084 -46.693619) (xy 62.763394 -46.670023) (xy 62.812824 -46.653962)
			(xy 62.864159 -46.645832) (xy 62.916133 -46.645832) (xy 62.967468 -46.653962) (xy 63.016898 -46.670023)
			(xy 63.063208 -46.693619) (xy 63.105256 -46.724169) (xy 63.142007 -46.76092) (xy 63.172557 -46.802968)
			(xy 63.196153 -46.849278) (xy 63.212214 -46.898708) (xy 63.220344 -46.950043) (xy 63.220854 -46.97603)
			(xy 63.220344 -47.002017) (xy 63.360048 -47.002017) (xy 63.360048 -46.950043) (xy 63.368178 -46.898708)
			(xy 63.384239 -46.849278) (xy 63.407835 -46.802968) (xy 63.438385 -46.76092) (xy 63.475136 -46.724169)
			(xy 63.517184 -46.693619) (xy 63.563494 -46.670023) (xy 63.612924 -46.653962) (xy 63.664259 -46.645832)
			(xy 63.716233 -46.645832) (xy 63.767568 -46.653962) (xy 63.816998 -46.670023) (xy 63.863308 -46.693619)
			(xy 63.905356 -46.724169) (xy 63.942107 -46.76092) (xy 63.972657 -46.802968) (xy 63.996253 -46.849278)
			(xy 64.012314 -46.898708) (xy 64.020444 -46.950043) (xy 64.020954 -46.97603) (xy 64.020444 -47.002017)
			(xy 64.159894 -47.002017) (xy 64.159894 -46.950043) (xy 64.168024 -46.898708) (xy 64.184085 -46.849278)
			(xy 64.207681 -46.802968) (xy 64.238231 -46.76092) (xy 64.274982 -46.724169) (xy 64.31703 -46.693619)
			(xy 64.36334 -46.670023) (xy 64.41277 -46.653962) (xy 64.464105 -46.645832) (xy 64.516079 -46.645832)
			(xy 64.567414 -46.653962) (xy 64.616844 -46.670023) (xy 64.663154 -46.693619) (xy 64.705202 -46.724169)
			(xy 64.741953 -46.76092) (xy 64.772503 -46.802968) (xy 64.796099 -46.849278) (xy 64.81216 -46.898708)
			(xy 64.82029 -46.950043) (xy 64.8208 -46.97603) (xy 64.82029 -47.002017) (xy 64.81216 -47.053352)
			(xy 64.796099 -47.102782) (xy 64.772503 -47.149092) (xy 64.741953 -47.19114) (xy 64.705202 -47.227891)
			(xy 64.663154 -47.258441) (xy 64.616844 -47.282037) (xy 64.567414 -47.298098) (xy 64.516079 -47.306228)
			(xy 64.464105 -47.306228) (xy 64.41277 -47.298098) (xy 64.36334 -47.282037) (xy 64.31703 -47.258441)
			(xy 64.274982 -47.227891) (xy 64.238231 -47.19114) (xy 64.207681 -47.149092) (xy 64.184085 -47.102782)
			(xy 64.168024 -47.053352) (xy 64.159894 -47.002017) (xy 64.020444 -47.002017) (xy 64.012314 -47.053352)
			(xy 63.996253 -47.102782) (xy 63.972657 -47.149092) (xy 63.942107 -47.19114) (xy 63.905356 -47.227891)
			(xy 63.863308 -47.258441) (xy 63.816998 -47.282037) (xy 63.767568 -47.298098) (xy 63.716233 -47.306228)
			(xy 63.664259 -47.306228) (xy 63.612924 -47.298098) (xy 63.563494 -47.282037) (xy 63.517184 -47.258441)
			(xy 63.475136 -47.227891) (xy 63.438385 -47.19114) (xy 63.407835 -47.149092) (xy 63.384239 -47.102782)
			(xy 63.368178 -47.053352) (xy 63.360048 -47.002017) (xy 63.220344 -47.002017) (xy 63.212214 -47.053352)
			(xy 63.196153 -47.102782) (xy 63.172557 -47.149092) (xy 63.142007 -47.19114) (xy 63.105256 -47.227891)
			(xy 63.063208 -47.258441) (xy 63.016898 -47.282037) (xy 62.967468 -47.298098) (xy 62.916133 -47.306228)
			(xy 62.864159 -47.306228) (xy 62.812824 -47.298098) (xy 62.763394 -47.282037) (xy 62.717084 -47.258441)
			(xy 62.675036 -47.227891) (xy 62.638285 -47.19114) (xy 62.607735 -47.149092) (xy 62.584139 -47.102782)
			(xy 62.568078 -47.053352) (xy 62.559948 -47.002017) (xy 62.420498 -47.002017) (xy 62.412368 -47.053352)
			(xy 62.396307 -47.102782) (xy 62.372711 -47.149092) (xy 62.342161 -47.19114) (xy 62.30541 -47.227891)
			(xy 62.263362 -47.258441) (xy 62.217052 -47.282037) (xy 62.167622 -47.298098) (xy 62.116287 -47.306228)
			(xy 62.064313 -47.306228) (xy 62.012978 -47.298098) (xy 61.963548 -47.282037) (xy 61.917238 -47.258441)
			(xy 61.87519 -47.227891) (xy 61.838439 -47.19114) (xy 61.807889 -47.149092) (xy 61.784293 -47.102782)
			(xy 61.768232 -47.053352) (xy 61.760102 -47.002017) (xy 61.620398 -47.002017) (xy 61.612268 -47.053352)
			(xy 61.596207 -47.102782) (xy 61.572611 -47.149092) (xy 61.542061 -47.19114) (xy 61.50531 -47.227891)
			(xy 61.463262 -47.258441) (xy 61.416952 -47.282037) (xy 61.367522 -47.298098) (xy 61.316187 -47.306228)
			(xy 61.264213 -47.306228) (xy 61.212878 -47.298098) (xy 61.163448 -47.282037) (xy 61.117138 -47.258441)
			(xy 61.07509 -47.227891) (xy 61.038339 -47.19114) (xy 61.007789 -47.149092) (xy 60.984193 -47.102782)
			(xy 60.968132 -47.053352) (xy 60.960002 -47.002017) (xy 60.5536 -47.002017) (xy 60.5536 -47.719234)
			(xy 60.636483 -47.802117) (xy 60.960002 -47.802117) (xy 60.960002 -47.750143) (xy 60.968132 -47.698808)
			(xy 60.984193 -47.649378) (xy 61.007789 -47.603068) (xy 61.038339 -47.56102) (xy 61.07509 -47.524269)
			(xy 61.117138 -47.493719) (xy 61.163448 -47.470123) (xy 61.212878 -47.454062) (xy 61.264213 -47.445932)
			(xy 61.316187 -47.445932) (xy 61.367522 -47.454062) (xy 61.416952 -47.470123) (xy 61.463262 -47.493719)
			(xy 61.50531 -47.524269) (xy 61.542061 -47.56102) (xy 61.572611 -47.603068) (xy 61.596207 -47.649378)
			(xy 61.612268 -47.698808) (xy 61.620398 -47.750143) (xy 61.620908 -47.77613) (xy 61.620398 -47.802117)
			(xy 61.760102 -47.802117) (xy 61.760102 -47.750143) (xy 61.768232 -47.698808) (xy 61.784293 -47.649378)
			(xy 61.807889 -47.603068) (xy 61.838439 -47.56102) (xy 61.87519 -47.524269) (xy 61.917238 -47.493719)
			(xy 61.963548 -47.470123) (xy 62.012978 -47.454062) (xy 62.064313 -47.445932) (xy 62.116287 -47.445932)
			(xy 62.167622 -47.454062) (xy 62.217052 -47.470123) (xy 62.263362 -47.493719) (xy 62.30541 -47.524269)
			(xy 62.342161 -47.56102) (xy 62.372711 -47.603068) (xy 62.396307 -47.649378) (xy 62.412368 -47.698808)
			(xy 62.420498 -47.750143) (xy 62.421008 -47.77613) (xy 62.420498 -47.802117) (xy 62.559948 -47.802117)
			(xy 62.559948 -47.750143) (xy 62.568078 -47.698808) (xy 62.584139 -47.649378) (xy 62.607735 -47.603068)
			(xy 62.638285 -47.56102) (xy 62.675036 -47.524269) (xy 62.717084 -47.493719) (xy 62.763394 -47.470123)
			(xy 62.812824 -47.454062) (xy 62.864159 -47.445932) (xy 62.916133 -47.445932) (xy 62.967468 -47.454062)
			(xy 63.016898 -47.470123) (xy 63.063208 -47.493719) (xy 63.105256 -47.524269) (xy 63.142007 -47.56102)
			(xy 63.172557 -47.603068) (xy 63.196153 -47.649378) (xy 63.212214 -47.698808) (xy 63.220344 -47.750143)
			(xy 63.220854 -47.77613) (xy 63.220344 -47.802117) (xy 63.360048 -47.802117) (xy 63.360048 -47.750143)
			(xy 63.368178 -47.698808) (xy 63.384239 -47.649378) (xy 63.407835 -47.603068) (xy 63.438385 -47.56102)
			(xy 63.475136 -47.524269) (xy 63.517184 -47.493719) (xy 63.563494 -47.470123) (xy 63.612924 -47.454062)
			(xy 63.664259 -47.445932) (xy 63.716233 -47.445932) (xy 63.767568 -47.454062) (xy 63.816998 -47.470123)
			(xy 63.863308 -47.493719) (xy 63.905356 -47.524269) (xy 63.942107 -47.56102) (xy 63.972657 -47.603068)
			(xy 63.996253 -47.649378) (xy 64.012314 -47.698808) (xy 64.020444 -47.750143) (xy 64.020954 -47.77613)
			(xy 64.020444 -47.802117) (xy 64.012314 -47.853452) (xy 63.996253 -47.902882) (xy 63.972657 -47.949192)
			(xy 63.942107 -47.99124) (xy 63.905356 -48.027991) (xy 63.863308 -48.058541) (xy 63.816998 -48.082137)
			(xy 63.767568 -48.098198) (xy 63.716233 -48.106328) (xy 63.664259 -48.106328) (xy 63.612924 -48.098198)
			(xy 63.563494 -48.082137) (xy 63.517184 -48.058541) (xy 63.475136 -48.027991) (xy 63.438385 -47.99124)
			(xy 63.407835 -47.949192) (xy 63.384239 -47.902882) (xy 63.368178 -47.853452) (xy 63.360048 -47.802117)
			(xy 63.220344 -47.802117) (xy 63.212214 -47.853452) (xy 63.196153 -47.902882) (xy 63.172557 -47.949192)
			(xy 63.142007 -47.99124) (xy 63.105256 -48.027991) (xy 63.063208 -48.058541) (xy 63.016898 -48.082137)
			(xy 62.967468 -48.098198) (xy 62.916133 -48.106328) (xy 62.864159 -48.106328) (xy 62.812824 -48.098198)
			(xy 62.763394 -48.082137) (xy 62.717084 -48.058541) (xy 62.675036 -48.027991) (xy 62.638285 -47.99124)
			(xy 62.607735 -47.949192) (xy 62.584139 -47.902882) (xy 62.568078 -47.853452) (xy 62.559948 -47.802117)
			(xy 62.420498 -47.802117) (xy 62.412368 -47.853452) (xy 62.396307 -47.902882) (xy 62.372711 -47.949192)
			(xy 62.342161 -47.99124) (xy 62.30541 -48.027991) (xy 62.263362 -48.058541) (xy 62.217052 -48.082137)
			(xy 62.167622 -48.098198) (xy 62.116287 -48.106328) (xy 62.064313 -48.106328) (xy 62.012978 -48.098198)
			(xy 61.963548 -48.082137) (xy 61.917238 -48.058541) (xy 61.87519 -48.027991) (xy 61.838439 -47.99124)
			(xy 61.807889 -47.949192) (xy 61.784293 -47.902882) (xy 61.768232 -47.853452) (xy 61.760102 -47.802117)
			(xy 61.620398 -47.802117) (xy 61.612268 -47.853452) (xy 61.596207 -47.902882) (xy 61.572611 -47.949192)
			(xy 61.542061 -47.99124) (xy 61.50531 -48.027991) (xy 61.463262 -48.058541) (xy 61.416952 -48.082137)
			(xy 61.367522 -48.098198) (xy 61.316187 -48.106328) (xy 61.264213 -48.106328) (xy 61.212878 -48.098198)
			(xy 61.163448 -48.082137) (xy 61.117138 -48.058541) (xy 61.07509 -48.027991) (xy 61.038339 -47.99124)
			(xy 61.007789 -47.949192) (xy 60.984193 -47.902882) (xy 60.968132 -47.853452) (xy 60.960002 -47.802117)
			(xy 60.636483 -47.802117) (xy 61.122814 -48.288448) (xy 61.154818 -48.274224) (xy 61.176201 -48.26507)
			(xy 61.220889 -48.252173) (xy 61.266944 -48.24566) (xy 61.2902 -48.245268) (xy 61.316188 -48.245778)
			(xy 61.367524 -48.253908) (xy 61.416956 -48.269969) (xy 61.463267 -48.293564) (xy 61.505317 -48.324113)
			(xy 61.542071 -48.360865) (xy 61.572623 -48.402912) (xy 61.596222 -48.449222) (xy 61.612286 -48.498653)
			(xy 61.620421 -48.549988) (xy 61.620908 -48.575976) (xy 61.620776 -48.587895) (xy 61.618995 -48.611668)
			(xy 61.617352 -48.623474) (xy 61.615734 -48.63794) (xy 61.619861 -48.666742) (xy 61.631939 -48.693214)
			(xy 61.65099 -48.715207) (xy 61.675468 -48.730937) (xy 61.703387 -48.73913) (xy 61.717936 -48.739552)
		)
		(stroke
			(width 0)
			(type solid)
		)
		(fill yes)
		(layer "In4.Cu")
		(net "P1V8_STBY_AVDDPLL")
	)
	(gr_poly
		(pts
			(xy 56.427624 -74.719942) (xy 56.425846 -74.696574) (xy 56.424576 -74.66584) (xy 56.425083 -74.638031)
			(xy 56.433168 -74.583004) (xy 56.449156 -74.529733) (xy 56.47271 -74.479349) (xy 56.50333 -74.432918)
			(xy 56.540367 -74.391426) (xy 56.583036 -74.35575) (xy 56.60644 -74.34072) (xy 56.618724 -74.332597)
			(xy 56.63837 -74.310675) (xy 56.650946 -74.284059) (xy 56.655407 -74.254962) (xy 56.651381 -74.225802)
			(xy 56.639204 -74.199001) (xy 56.619887 -74.176789) (xy 56.60771 -74.168508) (xy 56.584877 -74.153413)
			(xy 56.543379 -74.117721) (xy 56.507411 -74.076463) (xy 56.477711 -74.030486) (xy 56.454889 -73.980735)
			(xy 56.439414 -73.928233) (xy 56.431605 -73.874058) (xy 56.43118 -73.84669) (xy 56.4317 -73.817967)
			(xy 56.440312 -73.76117) (xy 56.45734 -73.706305) (xy 56.482398 -73.654613) (xy 56.514922 -73.60726)
			(xy 56.554176 -73.565317) (xy 56.599273 -73.529732) (xy 56.649194 -73.501308) (xy 56.702812 -73.480687)
			(xy 56.758914 -73.468336) (xy 56.787542 -73.465944) (xy 56.797069 -73.464898) (xy 56.81438 -73.456708)
			(xy 56.827497 -73.442755) (xy 56.834604 -73.424971) (xy 56.83504 -73.415398) (xy 56.83504 -70.478142)
			(xy 56.754522 -70.397878) (xy 56.737752 -70.380437) (xy 56.709315 -70.341296) (xy 56.68735 -70.298189)
			(xy 56.6724 -70.252176) (xy 56.664831 -70.20439) (xy 56.664352 -70.1802) (xy 56.664352 -67.02298)
			(xy 56.460898 -66.819272) (xy 56.451754 -66.815208) (xy 56.426151 -66.803928) (xy 56.378284 -66.774968)
			(xy 56.335164 -66.739322) (xy 56.297717 -66.697757) (xy 56.266746 -66.651166) (xy 56.242918 -66.600548)
			(xy 56.226744 -66.546991) (xy 56.218571 -66.491645) (xy 56.218074 -66.463672) (xy 56.218578 -66.435871)
			(xy 56.226648 -66.380859) (xy 56.242615 -66.3276) (xy 56.266139 -66.27722) (xy 56.296723 -66.230786)
			(xy 56.33372 -66.189281) (xy 56.354726 -66.171064) (xy 56.354726 -62.190122) (xy 56.354199 -62.174665)
			(xy 56.344979 -62.145159) (xy 56.327348 -62.119767) (xy 56.302923 -62.100818) (xy 56.273945 -62.090052)
			(xy 56.243074 -62.088456) (xy 56.22798 -62.091824) (xy 56.204874 -62.09731) (xy 56.157746 -62.103175)
			(xy 56.134 -62.103508) (xy 56.106749 -62.103022) (xy 56.052801 -62.095266) (xy 56.000506 -62.079911)
			(xy 55.950929 -62.057269) (xy 55.905079 -62.027803) (xy 55.863888 -61.992112) (xy 55.828197 -61.950921)
			(xy 55.798731 -61.905071) (xy 55.776089 -61.855494) (xy 55.760734 -61.803199) (xy 55.752978 -61.749251)
			(xy 55.752978 -61.694749) (xy 55.760734 -61.640801) (xy 55.776089 -61.588506) (xy 55.798731 -61.538929)
			(xy 55.828197 -61.493079) (xy 55.863888 -61.451888) (xy 55.905079 -61.416197) (xy 55.950929 -61.386731)
			(xy 56.000506 -61.364089) (xy 56.052801 -61.348734) (xy 56.106749 -61.340978) (xy 56.134 -61.340492)
			(xy 56.157745 -61.34084) (xy 56.204872 -61.346702) (xy 56.22798 -61.352176) (xy 56.243075 -61.35547)
			(xy 56.273911 -61.353823) (xy 56.30285 -61.343045) (xy 56.327253 -61.324121) (xy 56.344893 -61.298774)
			(xy 56.354163 -61.269317) (xy 56.354726 -61.253878) (xy 56.354726 -60.546488) (xy 56.35427 -60.532725)
			(xy 56.346914 -60.506201) (xy 56.33274 -60.482605) (xy 56.312778 -60.463653) (xy 56.288479 -60.450722)
			(xy 56.261609 -60.444752) (xy 56.23412 -60.446176) (xy 56.208011 -60.454892) (xy 56.185178 -60.470265)
			(xy 56.17591 -60.480448) (xy 56.158913 -60.499613) (xy 56.120362 -60.533346) (xy 56.077374 -60.561205)
			(xy 56.030837 -60.582615) (xy 55.981712 -60.597134) (xy 55.931013 -60.604462) (xy 55.9054 -60.604908)
			(xy 55.877417 -60.604359) (xy 55.82214 -60.595604) (xy 55.768913 -60.578309) (xy 55.719046 -60.552901)
			(xy 55.673769 -60.520005) (xy 55.634195 -60.480431) (xy 55.601299 -60.435154) (xy 55.575891 -60.385287)
			(xy 55.558596 -60.33206) (xy 55.549841 -60.276783) (xy 55.549292 -60.2488) (xy 55.549805 -60.221287)
			(xy 55.558271 -60.166915) (xy 55.575003 -60.114494) (xy 55.599602 -60.065272) (xy 55.631481 -60.020421)
			(xy 55.669882 -59.981008) (xy 55.71389 -59.947974) (xy 55.762456 -59.922105) (xy 55.814425 -59.904017)
			(xy 55.841392 -59.898534) (xy 55.856886 -59.89574) (xy 55.90413 -59.848496) (xy 55.865522 -59.810142)
			(xy 55.851279 -59.795389) (xy 55.82643 -59.762769) (xy 55.815992 -59.745118) (xy 55.81269 -59.739276)
			(xy 55.764684 -59.69127) (xy 55.764684 -59.3979) (xy 55.764196 -59.382514) (xy 55.755118 -59.353115)
			(xy 55.737695 -59.327755) (xy 55.713509 -59.308736) (xy 55.684756 -59.297784) (xy 55.669434 -59.2963)
			(xy 55.644578 -59.294267) (xy 55.595848 -59.283671) (xy 55.549261 -59.265879) (xy 55.505872 -59.241295)
			(xy 55.466666 -59.210476) (xy 55.43253 -59.174121) (xy 55.40424 -59.133053) (xy 55.382434 -59.088203)
			(xy 55.367609 -59.040589) (xy 55.3601 -58.991288) (xy 55.359554 -58.966354) (xy 55.360067 -58.940368)
			(xy 55.368203 -58.889037) (xy 55.384268 -58.83961) (xy 55.407865 -58.793304) (xy 55.438415 -58.751259)
			(xy 55.475165 -58.71451) (xy 55.517211 -58.683961) (xy 55.563518 -58.660364) (xy 55.612945 -58.644301)
			(xy 55.664276 -58.636166) (xy 55.690262 -58.635646) (xy 55.710836 -58.636154) (xy 55.721225 -58.636271)
			(xy 55.74074 -58.629202) (xy 55.755881 -58.615005) (xy 55.764189 -58.595983) (xy 55.764684 -58.585608)
			(xy 55.764684 -58.547254) (xy 55.764212 -58.536849) (xy 55.755983 -58.51774) (xy 55.740825 -58.503488)
			(xy 55.721244 -58.496452) (xy 55.710836 -58.496708) (xy 55.690262 -58.497216) (xy 55.664276 -58.496704)
			(xy 55.612945 -58.488568) (xy 55.563518 -58.472503) (xy 55.517213 -58.448905) (xy 55.475169 -58.418354)
			(xy 55.438422 -58.381602) (xy 55.407875 -58.339555) (xy 55.384282 -58.293246) (xy 55.368223 -58.243818)
			(xy 55.360093 -58.192486) (xy 55.360093 -58.140514) (xy 55.368223 -58.089182) (xy 55.384282 -58.039754)
			(xy 55.407875 -57.993445) (xy 55.438422 -57.951398) (xy 55.475169 -57.914646) (xy 55.517213 -57.884095)
			(xy 55.563518 -57.860497) (xy 55.612945 -57.844432) (xy 55.664276 -57.836296) (xy 55.690262 -57.8358)
			(xy 55.710836 -57.836308) (xy 55.721222 -57.836425) (xy 55.74073 -57.829355) (xy 55.75586 -57.815155)
			(xy 55.764152 -57.796134) (xy 55.764684 -57.785762) (xy 55.764684 -57.747662) (xy 55.764215 -57.737419)
			(xy 55.756207 -57.718563) (xy 55.741477 -57.704325) (xy 55.722358 -57.696964) (xy 55.712106 -57.696862)
			(xy 55.69966 -57.697116) (xy 55.673675 -57.696603) (xy 55.622345 -57.688468) (xy 55.572919 -57.672404)
			(xy 55.526614 -57.648806) (xy 55.484571 -57.618255) (xy 55.447824 -57.581505) (xy 55.417278 -57.539458)
			(xy 55.393684 -57.493152) (xy 55.377625 -57.443724) (xy 55.369494 -57.392393) (xy 55.368952 -57.366408)
			(xy 55.369417 -57.341314) (xy 55.377 -57.291703) (xy 55.391994 -57.243808) (xy 55.414054 -57.198729)
			(xy 55.442673 -57.157501) (xy 55.477194 -57.121072) (xy 55.496714 -57.105296) (xy 55.499254 -57.103264)
			(xy 55.537354 -57.065164) (xy 55.481982 -57.009792) (xy 55.465213 -56.992351) (xy 55.436778 -56.953209)
			(xy 55.414814 -56.910101) (xy 55.399864 -56.864089) (xy 55.392294 -56.816304) (xy 55.391812 -56.792114)
			(xy 55.391812 -56.687974) (xy 55.388764 -56.679592) (xy 55.379477 -56.652264) (xy 55.369512 -56.595419)
			(xy 55.368952 -56.566562) (xy 55.369464 -56.540576) (xy 55.377599 -56.489243) (xy 55.393663 -56.439815)
			(xy 55.41726 -56.393508) (xy 55.44781 -56.351462) (xy 55.48456 -56.314711) (xy 55.526607 -56.284161)
			(xy 55.572914 -56.260564) (xy 55.622341 -56.2445) (xy 55.673674 -56.236364) (xy 55.69966 -56.235854)
			(xy 55.712106 -56.236108) (xy 55.722359 -56.236005) (xy 55.741484 -56.228661) (xy 55.756211 -56.21442)
			(xy 55.764192 -56.195552) (xy 55.764684 -56.185308) (xy 55.764684 -56.147208) (xy 55.764203 -56.13681)
			(xy 55.755967 -56.117717) (xy 55.740811 -56.10348) (xy 55.721241 -56.096452) (xy 55.710836 -56.096662)
			(xy 55.690262 -56.09717) (xy 55.664278 -56.096657) (xy 55.61295 -56.088522) (xy 55.563527 -56.072457)
			(xy 55.517226 -56.048858) (xy 55.475186 -56.018307) (xy 55.438443 -55.981556) (xy 55.407902 -55.939509)
			(xy 55.384314 -55.893202) (xy 55.368261 -55.843776) (xy 55.360137 -55.792446) (xy 55.359554 -55.766462)
			(xy 55.359966 -55.742156) (xy 55.367052 -55.694064) (xy 55.381109 -55.647529) (xy 55.401834 -55.603557)
			(xy 55.414926 -55.583074) (xy 55.422929 -55.570065) (xy 55.43153 -55.540771) (xy 55.43111 -55.510244)
			(xy 55.421706 -55.481198) (xy 55.404156 -55.456217) (xy 55.38002 -55.437522) (xy 55.365904 -55.43169)
			(xy 55.345464 -55.423654) (xy 55.306909 -55.40262) (xy 55.271736 -55.376319) (xy 55.255922 -55.361078)
			(xy 54.315614 -54.420516) (xy 54.28107 -54.443122) (xy 54.260756 -54.455913) (xy 54.217219 -54.476131)
			(xy 54.171217 -54.489846) (xy 54.123716 -54.49677) (xy 54.099714 -54.497224) (xy 54.073726 -54.496716)
			(xy 54.022389 -54.488587) (xy 53.972955 -54.472527) (xy 53.926642 -54.448932) (xy 53.884591 -54.418383)
			(xy 53.847836 -54.381632) (xy 53.817283 -54.339583) (xy 53.793684 -54.293273) (xy 53.77762 -54.243841)
			(xy 53.769487 -54.192504) (xy 53.769006 -54.166516) (xy 53.77053 -54.13502) (xy 53.770784 -54.132734)
			(xy 53.770784 -54.079648) (xy 53.628798 -54.079648) (xy 53.628798 -54.132734) (xy 53.629052 -54.13502)
			(xy 53.630576 -54.166516) (xy 53.630066 -54.192503) (xy 53.621936 -54.243838) (xy 53.605875 -54.293268)
			(xy 53.582279 -54.339578) (xy 53.551729 -54.381626) (xy 53.514978 -54.418377) (xy 53.47293 -54.448927)
			(xy 53.42662 -54.472523) (xy 53.37719 -54.488584) (xy 53.325855 -54.496714) (xy 53.273881 -54.496714)
			(xy 53.222546 -54.488584) (xy 53.173116 -54.472523) (xy 53.126806 -54.448927) (xy 53.084758 -54.418377)
			(xy 53.048007 -54.381626) (xy 53.017457 -54.339578) (xy 52.993861 -54.293268) (xy 52.9778 -54.243838)
			(xy 52.96967 -54.192503) (xy 52.96916 -54.166516) (xy 52.969249 -54.154665) (xy 52.970901 -54.13102)
			(xy 52.972462 -54.119272) (xy 52.973499 -54.107458) (xy 52.965969 -54.084999) (xy 52.9492 -54.068269)
			(xy 52.938172 -54.0639) (xy 52.915678 -54.055953) (xy 52.873264 -54.034117) (xy 52.834713 -54.006019)
			(xy 52.817522 -53.989478) (xy 52.197254 -53.36921) (xy 52.18711 -53.359782) (xy 52.162957 -53.346257)
			(xy 52.136058 -53.339716) (xy 52.108392 -53.340639) (xy 52.08199 -53.348959) (xy 52.058792 -53.364064)
			(xy 52.040503 -53.384845) (xy 52.028467 -53.409774) (xy 52.02555 -53.423312) (xy 52.020652 -53.448548)
			(xy 52.004085 -53.49721) (xy 51.980185 -53.542721) (xy 51.949529 -53.583983) (xy 51.912855 -53.620003)
			(xy 51.871047 -53.649912) (xy 51.825113 -53.672989) (xy 51.776161 -53.688677) (xy 51.725371 -53.696598)
			(xy 51.699668 -53.697124) (xy 51.673682 -53.696612) (xy 51.62235 -53.688478) (xy 51.572923 -53.672414)
			(xy 51.526617 -53.648817) (xy 51.484572 -53.618267) (xy 51.447823 -53.581516) (xy 51.417275 -53.539469)
			(xy 51.39368 -53.493162) (xy 51.377619 -53.443734) (xy 51.369487 -53.392402) (xy 51.36896 -53.366416)
			(xy 51.369523 -53.338681) (xy 51.378775 -53.283988) (xy 51.39702 -53.231605) (xy 51.423749 -53.182999)
			(xy 51.458211 -53.139534) (xy 51.478434 -53.120544) (xy 51.488254 -53.111104) (xy 51.502934 -53.088171)
			(xy 51.511029 -53.062173) (xy 51.511962 -53.03496) (xy 51.505667 -53.008468) (xy 51.492592 -52.984584)
			(xy 51.473667 -52.965007) (xy 51.45024 -52.951129) (xy 51.423977 -52.94394) (xy 51.410362 -52.943506)
			(xy 51.189128 -52.943506) (xy 51.175514 -52.943937) (xy 51.149252 -52.951128) (xy 51.125826 -52.965006)
			(xy 51.106903 -52.984584) (xy 51.093828 -53.008468) (xy 51.087534 -53.034959) (xy 51.088466 -53.062171)
			(xy 51.09656 -53.088169) (xy 51.111239 -53.111102) (xy 51.121056 -53.120544) (xy 51.141286 -53.139526)
			(xy 51.175739 -53.183001) (xy 51.202466 -53.231609) (xy 51.220721 -53.28399) (xy 51.229994 -53.338681)
			(xy 51.23053 -53.366416) (xy 51.23002 -53.392403) (xy 51.22189 -53.443738) (xy 51.205829 -53.493168)
			(xy 51.182233 -53.539478) (xy 51.151683 -53.581526) (xy 51.114932 -53.618277) (xy 51.072884 -53.648827)
			(xy 51.026574 -53.672423) (xy 50.977144 -53.688484) (xy 50.925809 -53.696614) (xy 50.873835 -53.696614)
			(xy 50.8225 -53.688484) (xy 50.77307 -53.672423) (xy 50.72676 -53.648827) (xy 50.684712 -53.618277)
			(xy 50.647961 -53.581526) (xy 50.617411 -53.539478) (xy 50.593815 -53.493168) (xy 50.577754 -53.443738)
			(xy 50.569624 -53.392403) (xy 50.569114 -53.366416) (xy 50.569678 -53.338682) (xy 50.57893 -53.28399)
			(xy 50.597178 -53.231608) (xy 50.623909 -53.183006) (xy 50.658376 -53.139545) (xy 50.678588 -53.120544)
			(xy 50.688404 -53.1111) (xy 50.703077 -53.088164) (xy 50.711167 -53.062165) (xy 50.712098 -53.034953)
			(xy 50.705803 -53.008462) (xy 50.692731 -52.984577) (xy 50.673811 -52.964996) (xy 50.650389 -52.951111)
			(xy 50.62413 -52.943911) (xy 50.610516 -52.943506) (xy 49.560734 -52.943506) (xy 49.23028 -53.27396)
			(xy 49.23028 -54.192503) (xy 50.569624 -54.192503) (xy 50.569624 -54.140529) (xy 50.577754 -54.089194)
			(xy 50.593815 -54.039764) (xy 50.617411 -53.993454) (xy 50.647961 -53.951406) (xy 50.684712 -53.914655)
			(xy 50.72676 -53.884105) (xy 50.77307 -53.860509) (xy 50.8225 -53.844448) (xy 50.873835 -53.836318)
			(xy 50.925809 -53.836318) (xy 50.977144 -53.844448) (xy 51.026574 -53.860509) (xy 51.072884 -53.884105)
			(xy 51.114932 -53.914655) (xy 51.151683 -53.951406) (xy 51.182233 -53.993454) (xy 51.205829 -54.039764)
			(xy 51.22189 -54.089194) (xy 51.23002 -54.140529) (xy 51.23053 -54.166516) (xy 51.23002 -54.192503)
			(xy 51.229915 -54.193165) (xy 51.344058 -54.193165) (xy 51.344058 -54.139867) (xy 51.352001 -54.087163)
			(xy 51.367711 -54.036233) (xy 51.390837 -53.988212) (xy 51.420861 -53.944175) (xy 51.457113 -53.905104)
			(xy 51.498784 -53.871873) (xy 51.544942 -53.845224) (xy 51.594556 -53.825752) (xy 51.646518 -53.813892)
			(xy 51.699668 -53.809909) (xy 51.752818 -53.813892) (xy 51.80478 -53.825752) (xy 51.854394 -53.845224)
			(xy 51.900552 -53.871873) (xy 51.942223 -53.905104) (xy 51.978475 -53.944175) (xy 52.008499 -53.988212)
			(xy 52.031625 -54.036233) (xy 52.047335 -54.087163) (xy 52.055278 -54.139867) (xy 52.055776 -54.166516)
			(xy 52.055278 -54.193165) (xy 52.047335 -54.245869) (xy 52.031625 -54.296799) (xy 52.008499 -54.34482)
			(xy 51.978475 -54.388857) (xy 51.942223 -54.427928) (xy 51.900552 -54.461159) (xy 51.854394 -54.487808)
			(xy 51.80478 -54.50728) (xy 51.752818 -54.51914) (xy 51.699668 -54.523124) (xy 51.646518 -54.51914)
			(xy 51.594556 -54.50728) (xy 51.544942 -54.487808) (xy 51.498784 -54.461159) (xy 51.457113 -54.427928)
			(xy 51.420861 -54.388857) (xy 51.390837 -54.34482) (xy 51.367711 -54.296799) (xy 51.352001 -54.245869)
			(xy 51.344058 -54.193165) (xy 51.229915 -54.193165) (xy 51.22189 -54.243838) (xy 51.205829 -54.293268)
			(xy 51.182233 -54.339578) (xy 51.151683 -54.381626) (xy 51.114932 -54.418377) (xy 51.072884 -54.448927)
			(xy 51.026574 -54.472523) (xy 50.977144 -54.488584) (xy 50.925809 -54.496714) (xy 50.873835 -54.496714)
			(xy 50.8225 -54.488584) (xy 50.77307 -54.472523) (xy 50.72676 -54.448927) (xy 50.684712 -54.418377)
			(xy 50.647961 -54.381626) (xy 50.617411 -54.339578) (xy 50.593815 -54.293268) (xy 50.577754 -54.243838)
			(xy 50.569624 -54.192503) (xy 49.23028 -54.192503) (xy 49.23028 -55.335424) (xy 49.23085 -55.350648)
			(xy 49.239828 -55.379744) (xy 49.25698 -55.404902) (xy 49.280783 -55.423891) (xy 49.309124 -55.435024)
			(xy 49.32426 -55.43677) (xy 49.348921 -55.439039) (xy 49.39721 -55.450021) (xy 49.443323 -55.468077)
			(xy 49.48623 -55.492805) (xy 49.524971 -55.523652) (xy 49.558682 -55.559928) (xy 49.58661 -55.600824)
			(xy 49.60813 -55.645426) (xy 49.622762 -55.692738) (xy 49.630178 -55.741701) (xy 49.630584 -55.766462)
			(xy 49.630104 -55.792449) (xy 49.769524 -55.792449) (xy 49.769524 -55.740475) (xy 49.777654 -55.68914)
			(xy 49.793715 -55.63971) (xy 49.817311 -55.5934) (xy 49.847861 -55.551352) (xy 49.884612 -55.514601)
			(xy 49.92666 -55.484051) (xy 49.97297 -55.460455) (xy 50.0224 -55.444394) (xy 50.073735 -55.436264)
			(xy 50.125709 -55.436264) (xy 50.177044 -55.444394) (xy 50.226474 -55.460455) (xy 50.272784 -55.484051)
			(xy 50.314832 -55.514601) (xy 50.351583 -55.551352) (xy 50.382133 -55.5934) (xy 50.405729 -55.63971)
			(xy 50.42179 -55.68914) (xy 50.42992 -55.740475) (xy 50.43043 -55.766462) (xy 50.42992 -55.792449)
			(xy 50.42179 -55.843784) (xy 50.405729 -55.893214) (xy 50.382133 -55.939524) (xy 50.351583 -55.981572)
			(xy 50.314832 -56.018323) (xy 50.272784 -56.048873) (xy 50.226474 -56.072469) (xy 50.177044 -56.08853)
			(xy 50.125709 -56.09666) (xy 50.073735 -56.09666) (xy 50.0224 -56.08853) (xy 49.97297 -56.072469)
			(xy 49.92666 -56.048873) (xy 49.884612 -56.018323) (xy 49.847861 -55.981572) (xy 49.817311 -55.939524)
			(xy 49.793715 -55.893214) (xy 49.777654 -55.843784) (xy 49.769524 -55.792449) (xy 49.630104 -55.792449)
			(xy 49.630104 -55.792453) (xy 49.621977 -55.843794) (xy 49.605918 -55.893232) (xy 49.582322 -55.939549)
			(xy 49.55177 -55.981604) (xy 49.515014 -56.018361) (xy 49.472961 -56.048914) (xy 49.426645 -56.072512)
			(xy 49.377208 -56.088574) (xy 49.325867 -56.096703) (xy 49.299876 -56.09717) (xy 49.28362 -56.096662)
			(xy 49.273254 -56.096614) (xy 49.253831 -56.103799) (xy 49.238823 -56.11807) (xy 49.230669 -56.137107)
			(xy 49.23028 -56.147462) (xy 49.23028 -56.185562) (xy 49.230772 -56.195899) (xy 49.238928 -56.214897)
			(xy 49.253899 -56.229155) (xy 49.273272 -56.236375) (xy 49.28362 -56.236362) (xy 49.299876 -56.235854)
			(xy 49.325866 -56.236362) (xy 49.377205 -56.244489) (xy 49.426641 -56.260547) (xy 49.472957 -56.284141)
			(xy 49.515011 -56.31469) (xy 49.55177 -56.351441) (xy 49.582326 -56.39349) (xy 49.605929 -56.439801)
			(xy 49.621996 -56.489235) (xy 49.630133 -56.540573) (xy 49.630584 -56.566562) (xy 49.630132 -56.591265)
			(xy 49.622737 -56.640116) (xy 49.615852 -56.663844) (xy 49.612253 -56.676974) (xy 49.611385 -56.704176)
			(xy 49.617738 -56.730639) (xy 49.63086 -56.754482) (xy 49.649817 -56.774009) (xy 49.673261 -56.78783)
			(xy 49.699525 -56.794963) (xy 49.713134 -56.795416) (xy 49.81321 -56.795416) (xy 49.81321 -56.731916)
			(xy 49.807368 -56.720994) (xy 49.79529 -56.697063) (xy 49.778197 -56.64626) (xy 49.76954 -56.593363)
			(xy 49.769014 -56.566562) (xy 49.769524 -56.540575) (xy 49.777654 -56.48924) (xy 49.793715 -56.43981)
			(xy 49.817311 -56.3935) (xy 49.847861 -56.351452) (xy 49.884612 -56.314701) (xy 49.92666 -56.284151)
			(xy 49.97297 -56.260555) (xy 50.0224 -56.244494) (xy 50.073735 -56.236364) (xy 50.125709 -56.236364)
			(xy 50.177044 -56.244494) (xy 50.226474 -56.260555) (xy 50.272784 -56.284151) (xy 50.314832 -56.314701)
			(xy 50.351583 -56.351452) (xy 50.382133 -56.3935) (xy 50.405729 -56.43981) (xy 50.42179 -56.48924)
			(xy 50.42992 -56.540575) (xy 50.43043 -56.566562) (xy 50.429978 -56.591265) (xy 50.422585 -56.640116)
			(xy 50.415698 -56.663844) (xy 50.4121 -56.676977) (xy 50.411234 -56.704182) (xy 50.417587 -56.730649)
			(xy 50.430707 -56.754497) (xy 50.449662 -56.774031) (xy 50.473105 -56.787863) (xy 50.49937 -56.795008)
			(xy 50.51298 -56.795416) (xy 50.968148 -56.795416) (xy 50.96891 -56.796178) (xy 51.121056 -56.644286)
			(xy 51.121056 -56.41467) (xy 51.108783 -56.406268) (xy 51.085754 -56.387439) (xy 51.075082 -56.377078)
			(xy 50.76825 -56.069992) (xy 50.760122 -56.066182) (xy 50.736038 -56.054379) (xy 50.691723 -56.024169)
			(xy 50.652863 -55.987206) (xy 50.620475 -55.944457) (xy 50.595409 -55.897043) (xy 50.57832 -55.846206)
			(xy 50.569657 -55.793278) (xy 50.569114 -55.766462) (xy 50.569626 -55.740477) (xy 50.577762 -55.689149)
			(xy 50.593826 -55.639725) (xy 50.617425 -55.593422) (xy 50.647975 -55.551381) (xy 50.684727 -55.514636)
			(xy 50.726773 -55.484093) (xy 50.77308 -55.460503) (xy 50.822507 -55.444448) (xy 50.873837 -55.436322)
			(xy 50.899822 -55.435754) (xy 50.926354 -55.436283) (xy 50.978735 -55.444767) (xy 51.029087 -55.461512)
			(xy 51.076116 -55.486088) (xy 51.118614 -55.517864) (xy 51.155487 -55.556023) (xy 51.171094 -55.577486)
			(xy 51.179995 -55.589345) (xy 51.203226 -55.607752) (xy 51.230762 -55.618717) (xy 51.260286 -55.621319)
			(xy 51.289315 -55.615339) (xy 51.315407 -55.601279) (xy 51.326288 -55.591202) (xy 51.484022 -55.433468)
			(xy 53.020468 -55.433468) (xy 53.379449 -55.792449) (xy 53.769516 -55.792449) (xy 53.769516 -55.740475)
			(xy 53.777646 -55.68914) (xy 53.793707 -55.63971) (xy 53.817303 -55.5934) (xy 53.847853 -55.551352)
			(xy 53.884604 -55.514601) (xy 53.926652 -55.484051) (xy 53.972962 -55.460455) (xy 54.022392 -55.444394)
			(xy 54.073727 -55.436264) (xy 54.125701 -55.436264) (xy 54.177036 -55.444394) (xy 54.226466 -55.460455)
			(xy 54.272776 -55.484051) (xy 54.314824 -55.514601) (xy 54.351575 -55.551352) (xy 54.382125 -55.5934)
			(xy 54.405721 -55.63971) (xy 54.421782 -55.68914) (xy 54.429912 -55.740475) (xy 54.430422 -55.766462)
			(xy 54.429912 -55.792449) (xy 54.428383 -55.802101) (xy 54.559964 -55.802101) (xy 54.559964 -55.750127)
			(xy 54.568094 -55.698792) (xy 54.584155 -55.649362) (xy 54.607751 -55.603052) (xy 54.638301 -55.561004)
			(xy 54.675052 -55.524253) (xy 54.7171 -55.493703) (xy 54.76341 -55.470107) (xy 54.81284 -55.454046)
			(xy 54.864175 -55.445916) (xy 54.916149 -55.445916) (xy 54.967484 -55.454046) (xy 55.016914 -55.470107)
			(xy 55.063224 -55.493703) (xy 55.105272 -55.524253) (xy 55.142023 -55.561004) (xy 55.172573 -55.603052)
			(xy 55.196169 -55.649362) (xy 55.21223 -55.698792) (xy 55.22036 -55.750127) (xy 55.22087 -55.776114)
			(xy 55.22036 -55.802101) (xy 55.21223 -55.853436) (xy 55.196169 -55.902866) (xy 55.172573 -55.949176)
			(xy 55.142023 -55.991224) (xy 55.105272 -56.027975) (xy 55.063224 -56.058525) (xy 55.016914 -56.082121)
			(xy 54.967484 -56.098182) (xy 54.916149 -56.106312) (xy 54.864175 -56.106312) (xy 54.81284 -56.098182)
			(xy 54.76341 -56.082121) (xy 54.7171 -56.058525) (xy 54.675052 -56.027975) (xy 54.638301 -55.991224)
			(xy 54.607751 -55.949176) (xy 54.584155 -55.902866) (xy 54.568094 -55.853436) (xy 54.559964 -55.802101)
			(xy 54.428383 -55.802101) (xy 54.421782 -55.843784) (xy 54.405721 -55.893214) (xy 54.382125 -55.939524)
			(xy 54.351575 -55.981572) (xy 54.314824 -56.018323) (xy 54.272776 -56.048873) (xy 54.226466 -56.072469)
			(xy 54.177036 -56.08853) (xy 54.125701 -56.09666) (xy 54.073727 -56.09666) (xy 54.022392 -56.08853)
			(xy 53.972962 -56.072469) (xy 53.926652 -56.048873) (xy 53.884604 -56.018323) (xy 53.847853 -55.981572)
			(xy 53.817303 -55.939524) (xy 53.793707 -55.893214) (xy 53.777646 -55.843784) (xy 53.769516 -55.792449)
			(xy 53.379449 -55.792449) (xy 53.438044 -55.851044) (xy 53.457602 -55.85206) (xy 53.480164 -55.853595)
			(xy 53.524509 -55.862458) (xy 53.567075 -55.877726) (xy 53.606943 -55.899069) (xy 53.643252 -55.926025)
			(xy 53.659532 -55.941722) (xy 53.901086 -56.183276) (xy 53.920318 -56.203422) (xy 53.951889 -56.249297)
			(xy 53.963824 -56.274462) (xy 53.985277 -56.265236) (xy 54.030129 -56.25223) (xy 54.076364 -56.245663)
			(xy 54.099714 -56.245252) (xy 54.125704 -56.245763) (xy 54.177043 -56.253896) (xy 54.226477 -56.26996)
			(xy 54.27279 -56.29356) (xy 54.314842 -56.324113) (xy 54.351596 -56.360869) (xy 54.382148 -56.402922)
			(xy 54.405745 -56.449236) (xy 54.421807 -56.498671) (xy 54.429938 -56.55001) (xy 54.429938 -56.592549)
			(xy 54.569616 -56.592549) (xy 54.569616 -56.540575) (xy 54.577746 -56.48924) (xy 54.593807 -56.43981)
			(xy 54.617403 -56.3935) (xy 54.647953 -56.351452) (xy 54.684704 -56.314701) (xy 54.726752 -56.284151)
			(xy 54.773062 -56.260555) (xy 54.822492 -56.244494) (xy 54.873827 -56.236364) (xy 54.925801 -56.236364)
			(xy 54.977136 -56.244494) (xy 55.026566 -56.260555) (xy 55.072876 -56.284151) (xy 55.114924 -56.314701)
			(xy 55.151675 -56.351452) (xy 55.182225 -56.3935) (xy 55.205821 -56.43981) (xy 55.221882 -56.48924)
			(xy 55.230012 -56.540575) (xy 55.230522 -56.566562) (xy 55.230012 -56.592549) (xy 55.221882 -56.643884)
			(xy 55.205821 -56.693314) (xy 55.182225 -56.739624) (xy 55.151675 -56.781672) (xy 55.114924 -56.818423)
			(xy 55.072876 -56.848973) (xy 55.026566 -56.872569) (xy 54.977136 -56.88863) (xy 54.925801 -56.89676)
			(xy 54.873827 -56.89676) (xy 54.822492 -56.88863) (xy 54.773062 -56.872569) (xy 54.726752 -56.848973)
			(xy 54.684704 -56.818423) (xy 54.647953 -56.781672) (xy 54.617403 -56.739624) (xy 54.593807 -56.693314)
			(xy 54.577746 -56.643884) (xy 54.569616 -56.592549) (xy 54.429938 -56.592549) (xy 54.429938 -56.60199)
			(xy 54.421807 -56.653329) (xy 54.405745 -56.702764) (xy 54.382148 -56.749078) (xy 54.351596 -56.791131)
			(xy 54.314842 -56.827887) (xy 54.27279 -56.85844) (xy 54.226477 -56.88204) (xy 54.177043 -56.898104)
			(xy 54.125704 -56.906237) (xy 54.099714 -56.906668) (xy 54.06644 -56.90489) (xy 54.0639 -56.904636)
			(xy 54.01056 -56.904636) (xy 54.01056 -57.047384) (xy 54.0639 -57.047384) (xy 54.06644 -57.04713)
			(xy 54.099714 -57.045352) (xy 54.125704 -57.045863) (xy 54.177043 -57.053996) (xy 54.226477 -57.07006)
			(xy 54.27279 -57.09366) (xy 54.314842 -57.124213) (xy 54.351596 -57.160969) (xy 54.382148 -57.203022)
			(xy 54.405745 -57.249336) (xy 54.421807 -57.298771) (xy 54.429938 -57.35011) (xy 54.429938 -57.40209)
			(xy 54.421807 -57.453429) (xy 54.405745 -57.502864) (xy 54.382148 -57.549178) (xy 54.351596 -57.591231)
			(xy 54.314842 -57.627987) (xy 54.27279 -57.65854) (xy 54.226477 -57.68214) (xy 54.177043 -57.698204)
			(xy 54.125704 -57.706337) (xy 54.099714 -57.706768) (xy 54.06644 -57.70499) (xy 54.0639 -57.704736)
			(xy 54.01056 -57.704736) (xy 54.01056 -57.837832) (xy 54.0639 -57.837832) (xy 54.06644 -57.837578)
			(xy 54.099714 -57.8358) (xy 54.1257 -57.836311) (xy 54.177033 -57.844443) (xy 54.226461 -57.860505)
			(xy 54.272768 -57.884102) (xy 54.314813 -57.914652) (xy 54.351562 -57.951403) (xy 54.38211 -57.993451)
			(xy 54.405703 -58.03976) (xy 54.421762 -58.089189) (xy 54.429891 -58.140522) (xy 54.430422 -58.166508)
			(xy 54.4298 -58.196451) (xy 54.419066 -58.255365) (xy 54.409086 -58.283602) (xy 54.43257 -58.295355)
			(xy 54.475478 -58.325622) (xy 54.49443 -58.3438) (xy 54.804818 -58.654188) (xy 54.821588 -58.671629)
			(xy 54.850026 -58.71077) (xy 54.871992 -58.753878) (xy 54.886946 -58.79989) (xy 54.894519 -58.847675)
			(xy 54.894988 -58.871866) (xy 54.894988 -60.27674) (xy 54.894535 -60.300931) (xy 54.886959 -60.348716)
			(xy 54.872 -60.394728) (xy 54.850027 -60.437833) (xy 54.82158 -60.476969) (xy 54.804818 -60.494418)
			(xy 54.2798 -61.019182) (xy 54.2798 -61.42736) (xy 54.186328 -61.521086) (xy 54.186328 -61.665866)
			(xy 54.186871 -61.680949) (xy 54.19568 -61.709799) (xy 54.21254 -61.734814) (xy 54.235976 -61.753806)
			(xy 54.263941 -61.765117) (xy 54.29399 -61.767757) (xy 54.323499 -61.761497) (xy 54.349888 -61.746883)
			(xy 54.360826 -61.736478) (xy 54.37886 -61.718371) (xy 54.418931 -61.686656) (xy 54.462879 -61.660576)
			(xy 54.509916 -61.6406) (xy 54.5592 -61.627084) (xy 54.609848 -61.620272) (xy 54.6354 -61.619892)
			(xy 54.662651 -61.620378) (xy 54.716599 -61.628134) (xy 54.768894 -61.643489) (xy 54.818471 -61.666131)
			(xy 54.864321 -61.695597) (xy 54.905512 -61.731288) (xy 54.941203 -61.772479) (xy 54.970669 -61.818329)
			(xy 54.993311 -61.867906) (xy 55.008666 -61.920201) (xy 55.016422 -61.974149) (xy 55.016908 -62.0014)
			(xy 55.016328 -62.031668) (xy 55.006765 -62.091443) (xy 54.987881 -62.148957) (xy 54.960149 -62.202767)
			(xy 54.924266 -62.25152) (xy 54.903116 -62.27318) (xy 54.893834 -62.282906) (xy 54.880284 -62.306117)
			(xy 54.873266 -62.332061) (xy 54.873265 -62.358937) (xy 54.880283 -62.384881) (xy 54.893833 -62.408092)
			(xy 54.912974 -62.426959) (xy 54.924452 -62.433962) (xy 54.949291 -62.448585) (xy 54.994657 -62.484139)
			(xy 55.034159 -62.526112) (xy 55.0669 -62.573548) (xy 55.092134 -62.625369) (xy 55.109289 -62.680395)
			(xy 55.117973 -62.737375) (xy 55.118508 -62.766194) (xy 55.118045 -62.793447) (xy 55.110289 -62.847399)
			(xy 55.094933 -62.899697) (xy 55.072291 -62.949278) (xy 55.042823 -62.995132) (xy 55.00713 -63.036325)
			(xy 54.965937 -63.07202) (xy 54.920083 -63.101488) (xy 54.870503 -63.124131) (xy 54.818205 -63.139488)
			(xy 54.764253 -63.147245) (xy 54.737 -63.147702) (xy 54.710681 -63.14728) (xy 54.658539 -63.140079)
			(xy 54.607883 -63.125772) (xy 54.559677 -63.104632) (xy 54.514839 -63.07706) (xy 54.47422 -63.043582)
			(xy 54.456076 -63.024512) (xy 54.446589 -63.014852) (xy 54.423653 -63.000481) (xy 54.397747 -62.992642)
			(xy 54.370692 -62.991888) (xy 54.34439 -62.998271) (xy 54.320689 -63.011342) (xy 54.301257 -63.030183)
			(xy 54.28746 -63.053468) (xy 54.280268 -63.07956) (xy 54.2798 -63.093092) (xy 54.2798 -63.15075)
			(xy 54.486048 -63.356744) (xy 54.502826 -63.374169) (xy 54.531237 -63.413316) (xy 54.553162 -63.456432)
			(xy 54.568058 -63.502451) (xy 54.575558 -63.550236) (xy 54.575964 -63.574422) (xy 54.575964 -63.861696)
			(xy 54.576503 -63.876105) (xy 54.584626 -63.903759) (xy 54.600143 -63.928047) (xy 54.621821 -63.947042)
			(xy 54.647937 -63.959232) (xy 54.676418 -63.963651) (xy 54.690772 -63.96228) (xy 54.702911 -63.960826)
			(xy 54.727314 -63.959298) (xy 54.73954 -63.959232) (xy 54.766788 -63.959721) (xy 54.82073 -63.967482)
			(xy 54.873017 -63.982841) (xy 54.922587 -64.005485) (xy 54.968429 -64.034953) (xy 55.009611 -64.070645)
			(xy 55.045295 -64.111835) (xy 55.074753 -64.157684) (xy 55.097387 -64.207258) (xy 55.112735 -64.259549)
			(xy 55.120485 -64.313492) (xy 55.121048 -64.34074) (xy 55.120729 -64.362199) (xy 55.115891 -64.404844)
			(xy 55.111396 -64.42583) (xy 55.10849 -64.440795) (xy 55.11075 -64.471182) (xy 55.121877 -64.499549)
			(xy 55.140879 -64.523369) (xy 55.166064 -64.540521) (xy 55.180484 -64.545464) (xy 55.206041 -64.553901)
			(xy 55.254671 -64.576955) (xy 55.29958 -64.606613) (xy 55.339875 -64.642288) (xy 55.374758 -64.683271)
			(xy 55.403536 -64.728749) (xy 55.425639 -64.777819) (xy 55.440627 -64.829509) (xy 55.448203 -64.882791)
			(xy 55.448708 -64.9097) (xy 55.448222 -64.936951) (xy 55.440466 -64.990899) (xy 55.425111 -65.043194)
			(xy 55.402469 -65.092771) (xy 55.373003 -65.138621) (xy 55.337312 -65.179812) (xy 55.296121 -65.215503)
			(xy 55.250271 -65.244969) (xy 55.200694 -65.267611) (xy 55.148399 -65.282966) (xy 55.094451 -65.290722)
			(xy 55.039949 -65.290722) (xy 54.986001 -65.282966) (xy 54.933706 -65.267611) (xy 54.884129 -65.244969)
			(xy 54.838279 -65.215503) (xy 54.797088 -65.179812) (xy 54.761397 -65.138621) (xy 54.731931 -65.092771)
			(xy 54.709289 -65.043194) (xy 54.693934 -64.990899) (xy 54.686178 -64.936951) (xy 54.685692 -64.9097)
			(xy 54.686343 -64.877242) (xy 54.697322 -64.813262) (xy 54.707536 -64.782446) (xy 54.710649 -64.771885)
			(xy 54.708572 -64.749989) (xy 54.697568 -64.730944) (xy 54.679634 -64.71821) (xy 54.668928 -64.715644)
			(xy 54.640226 -64.70904) (xy 54.633622 -64.707262) (xy 54.575964 -64.707262) (xy 54.575964 -65.062862)
			(xy 54.575474 -65.088035) (xy 54.567336 -65.137719) (xy 54.551267 -65.185433) (xy 54.539896 -65.207896)
			(xy 54.5338 -65.219072) (xy 54.5338 -66.074544) (xy 54.55891 -66.087544) (xy 54.605328 -66.119832)
			(xy 54.646471 -66.158618) (xy 54.681437 -66.203053) (xy 54.709461 -66.252163) (xy 54.729927 -66.304872)
			(xy 54.742389 -66.360024) (xy 54.746572 -66.416412) (xy 54.742385 -66.4728) (xy 54.72992 -66.527952)
			(xy 54.70945 -66.580659) (xy 54.681423 -66.629767) (xy 54.646454 -66.6742) (xy 54.605309 -66.712984)
			(xy 54.558889 -66.745268) (xy 54.5338 -66.758312) (xy 54.5338 -66.829178) (xy 54.663848 -66.958972)
			(xy 54.680624 -66.976398) (xy 54.709032 -67.015545) (xy 54.7296 -67.056) (xy 54.862982 -67.056) (xy 54.867053 -67.000378)
			(xy 54.879179 -66.945941) (xy 54.899102 -66.89385) (xy 54.926398 -66.845215) (xy 54.960484 -66.801072)
			(xy 55.000633 -66.762363) (xy 55.045991 -66.729912) (xy 55.095591 -66.704411) (xy 55.148375 -66.686404)
			(xy 55.203218 -66.676274) (xy 55.258952 -66.674237) (xy 55.314389 -66.680337) (xy 55.368346 -66.694443)
			(xy 55.419675 -66.716255) (xy 55.467281 -66.745309) (xy 55.510149 -66.780984) (xy 55.547366 -66.822521)
			(xy 55.578139 -66.869034) (xy 55.601811 -66.919531) (xy 55.617879 -66.972938) (xy 55.625999 -67.028114)
			(xy 55.626508 -67.056) (xy 55.625999 -67.083886) (xy 55.617879 -67.139062) (xy 55.601811 -67.192469)
			(xy 55.578139 -67.242966) (xy 55.547366 -67.289479) (xy 55.510149 -67.331016) (xy 55.467281 -67.366691)
			(xy 55.419675 -67.395745) (xy 55.368346 -67.417557) (xy 55.314389 -67.431663) (xy 55.258952 -67.437763)
			(xy 55.203218 -67.435726) (xy 55.148375 -67.425596) (xy 55.095591 -67.407589) (xy 55.045991 -67.382088)
			(xy 55.000633 -67.349637) (xy 54.960484 -67.310928) (xy 54.926398 -67.266785) (xy 54.899102 -67.21815)
			(xy 54.879179 -67.166059) (xy 54.867053 -67.111622) (xy 54.862982 -67.056) (xy 54.7296 -67.056) (xy 54.730953 -67.058661)
			(xy 54.745845 -67.10468) (xy 54.75334 -67.152465) (xy 54.753764 -67.17665) (xy 54.753764 -67.8434)
			(xy 55.472582 -67.8434) (xy 55.476653 -67.787778) (xy 55.488779 -67.733341) (xy 55.508702 -67.68125)
			(xy 55.535998 -67.632615) (xy 55.570084 -67.588472) (xy 55.610233 -67.549763) (xy 55.655591 -67.517312)
			(xy 55.705191 -67.491811) (xy 55.757975 -67.473804) (xy 55.812818 -67.463674) (xy 55.868552 -67.461637)
			(xy 55.923989 -67.467737) (xy 55.977946 -67.481843) (xy 56.029275 -67.503655) (xy 56.076881 -67.532709)
			(xy 56.119749 -67.568384) (xy 56.156966 -67.609921) (xy 56.187739 -67.656434) (xy 56.211411 -67.706931)
			(xy 56.227479 -67.760338) (xy 56.235599 -67.815514) (xy 56.236108 -67.8434) (xy 56.235599 -67.871286)
			(xy 56.227479 -67.926462) (xy 56.211411 -67.979869) (xy 56.187739 -68.030366) (xy 56.156966 -68.076879)
			(xy 56.119749 -68.118416) (xy 56.076881 -68.154091) (xy 56.029275 -68.183145) (xy 55.977946 -68.204957)
			(xy 55.923989 -68.219063) (xy 55.868552 -68.225163) (xy 55.812818 -68.223126) (xy 55.757975 -68.212996)
			(xy 55.705191 -68.194989) (xy 55.655591 -68.169488) (xy 55.610233 -68.137037) (xy 55.570084 -68.098328)
			(xy 55.535998 -68.054185) (xy 55.508702 -68.00555) (xy 55.488779 -67.953459) (xy 55.476653 -67.899022)
			(xy 55.472582 -67.8434) (xy 54.753764 -67.8434) (xy 54.753764 -68.187824) (xy 54.753305 -68.212004)
			(xy 54.745776 -68.259774) (xy 54.730875 -68.305781) (xy 54.708969 -68.348894) (xy 54.680595 -68.388054)
			(xy 54.663848 -68.405502) (xy 54.202838 -68.866512) (xy 54.19359 -68.876409) (xy 54.180209 -68.899949)
			(xy 54.173485 -68.926178) (xy 54.17389 -68.953252) (xy 54.181396 -68.979268) (xy 54.195476 -69.002397)
			(xy 54.215138 -69.021013) (xy 54.239002 -69.033808) (xy 54.252114 -69.0372) (xy 54.27987 -69.044023)
			(xy 54.333096 -69.064851) (xy 54.382618 -69.093389) (xy 54.426879 -69.12864) (xy 55.717946 -69.12864)
			(xy 55.722017 -69.073018) (xy 55.734143 -69.018581) (xy 55.754066 -68.96649) (xy 55.781362 -68.917855)
			(xy 55.815448 -68.873712) (xy 55.855597 -68.835003) (xy 55.900955 -68.802552) (xy 55.950555 -68.777051)
			(xy 56.003339 -68.759044) (xy 56.058182 -68.748914) (xy 56.113916 -68.746877) (xy 56.169353 -68.752977)
			(xy 56.22331 -68.767083) (xy 56.274639 -68.788895) (xy 56.322245 -68.817949) (xy 56.365113 -68.853624)
			(xy 56.40233 -68.895161) (xy 56.433103 -68.941674) (xy 56.456775 -68.992171) (xy 56.472843 -69.045578)
			(xy 56.480963 -69.100754) (xy 56.481472 -69.12864) (xy 56.480963 -69.156526) (xy 56.472843 -69.211702)
			(xy 56.456775 -69.265109) (xy 56.433103 -69.315606) (xy 56.40233 -69.362119) (xy 56.365113 -69.403656)
			(xy 56.322245 -69.439331) (xy 56.274639 -69.468385) (xy 56.22331 -69.490197) (xy 56.169353 -69.504303)
			(xy 56.113916 -69.510403) (xy 56.058182 -69.508366) (xy 56.003339 -69.498236) (xy 55.950555 -69.480229)
			(xy 55.900955 -69.454728) (xy 55.855597 -69.422277) (xy 55.815448 -69.383568) (xy 55.781362 -69.339425)
			(xy 55.754066 -69.29079) (xy 55.734143 -69.238699) (xy 55.722017 -69.184262) (xy 55.717946 -69.12864)
			(xy 54.426879 -69.12864) (xy 54.427327 -69.128997) (xy 54.46622 -69.170879) (xy 54.498428 -69.218096)
			(xy 54.523229 -69.269591) (xy 54.540067 -69.324211) (xy 54.548566 -69.380732) (xy 54.54904 -69.40931)
			(xy 54.548554 -69.436561) (xy 54.540798 -69.490509) (xy 54.525443 -69.542804) (xy 54.502801 -69.592381)
			(xy 54.473335 -69.638231) (xy 54.437644 -69.679422) (xy 54.396453 -69.715113) (xy 54.350603 -69.744579)
			(xy 54.301026 -69.767221) (xy 54.248731 -69.782576) (xy 54.194783 -69.790332) (xy 54.140281 -69.790332)
			(xy 54.086333 -69.782576) (xy 54.034038 -69.767221) (xy 53.984461 -69.744579) (xy 53.938611 -69.715113)
			(xy 53.89742 -69.679422) (xy 53.861729 -69.638231) (xy 53.832263 -69.592381) (xy 53.809621 -69.542804)
			(xy 53.794266 -69.490509) (xy 53.78651 -69.436561) (xy 53.786024 -69.40931) (xy 53.786024 -69.406262)
			(xy 53.786278 -69.384926) (xy 53.735224 -69.333872) (xy 53.6448 -69.424296) (xy 53.6448 -72.171052)
			(xy 55.330598 -72.171052) (xy 55.33108 -72.142594) (xy 55.339496 -72.086306) (xy 55.356193 -72.031896)
			(xy 55.3808 -71.980576) (xy 55.412769 -71.933488) (xy 55.43169 -71.912226) (xy 55.441446 -71.900795)
			(xy 55.454527 -71.873761) (xy 55.459175 -71.84409) (xy 55.454987 -71.814351) (xy 55.442325 -71.787117)
			(xy 55.432706 -71.775574) (xy 55.414517 -71.754492) (xy 55.38385 -71.708018) (xy 55.360264 -71.657581)
			(xy 55.344259 -71.60425) (xy 55.336177 -71.54916) (xy 55.335678 -71.52132) (xy 55.336164 -71.494069)
			(xy 55.34392 -71.440121) (xy 55.359275 -71.387826) (xy 55.381917 -71.338249) (xy 55.411383 -71.292399)
			(xy 55.447074 -71.251208) (xy 55.488265 -71.215517) (xy 55.534115 -71.186051) (xy 55.583692 -71.163409)
			(xy 55.635987 -71.148054) (xy 55.689935 -71.140298) (xy 55.744437 -71.140298) (xy 55.798385 -71.148054)
			(xy 55.85068 -71.163409) (xy 55.900257 -71.186051) (xy 55.946107 -71.215517) (xy 55.987298 -71.251208)
			(xy 56.022989 -71.292399) (xy 56.052455 -71.338249) (xy 56.075097 -71.387826) (xy 56.090452 -71.440121)
			(xy 56.098208 -71.494069) (xy 56.098694 -71.52132) (xy 56.098197 -71.549777) (xy 56.089785 -71.606065)
			(xy 56.073092 -71.660475) (xy 56.048488 -71.711795) (xy 56.016522 -71.758883) (xy 55.997602 -71.780146)
			(xy 55.98777 -71.791519) (xy 55.974685 -71.818572) (xy 55.970046 -71.848263) (xy 55.974256 -71.878018)
			(xy 55.986949 -71.905257) (xy 55.996586 -71.916798) (xy 56.01476 -71.937892) (xy 56.04543 -71.984362)
			(xy 56.069019 -72.034797) (xy 56.085026 -72.088125) (xy 56.093112 -72.143213) (xy 56.093614 -72.171052)
			(xy 56.093041 -72.200257) (xy 56.0841 -72.257979) (xy 56.066482 -72.313669) (xy 56.040595 -72.36603)
			(xy 56.024272 -72.390254) (xy 56.015777 -72.403203) (xy 56.00639 -72.432704) (xy 56.006263 -72.463663)
			(xy 56.015406 -72.49324) (xy 56.032983 -72.518726) (xy 56.044846 -72.528684) (xy 56.067165 -72.546909)
			(xy 56.106633 -72.588887) (xy 56.139344 -72.63632) (xy 56.164554 -72.68813) (xy 56.18169 -72.743141)
			(xy 56.190364 -72.800103) (xy 56.190896 -72.828912) (xy 56.19041 -72.856163) (xy 56.182654 -72.910111)
			(xy 56.167299 -72.962406) (xy 56.144657 -73.011983) (xy 56.115191 -73.057833) (xy 56.0795 -73.099024)
			(xy 56.038309 -73.134715) (xy 55.992459 -73.164181) (xy 55.942882 -73.186823) (xy 55.890587 -73.202178)
			(xy 55.836639 -73.209934) (xy 55.782137 -73.209934) (xy 55.728189 -73.202178) (xy 55.675894 -73.186823)
			(xy 55.626317 -73.164181) (xy 55.580467 -73.134715) (xy 55.539276 -73.099024) (xy 55.503585 -73.057833)
			(xy 55.474119 -73.011983) (xy 55.451477 -72.962406) (xy 55.436122 -72.910111) (xy 55.428366 -72.856163)
			(xy 55.42788 -72.828912) (xy 55.428469 -72.799708) (xy 55.437402 -72.741985) (xy 55.455016 -72.686295)
			(xy 55.4809 -72.633934) (xy 55.497222 -72.60971) (xy 55.50565 -72.596721) (xy 55.515048 -72.567236)
			(xy 55.51519 -72.53629) (xy 55.506063 -72.506721) (xy 55.488503 -72.481238) (xy 55.476648 -72.47128)
			(xy 55.454311 -72.453076) (xy 55.414844 -72.411094) (xy 55.382135 -72.363657) (xy 55.356929 -72.311842)
			(xy 55.339796 -72.256827) (xy 55.331128 -72.199862) (xy 55.330598 -72.171052) (xy 53.6448 -72.171052)
			(xy 53.6448 -75.21702) (xy 53.848 -75.42022) (xy 55.727346 -75.42022)
		)
		(stroke
			(width 0)
			(type solid)
		)
		(fill yes)
		(layer "In4.Cu")
		(net "P1V2_SENSOR")
	)
	(gr_poly
		(pts
			(xy 19.812 -95.655638) (xy 19.824994 -95.653702) (xy 19.851187 -95.651665) (xy 19.864324 -95.651574)
			(xy 19.87746 -95.651686) (xy 19.903652 -95.653722) (xy 19.916648 -95.655638) (xy 19.920712 -95.6564)
			(xy 20.607782 -95.6564) (xy 20.611846 -95.655638) (xy 20.62484 -95.653704) (xy 20.651033 -95.65167)
			(xy 20.66417 -95.651574) (xy 20.677306 -95.651684) (xy 20.703499 -95.653716) (xy 20.716494 -95.655638)
			(xy 20.720558 -95.6564) (xy 22.19833 -95.6564) (xy 22.202394 -95.655638) (xy 22.215388 -95.653702)
			(xy 22.241581 -95.651664) (xy 22.254718 -95.651574) (xy 22.267854 -95.651685) (xy 22.294046 -95.653721)
			(xy 22.307042 -95.655638) (xy 22.311106 -95.6564) (xy 22.3774 -95.6564) (xy 22.741382 -95.292418)
			(xy 22.73427 -95.264224) (xy 22.729424 -95.24406) (xy 22.724203 -95.202918) (xy 22.723856 -95.182182)
			(xy 22.724337 -95.156874) (xy 22.732042 -95.106849) (xy 22.747271 -95.058579) (xy 22.769667 -95.013189)
			(xy 22.7838 -94.99219) (xy 22.7838 -94.572328) (xy 22.769662 -94.551329) (xy 22.74725 -94.505941)
			(xy 22.732009 -94.457669) (xy 22.724297 -94.40764) (xy 22.724293 -94.357019) (xy 22.731996 -94.306988)
			(xy 22.747228 -94.258714) (xy 22.769632 -94.213322) (xy 22.7838 -94.192344) (xy 22.7838 -92.98178)
			(xy 22.769666 -92.960781) (xy 22.747261 -92.915394) (xy 22.732027 -92.867124) (xy 22.724322 -92.817098)
			(xy 22.724323 -92.766482) (xy 22.732032 -92.716456) (xy 22.747268 -92.668188) (xy 22.769676 -92.622802)
			(xy 22.7838 -92.601796) (xy 22.7838 -92.181934) (xy 22.770804 -92.162704) (xy 22.749748 -92.121342)
			(xy 22.734688 -92.077441) (xy 22.72592 -92.031864) (xy 22.724364 -92.008706) (xy 22.723348 -91.989148)
			(xy 22.635718 -91.901518) (xy 22.583902 -91.953334) (xy 22.584918 -91.97594) (xy 22.585426 -91.991942)
			(xy 22.584913 -92.01793) (xy 22.576776 -92.069266) (xy 22.560708 -92.118696) (xy 22.537106 -92.165005)
			(xy 22.50655 -92.207051) (xy 22.469793 -92.243799) (xy 22.42774 -92.274346) (xy 22.381426 -92.297937)
			(xy 22.331992 -92.313994) (xy 22.280654 -92.322119) (xy 22.228678 -92.322114) (xy 22.177342 -92.313978)
			(xy 22.127911 -92.297911) (xy 22.081602 -92.27431) (xy 22.039555 -92.243755) (xy 22.002806 -92.206999)
			(xy 21.972259 -92.164947) (xy 21.948666 -92.118633) (xy 21.932608 -92.069199) (xy 21.924482 -92.017862)
			(xy 21.924486 -91.965886) (xy 21.93262 -91.91455) (xy 21.948686 -91.865119) (xy 21.972286 -91.818809)
			(xy 22.00284 -91.776761) (xy 22.039595 -91.740011) (xy 22.081647 -91.709463) (xy 22.127959 -91.685869)
			(xy 22.177393 -91.66981) (xy 22.22873 -91.661682) (xy 22.254718 -91.661234) (xy 22.27072 -91.661742)
			(xy 22.293326 -91.662758) (xy 22.345142 -91.610942) (xy 22.257258 -91.523058) (xy 22.2377 -91.522042)
			(xy 22.213015 -91.520304) (xy 22.164528 -91.510418) (xy 22.118054 -91.493424) (xy 22.074627 -91.4697)
			(xy 22.035217 -91.439776) (xy 22.0007 -91.404317) (xy 21.971848 -91.364115) (xy 21.949302 -91.320065)
			(xy 21.941028 -91.296744) (xy 21.929598 -91.2622) (xy 20.7518 -91.2622) (xy 20.217384 -90.727784)
			(xy 20.214719 -90.713092) (xy 20.202066 -90.68606) (xy 20.182138 -90.663842) (xy 20.156637 -90.648334)
			(xy 20.127742 -90.640862) (xy 20.09792 -90.642065) (xy 20.069719 -90.651838) (xy 20.057364 -90.66022)
			(xy 20.036148 -90.674878) (xy 19.990124 -90.69813) (xy 19.941046 -90.713948) (xy 19.890106 -90.721949)
			(xy 19.864324 -90.72245) (xy 19.83833 -90.721969) (xy 19.786982 -90.713839) (xy 19.737538 -90.697777)
			(xy 19.691216 -90.674178) (xy 19.649156 -90.643622) (xy 19.612394 -90.606863) (xy 19.581835 -90.564805)
			(xy 19.558232 -90.518484) (xy 19.542166 -90.469041) (xy 19.534033 -90.417694) (xy 19.534033 -90.365706)
			(xy 19.542166 -90.314359) (xy 19.558232 -90.264916) (xy 19.581835 -90.218595) (xy 19.612394 -90.176537)
			(xy 19.649156 -90.139778) (xy 19.691216 -90.109222) (xy 19.737538 -90.085623) (xy 19.786982 -90.069561)
			(xy 19.83833 -90.061431) (xy 19.864324 -90.061034) (xy 19.890106 -90.06153) (xy 19.941043 -90.06954)
			(xy 19.99012 -90.085362) (xy 20.036144 -90.108613) (xy 20.057364 -90.123264) (xy 20.068957 -90.131088)
			(xy 20.095216 -90.140684) (xy 20.123095 -90.142798) (xy 20.150501 -90.137269) (xy 20.175379 -90.124514)
			(xy 20.195865 -90.105487) (xy 20.210421 -90.081617) (xy 20.217956 -90.054694) (xy 20.2184 -90.040714)
			(xy 20.2184 -89.5858) (xy 20.550124 -89.254076) (xy 20.559667 -89.243946) (xy 20.573321 -89.219706)
			(xy 20.579923 -89.19268) (xy 20.578982 -89.164876) (xy 20.570567 -89.138358) (xy 20.555303 -89.115098)
			(xy 20.534326 -89.096824) (xy 20.52193 -89.0905) (xy 20.498127 -89.078557) (xy 20.454355 -89.048231)
			(xy 20.416003 -89.011288) (xy 20.384061 -88.96868) (xy 20.359355 -88.921506) (xy 20.342522 -88.870986)
			(xy 20.333995 -88.818422) (xy 20.333462 -88.791796) (xy 20.333925 -88.76642) (xy 20.341681 -88.716264)
			(xy 20.357011 -88.667882) (xy 20.379553 -88.62241) (xy 20.40878 -88.580918) (xy 20.444003 -88.544379)
			(xy 20.484397 -88.513652) (xy 20.529011 -88.489458) (xy 20.576799 -88.472366) (xy 20.626637 -88.462777)
			(xy 20.651978 -88.461342) (xy 20.661746 -88.460554) (xy 20.679629 -88.452584) (xy 20.69322 -88.438491)
			(xy 20.700539 -88.420332) (xy 20.701 -88.410542) (xy 20.701 -88.373204) (xy 20.700557 -88.363409)
			(xy 20.693229 -88.345242) (xy 20.679636 -88.331135) (xy 20.661752 -88.32314) (xy 20.651978 -88.322404)
			(xy 20.626636 -88.321007) (xy 20.5768 -88.311408) (xy 20.529016 -88.294308) (xy 20.484405 -88.270107)
			(xy 20.444016 -88.239375) (xy 20.408796 -88.202832) (xy 20.379574 -88.161337) (xy 20.357035 -88.115865)
			(xy 20.341708 -88.067482) (xy 20.333953 -88.017326) (xy 20.333953 -87.966574) (xy 20.341708 -87.916418)
			(xy 20.357035 -87.868035) (xy 20.379574 -87.822563) (xy 20.408796 -87.781068) (xy 20.444016 -87.744525)
			(xy 20.484405 -87.713793) (xy 20.529016 -87.689592) (xy 20.5768 -87.672492) (xy 20.626636 -87.662893)
			(xy 20.651978 -87.661496) (xy 20.661742 -87.660707) (xy 20.679617 -87.652735) (xy 20.693197 -87.638641)
			(xy 20.700501 -87.620483) (xy 20.701 -87.610696) (xy 20.701 -87.374984) (xy 20.6629 -87.365332) (xy 20.63775 -87.358357)
			(xy 20.589668 -87.338058) (xy 20.545062 -87.310962) (xy 20.504886 -87.277647) (xy 20.470001 -87.238828)
			(xy 20.441152 -87.195335) (xy 20.418957 -87.148098) (xy 20.403891 -87.098128) (xy 20.396277 -87.046496)
			(xy 20.396277 -86.994304) (xy 20.403891 -86.942672) (xy 20.418957 -86.892702) (xy 20.441152 -86.845465)
			(xy 20.470001 -86.801972) (xy 20.504886 -86.763153) (xy 20.545062 -86.729838) (xy 20.589668 -86.702742)
			(xy 20.63775 -86.682443) (xy 20.6629 -86.675468) (xy 20.701 -86.665816) (xy 20.701 -85.992716) (xy 20.668234 -85.980524)
			(xy 20.642247 -85.97023) (xy 20.593362 -85.943128) (xy 20.548962 -85.909174) (xy 20.509999 -85.869097)
			(xy 20.47731 -85.823757) (xy 20.464018 -85.799168) (xy 20.457425 -85.787414) (xy 20.439162 -85.767608)
			(xy 20.416359 -85.753261) (xy 20.3906 -85.74537) (xy 20.363674 -85.744483) (xy 20.337451 -85.750661)
			(xy 20.313753 -85.763476) (xy 20.303744 -85.772498) (xy 20.28234 -85.792159) (xy 20.234686 -85.825426)
			(xy 20.182537 -85.851079) (xy 20.1271 -85.868523) (xy 20.069658 -85.877355) (xy 20.0406 -85.877908)
			(xy 20.013349 -85.877422) (xy 19.959401 -85.869666) (xy 19.907106 -85.854311) (xy 19.857529 -85.831669)
			(xy 19.811679 -85.802203) (xy 19.770488 -85.766512) (xy 19.734797 -85.725321) (xy 19.705331 -85.679471)
			(xy 19.682689 -85.629894) (xy 19.667334 -85.577599) (xy 19.659578 -85.523651) (xy 19.659578 -85.469149)
			(xy 19.667334 -85.415201) (xy 19.682689 -85.362906) (xy 19.705331 -85.313329) (xy 19.734797 -85.267479)
			(xy 19.770488 -85.226288) (xy 19.811679 -85.190597) (xy 19.857529 -85.161131) (xy 19.907106 -85.138489)
			(xy 19.959401 -85.123134) (xy 20.013349 -85.115378) (xy 20.0406 -85.114892) (xy 20.066646 -85.115336)
			(xy 20.118253 -85.122426) (xy 20.168415 -85.136473) (xy 20.216198 -85.157217) (xy 20.260714 -85.184271)
			(xy 20.301133 -85.217132) (xy 20.336704 -85.255189) (xy 20.366764 -85.297732) (xy 20.379182 -85.320632)
			(xy 20.385775 -85.332386) (xy 20.404038 -85.352192) (xy 20.426841 -85.366539) (xy 20.4526 -85.37443)
			(xy 20.479526 -85.375317) (xy 20.505749 -85.369139) (xy 20.529447 -85.356324) (xy 20.539456 -85.347302)
			(xy 20.558209 -85.329959) (xy 20.599526 -85.299924) (xy 20.64448 -85.275667) (xy 20.668234 -85.266276)
			(xy 20.701 -85.254084) (xy 20.701 -82.6516) (xy 20.2184 -82.169) (xy 19.893788 -82.169) (xy 19.880326 -82.198972)
			(xy 19.868641 -82.223713) (xy 19.839236 -82.269854) (xy 19.803541 -82.311321) (xy 19.762289 -82.347264)
			(xy 19.716324 -82.376945) (xy 19.666592 -82.399756) (xy 19.61411 -82.415228) (xy 19.559957 -82.423044)
			(xy 19.505243 -82.423044) (xy 19.45109 -82.415228) (xy 19.398608 -82.399756) (xy 19.348876 -82.376945)
			(xy 19.302911 -82.347264) (xy 19.261659 -82.311321) (xy 19.225964 -82.269854) (xy 19.196559 -82.223713)
			(xy 19.184874 -82.198972) (xy 19.171412 -82.169) (xy 18.925032 -82.169) (xy 18.917412 -82.21091)
			(xy 18.912289 -82.237008) (xy 18.895763 -82.287559) (xy 18.87237 -82.335322) (xy 18.842563 -82.379368)
			(xy 18.806922 -82.418843) (xy 18.766138 -82.452978) (xy 18.721005 -82.481112) (xy 18.672399 -82.502698)
			(xy 18.621263 -82.517316) (xy 18.568592 -82.524683) (xy 18.542 -82.525108) (xy 18.51213 -82.524528)
			(xy 18.45312 -82.515211) (xy 18.396286 -82.496806) (xy 18.343017 -82.469762) (xy 18.31848 -82.452718)
			(xy 18.283428 -82.427572) (xy 18.186908 -82.524346) (xy 18.186908 -82.76082) (xy 18.186456 -82.785012)
			(xy 18.178884 -82.832799) (xy 18.163928 -82.878813) (xy 18.141958 -82.921921) (xy 18.113513 -82.961061)
			(xy 18.096738 -82.978498) (xy 17.6784 -83.396582) (xy 17.6784 -86.5124) (xy 17.829782 -86.5124) (xy 17.833853 -86.456778)
			(xy 17.845979 -86.402341) (xy 17.865902 -86.35025) (xy 17.893198 -86.301615) (xy 17.927284 -86.257472)
			(xy 17.967433 -86.218763) (xy 18.012791 -86.186312) (xy 18.062391 -86.160811) (xy 18.115175 -86.142804)
			(xy 18.170018 -86.132674) (xy 18.225752 -86.130637) (xy 18.281189 -86.136737) (xy 18.335146 -86.150843)
			(xy 18.386475 -86.172655) (xy 18.434081 -86.201709) (xy 18.476949 -86.237384) (xy 18.514166 -86.278921)
			(xy 18.544939 -86.325434) (xy 18.561143 -86.36) (xy 19.607782 -86.36) (xy 19.611853 -86.304378) (xy 19.623979 -86.249941)
			(xy 19.643902 -86.19785) (xy 19.671198 -86.149215) (xy 19.705284 -86.105072) (xy 19.745433 -86.066363)
			(xy 19.790791 -86.033912) (xy 19.840391 -86.008411) (xy 19.893175 -85.990404) (xy 19.948018 -85.980274)
			(xy 20.003752 -85.978237) (xy 20.059189 -85.984337) (xy 20.113146 -85.998443) (xy 20.164475 -86.020255)
			(xy 20.212081 -86.049309) (xy 20.254949 -86.084984) (xy 20.292166 -86.126521) (xy 20.322939 -86.173034)
			(xy 20.346611 -86.223531) (xy 20.362679 -86.276938) (xy 20.370799 -86.332114) (xy 20.371308 -86.36)
			(xy 20.370799 -86.387886) (xy 20.362679 -86.443062) (xy 20.346611 -86.496469) (xy 20.322939 -86.546966)
			(xy 20.292166 -86.593479) (xy 20.254949 -86.635016) (xy 20.212081 -86.670691) (xy 20.164475 -86.699745)
			(xy 20.113146 -86.721557) (xy 20.059189 -86.735663) (xy 20.003752 -86.741763) (xy 19.948018 -86.739726)
			(xy 19.893175 -86.729596) (xy 19.840391 -86.711589) (xy 19.790791 -86.686088) (xy 19.745433 -86.653637)
			(xy 19.705284 -86.614928) (xy 19.671198 -86.570785) (xy 19.643902 -86.52215) (xy 19.623979 -86.470059)
			(xy 19.611853 -86.415622) (xy 19.607782 -86.36) (xy 18.561143 -86.36) (xy 18.568611 -86.375931) (xy 18.584679 -86.429338)
			(xy 18.592799 -86.484514) (xy 18.593308 -86.5124) (xy 18.592799 -86.540286) (xy 18.584679 -86.595462)
			(xy 18.568611 -86.648869) (xy 18.544939 -86.699366) (xy 18.514166 -86.745879) (xy 18.476949 -86.787416)
			(xy 18.434081 -86.823091) (xy 18.386475 -86.852145) (xy 18.335146 -86.873957) (xy 18.281189 -86.888063)
			(xy 18.225752 -86.894163) (xy 18.170018 -86.892126) (xy 18.115175 -86.881996) (xy 18.062391 -86.863989)
			(xy 18.012791 -86.838488) (xy 17.967433 -86.806037) (xy 17.927284 -86.767328) (xy 17.893198 -86.723185)
			(xy 17.865902 -86.67455) (xy 17.845979 -86.622459) (xy 17.833853 -86.568022) (xy 17.829782 -86.5124)
			(xy 17.6784 -86.5124) (xy 17.6784 -87.739982) (xy 17.697954 -87.757223) (xy 17.731908 -87.796777)
			(xy 17.759232 -87.841171) (xy 17.779248 -87.889304) (xy 17.79146 -87.939983) (xy 17.795564 -87.99195)
			(xy 17.793512 -88.017937) (xy 18.734026 -88.017937) (xy 18.734026 -87.965963) (xy 18.742156 -87.914628)
			(xy 18.758217 -87.865198) (xy 18.781813 -87.818888) (xy 18.812363 -87.77684) (xy 18.849114 -87.740089)
			(xy 18.891162 -87.709539) (xy 18.937472 -87.685943) (xy 18.986902 -87.669882) (xy 19.038237 -87.661752)
			(xy 19.090211 -87.661752) (xy 19.141546 -87.669882) (xy 19.190976 -87.685943) (xy 19.237286 -87.709539)
			(xy 19.279334 -87.740089) (xy 19.316085 -87.77684) (xy 19.346635 -87.818888) (xy 19.370231 -87.865198)
			(xy 19.386292 -87.914628) (xy 19.394422 -87.965963) (xy 19.394932 -87.99195) (xy 19.394422 -88.017937)
			(xy 19.386292 -88.069272) (xy 19.370231 -88.118702) (xy 19.346635 -88.165012) (xy 19.316085 -88.20706)
			(xy 19.279334 -88.243811) (xy 19.237286 -88.274361) (xy 19.190976 -88.297957) (xy 19.141546 -88.314018)
			(xy 19.090211 -88.322148) (xy 19.038237 -88.322148) (xy 18.986902 -88.314018) (xy 18.937472 -88.297957)
			(xy 18.891162 -88.274361) (xy 18.849114 -88.243811) (xy 18.812363 -88.20706) (xy 18.781813 -88.165012)
			(xy 18.758217 -88.118702) (xy 18.742156 -88.069272) (xy 18.734026 -88.017937) (xy 17.793512 -88.017937)
			(xy 17.79146 -88.043917) (xy 17.779248 -88.094596) (xy 17.759232 -88.142729) (xy 17.731908 -88.187123)
			(xy 17.697954 -88.226677) (xy 17.6784 -88.243918) (xy 17.6784 -88.539828) (xy 17.697953 -88.557069)
			(xy 17.731905 -88.596625) (xy 17.759227 -88.64102) (xy 17.779242 -88.689153) (xy 17.791452 -88.739831)
			(xy 17.795557 -88.791797) (xy 17.793505 -88.817783) (xy 17.933926 -88.817783) (xy 17.933926 -88.765809)
			(xy 17.942056 -88.714474) (xy 17.958117 -88.665044) (xy 17.981713 -88.618734) (xy 18.012263 -88.576686)
			(xy 18.049014 -88.539935) (xy 18.091062 -88.509385) (xy 18.137372 -88.485789) (xy 18.186802 -88.469728)
			(xy 18.238137 -88.461598) (xy 18.290111 -88.461598) (xy 18.341446 -88.469728) (xy 18.390876 -88.485789)
			(xy 18.437186 -88.509385) (xy 18.479234 -88.539935) (xy 18.515985 -88.576686) (xy 18.546535 -88.618734)
			(xy 18.570131 -88.665044) (xy 18.586192 -88.714474) (xy 18.594322 -88.765809) (xy 18.594832 -88.791796)
			(xy 18.594322 -88.817783) (xy 18.734026 -88.817783) (xy 18.734026 -88.765809) (xy 18.742156 -88.714474)
			(xy 18.758217 -88.665044) (xy 18.781813 -88.618734) (xy 18.812363 -88.576686) (xy 18.849114 -88.539935)
			(xy 18.891162 -88.509385) (xy 18.937472 -88.485789) (xy 18.986902 -88.469728) (xy 19.038237 -88.461598)
			(xy 19.090211 -88.461598) (xy 19.141546 -88.469728) (xy 19.190976 -88.485789) (xy 19.237286 -88.509385)
			(xy 19.279334 -88.539935) (xy 19.316085 -88.576686) (xy 19.346635 -88.618734) (xy 19.370231 -88.665044)
			(xy 19.386292 -88.714474) (xy 19.394422 -88.765809) (xy 19.394932 -88.791796) (xy 19.394422 -88.817783)
			(xy 19.534126 -88.817783) (xy 19.534126 -88.765809) (xy 19.542256 -88.714474) (xy 19.558317 -88.665044)
			(xy 19.581913 -88.618734) (xy 19.612463 -88.576686) (xy 19.649214 -88.539935) (xy 19.691262 -88.509385)
			(xy 19.737572 -88.485789) (xy 19.787002 -88.469728) (xy 19.838337 -88.461598) (xy 19.890311 -88.461598)
			(xy 19.941646 -88.469728) (xy 19.991076 -88.485789) (xy 20.037386 -88.509385) (xy 20.079434 -88.539935)
			(xy 20.116185 -88.576686) (xy 20.146735 -88.618734) (xy 20.170331 -88.665044) (xy 20.186392 -88.714474)
			(xy 20.194522 -88.765809) (xy 20.195032 -88.791796) (xy 20.194522 -88.817783) (xy 20.186392 -88.869118)
			(xy 20.170331 -88.918548) (xy 20.146735 -88.964858) (xy 20.116185 -89.006906) (xy 20.079434 -89.043657)
			(xy 20.037386 -89.074207) (xy 19.991076 -89.097803) (xy 19.941646 -89.113864) (xy 19.890311 -89.121994)
			(xy 19.838337 -89.121994) (xy 19.787002 -89.113864) (xy 19.737572 -89.097803) (xy 19.691262 -89.074207)
			(xy 19.649214 -89.043657) (xy 19.612463 -89.006906) (xy 19.581913 -88.964858) (xy 19.558317 -88.918548)
			(xy 19.542256 -88.869118) (xy 19.534126 -88.817783) (xy 19.394422 -88.817783) (xy 19.386292 -88.869118)
			(xy 19.370231 -88.918548) (xy 19.346635 -88.964858) (xy 19.316085 -89.006906) (xy 19.279334 -89.043657)
			(xy 19.237286 -89.074207) (xy 19.190976 -89.097803) (xy 19.141546 -89.113864) (xy 19.090211 -89.121994)
			(xy 19.038237 -89.121994) (xy 18.986902 -89.113864) (xy 18.937472 -89.097803) (xy 18.891162 -89.074207)
			(xy 18.849114 -89.043657) (xy 18.812363 -89.006906) (xy 18.781813 -88.964858) (xy 18.758217 -88.918548)
			(xy 18.742156 -88.869118) (xy 18.734026 -88.817783) (xy 18.594322 -88.817783) (xy 18.586192 -88.869118)
			(xy 18.570131 -88.918548) (xy 18.546535 -88.964858) (xy 18.515985 -89.006906) (xy 18.479234 -89.043657)
			(xy 18.437186 -89.074207) (xy 18.390876 -89.097803) (xy 18.341446 -89.113864) (xy 18.290111 -89.121994)
			(xy 18.238137 -89.121994) (xy 18.186802 -89.113864) (xy 18.137372 -89.097803) (xy 18.091062 -89.074207)
			(xy 18.049014 -89.043657) (xy 18.012263 -89.006906) (xy 17.981713 -88.964858) (xy 17.958117 -88.918548)
			(xy 17.942056 -88.869118) (xy 17.933926 -88.817783) (xy 17.793505 -88.817783) (xy 17.791453 -88.843764)
			(xy 17.779243 -88.894442) (xy 17.759229 -88.942576) (xy 17.731908 -88.986971) (xy 17.697957 -89.026527)
			(xy 17.6784 -89.043764) (xy 17.6784 -89.339928) (xy 17.697953 -89.357169) (xy 17.731905 -89.396725)
			(xy 17.759227 -89.44112) (xy 17.779242 -89.489253) (xy 17.791452 -89.539931) (xy 17.795557 -89.591897)
			(xy 17.793505 -89.617883) (xy 17.933926 -89.617883) (xy 17.933926 -89.565909) (xy 17.942056 -89.514574)
			(xy 17.958117 -89.465144) (xy 17.981713 -89.418834) (xy 18.012263 -89.376786) (xy 18.049014 -89.340035)
			(xy 18.091062 -89.309485) (xy 18.137372 -89.285889) (xy 18.186802 -89.269828) (xy 18.238137 -89.261698)
			(xy 18.290111 -89.261698) (xy 18.341446 -89.269828) (xy 18.390876 -89.285889) (xy 18.437186 -89.309485)
			(xy 18.479234 -89.340035) (xy 18.515985 -89.376786) (xy 18.546535 -89.418834) (xy 18.570131 -89.465144)
			(xy 18.586192 -89.514574) (xy 18.594322 -89.565909) (xy 18.594832 -89.591896) (xy 18.594322 -89.617883)
			(xy 18.734026 -89.617883) (xy 18.734026 -89.565909) (xy 18.742156 -89.514574) (xy 18.758217 -89.465144)
			(xy 18.781813 -89.418834) (xy 18.812363 -89.376786) (xy 18.849114 -89.340035) (xy 18.891162 -89.309485)
			(xy 18.937472 -89.285889) (xy 18.986902 -89.269828) (xy 19.038237 -89.261698) (xy 19.090211 -89.261698)
			(xy 19.141546 -89.269828) (xy 19.190976 -89.285889) (xy 19.237286 -89.309485) (xy 19.279334 -89.340035)
			(xy 19.316085 -89.376786) (xy 19.346635 -89.418834) (xy 19.370231 -89.465144) (xy 19.386292 -89.514574)
			(xy 19.394422 -89.565909) (xy 19.394932 -89.591896) (xy 19.394422 -89.617883) (xy 19.386292 -89.669218)
			(xy 19.370231 -89.718648) (xy 19.346635 -89.764958) (xy 19.316085 -89.807006) (xy 19.279334 -89.843757)
			(xy 19.237286 -89.874307) (xy 19.190976 -89.897903) (xy 19.141546 -89.913964) (xy 19.090211 -89.922094)
			(xy 19.038237 -89.922094) (xy 18.986902 -89.913964) (xy 18.937472 -89.897903) (xy 18.891162 -89.874307)
			(xy 18.849114 -89.843757) (xy 18.812363 -89.807006) (xy 18.781813 -89.764958) (xy 18.758217 -89.718648)
			(xy 18.742156 -89.669218) (xy 18.734026 -89.617883) (xy 18.594322 -89.617883) (xy 18.586192 -89.669218)
			(xy 18.570131 -89.718648) (xy 18.546535 -89.764958) (xy 18.515985 -89.807006) (xy 18.479234 -89.843757)
			(xy 18.437186 -89.874307) (xy 18.390876 -89.897903) (xy 18.341446 -89.913964) (xy 18.290111 -89.922094)
			(xy 18.238137 -89.922094) (xy 18.186802 -89.913964) (xy 18.137372 -89.897903) (xy 18.091062 -89.874307)
			(xy 18.049014 -89.843757) (xy 18.012263 -89.807006) (xy 17.981713 -89.764958) (xy 17.958117 -89.718648)
			(xy 17.942056 -89.669218) (xy 17.933926 -89.617883) (xy 17.793505 -89.617883) (xy 17.791453 -89.643864)
			(xy 17.779243 -89.694542) (xy 17.759229 -89.742676) (xy 17.731908 -89.787071) (xy 17.697957 -89.826627)
			(xy 17.6784 -89.843864) (xy 17.6784 -90.139774) (xy 17.697954 -90.157015) (xy 17.731908 -90.196569)
			(xy 17.759232 -90.240963) (xy 17.779247 -90.289096) (xy 17.791459 -90.339774) (xy 17.795563 -90.391741)
			(xy 17.79351 -90.417729) (xy 17.933926 -90.417729) (xy 17.933926 -90.365755) (xy 17.942056 -90.31442)
			(xy 17.958117 -90.26499) (xy 17.981713 -90.21868) (xy 18.012263 -90.176632) (xy 18.049014 -90.139881)
			(xy 18.091062 -90.109331) (xy 18.137372 -90.085735) (xy 18.186802 -90.069674) (xy 18.238137 -90.061544)
			(xy 18.290111 -90.061544) (xy 18.341446 -90.069674) (xy 18.390876 -90.085735) (xy 18.437186 -90.109331)
			(xy 18.479234 -90.139881) (xy 18.515985 -90.176632) (xy 18.546535 -90.21868) (xy 18.570131 -90.26499)
			(xy 18.586192 -90.31442) (xy 18.594322 -90.365755) (xy 18.594832 -90.391742) (xy 18.594322 -90.417729)
			(xy 18.734026 -90.417729) (xy 18.734026 -90.365755) (xy 18.742156 -90.31442) (xy 18.758217 -90.26499)
			(xy 18.781813 -90.21868) (xy 18.812363 -90.176632) (xy 18.849114 -90.139881) (xy 18.891162 -90.109331)
			(xy 18.937472 -90.085735) (xy 18.986902 -90.069674) (xy 19.038237 -90.061544) (xy 19.090211 -90.061544)
			(xy 19.141546 -90.069674) (xy 19.190976 -90.085735) (xy 19.237286 -90.109331) (xy 19.279334 -90.139881)
			(xy 19.316085 -90.176632) (xy 19.346635 -90.21868) (xy 19.370231 -90.26499) (xy 19.386292 -90.31442)
			(xy 19.394422 -90.365755) (xy 19.394932 -90.391742) (xy 19.394422 -90.417729) (xy 19.386292 -90.469064)
			(xy 19.370231 -90.518494) (xy 19.346635 -90.564804) (xy 19.316085 -90.606852) (xy 19.279334 -90.643603)
			(xy 19.237286 -90.674153) (xy 19.190976 -90.697749) (xy 19.141546 -90.71381) (xy 19.090211 -90.72194)
			(xy 19.038237 -90.72194) (xy 18.986902 -90.71381) (xy 18.937472 -90.697749) (xy 18.891162 -90.674153)
			(xy 18.849114 -90.643603) (xy 18.812363 -90.606852) (xy 18.781813 -90.564804) (xy 18.758217 -90.518494)
			(xy 18.742156 -90.469064) (xy 18.734026 -90.417729) (xy 18.594322 -90.417729) (xy 18.586192 -90.469064)
			(xy 18.570131 -90.518494) (xy 18.546535 -90.564804) (xy 18.515985 -90.606852) (xy 18.479234 -90.643603)
			(xy 18.437186 -90.674153) (xy 18.390876 -90.697749) (xy 18.341446 -90.71381) (xy 18.290111 -90.72194)
			(xy 18.238137 -90.72194) (xy 18.186802 -90.71381) (xy 18.137372 -90.697749) (xy 18.091062 -90.674153)
			(xy 18.049014 -90.643603) (xy 18.012263 -90.606852) (xy 17.981713 -90.564804) (xy 17.958117 -90.518494)
			(xy 17.942056 -90.469064) (xy 17.933926 -90.417729) (xy 17.79351 -90.417729) (xy 17.791458 -90.443708)
			(xy 17.779247 -90.494387) (xy 17.75923 -90.542519) (xy 17.731906 -90.586913) (xy 17.697952 -90.626467)
			(xy 17.6784 -90.64371) (xy 17.6784 -90.939874) (xy 17.697954 -90.957115) (xy 17.731908 -90.996669)
			(xy 17.759232 -91.041063) (xy 17.779247 -91.089196) (xy 17.791459 -91.139874) (xy 17.795563 -91.191841)
			(xy 17.79351 -91.217829) (xy 17.933926 -91.217829) (xy 17.933926 -91.165855) (xy 17.942056 -91.11452)
			(xy 17.958117 -91.06509) (xy 17.981713 -91.01878) (xy 18.012263 -90.976732) (xy 18.049014 -90.939981)
			(xy 18.091062 -90.909431) (xy 18.137372 -90.885835) (xy 18.186802 -90.869774) (xy 18.238137 -90.861644)
			(xy 18.290111 -90.861644) (xy 18.341446 -90.869774) (xy 18.390876 -90.885835) (xy 18.437186 -90.909431)
			(xy 18.479234 -90.939981) (xy 18.515985 -90.976732) (xy 18.546535 -91.01878) (xy 18.570131 -91.06509)
			(xy 18.586192 -91.11452) (xy 18.594322 -91.165855) (xy 18.594832 -91.191842) (xy 18.594322 -91.217829)
			(xy 18.734026 -91.217829) (xy 18.734026 -91.165855) (xy 18.742156 -91.11452) (xy 18.758217 -91.06509)
			(xy 18.781813 -91.01878) (xy 18.812363 -90.976732) (xy 18.849114 -90.939981) (xy 18.891162 -90.909431)
			(xy 18.937472 -90.885835) (xy 18.986902 -90.869774) (xy 19.038237 -90.861644) (xy 19.090211 -90.861644)
			(xy 19.141546 -90.869774) (xy 19.190976 -90.885835) (xy 19.237286 -90.909431) (xy 19.279334 -90.939981)
			(xy 19.316085 -90.976732) (xy 19.346635 -91.01878) (xy 19.370231 -91.06509) (xy 19.386292 -91.11452)
			(xy 19.394422 -91.165855) (xy 19.394932 -91.191842) (xy 19.394422 -91.217829) (xy 19.534126 -91.217829)
			(xy 19.534126 -91.165855) (xy 19.542256 -91.11452) (xy 19.558317 -91.06509) (xy 19.581913 -91.01878)
			(xy 19.612463 -90.976732) (xy 19.649214 -90.939981) (xy 19.691262 -90.909431) (xy 19.737572 -90.885835)
			(xy 19.787002 -90.869774) (xy 19.838337 -90.861644) (xy 19.890311 -90.861644) (xy 19.941646 -90.869774)
			(xy 19.991076 -90.885835) (xy 20.037386 -90.909431) (xy 20.079434 -90.939981) (xy 20.116185 -90.976732)
			(xy 20.146735 -91.01878) (xy 20.170331 -91.06509) (xy 20.186392 -91.11452) (xy 20.194522 -91.165855)
			(xy 20.195032 -91.191842) (xy 20.194522 -91.217829) (xy 20.186392 -91.269164) (xy 20.170331 -91.318594)
			(xy 20.146735 -91.364904) (xy 20.116185 -91.406952) (xy 20.079434 -91.443703) (xy 20.037386 -91.474253)
			(xy 19.991076 -91.497849) (xy 19.941646 -91.51391) (xy 19.890311 -91.52204) (xy 19.838337 -91.52204)
			(xy 19.787002 -91.51391) (xy 19.737572 -91.497849) (xy 19.691262 -91.474253) (xy 19.649214 -91.443703)
			(xy 19.612463 -91.406952) (xy 19.581913 -91.364904) (xy 19.558317 -91.318594) (xy 19.542256 -91.269164)
			(xy 19.534126 -91.217829) (xy 19.394422 -91.217829) (xy 19.386292 -91.269164) (xy 19.370231 -91.318594)
			(xy 19.346635 -91.364904) (xy 19.316085 -91.406952) (xy 19.279334 -91.443703) (xy 19.237286 -91.474253)
			(xy 19.190976 -91.497849) (xy 19.141546 -91.51391) (xy 19.090211 -91.52204) (xy 19.038237 -91.52204)
			(xy 18.986902 -91.51391) (xy 18.937472 -91.497849) (xy 18.891162 -91.474253) (xy 18.849114 -91.443703)
			(xy 18.812363 -91.406952) (xy 18.781813 -91.364904) (xy 18.758217 -91.318594) (xy 18.742156 -91.269164)
			(xy 18.734026 -91.217829) (xy 18.594322 -91.217829) (xy 18.586192 -91.269164) (xy 18.570131 -91.318594)
			(xy 18.546535 -91.364904) (xy 18.515985 -91.406952) (xy 18.479234 -91.443703) (xy 18.437186 -91.474253)
			(xy 18.390876 -91.497849) (xy 18.341446 -91.51391) (xy 18.290111 -91.52204) (xy 18.238137 -91.52204)
			(xy 18.186802 -91.51391) (xy 18.137372 -91.497849) (xy 18.091062 -91.474253) (xy 18.049014 -91.443703)
			(xy 18.012263 -91.406952) (xy 17.981713 -91.364904) (xy 17.958117 -91.318594) (xy 17.942056 -91.269164)
			(xy 17.933926 -91.217829) (xy 17.79351 -91.217829) (xy 17.791458 -91.243808) (xy 17.779247 -91.294487)
			(xy 17.75923 -91.342619) (xy 17.731906 -91.387013) (xy 17.697952 -91.426567) (xy 17.6784 -91.44381)
			(xy 17.6784 -91.739974) (xy 17.697954 -91.757215) (xy 17.731908 -91.796769) (xy 17.759232 -91.841163)
			(xy 17.779247 -91.889296) (xy 17.791459 -91.939974) (xy 17.795563 -91.991941) (xy 17.79351 -92.017929)
			(xy 17.933926 -92.017929) (xy 17.933926 -91.965955) (xy 17.942056 -91.91462) (xy 17.958117 -91.86519)
			(xy 17.981713 -91.81888) (xy 18.012263 -91.776832) (xy 18.049014 -91.740081) (xy 18.091062 -91.709531)
			(xy 18.137372 -91.685935) (xy 18.186802 -91.669874) (xy 18.238137 -91.661744) (xy 18.290111 -91.661744)
			(xy 18.341446 -91.669874) (xy 18.390876 -91.685935) (xy 18.437186 -91.709531) (xy 18.479234 -91.740081)
			(xy 18.515985 -91.776832) (xy 18.546535 -91.81888) (xy 18.570131 -91.86519) (xy 18.586192 -91.91462)
			(xy 18.594322 -91.965955) (xy 18.594832 -91.991942) (xy 18.594322 -92.017929) (xy 18.734026 -92.017929)
			(xy 18.734026 -91.965955) (xy 18.742156 -91.91462) (xy 18.758217 -91.86519) (xy 18.781813 -91.81888)
			(xy 18.812363 -91.776832) (xy 18.849114 -91.740081) (xy 18.891162 -91.709531) (xy 18.937472 -91.685935)
			(xy 18.986902 -91.669874) (xy 19.038237 -91.661744) (xy 19.090211 -91.661744) (xy 19.141546 -91.669874)
			(xy 19.190976 -91.685935) (xy 19.237286 -91.709531) (xy 19.279334 -91.740081) (xy 19.316085 -91.776832)
			(xy 19.346635 -91.81888) (xy 19.370231 -91.86519) (xy 19.386292 -91.91462) (xy 19.394422 -91.965955)
			(xy 19.394932 -91.991942) (xy 19.394422 -92.017929) (xy 19.534126 -92.017929) (xy 19.534126 -91.965955)
			(xy 19.542256 -91.91462) (xy 19.558317 -91.86519) (xy 19.581913 -91.81888) (xy 19.612463 -91.776832)
			(xy 19.649214 -91.740081) (xy 19.691262 -91.709531) (xy 19.737572 -91.685935) (xy 19.787002 -91.669874)
			(xy 19.838337 -91.661744) (xy 19.890311 -91.661744) (xy 19.941646 -91.669874) (xy 19.991076 -91.685935)
			(xy 20.037386 -91.709531) (xy 20.079434 -91.740081) (xy 20.116185 -91.776832) (xy 20.146735 -91.81888)
			(xy 20.170331 -91.86519) (xy 20.186392 -91.91462) (xy 20.194522 -91.965955) (xy 20.195032 -91.991942)
			(xy 20.194522 -92.017929) (xy 20.333972 -92.017929) (xy 20.333972 -91.965955) (xy 20.342102 -91.91462)
			(xy 20.358163 -91.86519) (xy 20.381759 -91.81888) (xy 20.412309 -91.776832) (xy 20.44906 -91.740081)
			(xy 20.491108 -91.709531) (xy 20.537418 -91.685935) (xy 20.586848 -91.669874) (xy 20.638183 -91.661744)
			(xy 20.690157 -91.661744) (xy 20.741492 -91.669874) (xy 20.790922 -91.685935) (xy 20.837232 -91.709531)
			(xy 20.87928 -91.740081) (xy 20.916031 -91.776832) (xy 20.946581 -91.81888) (xy 20.970177 -91.86519)
			(xy 20.986238 -91.91462) (xy 20.994368 -91.965955) (xy 20.994878 -91.991942) (xy 20.994368 -92.017929)
			(xy 20.986238 -92.069264) (xy 20.970177 -92.118694) (xy 20.946581 -92.165004) (xy 20.916031 -92.207052)
			(xy 20.87928 -92.243803) (xy 20.837232 -92.274353) (xy 20.790922 -92.297949) (xy 20.741492 -92.31401)
			(xy 20.690157 -92.32214) (xy 20.638183 -92.32214) (xy 20.586848 -92.31401) (xy 20.537418 -92.297949)
			(xy 20.491108 -92.274353) (xy 20.44906 -92.243803) (xy 20.412309 -92.207052) (xy 20.381759 -92.165004)
			(xy 20.358163 -92.118694) (xy 20.342102 -92.069264) (xy 20.333972 -92.017929) (xy 20.194522 -92.017929)
			(xy 20.186392 -92.069264) (xy 20.170331 -92.118694) (xy 20.146735 -92.165004) (xy 20.116185 -92.207052)
			(xy 20.079434 -92.243803) (xy 20.037386 -92.274353) (xy 19.991076 -92.297949) (xy 19.941646 -92.31401)
			(xy 19.890311 -92.32214) (xy 19.838337 -92.32214) (xy 19.787002 -92.31401) (xy 19.737572 -92.297949)
			(xy 19.691262 -92.274353) (xy 19.649214 -92.243803) (xy 19.612463 -92.207052) (xy 19.581913 -92.165004)
			(xy 19.558317 -92.118694) (xy 19.542256 -92.069264) (xy 19.534126 -92.017929) (xy 19.394422 -92.017929)
			(xy 19.386292 -92.069264) (xy 19.370231 -92.118694) (xy 19.346635 -92.165004) (xy 19.316085 -92.207052)
			(xy 19.279334 -92.243803) (xy 19.237286 -92.274353) (xy 19.190976 -92.297949) (xy 19.141546 -92.31401)
			(xy 19.090211 -92.32214) (xy 19.038237 -92.32214) (xy 18.986902 -92.31401) (xy 18.937472 -92.297949)
			(xy 18.891162 -92.274353) (xy 18.849114 -92.243803) (xy 18.812363 -92.207052) (xy 18.781813 -92.165004)
			(xy 18.758217 -92.118694) (xy 18.742156 -92.069264) (xy 18.734026 -92.017929) (xy 18.594322 -92.017929)
			(xy 18.586192 -92.069264) (xy 18.570131 -92.118694) (xy 18.546535 -92.165004) (xy 18.515985 -92.207052)
			(xy 18.479234 -92.243803) (xy 18.437186 -92.274353) (xy 18.390876 -92.297949) (xy 18.341446 -92.31401)
			(xy 18.290111 -92.32214) (xy 18.238137 -92.32214) (xy 18.186802 -92.31401) (xy 18.137372 -92.297949)
			(xy 18.091062 -92.274353) (xy 18.049014 -92.243803) (xy 18.012263 -92.207052) (xy 17.981713 -92.165004)
			(xy 17.958117 -92.118694) (xy 17.942056 -92.069264) (xy 17.933926 -92.017929) (xy 17.79351 -92.017929)
			(xy 17.791458 -92.043908) (xy 17.779247 -92.094587) (xy 17.75923 -92.142719) (xy 17.731906 -92.187113)
			(xy 17.697952 -92.226667) (xy 17.6784 -92.24391) (xy 17.6784 -92.53982) (xy 17.697954 -92.557061)
			(xy 17.731907 -92.596617) (xy 17.75923 -92.641012) (xy 17.779246 -92.689146) (xy 17.791458 -92.739825)
			(xy 17.795563 -92.791792) (xy 17.793512 -92.817775) (xy 17.933926 -92.817775) (xy 17.933926 -92.765801)
			(xy 17.942056 -92.714466) (xy 17.958117 -92.665036) (xy 17.981713 -92.618726) (xy 18.012263 -92.576678)
			(xy 18.049014 -92.539927) (xy 18.091062 -92.509377) (xy 18.137372 -92.485781) (xy 18.186802 -92.46972)
			(xy 18.238137 -92.46159) (xy 18.290111 -92.46159) (xy 18.341446 -92.46972) (xy 18.390876 -92.485781)
			(xy 18.437186 -92.509377) (xy 18.479234 -92.539927) (xy 18.515985 -92.576678) (xy 18.546535 -92.618726)
			(xy 18.570131 -92.665036) (xy 18.586192 -92.714466) (xy 18.594322 -92.765801) (xy 18.594832 -92.791788)
			(xy 18.594322 -92.817775) (xy 18.734026 -92.817775) (xy 18.734026 -92.765801) (xy 18.742156 -92.714466)
			(xy 18.758217 -92.665036) (xy 18.781813 -92.618726) (xy 18.812363 -92.576678) (xy 18.849114 -92.539927)
			(xy 18.891162 -92.509377) (xy 18.937472 -92.485781) (xy 18.986902 -92.46972) (xy 19.038237 -92.46159)
			(xy 19.090211 -92.46159) (xy 19.141546 -92.46972) (xy 19.190976 -92.485781) (xy 19.237286 -92.509377)
			(xy 19.279334 -92.539927) (xy 19.316085 -92.576678) (xy 19.346635 -92.618726) (xy 19.370231 -92.665036)
			(xy 19.386292 -92.714466) (xy 19.394422 -92.765801) (xy 19.394932 -92.791788) (xy 19.394422 -92.817775)
			(xy 19.534126 -92.817775) (xy 19.534126 -92.765801) (xy 19.542256 -92.714466) (xy 19.558317 -92.665036)
			(xy 19.581913 -92.618726) (xy 19.612463 -92.576678) (xy 19.649214 -92.539927) (xy 19.691262 -92.509377)
			(xy 19.737572 -92.485781) (xy 19.787002 -92.46972) (xy 19.838337 -92.46159) (xy 19.890311 -92.46159)
			(xy 19.941646 -92.46972) (xy 19.991076 -92.485781) (xy 20.037386 -92.509377) (xy 20.079434 -92.539927)
			(xy 20.116185 -92.576678) (xy 20.146735 -92.618726) (xy 20.170331 -92.665036) (xy 20.186392 -92.714466)
			(xy 20.194522 -92.765801) (xy 20.195032 -92.791788) (xy 20.194522 -92.817775) (xy 20.333972 -92.817775)
			(xy 20.333972 -92.765801) (xy 20.342102 -92.714466) (xy 20.358163 -92.665036) (xy 20.381759 -92.618726)
			(xy 20.412309 -92.576678) (xy 20.44906 -92.539927) (xy 20.491108 -92.509377) (xy 20.537418 -92.485781)
			(xy 20.586848 -92.46972) (xy 20.638183 -92.46159) (xy 20.690157 -92.46159) (xy 20.741492 -92.46972)
			(xy 20.790922 -92.485781) (xy 20.837232 -92.509377) (xy 20.87928 -92.539927) (xy 20.916031 -92.576678)
			(xy 20.946581 -92.618726) (xy 20.970177 -92.665036) (xy 20.986238 -92.714466) (xy 20.994368 -92.765801)
			(xy 20.994878 -92.791788) (xy 20.994368 -92.817775) (xy 21.92452 -92.817775) (xy 21.92452 -92.765801)
			(xy 21.93265 -92.714466) (xy 21.948711 -92.665036) (xy 21.972307 -92.618726) (xy 22.002857 -92.576678)
			(xy 22.039608 -92.539927) (xy 22.081656 -92.509377) (xy 22.127966 -92.485781) (xy 22.177396 -92.46972)
			(xy 22.228731 -92.46159) (xy 22.280705 -92.46159) (xy 22.33204 -92.46972) (xy 22.38147 -92.485781)
			(xy 22.42778 -92.509377) (xy 22.469828 -92.539927) (xy 22.506579 -92.576678) (xy 22.537129 -92.618726)
			(xy 22.560725 -92.665036) (xy 22.576786 -92.714466) (xy 22.584916 -92.765801) (xy 22.585426 -92.791788)
			(xy 22.584916 -92.817775) (xy 22.576786 -92.86911) (xy 22.560725 -92.91854) (xy 22.537129 -92.96485)
			(xy 22.506579 -93.006898) (xy 22.469828 -93.043649) (xy 22.42778 -93.074199) (xy 22.38147 -93.097795)
			(xy 22.33204 -93.113856) (xy 22.280705 -93.121986) (xy 22.228731 -93.121986) (xy 22.177396 -93.113856)
			(xy 22.127966 -93.097795) (xy 22.081656 -93.074199) (xy 22.039608 -93.043649) (xy 22.002857 -93.006898)
			(xy 21.972307 -92.96485) (xy 21.948711 -92.91854) (xy 21.93265 -92.86911) (xy 21.92452 -92.817775)
			(xy 20.994368 -92.817775) (xy 20.986238 -92.86911) (xy 20.970177 -92.91854) (xy 20.946581 -92.96485)
			(xy 20.916031 -93.006898) (xy 20.87928 -93.043649) (xy 20.837232 -93.074199) (xy 20.790922 -93.097795)
			(xy 20.741492 -93.113856) (xy 20.690157 -93.121986) (xy 20.638183 -93.121986) (xy 20.586848 -93.113856)
			(xy 20.537418 -93.097795) (xy 20.491108 -93.074199) (xy 20.44906 -93.043649) (xy 20.412309 -93.006898)
			(xy 20.381759 -92.96485) (xy 20.358163 -92.91854) (xy 20.342102 -92.86911) (xy 20.333972 -92.817775)
			(xy 20.194522 -92.817775) (xy 20.186392 -92.86911) (xy 20.170331 -92.91854) (xy 20.146735 -92.96485)
			(xy 20.116185 -93.006898) (xy 20.079434 -93.043649) (xy 20.037386 -93.074199) (xy 19.991076 -93.097795)
			(xy 19.941646 -93.113856) (xy 19.890311 -93.121986) (xy 19.838337 -93.121986) (xy 19.787002 -93.113856)
			(xy 19.737572 -93.097795) (xy 19.691262 -93.074199) (xy 19.649214 -93.043649) (xy 19.612463 -93.006898)
			(xy 19.581913 -92.96485) (xy 19.558317 -92.91854) (xy 19.542256 -92.86911) (xy 19.534126 -92.817775)
			(xy 19.394422 -92.817775) (xy 19.386292 -92.86911) (xy 19.370231 -92.91854) (xy 19.346635 -92.96485)
			(xy 19.316085 -93.006898) (xy 19.279334 -93.043649) (xy 19.237286 -93.074199) (xy 19.190976 -93.097795)
			(xy 19.141546 -93.113856) (xy 19.090211 -93.121986) (xy 19.038237 -93.121986) (xy 18.986902 -93.113856)
			(xy 18.937472 -93.097795) (xy 18.891162 -93.074199) (xy 18.849114 -93.043649) (xy 18.812363 -93.006898)
			(xy 18.781813 -92.96485) (xy 18.758217 -92.91854) (xy 18.742156 -92.86911) (xy 18.734026 -92.817775)
			(xy 18.594322 -92.817775) (xy 18.586192 -92.86911) (xy 18.570131 -92.91854) (xy 18.546535 -92.96485)
			(xy 18.515985 -93.006898) (xy 18.479234 -93.043649) (xy 18.437186 -93.074199) (xy 18.390876 -93.097795)
			(xy 18.341446 -93.113856) (xy 18.290111 -93.121986) (xy 18.238137 -93.121986) (xy 18.186802 -93.113856)
			(xy 18.137372 -93.097795) (xy 18.091062 -93.074199) (xy 18.049014 -93.043649) (xy 18.012263 -93.006898)
			(xy 17.981713 -92.96485) (xy 17.958117 -92.91854) (xy 17.942056 -92.86911) (xy 17.933926 -92.817775)
			(xy 17.793512 -92.817775) (xy 17.79146 -92.84376) (xy 17.779251 -92.894439) (xy 17.759237 -92.942574)
			(xy 17.731916 -92.98697) (xy 17.697965 -93.026528) (xy 17.6784 -93.043756) (xy 17.6784 -93.598238)
			(xy 18.096738 -94.016322) (xy 18.109682 -94.029678) (xy 18.132606 -94.058967) (xy 18.142458 -94.074742)
			(xy 18.171714 -94.063969) (xy 18.232956 -94.05234) (xy 18.264124 -94.051628) (xy 18.290111 -94.052113)
			(xy 18.341445 -94.060247) (xy 18.390874 -94.076312) (xy 18.437181 -94.099912) (xy 18.479226 -94.130465)
			(xy 18.515974 -94.16722) (xy 18.54652 -94.20927) (xy 18.570111 -94.255582) (xy 18.586167 -94.305014)
			(xy 18.594292 -94.356349) (xy 18.594832 -94.382336) (xy 18.594345 -94.408323) (xy 19.534126 -94.408323)
			(xy 19.534126 -94.356349) (xy 19.542256 -94.305014) (xy 19.558317 -94.255584) (xy 19.581913 -94.209274)
			(xy 19.612463 -94.167226) (xy 19.649214 -94.130475) (xy 19.691262 -94.099925) (xy 19.737572 -94.076329)
			(xy 19.787002 -94.060268) (xy 19.838337 -94.052138) (xy 19.890311 -94.052138) (xy 19.941646 -94.060268)
			(xy 19.991076 -94.076329) (xy 20.037386 -94.099925) (xy 20.079434 -94.130475) (xy 20.116185 -94.167226)
			(xy 20.146735 -94.209274) (xy 20.170331 -94.255584) (xy 20.186392 -94.305014) (xy 20.194522 -94.356349)
			(xy 20.195032 -94.382336) (xy 20.194522 -94.408323) (xy 20.333972 -94.408323) (xy 20.333972 -94.356349)
			(xy 20.342102 -94.305014) (xy 20.358163 -94.255584) (xy 20.381759 -94.209274) (xy 20.412309 -94.167226)
			(xy 20.44906 -94.130475) (xy 20.491108 -94.099925) (xy 20.537418 -94.076329) (xy 20.586848 -94.060268)
			(xy 20.638183 -94.052138) (xy 20.690157 -94.052138) (xy 20.741492 -94.060268) (xy 20.790922 -94.076329)
			(xy 20.837232 -94.099925) (xy 20.87928 -94.130475) (xy 20.916031 -94.167226) (xy 20.946581 -94.209274)
			(xy 20.970177 -94.255584) (xy 20.986238 -94.305014) (xy 20.994368 -94.356349) (xy 20.994878 -94.382336)
			(xy 20.994368 -94.408323) (xy 21.92452 -94.408323) (xy 21.92452 -94.356349) (xy 21.93265 -94.305014)
			(xy 21.948711 -94.255584) (xy 21.972307 -94.209274) (xy 22.002857 -94.167226) (xy 22.039608 -94.130475)
			(xy 22.081656 -94.099925) (xy 22.127966 -94.076329) (xy 22.177396 -94.060268) (xy 22.228731 -94.052138)
			(xy 22.280705 -94.052138) (xy 22.33204 -94.060268) (xy 22.38147 -94.076329) (xy 22.42778 -94.099925)
			(xy 22.469828 -94.130475) (xy 22.506579 -94.167226) (xy 22.537129 -94.209274) (xy 22.560725 -94.255584)
			(xy 22.576786 -94.305014) (xy 22.584916 -94.356349) (xy 22.585426 -94.382336) (xy 22.584916 -94.408323)
			(xy 22.576786 -94.459658) (xy 22.560725 -94.509088) (xy 22.537129 -94.555398) (xy 22.506579 -94.597446)
			(xy 22.469828 -94.634197) (xy 22.42778 -94.664747) (xy 22.38147 -94.688343) (xy 22.33204 -94.704404)
			(xy 22.280705 -94.712534) (xy 22.228731 -94.712534) (xy 22.177396 -94.704404) (xy 22.127966 -94.688343)
			(xy 22.081656 -94.664747) (xy 22.039608 -94.634197) (xy 22.002857 -94.597446) (xy 21.972307 -94.555398)
			(xy 21.948711 -94.509088) (xy 21.93265 -94.459658) (xy 21.92452 -94.408323) (xy 20.994368 -94.408323)
			(xy 20.986238 -94.459658) (xy 20.970177 -94.509088) (xy 20.946581 -94.555398) (xy 20.916031 -94.597446)
			(xy 20.87928 -94.634197) (xy 20.837232 -94.664747) (xy 20.790922 -94.688343) (xy 20.741492 -94.704404)
			(xy 20.690157 -94.712534) (xy 20.638183 -94.712534) (xy 20.586848 -94.704404) (xy 20.537418 -94.688343)
			(xy 20.491108 -94.664747) (xy 20.44906 -94.634197) (xy 20.412309 -94.597446) (xy 20.381759 -94.555398)
			(xy 20.358163 -94.509088) (xy 20.342102 -94.459658) (xy 20.333972 -94.408323) (xy 20.194522 -94.408323)
			(xy 20.186392 -94.459658) (xy 20.170331 -94.509088) (xy 20.146735 -94.555398) (xy 20.116185 -94.597446)
			(xy 20.079434 -94.634197) (xy 20.037386 -94.664747) (xy 19.991076 -94.688343) (xy 19.941646 -94.704404)
			(xy 19.890311 -94.712534) (xy 19.838337 -94.712534) (xy 19.787002 -94.704404) (xy 19.737572 -94.688343)
			(xy 19.691262 -94.664747) (xy 19.649214 -94.634197) (xy 19.612463 -94.597446) (xy 19.581913 -94.555398)
			(xy 19.558317 -94.509088) (xy 19.542256 -94.459658) (xy 19.534126 -94.408323) (xy 18.594345 -94.408323)
			(xy 18.594343 -94.408448) (xy 18.586141 -94.460022) (xy 18.569931 -94.509666) (xy 18.546117 -94.556142)
			(xy 18.51529 -94.598296) (xy 18.478218 -94.635078) (xy 18.435824 -94.665573) (xy 18.412714 -94.677738)
			(xy 18.400596 -94.684296) (xy 18.380145 -94.702742) (xy 18.365379 -94.725991) (xy 18.357379 -94.752345)
			(xy 18.356728 -94.779879) (xy 18.363473 -94.806582) (xy 18.377123 -94.830504) (xy 18.386552 -94.840552)
			(xy 18.46707 -94.92107) (xy 18.469356 -94.922848) (xy 18.484222 -94.934964) (xy 18.511341 -94.962084)
			(xy 18.523458 -94.97695) (xy 18.525236 -94.979236) (xy 18.606008 -95.060008) (xy 18.616033 -95.069405)
			(xy 18.639927 -95.082951) (xy 18.666571 -95.089626) (xy 18.694029 -95.088947) (xy 18.720309 -95.080961)
			(xy 18.743504 -95.06625) (xy 18.761929 -95.04588) (xy 18.768568 -95.033846) (xy 18.780749 -95.010718)
			(xy 18.811277 -94.968288) (xy 18.848091 -94.931181) (xy 18.890278 -94.900319) (xy 18.93679 -94.876468)
			(xy 18.986472 -94.860221) (xy 19.038089 -94.851981) (xy 19.064224 -94.851474) (xy 19.09021 -94.851985)
			(xy 19.141543 -94.860119) (xy 19.190972 -94.876182) (xy 19.237279 -94.899778) (xy 19.279325 -94.930328)
			(xy 19.316076 -94.967079) (xy 19.346625 -95.009126) (xy 19.370221 -95.055434) (xy 19.386283 -95.104863)
			(xy 19.394415 -95.156196) (xy 19.394932 -95.182182) (xy 19.394442 -95.208169) (xy 19.534126 -95.208169)
			(xy 19.534126 -95.156195) (xy 19.542256 -95.10486) (xy 19.558317 -95.05543) (xy 19.581913 -95.00912)
			(xy 19.612463 -94.967072) (xy 19.649214 -94.930321) (xy 19.691262 -94.899771) (xy 19.737572 -94.876175)
			(xy 19.787002 -94.860114) (xy 19.838337 -94.851984) (xy 19.890311 -94.851984) (xy 19.941646 -94.860114)
			(xy 19.991076 -94.876175) (xy 20.037386 -94.899771) (xy 20.079434 -94.930321) (xy 20.116185 -94.967072)
			(xy 20.146735 -95.00912) (xy 20.170331 -95.05543) (xy 20.186392 -95.10486) (xy 20.194522 -95.156195)
			(xy 20.195032 -95.182182) (xy 20.194522 -95.208169) (xy 20.186392 -95.259504) (xy 20.170331 -95.308934)
			(xy 20.146735 -95.355244) (xy 20.116185 -95.397292) (xy 20.079434 -95.434043) (xy 20.037386 -95.464593)
			(xy 19.991076 -95.488189) (xy 19.941646 -95.50425) (xy 19.890311 -95.51238) (xy 19.838337 -95.51238)
			(xy 19.787002 -95.50425) (xy 19.737572 -95.488189) (xy 19.691262 -95.464593) (xy 19.649214 -95.434043)
			(xy 19.612463 -95.397292) (xy 19.581913 -95.355244) (xy 19.558317 -95.308934) (xy 19.542256 -95.259504)
			(xy 19.534126 -95.208169) (xy 19.394442 -95.208169) (xy 19.394439 -95.208319) (xy 19.386218 -95.259943)
			(xy 19.36998 -95.30963) (xy 19.346127 -95.356145) (xy 19.315254 -95.398329) (xy 19.27813 -95.43513)
			(xy 19.235679 -95.465634) (xy 19.21256 -95.477838) (xy 19.200508 -95.484428) (xy 19.180181 -95.502886)
			(xy 19.165505 -95.526092) (xy 19.157539 -95.552368) (xy 19.156859 -95.579817) (xy 19.163513 -95.606455)
			(xy 19.177023 -95.630359) (xy 19.186398 -95.640398) (xy 19.2024 -95.6564) (xy 19.807936 -95.6564)
		)
		(stroke
			(width 0)
			(type solid)
		)
		(fill yes)
		(layer "In4.Cu")
		(net "VCCIO2")
	)
	(gr_poly
		(pts
			(xy 82.611468 -95.118936) (xy 82.635593 -95.102821) (xy 82.687688 -95.07729) (xy 82.743046 -95.059937)
			(xy 82.800393 -95.051159) (xy 82.858407 -95.051159) (xy 82.915754 -95.059937) (xy 82.971112 -95.07729)
			(xy 83.023207 -95.102821) (xy 83.047332 -95.118936) (xy 84.593176 -95.118936) (xy 84.787486 -94.924626)
			(xy 84.787486 -87.839804) (xy 84.770558 -87.81885) (xy 84.74355 -87.772247) (xy 84.725068 -87.721654)
			(xy 84.715677 -87.668616) (xy 84.715096 -87.641684) (xy 84.715096 -80.833976) (xy 84.715679 -80.807047)
			(xy 84.725095 -80.754017) (xy 84.743583 -80.703431) (xy 84.770582 -80.656827) (xy 84.787486 -80.635856)
			(xy 84.787486 -80.423512) (xy 87.361268 -77.849476) (xy 87.361268 -32.092646) (xy 86.90229 -31.633414)
			(xy 83.106514 -31.633414) (xy 82.24266 -32.497268) (xy 82.24266 -32.99206) (xy 83.25942 -32.99206)
			(xy 83.263491 -32.936438) (xy 83.275617 -32.882001) (xy 83.29554 -32.82991) (xy 83.322836 -32.781275)
			(xy 83.356922 -32.737132) (xy 83.397071 -32.698423) (xy 83.442429 -32.665972) (xy 83.492029 -32.640471)
			(xy 83.544813 -32.622464) (xy 83.599656 -32.612334) (xy 83.65539 -32.610297) (xy 83.710827 -32.616397)
			(xy 83.764784 -32.630503) (xy 83.804504 -32.647382) (xy 85.42985 -32.647382) (xy 85.433921 -32.59176)
			(xy 85.446047 -32.537323) (xy 85.46597 -32.485232) (xy 85.493266 -32.436597) (xy 85.527352 -32.392454)
			(xy 85.567501 -32.353745) (xy 85.612859 -32.321294) (xy 85.662459 -32.295793) (xy 85.715243 -32.277786)
			(xy 85.770086 -32.267656) (xy 85.82582 -32.265619) (xy 85.881257 -32.271719) (xy 85.935214 -32.285825)
			(xy 85.986543 -32.307637) (xy 86.034149 -32.336691) (xy 86.077017 -32.372366) (xy 86.114234 -32.413903)
			(xy 86.145007 -32.460416) (xy 86.168679 -32.510913) (xy 86.184747 -32.56432) (xy 86.192867 -32.619496)
			(xy 86.193376 -32.647382) (xy 86.192867 -32.675268) (xy 86.184747 -32.730444) (xy 86.168679 -32.783851)
			(xy 86.145007 -32.834348) (xy 86.114234 -32.880861) (xy 86.077017 -32.922398) (xy 86.034149 -32.958073)
			(xy 85.986543 -32.987127) (xy 85.935214 -33.008939) (xy 85.881257 -33.023045) (xy 85.82582 -33.029145)
			(xy 85.770086 -33.027108) (xy 85.715243 -33.016978) (xy 85.662459 -32.998971) (xy 85.612859 -32.97347)
			(xy 85.567501 -32.941019) (xy 85.527352 -32.90231) (xy 85.493266 -32.858167) (xy 85.46597 -32.809532)
			(xy 85.446047 -32.757441) (xy 85.433921 -32.703004) (xy 85.42985 -32.647382) (xy 83.804504 -32.647382)
			(xy 83.816113 -32.652315) (xy 83.863719 -32.681369) (xy 83.906587 -32.717044) (xy 83.943804 -32.758581)
			(xy 83.974577 -32.805094) (xy 83.998249 -32.855591) (xy 84.014317 -32.908998) (xy 84.022437 -32.964174)
			(xy 84.022946 -32.99206) (xy 84.022437 -33.019946) (xy 84.014317 -33.075122) (xy 83.998249 -33.128529)
			(xy 83.974577 -33.179026) (xy 83.943804 -33.225539) (xy 83.906587 -33.267076) (xy 83.863719 -33.302751)
			(xy 83.816113 -33.331805) (xy 83.764784 -33.353617) (xy 83.710827 -33.367723) (xy 83.65539 -33.373823)
			(xy 83.599656 -33.371786) (xy 83.544813 -33.361656) (xy 83.492029 -33.343649) (xy 83.442429 -33.318148)
			(xy 83.397071 -33.285697) (xy 83.356922 -33.246988) (xy 83.322836 -33.202845) (xy 83.29554 -33.15421)
			(xy 83.275617 -33.102119) (xy 83.263491 -33.047682) (xy 83.25942 -32.99206) (xy 82.24266 -32.99206)
			(xy 82.24266 -34.186876) (xy 83.25942 -34.186876) (xy 83.263491 -34.131254) (xy 83.275617 -34.076817)
			(xy 83.29554 -34.024726) (xy 83.322836 -33.976091) (xy 83.356922 -33.931948) (xy 83.397071 -33.893239)
			(xy 83.442429 -33.860788) (xy 83.492029 -33.835287) (xy 83.544813 -33.81728) (xy 83.599656 -33.80715)
			(xy 83.65539 -33.805113) (xy 83.710827 -33.811213) (xy 83.764784 -33.825319) (xy 83.816113 -33.847131)
			(xy 83.863719 -33.876185) (xy 83.906587 -33.91186) (xy 83.943804 -33.953397) (xy 83.974577 -33.99991)
			(xy 83.998249 -34.050407) (xy 84.014317 -34.103814) (xy 84.022437 -34.15899) (xy 84.022946 -34.186876)
			(xy 84.022437 -34.214762) (xy 84.014317 -34.269938) (xy 83.998249 -34.323345) (xy 83.974577 -34.373842)
			(xy 83.943804 -34.420355) (xy 83.906587 -34.461892) (xy 83.863719 -34.497567) (xy 83.816113 -34.526621)
			(xy 83.764784 -34.548433) (xy 83.710827 -34.562539) (xy 83.65539 -34.568639) (xy 83.599656 -34.566602)
			(xy 83.544813 -34.556472) (xy 83.492029 -34.538465) (xy 83.442429 -34.512964) (xy 83.397071 -34.480513)
			(xy 83.356922 -34.441804) (xy 83.322836 -34.397661) (xy 83.29554 -34.349026) (xy 83.275617 -34.296935)
			(xy 83.263491 -34.242498) (xy 83.25942 -34.186876) (xy 82.24266 -34.186876) (xy 82.24266 -35.113722)
			(xy 83.880196 -35.113722) (xy 83.884267 -35.0581) (xy 83.896393 -35.003663) (xy 83.916316 -34.951572)
			(xy 83.943612 -34.902937) (xy 83.977698 -34.858794) (xy 84.017847 -34.820085) (xy 84.063205 -34.787634)
			(xy 84.112805 -34.762133) (xy 84.165589 -34.744126) (xy 84.220432 -34.733996) (xy 84.276166 -34.731959)
			(xy 84.331603 -34.738059) (xy 84.38556 -34.752165) (xy 84.436889 -34.773977) (xy 84.484495 -34.803031)
			(xy 84.527363 -34.838706) (xy 84.56458 -34.880243) (xy 84.595353 -34.926756) (xy 84.619025 -34.977253)
			(xy 84.635093 -35.03066) (xy 84.643213 -35.085836) (xy 84.643722 -35.113722) (xy 84.643213 -35.141608)
			(xy 84.635093 -35.196784) (xy 84.619025 -35.250191) (xy 84.595353 -35.300688) (xy 84.56458 -35.347201)
			(xy 84.527363 -35.388738) (xy 84.484495 -35.424413) (xy 84.436889 -35.453467) (xy 84.38556 -35.475279)
			(xy 84.331603 -35.489385) (xy 84.276166 -35.495485) (xy 84.220432 -35.493448) (xy 84.165589 -35.483318)
			(xy 84.112805 -35.465311) (xy 84.063205 -35.43981) (xy 84.017847 -35.407359) (xy 83.977698 -35.36865)
			(xy 83.943612 -35.324507) (xy 83.916316 -35.275872) (xy 83.896393 -35.223781) (xy 83.884267 -35.169344)
			(xy 83.880196 -35.113722) (xy 82.24266 -35.113722) (xy 82.24266 -35.968432) (xy 82.95208 -35.968432)
			(xy 82.956151 -35.91281) (xy 82.968277 -35.858373) (xy 82.9882 -35.806282) (xy 83.015496 -35.757647)
			(xy 83.049582 -35.713504) (xy 83.089731 -35.674795) (xy 83.135089 -35.642344) (xy 83.184689 -35.616843)
			(xy 83.237473 -35.598836) (xy 83.292316 -35.588706) (xy 83.34805 -35.586669) (xy 83.403487 -35.592769)
			(xy 83.457444 -35.606875) (xy 83.508773 -35.628687) (xy 83.556379 -35.657741) (xy 83.599247 -35.693416)
			(xy 83.636464 -35.734953) (xy 83.667237 -35.781466) (xy 83.690909 -35.831963) (xy 83.706977 -35.88537)
			(xy 83.715097 -35.940546) (xy 83.715606 -35.968432) (xy 83.715097 -35.996318) (xy 83.714155 -36.002722)
			(xy 83.854796 -36.002722) (xy 83.858867 -35.9471) (xy 83.870993 -35.892663) (xy 83.890916 -35.840572)
			(xy 83.918212 -35.791937) (xy 83.952298 -35.747794) (xy 83.992447 -35.709085) (xy 84.037805 -35.676634)
			(xy 84.087405 -35.651133) (xy 84.140189 -35.633126) (xy 84.195032 -35.622996) (xy 84.250766 -35.620959)
			(xy 84.306203 -35.627059) (xy 84.36016 -35.641165) (xy 84.411489 -35.662977) (xy 84.459095 -35.692031)
			(xy 84.501963 -35.727706) (xy 84.53918 -35.769243) (xy 84.569953 -35.815756) (xy 84.593625 -35.866253)
			(xy 84.609693 -35.91966) (xy 84.617813 -35.974836) (xy 84.618322 -36.002722) (xy 84.617813 -36.030608)
			(xy 84.609693 -36.085784) (xy 84.593625 -36.139191) (xy 84.569953 -36.189688) (xy 84.53918 -36.236201)
			(xy 84.501963 -36.277738) (xy 84.459095 -36.313413) (xy 84.411489 -36.342467) (xy 84.36016 -36.364279)
			(xy 84.306203 -36.378385) (xy 84.250766 -36.384485) (xy 84.195032 -36.382448) (xy 84.140189 -36.372318)
			(xy 84.087405 -36.354311) (xy 84.037805 -36.32881) (xy 83.992447 -36.296359) (xy 83.952298 -36.25765)
			(xy 83.918212 -36.213507) (xy 83.890916 -36.164872) (xy 83.870993 -36.112781) (xy 83.858867 -36.058344)
			(xy 83.854796 -36.002722) (xy 83.714155 -36.002722) (xy 83.706977 -36.051494) (xy 83.690909 -36.104901)
			(xy 83.667237 -36.155398) (xy 83.636464 -36.201911) (xy 83.599247 -36.243448) (xy 83.556379 -36.279123)
			(xy 83.508773 -36.308177) (xy 83.457444 -36.329989) (xy 83.403487 -36.344095) (xy 83.34805 -36.350195)
			(xy 83.292316 -36.348158) (xy 83.237473 -36.338028) (xy 83.184689 -36.320021) (xy 83.135089 -36.29452)
			(xy 83.089731 -36.262069) (xy 83.049582 -36.22336) (xy 83.015496 -36.179217) (xy 82.9882 -36.130582)
			(xy 82.968277 -36.078491) (xy 82.956151 -36.024054) (xy 82.95208 -35.968432) (xy 82.24266 -35.968432)
			(xy 82.24266 -36.984432) (xy 83.644994 -38.386766) (xy 84.270594 -38.386766) (xy 84.274665 -38.331144)
			(xy 84.286791 -38.276707) (xy 84.306714 -38.224616) (xy 84.33401 -38.175981) (xy 84.368096 -38.131838)
			(xy 84.408245 -38.093129) (xy 84.453603 -38.060678) (xy 84.503203 -38.035177) (xy 84.555987 -38.01717)
			(xy 84.61083 -38.00704) (xy 84.666564 -38.005003) (xy 84.722001 -38.011103) (xy 84.775958 -38.025209)
			(xy 84.827287 -38.047021) (xy 84.874893 -38.076075) (xy 84.917761 -38.11175) (xy 84.954978 -38.153287)
			(xy 84.985751 -38.1998) (xy 85.009423 -38.250297) (xy 85.025491 -38.303704) (xy 85.033611 -38.35888)
			(xy 85.03412 -38.386766) (xy 85.033611 -38.414652) (xy 85.025491 -38.469828) (xy 85.009423 -38.523235)
			(xy 84.985751 -38.573732) (xy 84.971146 -38.595808) (xy 85.818218 -38.595808) (xy 85.818704 -38.568557)
			(xy 85.82646 -38.514609) (xy 85.841815 -38.462314) (xy 85.864457 -38.412737) (xy 85.893923 -38.366887)
			(xy 85.929614 -38.325696) (xy 85.970805 -38.290005) (xy 86.016655 -38.260539) (xy 86.066232 -38.237897)
			(xy 86.118527 -38.222542) (xy 86.172475 -38.214786) (xy 86.226977 -38.214786) (xy 86.280925 -38.222542)
			(xy 86.33322 -38.237897) (xy 86.382797 -38.260539) (xy 86.428647 -38.290005) (xy 86.469838 -38.325696)
			(xy 86.505529 -38.366887) (xy 86.534995 -38.412737) (xy 86.557637 -38.462314) (xy 86.572992 -38.514609)
			(xy 86.580748 -38.568557) (xy 86.581234 -38.595808) (xy 86.580698 -38.62482) (xy 86.571929 -38.682177)
			(xy 86.554577 -38.737546) (xy 86.529044 -38.78965) (xy 86.495918 -38.837288) (xy 86.476332 -38.858698)
			(xy 86.466117 -38.87017) (xy 86.452538 -38.897709) (xy 86.447757 -38.92804) (xy 86.452205 -38.958421)
			(xy 86.465482 -38.986107) (xy 86.486386 -39.008597) (xy 86.499446 -39.016686) (xy 86.523989 -39.031368)
			(xy 86.568745 -39.066975) (xy 86.607685 -39.108862) (xy 86.639939 -39.15609) (xy 86.664783 -39.207604)
			(xy 86.681662 -39.262247) (xy 86.690198 -39.318798) (xy 86.690708 -39.347394) (xy 86.690222 -39.374645)
			(xy 86.682466 -39.428593) (xy 86.667111 -39.480888) (xy 86.644469 -39.530465) (xy 86.615003 -39.576315)
			(xy 86.579312 -39.617506) (xy 86.538121 -39.653197) (xy 86.492271 -39.682663) (xy 86.442694 -39.705305)
			(xy 86.390399 -39.72066) (xy 86.336451 -39.728416) (xy 86.281949 -39.728416) (xy 86.228001 -39.72066)
			(xy 86.175706 -39.705305) (xy 86.126129 -39.682663) (xy 86.080279 -39.653197) (xy 86.039088 -39.617506)
			(xy 86.003397 -39.576315) (xy 85.973931 -39.530465) (xy 85.951289 -39.480888) (xy 85.935934 -39.428593)
			(xy 85.928178 -39.374645) (xy 85.927692 -39.347394) (xy 85.928222 -39.318382) (xy 85.936992 -39.261024)
			(xy 85.954344 -39.205655) (xy 85.979879 -39.153551) (xy 86.013007 -39.105913) (xy 86.032594 -39.084504)
			(xy 86.042799 -39.073025) (xy 86.056374 -39.045488) (xy 86.061154 -39.01516) (xy 86.056707 -38.984782)
			(xy 86.043435 -38.957098) (xy 86.022537 -38.934607) (xy 86.00948 -38.926516) (xy 85.984943 -38.911823)
			(xy 85.940187 -38.876219) (xy 85.901245 -38.834335) (xy 85.86899 -38.787108) (xy 85.844145 -38.735596)
			(xy 85.827265 -38.680953) (xy 85.818728 -38.624403) (xy 85.818218 -38.595808) (xy 84.971146 -38.595808)
			(xy 84.954978 -38.620245) (xy 84.917761 -38.661782) (xy 84.874893 -38.697457) (xy 84.827287 -38.726511)
			(xy 84.775958 -38.748323) (xy 84.722001 -38.762429) (xy 84.666564 -38.768529) (xy 84.61083 -38.766492)
			(xy 84.555987 -38.756362) (xy 84.503203 -38.738355) (xy 84.453603 -38.712854) (xy 84.408245 -38.680403)
			(xy 84.368096 -38.641694) (xy 84.33401 -38.597551) (xy 84.306714 -38.548916) (xy 84.286791 -38.496825)
			(xy 84.274665 -38.442388) (xy 84.270594 -38.386766) (xy 83.644994 -38.386766) (xy 83.66379 -38.405562)
			(xy 83.676236 -38.409118) (xy 83.702024 -38.417289) (xy 83.751169 -38.439896) (xy 83.79663 -38.469214)
			(xy 83.837495 -38.504659) (xy 83.872947 -38.545518) (xy 83.902273 -38.590974) (xy 83.924888 -38.640115)
			(xy 83.93303 -38.665912) (xy 83.936586 -38.678358) (xy 84.227162 -38.968934) (xy 84.24291 -38.971728)
			(xy 84.269079 -38.976802) (xy 84.319782 -38.993252) (xy 84.367703 -39.016598) (xy 84.411908 -39.046385)
			(xy 84.451538 -39.082034) (xy 84.485821 -39.122851) (xy 84.514091 -39.168042) (xy 84.535797 -39.216728)
			(xy 84.550516 -39.26796) (xy 84.557962 -39.320742) (xy 84.558378 -39.347394) (xy 84.558218 -39.36206)
			(xy 84.555926 -39.391302) (xy 84.553806 -39.405814) (xy 84.553298 -39.409624) (xy 84.553298 -39.920164)
			(xy 84.553806 -39.923974) (xy 84.555935 -39.938485) (xy 84.558224 -39.967728) (xy 84.558378 -39.982394)
			(xy 84.558218 -39.99706) (xy 84.555926 -40.026302) (xy 84.553806 -40.040814) (xy 84.553298 -40.044624)
			(xy 84.553298 -40.555164) (xy 84.553806 -40.558974) (xy 84.555935 -40.573485) (xy 84.558224 -40.602728)
			(xy 84.558378 -40.617394) (xy 84.558218 -40.63206) (xy 84.555926 -40.661302) (xy 84.553806 -40.675814)
			(xy 84.553298 -40.679624) (xy 84.553298 -41.825164) (xy 84.553806 -41.828974) (xy 84.555935 -41.843485)
			(xy 84.558224 -41.872728) (xy 84.558378 -41.887394) (xy 84.558218 -41.90206) (xy 84.555926 -41.931302)
			(xy 84.553806 -41.945814) (xy 84.553298 -41.949624) (xy 84.553298 -42.141394) (xy 85.927692 -42.141394)
			(xy 85.928185 -42.115331) (xy 85.935294 -42.063692) (xy 85.949364 -42.013501) (xy 85.970135 -41.965692)
			(xy 85.997218 -41.921154) (xy 86.030112 -41.880717) (xy 86.068202 -41.845133) (xy 86.089236 -41.829736)
			(xy 86.101497 -41.820341) (xy 86.12022 -41.795794) (xy 86.130772 -41.766781) (xy 86.132194 -41.735942)
			(xy 86.124357 -41.706081) (xy 86.107973 -41.679915) (xy 86.096602 -41.669462) (xy 86.076035 -41.651247)
			(xy 86.039844 -41.609914) (xy 86.00995 -41.56382) (xy 85.986973 -41.513918) (xy 85.971386 -41.461237)
			(xy 85.963512 -41.406865) (xy 85.963512 -41.351927) (xy 85.971388 -41.297556) (xy 85.986976 -41.244875)
			(xy 86.009954 -41.194973) (xy 86.039848 -41.14888) (xy 86.076041 -41.107548) (xy 86.096602 -41.089326)
			(xy 86.107956 -41.078837) (xy 86.124402 -41.05269) (xy 86.13228 -41.022822) (xy 86.130871 -40.991965)
			(xy 86.120303 -40.962939) (xy 86.101543 -40.9384) (xy 86.089236 -40.929052) (xy 86.068199 -40.913653)
			(xy 86.030084 -40.878085) (xy 85.997169 -40.837656) (xy 85.97007 -40.793119) (xy 85.94929 -40.745306)
			(xy 85.935219 -40.695108) (xy 85.928117 -40.643461) (xy 85.927692 -40.617394) (xy 85.928178 -40.590143)
			(xy 85.935934 -40.536195) (xy 85.951289 -40.4839) (xy 85.973931 -40.434323) (xy 86.003397 -40.388473)
			(xy 86.039088 -40.347282) (xy 86.080279 -40.311591) (xy 86.126129 -40.282125) (xy 86.175706 -40.259483)
			(xy 86.228001 -40.244128) (xy 86.281949 -40.236372) (xy 86.336451 -40.236372) (xy 86.390399 -40.244128)
			(xy 86.442694 -40.259483) (xy 86.492271 -40.282125) (xy 86.538121 -40.311591) (xy 86.579312 -40.347282)
			(xy 86.615003 -40.388473) (xy 86.644469 -40.434323) (xy 86.667111 -40.4839) (xy 86.682466 -40.536195)
			(xy 86.690222 -40.590143) (xy 86.690708 -40.617394) (xy 86.690218 -40.644863) (xy 86.682332 -40.699234)
			(xy 86.666737 -40.751913) (xy 86.643754 -40.801814) (xy 86.613857 -40.847907) (xy 86.577665 -40.88924)
			(xy 86.557104 -40.907462) (xy 86.545657 -40.917858) (xy 86.529214 -40.944032) (xy 86.521345 -40.973924)
			(xy 86.522772 -41.004802) (xy 86.533363 -41.033842) (xy 86.55215 -41.058389) (xy 86.56447 -41.067736)
			(xy 86.587112 -41.084338) (xy 86.62774 -41.123086) (xy 86.662251 -41.16737) (xy 86.689897 -41.216234)
			(xy 86.710083 -41.268623) (xy 86.722371 -41.323405) (xy 86.726498 -41.379397) (xy 86.722372 -41.435388)
			(xy 86.710085 -41.49017) (xy 86.6899 -41.542559) (xy 86.662254 -41.591424) (xy 86.627745 -41.635709)
			(xy 86.587117 -41.674458) (xy 86.56447 -41.691052) (xy 86.55222 -41.700461) (xy 86.533496 -41.725004)
			(xy 86.522942 -41.754013) (xy 86.521518 -41.78485) (xy 86.529353 -41.814709) (xy 86.545734 -41.840874)
			(xy 86.557104 -41.851326) (xy 86.577652 -41.869565) (xy 86.613859 -41.910886) (xy 86.643766 -41.956973)
			(xy 86.666754 -42.006872) (xy 86.68235 -42.059552) (xy 86.690229 -42.113924) (xy 86.690708 -42.141394)
			(xy 86.690222 -42.168645) (xy 86.682466 -42.222593) (xy 86.667111 -42.274888) (xy 86.644469 -42.324465)
			(xy 86.615003 -42.370315) (xy 86.579312 -42.411506) (xy 86.538121 -42.447197) (xy 86.492271 -42.476663)
			(xy 86.442694 -42.499305) (xy 86.390399 -42.51466) (xy 86.336451 -42.522416) (xy 86.281949 -42.522416)
			(xy 86.228001 -42.51466) (xy 86.175706 -42.499305) (xy 86.126129 -42.476663) (xy 86.080279 -42.447197)
			(xy 86.039088 -42.411506) (xy 86.003397 -42.370315) (xy 85.973931 -42.324465) (xy 85.951289 -42.274888)
			(xy 85.935934 -42.222593) (xy 85.928178 -42.168645) (xy 85.927692 -42.141394) (xy 84.553298 -42.141394)
			(xy 84.553298 -42.460164) (xy 84.553806 -42.463974) (xy 84.555935 -42.478485) (xy 84.558224 -42.507728)
			(xy 84.558378 -42.522394) (xy 84.558218 -42.53706) (xy 84.555926 -42.566302) (xy 84.553806 -42.580814)
			(xy 84.553298 -42.584624) (xy 84.553298 -43.095164) (xy 84.553806 -43.098974) (xy 84.555935 -43.113485)
			(xy 84.558224 -43.142728) (xy 84.558378 -43.157394) (xy 85.927182 -43.157394) (xy 85.931253 -43.101772)
			(xy 85.943379 -43.047335) (xy 85.963302 -42.995244) (xy 85.990598 -42.946609) (xy 86.024684 -42.902466)
			(xy 86.064833 -42.863757) (xy 86.110191 -42.831306) (xy 86.159791 -42.805805) (xy 86.212575 -42.787798)
			(xy 86.267418 -42.777668) (xy 86.323152 -42.775631) (xy 86.378589 -42.781731) (xy 86.432546 -42.795837)
			(xy 86.483875 -42.817649) (xy 86.531481 -42.846703) (xy 86.574349 -42.882378) (xy 86.611566 -42.923915)
			(xy 86.642339 -42.970428) (xy 86.666011 -43.020925) (xy 86.682079 -43.074332) (xy 86.690199 -43.129508)
			(xy 86.690708 -43.157394) (xy 86.690199 -43.18528) (xy 86.682079 -43.240456) (xy 86.666011 -43.293863)
			(xy 86.642339 -43.34436) (xy 86.611566 -43.390873) (xy 86.574349 -43.43241) (xy 86.531481 -43.468085)
			(xy 86.483875 -43.497139) (xy 86.432546 -43.518951) (xy 86.378589 -43.533057) (xy 86.323152 -43.539157)
			(xy 86.267418 -43.53712) (xy 86.212575 -43.52699) (xy 86.159791 -43.508983) (xy 86.110191 -43.483482)
			(xy 86.064833 -43.451031) (xy 86.024684 -43.412322) (xy 85.990598 -43.368179) (xy 85.963302 -43.319544)
			(xy 85.943379 -43.267453) (xy 85.931253 -43.213016) (xy 85.927182 -43.157394) (xy 84.558378 -43.157394)
			(xy 84.558218 -43.17206) (xy 84.555926 -43.201302) (xy 84.553806 -43.215814) (xy 84.553298 -43.219624)
			(xy 84.553298 -43.730164) (xy 84.553806 -43.733974) (xy 84.555935 -43.748485) (xy 84.558224 -43.777728)
			(xy 84.558378 -43.792394) (xy 84.558218 -43.80706) (xy 84.555926 -43.836302) (xy 84.553806 -43.850814)
			(xy 84.553298 -43.854624) (xy 84.553298 -44.03852) (xy 85.93023 -44.03852) (xy 85.934301 -43.982898)
			(xy 85.946427 -43.928461) (xy 85.96635 -43.87637) (xy 85.993646 -43.827735) (xy 86.027732 -43.783592)
			(xy 86.067881 -43.744883) (xy 86.113239 -43.712432) (xy 86.162839 -43.686931) (xy 86.215623 -43.668924)
			(xy 86.270466 -43.658794) (xy 86.3262 -43.656757) (xy 86.381637 -43.662857) (xy 86.435594 -43.676963)
			(xy 86.486923 -43.698775) (xy 86.534529 -43.727829) (xy 86.577397 -43.763504) (xy 86.614614 -43.805041)
			(xy 86.645387 -43.851554) (xy 86.669059 -43.902051) (xy 86.685127 -43.955458) (xy 86.693247 -44.010634)
			(xy 86.693756 -44.03852) (xy 86.693247 -44.066406) (xy 86.685127 -44.121582) (xy 86.669059 -44.174989)
			(xy 86.645387 -44.225486) (xy 86.614614 -44.271999) (xy 86.577397 -44.313536) (xy 86.534529 -44.349211)
			(xy 86.486923 -44.378265) (xy 86.435594 -44.400077) (xy 86.381637 -44.414183) (xy 86.3262 -44.420283)
			(xy 86.270466 -44.418246) (xy 86.215623 -44.408116) (xy 86.162839 -44.390109) (xy 86.113239 -44.364608)
			(xy 86.067881 -44.332157) (xy 86.027732 -44.293448) (xy 85.993646 -44.249305) (xy 85.96635 -44.20067)
			(xy 85.946427 -44.148579) (xy 85.934301 -44.094142) (xy 85.93023 -44.03852) (xy 84.553298 -44.03852)
			(xy 84.553298 -44.365164) (xy 84.553806 -44.368974) (xy 84.555935 -44.383485) (xy 84.558224 -44.412728)
			(xy 84.558378 -44.427394) (xy 84.558218 -44.44206) (xy 84.555926 -44.471302) (xy 84.553806 -44.485814)
			(xy 84.553298 -44.489624) (xy 84.553298 -45.000164) (xy 84.553806 -45.003974) (xy 84.555935 -45.018485)
			(xy 84.558224 -45.047728) (xy 84.558378 -45.062394) (xy 84.558218 -45.07706) (xy 84.555926 -45.106302)
			(xy 84.553806 -45.120814) (xy 84.553298 -45.124624) (xy 84.553298 -45.635164) (xy 84.553806 -45.638974)
			(xy 84.555935 -45.653485) (xy 84.558224 -45.682728) (xy 84.558378 -45.697394) (xy 84.558218 -45.71206)
			(xy 84.555926 -45.741302) (xy 84.553806 -45.755814) (xy 84.553298 -45.759624) (xy 84.553298 -46.400974)
			(xy 84.553806 -46.404784) (xy 84.555935 -46.419295) (xy 84.558223 -46.448538) (xy 84.558378 -46.463204)
			(xy 84.558218 -46.47787) (xy 84.555925 -46.507111) (xy 84.553806 -46.521624) (xy 84.553298 -46.525434)
			(xy 84.553298 -47.221394) (xy 85.927692 -47.221394) (xy 85.928218 -47.192689) (xy 85.936827 -47.135928)
			(xy 85.953835 -47.081096) (xy 85.978858 -47.029426) (xy 86.011334 -46.982085) (xy 86.05053 -46.940137)
			(xy 86.072726 -46.921928) (xy 86.084425 -46.912049) (xy 86.101766 -46.88683) (xy 86.110846 -46.857602)
			(xy 86.110846 -46.826996) (xy 86.101766 -46.797768) (xy 86.084424 -46.77255) (xy 86.072726 -46.76267)
			(xy 86.050543 -46.744444) (xy 86.011332 -46.702509) (xy 85.978846 -46.655174) (xy 85.953818 -46.603506)
			(xy 85.936811 -46.548672) (xy 85.92821 -46.491909) (xy 85.927692 -46.463204) (xy 85.928232 -46.434107)
			(xy 85.937063 -46.376587) (xy 85.954536 -46.321079) (xy 85.980245 -46.268872) (xy 86.013592 -46.22118)
			(xy 86.053802 -46.179113) (xy 86.076536 -46.160944) (xy 86.086884 -46.152523) (xy 86.103137 -46.131377)
			(xy 86.113355 -46.106741) (xy 86.116841 -46.080299) (xy 86.113355 -46.053857) (xy 86.103137 -46.029222)
			(xy 86.086883 -46.008076) (xy 86.076536 -45.999654) (xy 86.053787 -45.981505) (xy 86.013593 -45.939424)
			(xy 85.980257 -45.891725) (xy 85.954553 -45.839516) (xy 85.937079 -45.784009) (xy 85.92824 -45.726491)
			(xy 85.927692 -45.697394) (xy 85.928171 -45.668475) (xy 85.936903 -45.611301) (xy 85.954167 -45.556099)
			(xy 85.979566 -45.504137) (xy 86.012518 -45.456605) (xy 86.052268 -45.414591) (xy 86.074758 -45.396404)
			(xy 86.086572 -45.386515) (xy 86.104094 -45.36119) (xy 86.113272 -45.331794) (xy 86.113271 -45.300999)
			(xy 86.104091 -45.271603) (xy 86.086567 -45.24628) (xy 86.074758 -45.236384) (xy 86.052258 -45.218213)
			(xy 86.012526 -45.176188) (xy 85.97959 -45.128648) (xy 85.954205 -45.076683) (xy 85.936952 -45.021483)
			(xy 85.928226 -44.964311) (xy 85.927692 -44.935394) (xy 85.928178 -44.908143) (xy 85.935934 -44.854195)
			(xy 85.951289 -44.8019) (xy 85.973931 -44.752323) (xy 86.003397 -44.706473) (xy 86.039088 -44.665282)
			(xy 86.080279 -44.629591) (xy 86.126129 -44.600125) (xy 86.175706 -44.577483) (xy 86.228001 -44.562128)
			(xy 86.281949 -44.554372) (xy 86.336451 -44.554372) (xy 86.390399 -44.562128) (xy 86.442694 -44.577483)
			(xy 86.492271 -44.600125) (xy 86.538121 -44.629591) (xy 86.579312 -44.665282) (xy 86.615003 -44.706473)
			(xy 86.644469 -44.752323) (xy 86.667111 -44.8019) (xy 86.682466 -44.854195) (xy 86.690222 -44.908143)
			(xy 86.690708 -44.935394) (xy 86.69022 -44.964312) (xy 86.68149 -45.021487) (xy 86.664228 -45.076688)
			(xy 86.638831 -45.12865) (xy 86.60588 -45.176183) (xy 86.566131 -45.218196) (xy 86.543642 -45.236384)
			(xy 86.53184 -45.246286) (xy 86.514317 -45.271607) (xy 86.505138 -45.301) (xy 86.505137 -45.331793)
			(xy 86.514314 -45.361186) (xy 86.531835 -45.386508) (xy 86.543642 -45.396404) (xy 86.566136 -45.414582)
			(xy 86.605869 -45.456606) (xy 86.638805 -45.504144) (xy 86.664191 -45.556107) (xy 86.681446 -45.611307)
			(xy 86.690173 -45.668477) (xy 86.690708 -45.697394) (xy 86.690167 -45.726491) (xy 86.681336 -45.784011)
			(xy 86.663863 -45.839519) (xy 86.638154 -45.891726) (xy 86.604807 -45.939418) (xy 86.564598 -45.981485)
			(xy 86.541864 -45.999654) (xy 86.531588 -46.00813) (xy 86.51542 -46.029286) (xy 86.505259 -46.053899)
			(xy 86.501794 -46.080299) (xy 86.505259 -46.1067) (xy 86.515419 -46.131312) (xy 86.531587 -46.152469)
			(xy 86.541864 -46.160944) (xy 86.564612 -46.179094) (xy 86.604807 -46.221175) (xy 86.638143 -46.268873)
			(xy 86.663846 -46.321082) (xy 86.68132 -46.37659) (xy 86.690159 -46.434107) (xy 86.690708 -46.463204)
			(xy 86.690181 -46.491909) (xy 86.681572 -46.548669) (xy 86.664564 -46.603502) (xy 86.639541 -46.655172)
			(xy 86.607066 -46.702513) (xy 86.56787 -46.744461) (xy 86.545674 -46.76267) (xy 86.534025 -46.772578)
			(xy 86.516769 -46.797811) (xy 86.507738 -46.827015) (xy 86.507738 -46.857584) (xy 86.516769 -46.886788)
			(xy 86.534024 -46.912021) (xy 86.545674 -46.921928) (xy 86.567856 -46.940155) (xy 86.607067 -46.98209)
			(xy 86.639553 -47.029425) (xy 86.664582 -47.081092) (xy 86.681589 -47.135926) (xy 86.690189 -47.192689)
			(xy 86.690708 -47.221394) (xy 86.690222 -47.248645) (xy 86.682466 -47.302593) (xy 86.667111 -47.354888)
			(xy 86.644469 -47.404465) (xy 86.615003 -47.450315) (xy 86.579312 -47.491506) (xy 86.538121 -47.527197)
			(xy 86.492271 -47.556663) (xy 86.442694 -47.579305) (xy 86.390399 -47.59466) (xy 86.336451 -47.602416)
			(xy 86.281949 -47.602416) (xy 86.228001 -47.59466) (xy 86.175706 -47.579305) (xy 86.126129 -47.556663)
			(xy 86.080279 -47.527197) (xy 86.039088 -47.491506) (xy 86.003397 -47.450315) (xy 85.973931 -47.404465)
			(xy 85.951289 -47.354888) (xy 85.935934 -47.302593) (xy 85.928178 -47.248645) (xy 85.927692 -47.221394)
			(xy 84.553298 -47.221394) (xy 84.553298 -47.540164) (xy 84.553806 -47.543974) (xy 84.555935 -47.558485)
			(xy 84.558224 -47.587728) (xy 84.558378 -47.602394) (xy 84.558218 -47.61706) (xy 84.555926 -47.646302)
			(xy 84.553806 -47.660814) (xy 84.553298 -47.664624) (xy 84.553298 -48.175164) (xy 84.553806 -48.178974)
			(xy 84.555935 -48.193485) (xy 84.558224 -48.222728) (xy 84.558378 -48.237394) (xy 85.927182 -48.237394)
			(xy 85.931253 -48.181772) (xy 85.943379 -48.127335) (xy 85.963302 -48.075244) (xy 85.990598 -48.026609)
			(xy 86.024684 -47.982466) (xy 86.064833 -47.943757) (xy 86.110191 -47.911306) (xy 86.159791 -47.885805)
			(xy 86.212575 -47.867798) (xy 86.267418 -47.857668) (xy 86.323152 -47.855631) (xy 86.378589 -47.861731)
			(xy 86.432546 -47.875837) (xy 86.483875 -47.897649) (xy 86.531481 -47.926703) (xy 86.574349 -47.962378)
			(xy 86.611566 -48.003915) (xy 86.642339 -48.050428) (xy 86.666011 -48.100925) (xy 86.682079 -48.154332)
			(xy 86.690199 -48.209508) (xy 86.690708 -48.237394) (xy 86.690199 -48.26528) (xy 86.682079 -48.320456)
			(xy 86.666011 -48.373863) (xy 86.642339 -48.42436) (xy 86.611566 -48.470873) (xy 86.574349 -48.51241)
			(xy 86.531481 -48.548085) (xy 86.483875 -48.577139) (xy 86.432546 -48.598951) (xy 86.378589 -48.613057)
			(xy 86.323152 -48.619157) (xy 86.267418 -48.61712) (xy 86.212575 -48.60699) (xy 86.159791 -48.588983)
			(xy 86.110191 -48.563482) (xy 86.064833 -48.531031) (xy 86.024684 -48.492322) (xy 85.990598 -48.448179)
			(xy 85.963302 -48.399544) (xy 85.943379 -48.347453) (xy 85.931253 -48.293016) (xy 85.927182 -48.237394)
			(xy 84.558378 -48.237394) (xy 84.558218 -48.25206) (xy 84.555926 -48.281302) (xy 84.553806 -48.295814)
			(xy 84.553298 -48.299624) (xy 84.553298 -48.810164) (xy 84.553806 -48.813974) (xy 84.555935 -48.828485)
			(xy 84.558224 -48.857728) (xy 84.558378 -48.872394) (xy 84.558218 -48.88706) (xy 84.555926 -48.916302)
			(xy 84.553806 -48.930814) (xy 84.553298 -48.934624) (xy 84.553298 -49.136046) (xy 85.317582 -49.136046)
			(xy 85.321653 -49.080424) (xy 85.333779 -49.025987) (xy 85.353702 -48.973896) (xy 85.380998 -48.925261)
			(xy 85.415084 -48.881118) (xy 85.455233 -48.842409) (xy 85.500591 -48.809958) (xy 85.550191 -48.784457)
			(xy 85.602975 -48.76645) (xy 85.657818 -48.75632) (xy 85.713552 -48.754283) (xy 85.768989 -48.760383)
			(xy 85.822946 -48.774489) (xy 85.874275 -48.796301) (xy 85.921881 -48.825355) (xy 85.964749 -48.86103)
			(xy 86.001966 -48.902567) (xy 86.032739 -48.94908) (xy 86.056411 -48.999577) (xy 86.072479 -49.052984)
			(xy 86.080599 -49.10816) (xy 86.081108 -49.136046) (xy 86.080599 -49.163932) (xy 86.072479 -49.219108)
			(xy 86.056411 -49.272515) (xy 86.032739 -49.323012) (xy 86.001966 -49.369525) (xy 85.964749 -49.411062)
			(xy 85.921881 -49.446737) (xy 85.874275 -49.475791) (xy 85.822946 -49.497603) (xy 85.768989 -49.511709)
			(xy 85.713552 -49.517809) (xy 85.657818 -49.515772) (xy 85.602975 -49.505642) (xy 85.550191 -49.487635)
			(xy 85.500591 -49.462134) (xy 85.455233 -49.429683) (xy 85.415084 -49.390974) (xy 85.380998 -49.346831)
			(xy 85.353702 -49.298196) (xy 85.333779 -49.246105) (xy 85.321653 -49.191668) (xy 85.317582 -49.136046)
			(xy 84.553298 -49.136046) (xy 84.553298 -49.469802) (xy 83.9851 -50.038) (xy 85.237064 -50.038) (xy 85.241135 -49.982378)
			(xy 85.253261 -49.927941) (xy 85.273184 -49.87585) (xy 85.30048 -49.827215) (xy 85.334566 -49.783072)
			(xy 85.374715 -49.744363) (xy 85.420073 -49.711912) (xy 85.469673 -49.686411) (xy 85.522457 -49.668404)
			(xy 85.5773 -49.658274) (xy 85.633034 -49.656237) (xy 85.688471 -49.662337) (xy 85.742428 -49.676443)
			(xy 85.793757 -49.698255) (xy 85.841363 -49.727309) (xy 85.884231 -49.762984) (xy 85.921448 -49.804521)
			(xy 85.952221 -49.851034) (xy 85.975893 -49.901531) (xy 85.991961 -49.954938) (xy 86.000081 -50.010114)
			(xy 86.00059 -50.038) (xy 86.000081 -50.065886) (xy 85.991961 -50.121062) (xy 85.975893 -50.174469)
			(xy 85.952221 -50.224966) (xy 85.921448 -50.271479) (xy 85.884231 -50.313016) (xy 85.841363 -50.348691)
			(xy 85.793757 -50.377745) (xy 85.742428 -50.399557) (xy 85.688471 -50.413663) (xy 85.633034 -50.419763)
			(xy 85.5773 -50.417726) (xy 85.522457 -50.407596) (xy 85.469673 -50.389589) (xy 85.420073 -50.364088)
			(xy 85.374715 -50.331637) (xy 85.334566 -50.292928) (xy 85.30048 -50.248785) (xy 85.273184 -50.20015)
			(xy 85.253261 -50.148059) (xy 85.241135 -50.093622) (xy 85.237064 -50.038) (xy 83.9851 -50.038) (xy 83.768692 -50.254408)
			(xy 83.768692 -51.336702) (xy 85.216998 -51.336702) (xy 85.221069 -51.28108) (xy 85.233195 -51.226643)
			(xy 85.253118 -51.174552) (xy 85.280414 -51.125917) (xy 85.3145 -51.081774) (xy 85.354649 -51.043065)
			(xy 85.400007 -51.010614) (xy 85.449607 -50.985113) (xy 85.502391 -50.967106) (xy 85.557234 -50.956976)
			(xy 85.612968 -50.954939) (xy 85.668405 -50.961039) (xy 85.722362 -50.975145) (xy 85.773691 -50.996957)
			(xy 85.821297 -51.026011) (xy 85.864165 -51.061686) (xy 85.901382 -51.103223) (xy 85.932155 -51.149736)
			(xy 85.955827 -51.200233) (xy 85.971895 -51.25364) (xy 85.980015 -51.308816) (xy 85.980524 -51.336702)
			(xy 85.980015 -51.364588) (xy 85.971895 -51.419764) (xy 85.955827 -51.473171) (xy 85.932155 -51.523668)
			(xy 85.901382 -51.570181) (xy 85.864165 -51.611718) (xy 85.821297 -51.647393) (xy 85.773691 -51.676447)
			(xy 85.722362 -51.698259) (xy 85.668405 -51.712365) (xy 85.612968 -51.718465) (xy 85.557234 -51.716428)
			(xy 85.502391 -51.706298) (xy 85.449607 -51.688291) (xy 85.400007 -51.66279) (xy 85.354649 -51.630339)
			(xy 85.3145 -51.59163) (xy 85.280414 -51.547487) (xy 85.253118 -51.498852) (xy 85.233195 -51.446761)
			(xy 85.221069 -51.392324) (xy 85.216998 -51.336702) (xy 83.768692 -51.336702) (xy 83.768692 -52.352702)
			(xy 85.216998 -52.352702) (xy 85.221069 -52.29708) (xy 85.233195 -52.242643) (xy 85.253118 -52.190552)
			(xy 85.280414 -52.141917) (xy 85.3145 -52.097774) (xy 85.354649 -52.059065) (xy 85.400007 -52.026614)
			(xy 85.449607 -52.001113) (xy 85.502391 -51.983106) (xy 85.557234 -51.972976) (xy 85.612968 -51.970939)
			(xy 85.668405 -51.977039) (xy 85.722362 -51.991145) (xy 85.773691 -52.012957) (xy 85.821297 -52.042011)
			(xy 85.864165 -52.077686) (xy 85.901382 -52.119223) (xy 85.932155 -52.165736) (xy 85.955827 -52.216233)
			(xy 85.971895 -52.26964) (xy 85.980015 -52.324816) (xy 85.980524 -52.352702) (xy 85.980015 -52.380588)
			(xy 85.971895 -52.435764) (xy 85.955827 -52.489171) (xy 85.932155 -52.539668) (xy 85.901382 -52.586181)
			(xy 85.864165 -52.627718) (xy 85.821297 -52.663393) (xy 85.773691 -52.692447) (xy 85.722362 -52.714259)
			(xy 85.668405 -52.728365) (xy 85.612968 -52.734465) (xy 85.557234 -52.732428) (xy 85.502391 -52.722298)
			(xy 85.449607 -52.704291) (xy 85.400007 -52.67879) (xy 85.354649 -52.646339) (xy 85.3145 -52.60763)
			(xy 85.280414 -52.563487) (xy 85.253118 -52.514852) (xy 85.233195 -52.462761) (xy 85.221069 -52.408324)
			(xy 85.216998 -52.352702) (xy 83.768692 -52.352702) (xy 83.768692 -53.368702) (xy 85.216998 -53.368702)
			(xy 85.221069 -53.31308) (xy 85.233195 -53.258643) (xy 85.253118 -53.206552) (xy 85.280414 -53.157917)
			(xy 85.3145 -53.113774) (xy 85.354649 -53.075065) (xy 85.400007 -53.042614) (xy 85.449607 -53.017113)
			(xy 85.502391 -52.999106) (xy 85.557234 -52.988976) (xy 85.612968 -52.986939) (xy 85.668405 -52.993039)
			(xy 85.722362 -53.007145) (xy 85.773691 -53.028957) (xy 85.821297 -53.058011) (xy 85.864165 -53.093686)
			(xy 85.901382 -53.135223) (xy 85.932155 -53.181736) (xy 85.955827 -53.232233) (xy 85.971895 -53.28564)
			(xy 85.980015 -53.340816) (xy 85.980524 -53.368702) (xy 85.980015 -53.396588) (xy 85.971895 -53.451764)
			(xy 85.955827 -53.505171) (xy 85.932155 -53.555668) (xy 85.901382 -53.602181) (xy 85.864165 -53.643718)
			(xy 85.821297 -53.679393) (xy 85.773691 -53.708447) (xy 85.722362 -53.730259) (xy 85.668405 -53.744365)
			(xy 85.612968 -53.750465) (xy 85.557234 -53.748428) (xy 85.502391 -53.738298) (xy 85.449607 -53.720291)
			(xy 85.400007 -53.69479) (xy 85.354649 -53.662339) (xy 85.3145 -53.62363) (xy 85.280414 -53.579487)
			(xy 85.253118 -53.530852) (xy 85.233195 -53.478761) (xy 85.221069 -53.424324) (xy 85.216998 -53.368702)
			(xy 83.768692 -53.368702) (xy 83.768692 -58.353452) (xy 84.638134 -58.353452) (xy 84.638587 -58.32723)
			(xy 84.645788 -58.275282) (xy 84.660034 -58.224809) (xy 84.681057 -58.176762) (xy 84.70846 -58.132046)
			(xy 84.741728 -58.091504) (xy 84.780233 -58.055898) (xy 84.823251 -58.0259) (xy 84.846414 -58.0136)
			(xy 84.858653 -58.00679) (xy 84.879227 -57.987811) (xy 84.893871 -57.963955) (xy 84.901482 -57.937018)
			(xy 84.901489 -57.909026) (xy 84.893889 -57.882086) (xy 84.879256 -57.858224) (xy 84.858689 -57.839235)
			(xy 84.846414 -57.832498) (xy 84.823232 -57.820227) (xy 84.780198 -57.79024) (xy 84.74168 -57.754638)
			(xy 84.708404 -57.714093) (xy 84.680999 -57.66937) (xy 84.659981 -57.621313) (xy 84.645747 -57.57083)
			(xy 84.638567 -57.518872) (xy 84.638134 -57.492646) (xy 84.63862 -57.465395) (xy 84.646376 -57.411447)
			(xy 84.661731 -57.359152) (xy 84.684373 -57.309575) (xy 84.713839 -57.263725) (xy 84.74953 -57.222534)
			(xy 84.790721 -57.186843) (xy 84.836571 -57.157377) (xy 84.886148 -57.134735) (xy 84.938443 -57.11938)
			(xy 84.992391 -57.111624) (xy 85.046893 -57.111624) (xy 85.100841 -57.11938) (xy 85.153136 -57.134735)
			(xy 85.202713 -57.157377) (xy 85.248563 -57.186843) (xy 85.289754 -57.222534) (xy 85.325445 -57.263725)
			(xy 85.354911 -57.309575) (xy 85.377553 -57.359152) (xy 85.392908 -57.411447) (xy 85.400664 -57.465395)
			(xy 85.40115 -57.492646) (xy 85.400704 -57.518869) (xy 85.393503 -57.570817) (xy 85.379256 -57.62129)
			(xy 85.358233 -57.669338) (xy 85.330829 -57.714054) (xy 85.29756 -57.754596) (xy 85.259053 -57.790201)
			(xy 85.216033 -57.820199) (xy 85.19287 -57.832498) (xy 85.180584 -57.839194) (xy 85.160082 -57.858228)
			(xy 85.1455 -57.882103) (xy 85.13793 -57.909034) (xy 85.137936 -57.93701) (xy 85.145518 -57.963938)
			(xy 85.16011 -57.987807) (xy 85.180621 -58.006832) (xy 85.19287 -58.0136) (xy 85.216047 -58.025879)
			(xy 85.259082 -58.055865) (xy 85.297601 -58.091465) (xy 85.330877 -58.132009) (xy 85.358283 -58.176731)
			(xy 85.379302 -58.224786) (xy 85.393536 -58.275269) (xy 85.400717 -58.327226) (xy 85.40115 -58.353452)
			(xy 85.400664 -58.380703) (xy 85.392908 -58.434651) (xy 85.377553 -58.486946) (xy 85.354911 -58.536523)
			(xy 85.325445 -58.582373) (xy 85.289754 -58.623564) (xy 85.248563 -58.659255) (xy 85.202713 -58.688721)
			(xy 85.153136 -58.711363) (xy 85.100841 -58.726718) (xy 85.046893 -58.734474) (xy 84.992391 -58.734474)
			(xy 84.938443 -58.726718) (xy 84.886148 -58.711363) (xy 84.836571 -58.688721) (xy 84.790721 -58.659255)
			(xy 84.74953 -58.623564) (xy 84.713839 -58.582373) (xy 84.684373 -58.536523) (xy 84.661731 -58.486946)
			(xy 84.646376 -58.434651) (xy 84.63862 -58.380703) (xy 84.638134 -58.353452) (xy 83.768692 -58.353452)
			(xy 83.768692 -60.621926) (xy 84.638388 -60.621926) (xy 84.63879 -60.595702) (xy 84.645996 -60.54375)
			(xy 84.660248 -60.493275) (xy 84.681277 -60.445227) (xy 84.708687 -60.40051) (xy 84.741963 -60.359969)
			(xy 84.780476 -60.324366) (xy 84.823502 -60.294371) (xy 84.846668 -60.282074) (xy 84.858925 -60.275299)
			(xy 84.879491 -60.256309) (xy 84.894127 -60.232447) (xy 84.901733 -60.205507) (xy 84.901735 -60.177514)
			(xy 84.894136 -60.150572) (xy 84.879505 -60.126708) (xy 84.858942 -60.107713) (xy 84.846668 -60.100972)
			(xy 84.823488 -60.088698) (xy 84.780451 -60.058713) (xy 84.741931 -60.023113) (xy 84.708653 -59.982569)
			(xy 84.681247 -59.937846) (xy 84.66023 -59.889789) (xy 84.645997 -59.839305) (xy 84.638819 -59.787346)
			(xy 84.638388 -59.76112) (xy 84.638874 -59.733868) (xy 84.646628 -59.679918) (xy 84.661981 -59.627621)
			(xy 84.684621 -59.578041) (xy 84.714087 -59.532188) (xy 84.749778 -59.490995) (xy 84.790969 -59.455301)
			(xy 84.83682 -59.425833) (xy 84.886398 -59.40319) (xy 84.938694 -59.387833) (xy 84.992644 -59.380076)
			(xy 85.019896 -59.379612) (xy 85.047125 -59.38008) (xy 85.10103 -59.387823) (xy 85.153286 -59.403153)
			(xy 85.20283 -59.425758) (xy 85.248657 -59.455179) (xy 85.289835 -59.490817) (xy 85.325526 -59.531948)
			(xy 85.355006 -59.577737) (xy 85.377675 -59.627253) (xy 85.393072 -59.679489) (xy 85.400885 -59.733384)
			(xy 85.401404 -59.760612) (xy 85.401897 -59.775375) (xy 85.410315 -59.803675) (xy 85.426476 -59.828386)
			(xy 85.449028 -59.847443) (xy 85.476088 -59.859255) (xy 85.505395 -59.862835) (xy 85.534503 -59.857885)
			(xy 85.547962 -59.851798) (xy 85.57433 -59.839393) (xy 85.629893 -59.821844) (xy 85.687483 -59.812975)
			(xy 85.716618 -59.812428) (xy 85.743871 -59.812843) (xy 85.797822 -59.820602) (xy 85.850119 -59.835961)
			(xy 85.899699 -59.858605) (xy 85.945551 -59.888074) (xy 85.986743 -59.923769) (xy 86.022436 -59.964963)
			(xy 86.051904 -60.010817) (xy 86.074546 -60.060398) (xy 86.089901 -60.112696) (xy 86.097658 -60.166647)
			(xy 86.097658 -60.221153) (xy 86.089901 -60.275104) (xy 86.074546 -60.327402) (xy 86.051904 -60.376983)
			(xy 86.022436 -60.422837) (xy 85.986743 -60.464031) (xy 85.945551 -60.499726) (xy 85.899699 -60.529195)
			(xy 85.850119 -60.551839) (xy 85.797822 -60.567198) (xy 85.743871 -60.574957) (xy 85.716618 -60.575444)
			(xy 85.687487 -60.574862) (xy 85.629906 -60.565971) (xy 85.574338 -60.548454) (xy 85.547962 -60.536074)
			(xy 85.534604 -60.529994) (xy 85.505684 -60.525054) (xy 85.47655 -60.528527) (xy 85.449602 -60.540128)
			(xy 85.427056 -60.558902) (xy 85.410767 -60.583305) (xy 85.402076 -60.611328) (xy 85.401404 -60.62599)
			(xy 85.400649 -60.653051) (xy 85.392423 -60.706558) (xy 85.376716 -60.758364) (xy 85.353844 -60.80743)
			(xy 85.324267 -60.852771) (xy 85.288577 -60.893475) (xy 85.247492 -60.928726) (xy 85.201836 -60.957816)
			(xy 85.152527 -60.98016) (xy 85.100555 -60.99531) (xy 85.046964 -61.002962) (xy 85.019896 -61.003434)
			(xy 84.992646 -61.002926) (xy 84.9387 -60.99517) (xy 84.886408 -60.979815) (xy 84.836832 -60.957176)
			(xy 84.790983 -60.927711) (xy 84.749793 -60.892022) (xy 84.714102 -60.850835) (xy 84.684635 -60.804987)
			(xy 84.661992 -60.755413) (xy 84.646635 -60.703121) (xy 84.638876 -60.649176) (xy 84.638388 -60.621926)
			(xy 83.768692 -60.621926) (xy 83.768692 -62.59322) (xy 82.426556 -63.935356) (xy 79.066644 -63.935356)
			(xy 78.772004 -64.229996) (xy 78.772004 -68.801996) (xy 80.302608 -70.3326) (xy 80.302608 -70.858888)
			(xy 82.71713 -70.858888) (xy 82.721201 -70.803266) (xy 82.733327 -70.748829) (xy 82.75325 -70.696738)
			(xy 82.780546 -70.648103) (xy 82.814632 -70.60396) (xy 82.854781 -70.565251) (xy 82.900139 -70.5328)
			(xy 82.949739 -70.507299) (xy 83.002523 -70.489292) (xy 83.057366 -70.479162) (xy 83.1131 -70.477125)
			(xy 83.168537 -70.483225) (xy 83.222494 -70.497331) (xy 83.273823 -70.519143) (xy 83.321429 -70.548197)
			(xy 83.364297 -70.583872) (xy 83.401514 -70.625409) (xy 83.432287 -70.671922) (xy 83.455959 -70.722419)
			(xy 83.472027 -70.775826) (xy 83.480147 -70.831002) (xy 83.480656 -70.858888) (xy 83.480147 -70.886774)
			(xy 83.472027 -70.94195) (xy 83.455959 -70.995357) (xy 83.432287 -71.045854) (xy 83.401514 -71.092367)
			(xy 83.364297 -71.133904) (xy 83.321429 -71.169579) (xy 83.273823 -71.198633) (xy 83.222494 -71.220445)
			(xy 83.168537 -71.234551) (xy 83.1131 -71.240651) (xy 83.057366 -71.238614) (xy 83.002523 -71.228484)
			(xy 82.949739 -71.210477) (xy 82.900139 -71.184976) (xy 82.854781 -71.152525) (xy 82.814632 -71.113816)
			(xy 82.780546 -71.069673) (xy 82.75325 -71.021038) (xy 82.733327 -70.968947) (xy 82.721201 -70.91451)
			(xy 82.71713 -70.858888) (xy 80.302608 -70.858888) (xy 80.302608 -72.733408) (xy 85.04174 -72.733408)
			(xy 85.042244 -72.705478) (xy 85.050394 -72.650216) (xy 85.06652 -72.596735) (xy 85.090279 -72.546179)
			(xy 85.12116 -72.499632) (xy 85.158503 -72.458089) (xy 85.201508 -72.42244) (xy 85.225128 -72.407526)
			(xy 85.237063 -72.399768) (xy 85.256352 -72.378848) (xy 85.269126 -72.353421) (xy 85.274395 -72.325457)
			(xy 85.27175 -72.297125) (xy 85.261395 -72.27062) (xy 85.244135 -72.247996) (xy 85.233002 -72.239124)
			(xy 85.209626 -72.220988) (xy 85.16823 -72.178719) (xy 85.133855 -72.130567) (xy 85.107326 -72.077686)
			(xy 85.089278 -72.021343) (xy 85.080143 -71.962889) (xy 85.079586 -71.933308) (xy 85.080072 -71.906057)
			(xy 85.087828 -71.852109) (xy 85.103183 -71.799814) (xy 85.125825 -71.750237) (xy 85.155291 -71.704387)
			(xy 85.190982 -71.663196) (xy 85.232173 -71.627505) (xy 85.278023 -71.598039) (xy 85.3276 -71.575397)
			(xy 85.379895 -71.560042) (xy 85.433843 -71.552286) (xy 85.488345 -71.552286) (xy 85.542293 -71.560042)
			(xy 85.594588 -71.575397) (xy 85.644165 -71.598039) (xy 85.690015 -71.627505) (xy 85.731206 -71.663196)
			(xy 85.766897 -71.704387) (xy 85.796363 -71.750237) (xy 85.819005 -71.799814) (xy 85.83436 -71.852109)
			(xy 85.842116 -71.906057) (xy 85.842602 -71.933308) (xy 85.842091 -71.961237) (xy 85.833939 -72.016498)
			(xy 85.817813 -72.069978) (xy 85.794055 -72.120533) (xy 85.763176 -72.16708) (xy 85.725835 -72.208624)
			(xy 85.682832 -72.244275) (xy 85.659214 -72.25919) (xy 85.647268 -72.266927) (xy 85.627987 -72.287856)
			(xy 85.615221 -72.313287) (xy 85.609957 -72.341251) (xy 85.612604 -72.369583) (xy 85.622955 -72.396089)
			(xy 85.64021 -72.418716) (xy 85.65134 -72.427592) (xy 85.674733 -72.445708) (xy 85.716126 -72.487982)
			(xy 85.750497 -72.536139) (xy 85.777024 -72.589024) (xy 85.795069 -72.64537) (xy 85.8042 -72.703826)
			(xy 85.804756 -72.733408) (xy 85.80427 -72.760659) (xy 85.796514 -72.814607) (xy 85.781159 -72.866902)
			(xy 85.758517 -72.916479) (xy 85.729051 -72.962329) (xy 85.69336 -73.00352) (xy 85.652169 -73.039211)
			(xy 85.606319 -73.068677) (xy 85.556742 -73.091319) (xy 85.504447 -73.106674) (xy 85.450499 -73.11443)
			(xy 85.395997 -73.11443) (xy 85.342049 -73.106674) (xy 85.289754 -73.091319) (xy 85.240177 -73.068677)
			(xy 85.194327 -73.039211) (xy 85.153136 -73.00352) (xy 85.117445 -72.962329) (xy 85.087979 -72.916479)
			(xy 85.065337 -72.866902) (xy 85.049982 -72.814607) (xy 85.042226 -72.760659) (xy 85.04174 -72.733408)
			(xy 80.302608 -72.733408) (xy 80.302608 -73.632314) (xy 80.303049 -73.646308) (xy 80.310644 -73.673245)
			(xy 80.32526 -73.697112) (xy 80.345802 -73.71612) (xy 80.370729 -73.728845) (xy 80.398173 -73.734331)
			(xy 80.426077 -73.732168) (xy 80.452347 -73.722518) (xy 80.463898 -73.71461) (xy 80.488485 -73.697434)
			(xy 80.54192 -73.670204) (xy 80.598958 -73.651668) (xy 80.658193 -73.642282) (xy 80.68818 -73.641712)
			(xy 80.715433 -73.642174) (xy 80.769385 -73.649929) (xy 80.821684 -73.665283) (xy 80.871266 -73.687925)
			(xy 80.91712 -73.717393) (xy 80.958313 -73.753087) (xy 80.994007 -73.79428) (xy 81.023475 -73.840134)
			(xy 81.046117 -73.889716) (xy 81.061471 -73.942015) (xy 81.069226 -73.995967) (xy 81.069688 -74.02322)
			(xy 81.069226 -74.050129) (xy 81.061663 -74.103413) (xy 81.04669 -74.155106) (xy 81.024605 -74.204184)
			(xy 80.995845 -74.249672) (xy 80.96098 -74.29067) (xy 80.920701 -74.326364) (xy 80.875809 -74.356045)
			(xy 80.827192 -74.379127) (xy 80.775814 -74.39515) (xy 80.722696 -74.403797) (xy 80.6958 -74.404728)
			(xy 80.682151 -74.405439) (xy 80.655959 -74.413211) (xy 80.632771 -74.427658) (xy 80.614251 -74.447744)
			(xy 80.601728 -74.472026) (xy 80.596103 -74.498761) (xy 80.596486 -74.512424) (xy 80.597248 -74.5363)
			(xy 80.597054 -74.552961) (xy 80.594128 -74.586155) (xy 80.591406 -74.602594) (xy 80.589471 -74.616128)
			(xy 80.59205 -74.643336) (xy 80.601767 -74.668879) (xy 80.617923 -74.690922) (xy 80.639356 -74.707879)
			(xy 80.664524 -74.71853) (xy 80.67802 -74.720704) (xy 80.705147 -74.724825) (xy 80.75792 -74.739839)
			(xy 80.807997 -74.762261) (xy 80.854344 -74.791627) (xy 80.896005 -74.827332) (xy 80.932119 -74.868639)
			(xy 80.961941 -74.914694) (xy 80.984855 -74.964548) (xy 81.000389 -75.01717) (xy 81.008222 -75.071476)
			(xy 81.008728 -75.09891) (xy 81.008242 -75.126161) (xy 81.003577 -75.1586) (xy 85.902292 -75.1586)
			(xy 85.90276 -75.131026) (xy 85.910713 -75.076453) (xy 85.926438 -75.023593) (xy 85.949607 -74.973547)
			(xy 85.979739 -74.927358) (xy 86.016205 -74.885986) (xy 86.036912 -74.86777) (xy 86.047808 -74.857871)
			(xy 86.063878 -74.83322) (xy 86.07226 -74.805013) (xy 86.07226 -74.775587) (xy 86.063878 -74.74738)
			(xy 86.047808 -74.722729) (xy 86.036912 -74.71283) (xy 86.016215 -74.694604) (xy 85.979743 -74.653239)
			(xy 85.949608 -74.607052) (xy 85.92644 -74.557007) (xy 85.910721 -74.504147) (xy 85.902779 -74.449574)
			(xy 85.902292 -74.422) (xy 85.902778 -74.394749) (xy 85.910534 -74.340801) (xy 85.925889 -74.288506)
			(xy 85.948531 -74.238929) (xy 85.977997 -74.193079) (xy 86.013688 -74.151888) (xy 86.054879 -74.116197)
			(xy 86.100729 -74.086731) (xy 86.150306 -74.064089) (xy 86.202601 -74.048734) (xy 86.256549 -74.040978)
			(xy 86.311051 -74.040978) (xy 86.364999 -74.048734) (xy 86.417294 -74.064089) (xy 86.466871 -74.086731)
			(xy 86.512721 -74.116197) (xy 86.553912 -74.151888) (xy 86.589603 -74.193079) (xy 86.619069 -74.238929)
			(xy 86.641711 -74.288506) (xy 86.657066 -74.340801) (xy 86.664822 -74.394749) (xy 86.665308 -74.422)
			(xy 86.66484 -74.449574) (xy 86.656887 -74.504147) (xy 86.641162 -74.557007) (xy 86.617993 -74.607053)
			(xy 86.587861 -74.653242) (xy 86.551395 -74.694614) (xy 86.530688 -74.71283) (xy 86.519792 -74.722729)
			(xy 86.503722 -74.74738) (xy 86.49534 -74.775587) (xy 86.49534 -74.805013) (xy 86.503722 -74.83322)
			(xy 86.519792 -74.857871) (xy 86.530688 -74.86777) (xy 86.551385 -74.885996) (xy 86.587857 -74.927361)
			(xy 86.617992 -74.973548) (xy 86.64116 -75.023593) (xy 86.656879 -75.076453) (xy 86.664821 -75.131026)
			(xy 86.665308 -75.1586) (xy 86.664822 -75.185851) (xy 86.657066 -75.239799) (xy 86.641711 -75.292094)
			(xy 86.619069 -75.341671) (xy 86.589603 -75.387521) (xy 86.553912 -75.428712) (xy 86.512721 -75.464403)
			(xy 86.466871 -75.493869) (xy 86.417294 -75.516511) (xy 86.364999 -75.531866) (xy 86.311051 -75.539622)
			(xy 86.256549 -75.539622) (xy 86.202601 -75.531866) (xy 86.150306 -75.516511) (xy 86.100729 -75.493869)
			(xy 86.054879 -75.464403) (xy 86.013688 -75.428712) (xy 85.977997 -75.387521) (xy 85.948531 -75.341671)
			(xy 85.925889 -75.292094) (xy 85.910534 -75.239799) (xy 85.902778 -75.185851) (xy 85.902292 -75.1586)
			(xy 81.003577 -75.1586) (xy 81.000484 -75.180109) (xy 80.985128 -75.232404) (xy 80.962487 -75.281981)
			(xy 80.933021 -75.327832) (xy 80.897329 -75.369022) (xy 80.85614 -75.404715) (xy 80.81029 -75.434182)
			(xy 80.760713 -75.456825) (xy 80.708419 -75.472182) (xy 80.654471 -75.479941) (xy 80.62722 -75.480418)
			(xy 80.596706 -75.479795) (xy 80.536462 -75.47003) (xy 80.478543 -75.450794) (xy 80.451198 -75.437238)
			(xy 80.437723 -75.430796) (xy 80.408395 -75.425225) (xy 80.378709 -75.428371) (xy 80.351199 -75.439963)
			(xy 80.328215 -75.459013) (xy 80.311719 -75.483894) (xy 80.30312 -75.512481) (xy 80.302608 -75.527408)
			(xy 80.302608 -77.991208) (xy 80.14081 -78.153006) (xy 80.137254 -78.159864) (xy 80.123353 -78.185287)
			(xy 80.08905 -78.231981) (xy 80.048081 -78.27295) (xy 80.001387 -78.307253) (xy 79.975964 -78.321154)
			(xy 79.969106 -78.32471) (xy 79.900526 -78.39329) (xy 79.94269 -78.435708) (xy 79.950818 -78.439518)
			(xy 79.975133 -78.451389) (xy 80.020436 -78.480972) (xy 80.061107 -78.516658) (xy 80.096329 -78.557731)
			(xy 80.125396 -78.603367) (xy 80.147726 -78.652651) (xy 80.16287 -78.704596) (xy 80.170525 -78.758159)
			(xy 80.171036 -78.785212) (xy 80.170549 -78.812463) (xy 80.162792 -78.866411) (xy 80.147436 -78.918706)
			(xy 80.124794 -78.968284) (xy 80.095328 -79.014135) (xy 80.059637 -79.055326) (xy 80.018447 -79.091019)
			(xy 79.972598 -79.120487) (xy 79.923021 -79.14313) (xy 79.870727 -79.158488) (xy 79.816779 -79.166248)
			(xy 79.789528 -79.16672) (xy 79.789528 -79.9338) (xy 83.666582 -79.9338) (xy 83.670653 -79.878178)
			(xy 83.682779 -79.823741) (xy 83.702702 -79.77165) (xy 83.729998 -79.723015) (xy 83.764084 -79.678872)
			(xy 83.804233 -79.640163) (xy 83.849591 -79.607712) (xy 83.899191 -79.582211) (xy 83.951975 -79.564204)
			(xy 84.006818 -79.554074) (xy 84.062552 -79.552037) (xy 84.117989 -79.558137) (xy 84.171946 -79.572243)
			(xy 84.223275 -79.594055) (xy 84.270881 -79.623109) (xy 84.313749 -79.658784) (xy 84.350966 -79.700321)
			(xy 84.381739 -79.746834) (xy 84.405411 -79.797331) (xy 84.421479 -79.850738) (xy 84.429599 -79.905914)
			(xy 84.430108 -79.9338) (xy 84.429599 -79.961686) (xy 84.421479 -80.016862) (xy 84.405411 -80.070269)
			(xy 84.381739 -80.120766) (xy 84.350966 -80.167279) (xy 84.313749 -80.208816) (xy 84.270881 -80.244491)
			(xy 84.223275 -80.273545) (xy 84.171946 -80.295357) (xy 84.117989 -80.309463) (xy 84.062552 -80.315563)
			(xy 84.006818 -80.313526) (xy 83.951975 -80.303396) (xy 83.899191 -80.285389) (xy 83.849591 -80.259888)
			(xy 83.804233 -80.227437) (xy 83.764084 -80.188728) (xy 83.729998 -80.144585) (xy 83.702702 -80.09595)
			(xy 83.682779 -80.043859) (xy 83.670653 -79.989422) (xy 83.666582 -79.9338) (xy 79.789528 -79.9338)
			(xy 79.789528 -81.246472) (xy 79.248 -81.788) (xy 78.359 -81.788) (xy 78.123796 -82.023204) (xy 78.123796 -83.466432)
			(xy 82.17027 -83.466432) (xy 82.17076 -83.437692) (xy 82.179392 -83.380863) (xy 82.196451 -83.325973)
			(xy 82.221549 -83.274262) (xy 82.254121 -83.2269) (xy 82.273394 -83.205574) (xy 82.283432 -83.194014)
			(xy 82.296775 -83.166477) (xy 82.301364 -83.136224) (xy 82.296789 -83.105968) (xy 82.283459 -83.078425)
			(xy 82.273394 -83.06689) (xy 82.254148 -83.045541) (xy 82.221576 -82.998186) (xy 82.196478 -82.94648)
			(xy 82.179422 -82.891594) (xy 82.170794 -82.83477) (xy 82.17027 -82.806032) (xy 82.170738 -82.778662)
			(xy 82.178553 -82.724482) (xy 82.19404 -82.671978) (xy 82.216882 -82.622231) (xy 82.246608 -82.576265)
			(xy 82.26425 -82.555334) (xy 82.273452 -82.543982) (xy 82.285627 -82.517432) (xy 82.289804 -82.488524)
			(xy 82.285641 -82.459614) (xy 82.273478 -82.433059) (xy 82.26425 -82.42173) (xy 82.246619 -82.400791)
			(xy 82.216904 -82.354821) (xy 82.194066 -82.305075) (xy 82.178573 -82.252576) (xy 82.170744 -82.198401)
			(xy 82.17027 -82.171032) (xy 82.170785 -82.143781) (xy 82.178537 -82.089833) (xy 82.193888 -82.037537)
			(xy 82.216525 -81.987959) (xy 82.245988 -81.942107) (xy 82.281676 -81.900914) (xy 82.322863 -81.86522)
			(xy 82.368711 -81.835751) (xy 82.418287 -81.813107) (xy 82.47058 -81.797749) (xy 82.524527 -81.789989)
			(xy 82.551778 -81.789524) (xy 82.577177 -81.789941) (xy 82.627525 -81.796679) (xy 82.676534 -81.810041)
			(xy 82.723336 -81.829788) (xy 82.767103 -81.855572) (xy 82.807061 -81.886937) (xy 82.825082 -81.90484)
			(xy 82.834695 -81.91413) (xy 82.85771 -81.927718) (xy 82.883461 -81.934872) (xy 82.910186 -81.935104)
			(xy 82.936058 -81.928396) (xy 82.959304 -81.915208) (xy 82.9691 -81.90611) (xy 82.990647 -81.885673)
			(xy 83.038895 -81.851053) (xy 83.091926 -81.82433) (xy 83.148458 -81.806148) (xy 83.207124 -81.796947)
			(xy 83.236816 -81.796382) (xy 83.264067 -81.796863) (xy 83.318015 -81.804621) (xy 83.370309 -81.819978)
			(xy 83.419885 -81.84262) (xy 83.465735 -81.872087) (xy 83.506925 -81.907779) (xy 83.542616 -81.94897)
			(xy 83.572083 -81.99482) (xy 83.594724 -82.044397) (xy 83.61008 -82.096691) (xy 83.617838 -82.150639)
			(xy 83.618324 -82.17789) (xy 83.617871 -82.205261) (xy 83.610053 -82.259441) (xy 83.594562 -82.311945)
			(xy 83.571716 -82.361692) (xy 83.541988 -82.407658) (xy 83.524344 -82.428588) (xy 83.515121 -82.439924)
			(xy 83.50295 -82.46648) (xy 83.498778 -82.495392) (xy 83.502945 -82.524306) (xy 83.515113 -82.550863)
			(xy 83.524344 -82.562192) (xy 83.542 -82.58311) (xy 83.571708 -82.629088) (xy 83.59454 -82.678839)
			(xy 83.610027 -82.731342) (xy 83.617852 -82.78552) (xy 83.618324 -82.81289) (xy 83.617788 -82.841628)
			(xy 83.609167 -82.898455) (xy 83.59212 -82.953345) (xy 83.567031 -83.005057) (xy 83.534469 -83.05242)
			(xy 83.5152 -83.073748) (xy 83.505141 -83.085291) (xy 83.491801 -83.112834) (xy 83.487216 -83.143093)
			(xy 83.491797 -83.173352) (xy 83.505132 -83.200897) (xy 83.5152 -83.212432) (xy 83.534455 -83.233773)
			(xy 83.567026 -83.28113) (xy 83.592122 -83.332838) (xy 83.609176 -83.387726) (xy 83.617802 -83.444552)
			(xy 83.618324 -83.47329) (xy 83.617812 -83.50054) (xy 83.610058 -83.554486) (xy 83.594705 -83.606779)
			(xy 83.572066 -83.656355) (xy 83.542602 -83.702205) (xy 83.506913 -83.743395) (xy 83.465726 -83.779087)
			(xy 83.419878 -83.808553) (xy 83.370304 -83.831196) (xy 83.318012 -83.846552) (xy 83.264066 -83.854311)
			(xy 83.236816 -83.854798) (xy 83.211417 -83.854379) (xy 83.161069 -83.847639) (xy 83.112061 -83.834278)
			(xy 83.065259 -83.814531) (xy 83.021492 -83.788748) (xy 82.981533 -83.757385) (xy 82.963512 -83.739482)
			(xy 82.953905 -83.730185) (xy 82.930889 -83.716594) (xy 82.905136 -83.709439) (xy 82.878408 -83.709209)
			(xy 82.852536 -83.715919) (xy 82.829289 -83.729111) (xy 82.819494 -83.738212) (xy 82.797954 -83.758656)
			(xy 82.749703 -83.793273) (xy 82.696671 -83.819995) (xy 82.640138 -83.838176) (xy 82.58147 -83.847376)
			(xy 82.551778 -83.84794) (xy 82.524528 -83.847443) (xy 82.470582 -83.839684) (xy 82.418289 -83.824328)
			(xy 82.368714 -83.801686) (xy 82.322866 -83.772221) (xy 82.281676 -83.736531) (xy 82.245985 -83.695342)
			(xy 82.216518 -83.649495) (xy 82.193876 -83.59992) (xy 82.178518 -83.547628) (xy 82.170758 -83.493682)
			(xy 82.17027 -83.466432) (xy 78.123796 -83.466432) (xy 78.123796 -86.124796) (xy 78.5368 -86.5378)
			(xy 78.942182 -86.5378) (xy 78.946253 -86.482178) (xy 78.958379 -86.427741) (xy 78.978302 -86.37565)
			(xy 79.005598 -86.327015) (xy 79.039684 -86.282872) (xy 79.079833 -86.244163) (xy 79.125191 -86.211712)
			(xy 79.174791 -86.186211) (xy 79.227575 -86.168204) (xy 79.282418 -86.158074) (xy 79.338152 -86.156037)
			(xy 79.393589 -86.162137) (xy 79.447546 -86.176243) (xy 79.498875 -86.198055) (xy 79.546481 -86.227109)
			(xy 79.589349 -86.262784) (xy 79.626566 -86.304321) (xy 79.657339 -86.350834) (xy 79.681011 -86.401331)
			(xy 79.697079 -86.454738) (xy 79.705199 -86.509914) (xy 79.705708 -86.5378) (xy 79.705199 -86.565686)
			(xy 79.697079 -86.620862) (xy 79.681011 -86.674269) (xy 79.657339 -86.724766) (xy 79.626566 -86.771279)
			(xy 79.589349 -86.812816) (xy 79.546481 -86.848491) (xy 79.498875 -86.877545) (xy 79.447546 -86.899357)
			(xy 79.393589 -86.913463) (xy 79.338152 -86.919563) (xy 79.282418 -86.917526) (xy 79.227575 -86.907396)
			(xy 79.174791 -86.889389) (xy 79.125191 -86.863888) (xy 79.079833 -86.831437) (xy 79.039684 -86.792728)
			(xy 79.005598 -86.748585) (xy 78.978302 -86.69995) (xy 78.958379 -86.647859) (xy 78.946253 -86.593422)
			(xy 78.942182 -86.5378) (xy 78.5368 -86.5378) (xy 78.54188 -86.54288) (xy 78.54188 -87.437468) (xy 78.559288 -87.461098)
			(xy 78.586976 -87.512844) (xy 78.605864 -87.56841) (xy 78.615448 -87.62631) (xy 78.616048 -87.655654)
			(xy 78.616048 -88.519) (xy 78.615439 -88.548342) (xy 78.605842 -88.606237) (xy 78.586952 -88.661799)
			(xy 78.559274 -88.713547) (xy 78.54188 -88.737186) (xy 78.54188 -90.65006) (xy 82.177634 -90.65006)
			(xy 82.181705 -90.594438) (xy 82.193831 -90.540001) (xy 82.213754 -90.48791) (xy 82.24105 -90.439275)
			(xy 82.275136 -90.395132) (xy 82.315285 -90.356423) (xy 82.360643 -90.323972) (xy 82.410243 -90.298471)
			(xy 82.463027 -90.280464) (xy 82.51787 -90.270334) (xy 82.573604 -90.268297) (xy 82.629041 -90.274397)
			(xy 82.682998 -90.288503) (xy 82.734327 -90.310315) (xy 82.781933 -90.339369) (xy 82.824801 -90.375044)
			(xy 82.862018 -90.416581) (xy 82.869615 -90.428064) (xy 83.418932 -90.428064) (xy 83.423003 -90.372442)
			(xy 83.435129 -90.318005) (xy 83.455052 -90.265914) (xy 83.482348 -90.217279) (xy 83.516434 -90.173136)
			(xy 83.556583 -90.134427) (xy 83.601941 -90.101976) (xy 83.651541 -90.076475) (xy 83.704325 -90.058468)
			(xy 83.759168 -90.048338) (xy 83.814902 -90.046301) (xy 83.870339 -90.052401) (xy 83.924296 -90.066507)
			(xy 83.975625 -90.088319) (xy 84.023231 -90.117373) (xy 84.066099 -90.153048) (xy 84.103316 -90.194585)
			(xy 84.134089 -90.241098) (xy 84.157761 -90.291595) (xy 84.173829 -90.345002) (xy 84.181949 -90.400178)
			(xy 84.182458 -90.428064) (xy 84.181949 -90.45595) (xy 84.173829 -90.511126) (xy 84.157761 -90.564533)
			(xy 84.134089 -90.61503) (xy 84.103316 -90.661543) (xy 84.066099 -90.70308) (xy 84.023231 -90.738755)
			(xy 83.975625 -90.767809) (xy 83.924296 -90.789621) (xy 83.870339 -90.803727) (xy 83.814902 -90.809827)
			(xy 83.759168 -90.80779) (xy 83.704325 -90.79766) (xy 83.651541 -90.779653) (xy 83.601941 -90.754152)
			(xy 83.556583 -90.721701) (xy 83.516434 -90.682992) (xy 83.482348 -90.638849) (xy 83.455052 -90.590214)
			(xy 83.435129 -90.538123) (xy 83.423003 -90.483686) (xy 83.418932 -90.428064) (xy 82.869615 -90.428064)
			(xy 82.892791 -90.463094) (xy 82.916463 -90.513591) (xy 82.932531 -90.566998) (xy 82.940651 -90.622174)
			(xy 82.94116 -90.65006) (xy 82.940651 -90.677946) (xy 82.932531 -90.733122) (xy 82.916463 -90.786529)
			(xy 82.892791 -90.837026) (xy 82.862018 -90.883539) (xy 82.824801 -90.925076) (xy 82.781933 -90.960751)
			(xy 82.734327 -90.989805) (xy 82.682998 -91.011617) (xy 82.629041 -91.025723) (xy 82.573604 -91.031823)
			(xy 82.51787 -91.029786) (xy 82.463027 -91.019656) (xy 82.410243 -91.001649) (xy 82.360643 -90.976148)
			(xy 82.315285 -90.943697) (xy 82.275136 -90.904988) (xy 82.24105 -90.860845) (xy 82.213754 -90.81221)
			(xy 82.193831 -90.760119) (xy 82.181705 -90.705682) (xy 82.177634 -90.65006) (xy 78.54188 -90.65006)
			(xy 78.54188 -91.06662) (xy 78.998572 -91.523312) (xy 78.998572 -92.619068) (xy 78.998973 -92.632451)
			(xy 79.005935 -92.658296) (xy 79.019385 -92.681437) (xy 79.038397 -92.700277) (xy 79.061659 -92.713517)
			(xy 79.087565 -92.720244) (xy 79.11433 -92.719992) (xy 79.12735 -92.716858) (xy 79.152256 -92.710431)
			(xy 79.203231 -92.703548) (xy 79.22895 -92.703142) (xy 79.25576 -92.703601) (xy 79.308849 -92.711121)
			(xy 79.360361 -92.726005) (xy 79.40928 -92.747959) (xy 79.45464 -92.776551) (xy 79.495546 -92.811217)
			(xy 79.531192 -92.851272) (xy 79.54645 -92.873322) (xy 79.554721 -92.884869) (xy 79.576369 -92.903239)
			(xy 79.602232 -92.914952) (xy 79.630318 -92.919106) (xy 79.658465 -92.915382) (xy 79.684504 -92.904065)
			(xy 79.70643 -92.886028) (xy 79.714852 -92.874592) (xy 79.730184 -92.853121) (xy 79.765816 -92.814213)
			(xy 79.806469 -92.780586) (xy 79.851369 -92.752881) (xy 79.899657 -92.731629) (xy 79.950414 -92.717233)
			(xy 80.002671 -92.70997) (xy 80.02905 -92.709492) (xy 80.056305 -92.709952) (xy 80.110262 -92.717703)
			(xy 80.162565 -92.733055) (xy 80.212152 -92.755694) (xy 80.258011 -92.785161) (xy 80.29921 -92.820855)
			(xy 80.334909 -92.862049) (xy 80.342155 -92.873322) (xy 82.396582 -92.873322) (xy 82.400653 -92.8177)
			(xy 82.412779 -92.763263) (xy 82.432702 -92.711172) (xy 82.459998 -92.662537) (xy 82.494084 -92.618394)
			(xy 82.534233 -92.579685) (xy 82.579591 -92.547234) (xy 82.629191 -92.521733) (xy 82.681975 -92.503726)
			(xy 82.736818 -92.493596) (xy 82.792552 -92.491559) (xy 82.847989 -92.497659) (xy 82.901946 -92.511765)
			(xy 82.953275 -92.533577) (xy 83.000881 -92.562631) (xy 83.043749 -92.598306) (xy 83.080966 -92.639843)
			(xy 83.111739 -92.686356) (xy 83.135411 -92.736853) (xy 83.151479 -92.79026) (xy 83.159599 -92.845436)
			(xy 83.160108 -92.873322) (xy 83.159599 -92.901208) (xy 83.151479 -92.956384) (xy 83.135411 -93.009791)
			(xy 83.111739 -93.060288) (xy 83.080966 -93.106801) (xy 83.043749 -93.148338) (xy 83.000881 -93.184013)
			(xy 82.953275 -93.213067) (xy 82.901946 -93.234879) (xy 82.847989 -93.248985) (xy 82.792552 -93.255085)
			(xy 82.736818 -93.253048) (xy 82.681975 -93.242918) (xy 82.629191 -93.224911) (xy 82.579591 -93.19941)
			(xy 82.534233 -93.166959) (xy 82.494084 -93.12825) (xy 82.459998 -93.084107) (xy 82.432702 -93.035472)
			(xy 82.412779 -92.983381) (xy 82.400653 -92.928944) (xy 82.396582 -92.873322) (xy 80.342155 -92.873322)
			(xy 80.364382 -92.907904) (xy 80.387028 -92.957488) (xy 80.402386 -93.00979) (xy 80.410145 -93.063745)
			(xy 80.410145 -93.118255) (xy 80.402386 -93.17221) (xy 80.387028 -93.224512) (xy 80.364382 -93.274096)
			(xy 80.334909 -93.319951) (xy 80.29921 -93.361145) (xy 80.258011 -93.396839) (xy 80.212152 -93.426306)
			(xy 80.162565 -93.448945) (xy 80.110262 -93.464297) (xy 80.056305 -93.472048) (xy 80.02905 -93.472508)
			(xy 80.00224 -93.472049) (xy 79.949149 -93.46453) (xy 79.897636 -93.449647) (xy 79.848715 -93.427695)
			(xy 79.803352 -93.399105) (xy 79.762442 -93.364442) (xy 79.726792 -93.324389) (xy 79.71155 -93.302328)
			(xy 79.703282 -93.290776) (xy 79.681636 -93.272398) (xy 79.655772 -93.260678) (xy 79.627682 -93.256522)
			(xy 79.599531 -93.260249) (xy 79.573491 -93.271571) (xy 79.551567 -93.289617) (xy 79.543148 -93.301058)
			(xy 79.527817 -93.322531) (xy 79.492188 -93.361444) (xy 79.451536 -93.395076) (xy 79.406636 -93.422784)
			(xy 79.358347 -93.444039) (xy 79.307588 -93.458436) (xy 79.25533 -93.465701) (xy 79.22895 -93.466158)
			(xy 79.203231 -93.465752) (xy 79.152258 -93.458864) (xy 79.12735 -93.452442) (xy 79.114348 -93.449256)
			(xy 79.087588 -93.449053) (xy 79.061693 -93.455809) (xy 79.038443 -93.469059) (xy 79.019433 -93.487894)
			(xy 79.005968 -93.511021) (xy 78.998974 -93.536852) (xy 78.998572 -93.550232) (xy 78.998572 -94.152974)
			(xy 82.472782 -94.152974) (xy 82.476853 -94.097352) (xy 82.488979 -94.042915) (xy 82.508902 -93.990824)
			(xy 82.536198 -93.942189) (xy 82.570284 -93.898046) (xy 82.610433 -93.859337) (xy 82.655791 -93.826886)
			(xy 82.705391 -93.801385) (xy 82.758175 -93.783378) (xy 82.813018 -93.773248) (xy 82.868752 -93.771211)
			(xy 82.924189 -93.777311) (xy 82.978146 -93.791417) (xy 83.029475 -93.813229) (xy 83.077081 -93.842283)
			(xy 83.119949 -93.877958) (xy 83.157166 -93.919495) (xy 83.187939 -93.966008) (xy 83.211611 -94.016505)
			(xy 83.227679 -94.069912) (xy 83.235799 -94.125088) (xy 83.236308 -94.152974) (xy 83.235799 -94.18086)
			(xy 83.227679 -94.236036) (xy 83.211611 -94.289443) (xy 83.187939 -94.33994) (xy 83.157166 -94.386453)
			(xy 83.119949 -94.42799) (xy 83.077081 -94.463665) (xy 83.029475 -94.492719) (xy 82.978146 -94.514531)
			(xy 82.924189 -94.528637) (xy 82.868752 -94.534737) (xy 82.813018 -94.5327) (xy 82.758175 -94.52257)
			(xy 82.705391 -94.504563) (xy 82.655791 -94.479062) (xy 82.610433 -94.446611) (xy 82.570284 -94.407902)
			(xy 82.536198 -94.363759) (xy 82.508902 -94.315124) (xy 82.488979 -94.263033) (xy 82.476853 -94.208596)
			(xy 82.472782 -94.152974) (xy 78.998572 -94.152974) (xy 78.998572 -94.96679) (xy 79.150718 -95.118936)
		)
		(stroke
			(width 0)
			(type solid)
		)
		(fill yes)
		(layer "In4.Cu")
		(net "P5V_AUX")
	)
	(gr_poly
		(pts
			(xy 78.517496 -64.19342) (xy 78.517496 -64.124586) (xy 78.961234 -63.680848) (xy 79.030068 -63.680848)
			(xy 79.0702 -63.64097) (xy 82.284316 -63.64097) (xy 83.38566 -62.539626) (xy 83.38566 -44.82719)
			(xy 82.671666 -44.113196) (xy 82.660777 -44.103029) (xy 82.634551 -44.088928) (xy 82.605373 -44.082989)
			(xy 82.575721 -44.085715) (xy 82.548115 -44.096875) (xy 82.5249 -44.115521) (xy 82.508047 -44.140069)
			(xy 82.50301 -44.15409) (xy 82.494443 -44.17944) (xy 82.471203 -44.22764) (xy 82.441453 -44.272118)
			(xy 82.405778 -44.312001) (xy 82.364879 -44.346506) (xy 82.319558 -44.374954) (xy 82.270705 -44.396788)
			(xy 82.219279 -44.411579) (xy 82.166291 -44.419036) (xy 82.139536 -44.41952) (xy 82.112281 -44.41906)
			(xy 82.058326 -44.411307) (xy 82.006023 -44.395954) (xy 81.956437 -44.373314) (xy 81.910579 -44.343847)
			(xy 81.869381 -44.308153) (xy 81.833682 -44.26696) (xy 81.804209 -44.221105) (xy 81.781563 -44.171522)
			(xy 81.766203 -44.119221) (xy 81.758444 -44.065267) (xy 81.758028 -44.038012) (xy 81.758282 -44.027852)
			(xy 81.758198 -44.014307) (xy 81.751738 -43.988011) (xy 81.738592 -43.964338) (xy 81.719685 -43.944954)
			(xy 81.696348 -43.931222) (xy 81.670221 -43.924108) (xy 81.656682 -43.923712) (xy 80.319626 -43.923712)
			(xy 80.305109 -43.924223) (xy 80.277248 -43.932387) (xy 80.25281 -43.948062) (xy 80.233772 -43.969982)
			(xy 80.221672 -43.996374) (xy 80.21749 -44.025104) (xy 80.221562 -44.05385) (xy 80.23356 -44.080288)
			(xy 80.242664 -44.091606) (xy 80.257732 -44.109696) (xy 80.283127 -44.149338) (xy 80.302638 -44.192183)
			(xy 80.315868 -44.237365) (xy 80.322551 -44.283967) (xy 80.322928 -44.307506) (xy 80.322418 -44.333493)
			(xy 80.314288 -44.384828) (xy 80.298227 -44.434258) (xy 80.274631 -44.480568) (xy 80.244081 -44.522616)
			(xy 80.20733 -44.559367) (xy 80.165282 -44.589917) (xy 80.118972 -44.613513) (xy 80.069542 -44.629574)
			(xy 80.018207 -44.637704) (xy 79.966233 -44.637704) (xy 79.914898 -44.629574) (xy 79.865468 -44.613513)
			(xy 79.819158 -44.589917) (xy 79.77711 -44.559367) (xy 79.740359 -44.522616) (xy 79.709809 -44.480568)
			(xy 79.686213 -44.434258) (xy 79.670152 -44.384828) (xy 79.662022 -44.333493) (xy 79.661512 -44.307506)
			(xy 79.661928 -44.283968) (xy 79.668605 -44.237368) (xy 79.681825 -44.192186) (xy 79.701322 -44.149337)
			(xy 79.7267 -44.109686) (xy 79.741776 -44.091606) (xy 79.750859 -44.080274) (xy 79.76285 -44.053839)
			(xy 79.766919 -44.025099) (xy 79.762736 -43.996374) (xy 79.750641 -43.969987) (xy 79.73161 -43.948069)
			(xy 79.707181 -43.932391) (xy 79.679328 -43.92422) (xy 79.664814 -43.923712) (xy 78.604364 -43.923712)
			(xy 78.598522 -43.967908) (xy 78.594854 -43.992764) (xy 78.580981 -44.041051) (xy 78.559962 -44.086684)
			(xy 78.53228 -44.128611) (xy 78.498573 -44.165867) (xy 78.459617 -44.197595) (xy 78.41631 -44.223063)
			(xy 78.369647 -44.241685) (xy 78.320704 -44.253032) (xy 78.270608 -44.256844) (xy 78.220512 -44.253032)
			(xy 78.171569 -44.241685) (xy 78.124906 -44.223063) (xy 78.081599 -44.197595) (xy 78.042643 -44.165867)
			(xy 78.008936 -44.128611) (xy 77.981254 -44.086684) (xy 77.960235 -44.041051) (xy 77.946362 -43.992764)
			(xy 77.942694 -43.967908) (xy 77.936852 -43.923712) (xy 77.804264 -43.923712) (xy 77.798422 -43.967908)
			(xy 77.794754 -43.992764) (xy 77.780881 -44.041051) (xy 77.759862 -44.086684) (xy 77.73218 -44.128611)
			(xy 77.698473 -44.165867) (xy 77.659517 -44.197595) (xy 77.61621 -44.223063) (xy 77.569547 -44.241685)
			(xy 77.520604 -44.253032) (xy 77.470508 -44.256844) (xy 77.420412 -44.253032) (xy 77.371469 -44.241685)
			(xy 77.324806 -44.223063) (xy 77.281499 -44.197595) (xy 77.242543 -44.165867) (xy 77.208836 -44.128611)
			(xy 77.181154 -44.086684) (xy 77.160135 -44.041051) (xy 77.146262 -43.992764) (xy 77.142594 -43.967908)
			(xy 77.136752 -43.923712) (xy 75.367896 -43.923712) (xy 75.362054 -43.967908) (xy 75.358386 -43.992764)
			(xy 75.344513 -44.041051) (xy 75.323494 -44.086684) (xy 75.295812 -44.128611) (xy 75.262105 -44.165867)
			(xy 75.223149 -44.197595) (xy 75.179842 -44.223063) (xy 75.133179 -44.241685) (xy 75.084236 -44.253032)
			(xy 75.03414 -44.256844) (xy 74.984044 -44.253032) (xy 74.935101 -44.241685) (xy 74.888438 -44.223063)
			(xy 74.845131 -44.197595) (xy 74.806175 -44.165867) (xy 74.772468 -44.128611) (xy 74.744786 -44.086684)
			(xy 74.723767 -44.041051) (xy 74.709894 -43.992764) (xy 74.706226 -43.967908) (xy 74.700384 -43.923712)
			(xy 74.599292 -43.923712) (xy 74.59345 -43.967908) (xy 74.589782 -43.992764) (xy 74.575909 -44.041051)
			(xy 74.55489 -44.086684) (xy 74.527208 -44.128611) (xy 74.493501 -44.165867) (xy 74.454545 -44.197595)
			(xy 74.411238 -44.223063) (xy 74.364575 -44.241685) (xy 74.315632 -44.253032) (xy 74.265536 -44.256844)
			(xy 74.21544 -44.253032) (xy 74.166497 -44.241685) (xy 74.119834 -44.223063) (xy 74.076527 -44.197595)
			(xy 74.037571 -44.165867) (xy 74.003864 -44.128611) (xy 73.976182 -44.086684) (xy 73.955163 -44.041051)
			(xy 73.94129 -43.992764) (xy 73.937622 -43.967908) (xy 73.93178 -43.923712) (xy 73.801986 -43.923712)
			(xy 73.792842 -43.963082) (xy 73.786503 -43.988494) (xy 73.766897 -44.037058) (xy 73.739882 -44.081925)
			(xy 73.706132 -44.121973) (xy 73.666493 -44.156201) (xy 73.621953 -44.183753) (xy 73.573628 -44.20394)
			(xy 73.522724 -44.216258) (xy 73.470516 -44.220398) (xy 73.418308 -44.216258) (xy 73.367404 -44.20394)
			(xy 73.319079 -44.183753) (xy 73.274539 -44.156201) (xy 73.2349 -44.121973) (xy 73.20115 -44.081925)
			(xy 73.174135 -44.037058) (xy 73.154529 -43.988494) (xy 73.14819 -43.963082) (xy 73.139046 -43.923712)
			(xy 73.004426 -43.923712) (xy 72.998584 -43.967908) (xy 72.994672 -43.994139) (xy 72.979585 -44.04498)
			(xy 72.95658 -44.092763) (xy 72.926246 -44.136264) (xy 72.889361 -44.174367) (xy 72.846869 -44.206098)
			(xy 72.799859 -44.230644) (xy 72.749535 -44.247375) (xy 72.697186 -44.255862) (xy 72.67067 -44.256452)
			(xy 72.646644 -44.256026) (xy 72.599097 -44.249076) (xy 72.553057 -44.235313) (xy 72.509497 -44.215027)
			(xy 72.469334 -44.188646) (xy 72.433415 -44.156726) (xy 72.402499 -44.11994) (xy 72.389492 -44.099734)
			(xy 72.381003 -44.087005) (xy 72.357939 -44.066922) (xy 72.329972 -44.054547) (xy 72.299598 -44.050987)
			(xy 72.269527 -44.056557) (xy 72.242443 -44.070762) (xy 72.23125 -44.081192) (xy 71.733664 -44.578778)
			(xy 71.733664 -44.751577) (xy 73.140318 -44.751577) (xy 73.140318 -44.699603) (xy 73.148448 -44.648268)
			(xy 73.164509 -44.598838) (xy 73.188105 -44.552528) (xy 73.218655 -44.51048) (xy 73.255406 -44.473729)
			(xy 73.297454 -44.443179) (xy 73.343764 -44.419583) (xy 73.393194 -44.403522) (xy 73.444529 -44.395392)
			(xy 73.496503 -44.395392) (xy 73.547838 -44.403522) (xy 73.597268 -44.419583) (xy 73.643578 -44.443179)
			(xy 73.685626 -44.473729) (xy 73.722377 -44.51048) (xy 73.752927 -44.552528) (xy 73.776523 -44.598838)
			(xy 73.792584 -44.648268) (xy 73.800714 -44.699603) (xy 73.801224 -44.72559) (xy 73.800714 -44.751577)
			(xy 73.940418 -44.751577) (xy 73.940418 -44.699603) (xy 73.948548 -44.648268) (xy 73.964609 -44.598838)
			(xy 73.988205 -44.552528) (xy 74.018755 -44.51048) (xy 74.055506 -44.473729) (xy 74.097554 -44.443179)
			(xy 74.143864 -44.419583) (xy 74.193294 -44.403522) (xy 74.244629 -44.395392) (xy 74.296603 -44.395392)
			(xy 74.347938 -44.403522) (xy 74.397368 -44.419583) (xy 74.443678 -44.443179) (xy 74.485726 -44.473729)
			(xy 74.522477 -44.51048) (xy 74.553027 -44.552528) (xy 74.576623 -44.598838) (xy 74.592684 -44.648268)
			(xy 74.600814 -44.699603) (xy 74.601324 -44.72559) (xy 74.600814 -44.751577) (xy 77.14031 -44.751577)
			(xy 77.14031 -44.699603) (xy 77.14844 -44.648268) (xy 77.164501 -44.598838) (xy 77.188097 -44.552528)
			(xy 77.218647 -44.51048) (xy 77.255398 -44.473729) (xy 77.297446 -44.443179) (xy 77.343756 -44.419583)
			(xy 77.393186 -44.403522) (xy 77.444521 -44.395392) (xy 77.496495 -44.395392) (xy 77.54783 -44.403522)
			(xy 77.59726 -44.419583) (xy 77.64357 -44.443179) (xy 77.685618 -44.473729) (xy 77.722369 -44.51048)
			(xy 77.752919 -44.552528) (xy 77.776515 -44.598838) (xy 77.792576 -44.648268) (xy 77.800706 -44.699603)
			(xy 77.801216 -44.72559) (xy 77.800706 -44.751577) (xy 77.94041 -44.751577) (xy 77.94041 -44.699603)
			(xy 77.94854 -44.648268) (xy 77.964601 -44.598838) (xy 77.988197 -44.552528) (xy 78.018747 -44.51048)
			(xy 78.055498 -44.473729) (xy 78.097546 -44.443179) (xy 78.143856 -44.419583) (xy 78.193286 -44.403522)
			(xy 78.244621 -44.395392) (xy 78.296595 -44.395392) (xy 78.34793 -44.403522) (xy 78.39736 -44.419583)
			(xy 78.44367 -44.443179) (xy 78.485718 -44.473729) (xy 78.522469 -44.51048) (xy 78.553019 -44.552528)
			(xy 78.576615 -44.598838) (xy 78.592676 -44.648268) (xy 78.600806 -44.699603) (xy 78.601316 -44.72559)
			(xy 78.600806 -44.751577) (xy 78.592676 -44.802912) (xy 78.576615 -44.852342) (xy 78.553019 -44.898652)
			(xy 78.522469 -44.9407) (xy 78.485718 -44.977451) (xy 78.44367 -45.008001) (xy 78.39736 -45.031597)
			(xy 78.34793 -45.047658) (xy 78.296595 -45.055788) (xy 78.244621 -45.055788) (xy 78.193286 -45.047658)
			(xy 78.143856 -45.031597) (xy 78.097546 -45.008001) (xy 78.055498 -44.977451) (xy 78.018747 -44.9407)
			(xy 77.988197 -44.898652) (xy 77.964601 -44.852342) (xy 77.94854 -44.802912) (xy 77.94041 -44.751577)
			(xy 77.800706 -44.751577) (xy 77.792576 -44.802912) (xy 77.776515 -44.852342) (xy 77.752919 -44.898652)
			(xy 77.722369 -44.9407) (xy 77.685618 -44.977451) (xy 77.64357 -45.008001) (xy 77.59726 -45.031597)
			(xy 77.54783 -45.047658) (xy 77.496495 -45.055788) (xy 77.444521 -45.055788) (xy 77.393186 -45.047658)
			(xy 77.343756 -45.031597) (xy 77.297446 -45.008001) (xy 77.255398 -44.977451) (xy 77.218647 -44.9407)
			(xy 77.188097 -44.898652) (xy 77.164501 -44.852342) (xy 77.14844 -44.802912) (xy 77.14031 -44.751577)
			(xy 74.600814 -44.751577) (xy 74.592684 -44.802912) (xy 74.576623 -44.852342) (xy 74.553027 -44.898652)
			(xy 74.522477 -44.9407) (xy 74.485726 -44.977451) (xy 74.443678 -45.008001) (xy 74.397368 -45.031597)
			(xy 74.347938 -45.047658) (xy 74.296603 -45.055788) (xy 74.244629 -45.055788) (xy 74.193294 -45.047658)
			(xy 74.143864 -45.031597) (xy 74.097554 -45.008001) (xy 74.055506 -44.977451) (xy 74.018755 -44.9407)
			(xy 73.988205 -44.898652) (xy 73.964609 -44.852342) (xy 73.948548 -44.802912) (xy 73.940418 -44.751577)
			(xy 73.800714 -44.751577) (xy 73.792584 -44.802912) (xy 73.776523 -44.852342) (xy 73.752927 -44.898652)
			(xy 73.722377 -44.9407) (xy 73.685626 -44.977451) (xy 73.643578 -45.008001) (xy 73.597268 -45.031597)
			(xy 73.547838 -45.047658) (xy 73.496503 -45.055788) (xy 73.444529 -45.055788) (xy 73.393194 -45.047658)
			(xy 73.343764 -45.031597) (xy 73.297454 -45.008001) (xy 73.255406 -44.977451) (xy 73.218655 -44.9407)
			(xy 73.188105 -44.898652) (xy 73.164509 -44.852342) (xy 73.148448 -44.802912) (xy 73.140318 -44.751577)
			(xy 71.733664 -44.751577) (xy 71.733664 -45.133339) (xy 79.662022 -45.133339) (xy 79.662022 -45.081365)
			(xy 79.670152 -45.03003) (xy 79.686213 -44.9806) (xy 79.709809 -44.93429) (xy 79.740359 -44.892242)
			(xy 79.77711 -44.855491) (xy 79.819158 -44.824941) (xy 79.865468 -44.801345) (xy 79.914898 -44.785284)
			(xy 79.966233 -44.777154) (xy 80.018207 -44.777154) (xy 80.069542 -44.785284) (xy 80.118972 -44.801345)
			(xy 80.165282 -44.824941) (xy 80.20733 -44.855491) (xy 80.244081 -44.892242) (xy 80.274631 -44.93429)
			(xy 80.298227 -44.9806) (xy 80.314288 -45.03003) (xy 80.318086 -45.054012) (xy 81.757518 -45.054012)
			(xy 81.761589 -44.99839) (xy 81.773715 -44.943953) (xy 81.793638 -44.891862) (xy 81.820934 -44.843227)
			(xy 81.85502 -44.799084) (xy 81.895169 -44.760375) (xy 81.940527 -44.727924) (xy 81.990127 -44.702423)
			(xy 82.042911 -44.684416) (xy 82.097754 -44.674286) (xy 82.153488 -44.672249) (xy 82.208925 -44.678349)
			(xy 82.262882 -44.692455) (xy 82.314211 -44.714267) (xy 82.361817 -44.743321) (xy 82.404685 -44.778996)
			(xy 82.441902 -44.820533) (xy 82.472675 -44.867046) (xy 82.496347 -44.917543) (xy 82.512415 -44.97095)
			(xy 82.520535 -45.026126) (xy 82.521044 -45.054012) (xy 82.520535 -45.081898) (xy 82.512415 -45.137074)
			(xy 82.496347 -45.190481) (xy 82.472675 -45.240978) (xy 82.441902 -45.287491) (xy 82.404685 -45.329028)
			(xy 82.361817 -45.364703) (xy 82.314211 -45.393757) (xy 82.262882 -45.415569) (xy 82.208925 -45.429675)
			(xy 82.153488 -45.435775) (xy 82.097754 -45.433738) (xy 82.042911 -45.423608) (xy 81.990127 -45.405601)
			(xy 81.940527 -45.3801) (xy 81.895169 -45.347649) (xy 81.85502 -45.30894) (xy 81.820934 -45.264797)
			(xy 81.793638 -45.216162) (xy 81.773715 -45.164071) (xy 81.761589 -45.109634) (xy 81.757518 -45.054012)
			(xy 80.318086 -45.054012) (xy 80.322418 -45.081365) (xy 80.322928 -45.107352) (xy 80.322418 -45.133339)
			(xy 80.314288 -45.184674) (xy 80.298227 -45.234104) (xy 80.274631 -45.280414) (xy 80.244081 -45.322462)
			(xy 80.20733 -45.359213) (xy 80.165282 -45.389763) (xy 80.118972 -45.413359) (xy 80.069542 -45.42942)
			(xy 80.018207 -45.43755) (xy 79.966233 -45.43755) (xy 79.914898 -45.42942) (xy 79.865468 -45.413359)
			(xy 79.819158 -45.389763) (xy 79.77711 -45.359213) (xy 79.740359 -45.322462) (xy 79.709809 -45.280414)
			(xy 79.686213 -45.234104) (xy 79.670152 -45.184674) (xy 79.662022 -45.133339) (xy 71.733664 -45.133339)
			(xy 71.733664 -45.551677) (xy 73.103996 -45.551677) (xy 73.103996 -45.499703) (xy 73.112126 -45.448368)
			(xy 73.128187 -45.398938) (xy 73.151783 -45.352628) (xy 73.182333 -45.31058) (xy 73.219084 -45.273829)
			(xy 73.261132 -45.243279) (xy 73.307442 -45.219683) (xy 73.356872 -45.203622) (xy 73.408207 -45.195492)
			(xy 73.460181 -45.195492) (xy 73.511516 -45.203622) (xy 73.560946 -45.219683) (xy 73.607256 -45.243279)
			(xy 73.649304 -45.273829) (xy 73.686055 -45.31058) (xy 73.716605 -45.352628) (xy 73.740201 -45.398938)
			(xy 73.756262 -45.448368) (xy 73.764392 -45.499703) (xy 73.764902 -45.52569) (xy 73.764392 -45.551677)
			(xy 73.903842 -45.551677) (xy 73.903842 -45.499703) (xy 73.911972 -45.448368) (xy 73.928033 -45.398938)
			(xy 73.951629 -45.352628) (xy 73.982179 -45.31058) (xy 74.01893 -45.273829) (xy 74.060978 -45.243279)
			(xy 74.107288 -45.219683) (xy 74.156718 -45.203622) (xy 74.208053 -45.195492) (xy 74.260027 -45.195492)
			(xy 74.311362 -45.203622) (xy 74.360792 -45.219683) (xy 74.407102 -45.243279) (xy 74.44915 -45.273829)
			(xy 74.485901 -45.31058) (xy 74.516451 -45.352628) (xy 74.540047 -45.398938) (xy 74.556108 -45.448368)
			(xy 74.564238 -45.499703) (xy 74.564748 -45.52569) (xy 74.564238 -45.551677) (xy 74.703942 -45.551677)
			(xy 74.703942 -45.499703) (xy 74.712072 -45.448368) (xy 74.728133 -45.398938) (xy 74.751729 -45.352628)
			(xy 74.782279 -45.31058) (xy 74.81903 -45.273829) (xy 74.861078 -45.243279) (xy 74.907388 -45.219683)
			(xy 74.956818 -45.203622) (xy 75.008153 -45.195492) (xy 75.060127 -45.195492) (xy 75.111462 -45.203622)
			(xy 75.160892 -45.219683) (xy 75.207202 -45.243279) (xy 75.24925 -45.273829) (xy 75.286001 -45.31058)
			(xy 75.316551 -45.352628) (xy 75.340147 -45.398938) (xy 75.356208 -45.448368) (xy 75.364338 -45.499703)
			(xy 75.364848 -45.52569) (xy 75.364338 -45.551677) (xy 77.14031 -45.551677) (xy 77.14031 -45.499703)
			(xy 77.14844 -45.448368) (xy 77.164501 -45.398938) (xy 77.188097 -45.352628) (xy 77.218647 -45.31058)
			(xy 77.255398 -45.273829) (xy 77.297446 -45.243279) (xy 77.343756 -45.219683) (xy 77.393186 -45.203622)
			(xy 77.444521 -45.195492) (xy 77.496495 -45.195492) (xy 77.54783 -45.203622) (xy 77.59726 -45.219683)
			(xy 77.64357 -45.243279) (xy 77.685618 -45.273829) (xy 77.722369 -45.31058) (xy 77.752919 -45.352628)
			(xy 77.776515 -45.398938) (xy 77.792576 -45.448368) (xy 77.800706 -45.499703) (xy 77.801216 -45.52569)
			(xy 77.800706 -45.551677) (xy 77.94041 -45.551677) (xy 77.94041 -45.499703) (xy 77.94854 -45.448368)
			(xy 77.964601 -45.398938) (xy 77.988197 -45.352628) (xy 78.018747 -45.31058) (xy 78.055498 -45.273829)
			(xy 78.097546 -45.243279) (xy 78.143856 -45.219683) (xy 78.193286 -45.203622) (xy 78.244621 -45.195492)
			(xy 78.296595 -45.195492) (xy 78.34793 -45.203622) (xy 78.39736 -45.219683) (xy 78.44367 -45.243279)
			(xy 78.485718 -45.273829) (xy 78.522469 -45.31058) (xy 78.553019 -45.352628) (xy 78.576615 -45.398938)
			(xy 78.592676 -45.448368) (xy 78.600806 -45.499703) (xy 78.601316 -45.52569) (xy 78.600806 -45.551677)
			(xy 78.592676 -45.603012) (xy 78.576615 -45.652442) (xy 78.553019 -45.698752) (xy 78.522469 -45.7408)
			(xy 78.485718 -45.777551) (xy 78.44367 -45.808101) (xy 78.39736 -45.831697) (xy 78.34793 -45.847758)
			(xy 78.296595 -45.855888) (xy 78.244621 -45.855888) (xy 78.193286 -45.847758) (xy 78.143856 -45.831697)
			(xy 78.097546 -45.808101) (xy 78.055498 -45.777551) (xy 78.018747 -45.7408) (xy 77.988197 -45.698752)
			(xy 77.964601 -45.652442) (xy 77.94854 -45.603012) (xy 77.94041 -45.551677) (xy 77.800706 -45.551677)
			(xy 77.792576 -45.603012) (xy 77.776515 -45.652442) (xy 77.752919 -45.698752) (xy 77.722369 -45.7408)
			(xy 77.685618 -45.777551) (xy 77.64357 -45.808101) (xy 77.59726 -45.831697) (xy 77.54783 -45.847758)
			(xy 77.496495 -45.855888) (xy 77.444521 -45.855888) (xy 77.393186 -45.847758) (xy 77.343756 -45.831697)
			(xy 77.297446 -45.808101) (xy 77.255398 -45.777551) (xy 77.218647 -45.7408) (xy 77.188097 -45.698752)
			(xy 77.164501 -45.652442) (xy 77.14844 -45.603012) (xy 77.14031 -45.551677) (xy 75.364338 -45.551677)
			(xy 75.356208 -45.603012) (xy 75.340147 -45.652442) (xy 75.316551 -45.698752) (xy 75.286001 -45.7408)
			(xy 75.24925 -45.777551) (xy 75.207202 -45.808101) (xy 75.160892 -45.831697) (xy 75.111462 -45.847758)
			(xy 75.060127 -45.855888) (xy 75.008153 -45.855888) (xy 74.956818 -45.847758) (xy 74.907388 -45.831697)
			(xy 74.861078 -45.808101) (xy 74.81903 -45.777551) (xy 74.782279 -45.7408) (xy 74.751729 -45.698752)
			(xy 74.728133 -45.652442) (xy 74.712072 -45.603012) (xy 74.703942 -45.551677) (xy 74.564238 -45.551677)
			(xy 74.556108 -45.603012) (xy 74.540047 -45.652442) (xy 74.516451 -45.698752) (xy 74.485901 -45.7408)
			(xy 74.44915 -45.777551) (xy 74.407102 -45.808101) (xy 74.360792 -45.831697) (xy 74.311362 -45.847758)
			(xy 74.260027 -45.855888) (xy 74.208053 -45.855888) (xy 74.156718 -45.847758) (xy 74.107288 -45.831697)
			(xy 74.060978 -45.808101) (xy 74.01893 -45.777551) (xy 73.982179 -45.7408) (xy 73.951629 -45.698752)
			(xy 73.928033 -45.652442) (xy 73.911972 -45.603012) (xy 73.903842 -45.551677) (xy 73.764392 -45.551677)
			(xy 73.756262 -45.603012) (xy 73.740201 -45.652442) (xy 73.716605 -45.698752) (xy 73.686055 -45.7408)
			(xy 73.649304 -45.777551) (xy 73.607256 -45.808101) (xy 73.560946 -45.831697) (xy 73.511516 -45.847758)
			(xy 73.460181 -45.855888) (xy 73.408207 -45.855888) (xy 73.356872 -45.847758) (xy 73.307442 -45.831697)
			(xy 73.261132 -45.808101) (xy 73.219084 -45.777551) (xy 73.182333 -45.7408) (xy 73.151783 -45.698752)
			(xy 73.128187 -45.652442) (xy 73.112126 -45.603012) (xy 73.103996 -45.551677) (xy 71.733664 -45.551677)
			(xy 71.733664 -45.933439) (xy 79.662022 -45.933439) (xy 79.662022 -45.881465) (xy 79.670152 -45.83013)
			(xy 79.686213 -45.7807) (xy 79.709809 -45.73439) (xy 79.740359 -45.692342) (xy 79.77711 -45.655591)
			(xy 79.819158 -45.625041) (xy 79.865468 -45.601445) (xy 79.914898 -45.585384) (xy 79.966233 -45.577254)
			(xy 80.018207 -45.577254) (xy 80.069542 -45.585384) (xy 80.118972 -45.601445) (xy 80.165282 -45.625041)
			(xy 80.20733 -45.655591) (xy 80.244081 -45.692342) (xy 80.274631 -45.73439) (xy 80.298227 -45.7807)
			(xy 80.314288 -45.83013) (xy 80.322418 -45.881465) (xy 80.322928 -45.907452) (xy 80.322418 -45.933439)
			(xy 80.314288 -45.984774) (xy 80.298227 -46.034204) (xy 80.274631 -46.080514) (xy 80.244081 -46.122562)
			(xy 80.20733 -46.159313) (xy 80.165282 -46.189863) (xy 80.118972 -46.213459) (xy 80.069542 -46.22952)
			(xy 80.018207 -46.23765) (xy 79.966233 -46.23765) (xy 79.914898 -46.22952) (xy 79.865468 -46.213459)
			(xy 79.819158 -46.189863) (xy 79.77711 -46.159313) (xy 79.740359 -46.122562) (xy 79.709809 -46.080514)
			(xy 79.686213 -46.034204) (xy 79.670152 -45.984774) (xy 79.662022 -45.933439) (xy 71.733664 -45.933439)
			(xy 71.733664 -46.351777) (xy 72.340472 -46.351777) (xy 72.340472 -46.299803) (xy 72.348602 -46.248468)
			(xy 72.364663 -46.199038) (xy 72.388259 -46.152728) (xy 72.418809 -46.11068) (xy 72.45556 -46.073929)
			(xy 72.497608 -46.043379) (xy 72.543918 -46.019783) (xy 72.593348 -46.003722) (xy 72.644683 -45.995592)
			(xy 72.696657 -45.995592) (xy 72.747992 -46.003722) (xy 72.797422 -46.019783) (xy 72.843732 -46.043379)
			(xy 72.88578 -46.073929) (xy 72.922531 -46.11068) (xy 72.953081 -46.152728) (xy 72.976677 -46.199038)
			(xy 72.992738 -46.248468) (xy 73.000868 -46.299803) (xy 73.001378 -46.32579) (xy 73.000868 -46.351777)
			(xy 73.140318 -46.351777) (xy 73.140318 -46.299803) (xy 73.148448 -46.248468) (xy 73.164509 -46.199038)
			(xy 73.188105 -46.152728) (xy 73.218655 -46.11068) (xy 73.255406 -46.073929) (xy 73.297454 -46.043379)
			(xy 73.343764 -46.019783) (xy 73.393194 -46.003722) (xy 73.444529 -45.995592) (xy 73.496503 -45.995592)
			(xy 73.547838 -46.003722) (xy 73.597268 -46.019783) (xy 73.643578 -46.043379) (xy 73.685626 -46.073929)
			(xy 73.722377 -46.11068) (xy 73.752927 -46.152728) (xy 73.776523 -46.199038) (xy 73.792584 -46.248468)
			(xy 73.800714 -46.299803) (xy 73.801224 -46.32579) (xy 73.800714 -46.351777) (xy 77.94041 -46.351777)
			(xy 77.94041 -46.299803) (xy 77.94854 -46.248468) (xy 77.964601 -46.199038) (xy 77.988197 -46.152728)
			(xy 78.018747 -46.11068) (xy 78.055498 -46.073929) (xy 78.097546 -46.043379) (xy 78.143856 -46.019783)
			(xy 78.193286 -46.003722) (xy 78.244621 -45.995592) (xy 78.296595 -45.995592) (xy 78.34793 -46.003722)
			(xy 78.39736 -46.019783) (xy 78.44367 -46.043379) (xy 78.485718 -46.073929) (xy 78.522469 -46.11068)
			(xy 78.553019 -46.152728) (xy 78.576615 -46.199038) (xy 78.592676 -46.248468) (xy 78.600806 -46.299803)
			(xy 78.601316 -46.32579) (xy 78.600806 -46.351777) (xy 78.740256 -46.351777) (xy 78.740256 -46.299803)
			(xy 78.748386 -46.248468) (xy 78.764447 -46.199038) (xy 78.788043 -46.152728) (xy 78.818593 -46.11068)
			(xy 78.855344 -46.073929) (xy 78.897392 -46.043379) (xy 78.943702 -46.019783) (xy 78.993132 -46.003722)
			(xy 79.044467 -45.995592) (xy 79.096441 -45.995592) (xy 79.147776 -46.003722) (xy 79.197206 -46.019783)
			(xy 79.243516 -46.043379) (xy 79.285564 -46.073929) (xy 79.322315 -46.11068) (xy 79.352865 -46.152728)
			(xy 79.376461 -46.199038) (xy 79.392522 -46.248468) (xy 79.400652 -46.299803) (xy 79.401162 -46.32579)
			(xy 79.400652 -46.351777) (xy 79.392522 -46.403112) (xy 79.376461 -46.452542) (xy 79.352865 -46.498852)
			(xy 79.322315 -46.5409) (xy 79.285564 -46.577651) (xy 79.243516 -46.608201) (xy 79.197206 -46.631797)
			(xy 79.147776 -46.647858) (xy 79.096441 -46.655988) (xy 79.044467 -46.655988) (xy 78.993132 -46.647858)
			(xy 78.943702 -46.631797) (xy 78.897392 -46.608201) (xy 78.855344 -46.577651) (xy 78.818593 -46.5409)
			(xy 78.788043 -46.498852) (xy 78.764447 -46.452542) (xy 78.748386 -46.403112) (xy 78.740256 -46.351777)
			(xy 78.600806 -46.351777) (xy 78.592676 -46.403112) (xy 78.576615 -46.452542) (xy 78.553019 -46.498852)
			(xy 78.522469 -46.5409) (xy 78.485718 -46.577651) (xy 78.44367 -46.608201) (xy 78.39736 -46.631797)
			(xy 78.34793 -46.647858) (xy 78.296595 -46.655988) (xy 78.244621 -46.655988) (xy 78.193286 -46.647858)
			(xy 78.143856 -46.631797) (xy 78.097546 -46.608201) (xy 78.055498 -46.577651) (xy 78.018747 -46.5409)
			(xy 77.988197 -46.498852) (xy 77.964601 -46.452542) (xy 77.94854 -46.403112) (xy 77.94041 -46.351777)
			(xy 73.800714 -46.351777) (xy 73.792584 -46.403112) (xy 73.776523 -46.452542) (xy 73.752927 -46.498852)
			(xy 73.722377 -46.5409) (xy 73.685626 -46.577651) (xy 73.643578 -46.608201) (xy 73.597268 -46.631797)
			(xy 73.547838 -46.647858) (xy 73.496503 -46.655988) (xy 73.444529 -46.655988) (xy 73.393194 -46.647858)
			(xy 73.343764 -46.631797) (xy 73.297454 -46.608201) (xy 73.255406 -46.577651) (xy 73.218655 -46.5409)
			(xy 73.188105 -46.498852) (xy 73.164509 -46.452542) (xy 73.148448 -46.403112) (xy 73.140318 -46.351777)
			(xy 73.000868 -46.351777) (xy 72.992738 -46.403112) (xy 72.976677 -46.452542) (xy 72.953081 -46.498852)
			(xy 72.922531 -46.5409) (xy 72.88578 -46.577651) (xy 72.843732 -46.608201) (xy 72.797422 -46.631797)
			(xy 72.747992 -46.647858) (xy 72.696657 -46.655988) (xy 72.644683 -46.655988) (xy 72.593348 -46.647858)
			(xy 72.543918 -46.631797) (xy 72.497608 -46.608201) (xy 72.45556 -46.577651) (xy 72.418809 -46.5409)
			(xy 72.388259 -46.498852) (xy 72.364663 -46.452542) (xy 72.348602 -46.403112) (xy 72.340472 -46.351777)
			(xy 71.733664 -46.351777) (xy 71.733664 -47.151623) (xy 72.340472 -47.151623) (xy 72.340472 -47.099649)
			(xy 72.348602 -47.048314) (xy 72.364663 -46.998884) (xy 72.388259 -46.952574) (xy 72.418809 -46.910526)
			(xy 72.45556 -46.873775) (xy 72.497608 -46.843225) (xy 72.543918 -46.819629) (xy 72.593348 -46.803568)
			(xy 72.644683 -46.795438) (xy 72.696657 -46.795438) (xy 72.747992 -46.803568) (xy 72.797422 -46.819629)
			(xy 72.843732 -46.843225) (xy 72.88578 -46.873775) (xy 72.922531 -46.910526) (xy 72.953081 -46.952574)
			(xy 72.976677 -46.998884) (xy 72.992738 -47.048314) (xy 73.000868 -47.099649) (xy 73.001378 -47.125636)
			(xy 73.000868 -47.151623) (xy 73.140318 -47.151623) (xy 73.140318 -47.099649) (xy 73.148448 -47.048314)
			(xy 73.164509 -46.998884) (xy 73.188105 -46.952574) (xy 73.218655 -46.910526) (xy 73.255406 -46.873775)
			(xy 73.297454 -46.843225) (xy 73.343764 -46.819629) (xy 73.393194 -46.803568) (xy 73.444529 -46.795438)
			(xy 73.496503 -46.795438) (xy 73.547838 -46.803568) (xy 73.597268 -46.819629) (xy 73.643578 -46.843225)
			(xy 73.685626 -46.873775) (xy 73.722377 -46.910526) (xy 73.752927 -46.952574) (xy 73.776523 -46.998884)
			(xy 73.792584 -47.048314) (xy 73.800714 -47.099649) (xy 73.801224 -47.125636) (xy 73.800714 -47.151623)
			(xy 73.940418 -47.151623) (xy 73.940418 -47.099649) (xy 73.948548 -47.048314) (xy 73.964609 -46.998884)
			(xy 73.988205 -46.952574) (xy 74.018755 -46.910526) (xy 74.055506 -46.873775) (xy 74.097554 -46.843225)
			(xy 74.143864 -46.819629) (xy 74.193294 -46.803568) (xy 74.244629 -46.795438) (xy 74.296603 -46.795438)
			(xy 74.347938 -46.803568) (xy 74.397368 -46.819629) (xy 74.443678 -46.843225) (xy 74.485726 -46.873775)
			(xy 74.522477 -46.910526) (xy 74.553027 -46.952574) (xy 74.576623 -46.998884) (xy 74.592684 -47.048314)
			(xy 74.600814 -47.099649) (xy 74.601324 -47.125636) (xy 74.600814 -47.151623) (xy 74.704196 -47.151623)
			(xy 74.704196 -47.099649) (xy 74.712326 -47.048314) (xy 74.728387 -46.998884) (xy 74.751983 -46.952574)
			(xy 74.782533 -46.910526) (xy 74.819284 -46.873775) (xy 74.861332 -46.843225) (xy 74.907642 -46.819629)
			(xy 74.957072 -46.803568) (xy 75.008407 -46.795438) (xy 75.060381 -46.795438) (xy 75.111716 -46.803568)
			(xy 75.161146 -46.819629) (xy 75.207456 -46.843225) (xy 75.249504 -46.873775) (xy 75.286255 -46.910526)
			(xy 75.316805 -46.952574) (xy 75.340401 -46.998884) (xy 75.356462 -47.048314) (xy 75.364592 -47.099649)
			(xy 75.364899 -47.115301) (xy 77.903834 -47.115301) (xy 77.903834 -47.063327) (xy 77.911964 -47.011992)
			(xy 77.928025 -46.962562) (xy 77.951621 -46.916252) (xy 77.982171 -46.874204) (xy 78.018922 -46.837453)
			(xy 78.06097 -46.806903) (xy 78.10728 -46.783307) (xy 78.15671 -46.767246) (xy 78.208045 -46.759116)
			(xy 78.260019 -46.759116) (xy 78.311354 -46.767246) (xy 78.360784 -46.783307) (xy 78.407094 -46.806903)
			(xy 78.449142 -46.837453) (xy 78.485893 -46.874204) (xy 78.516443 -46.916252) (xy 78.540039 -46.962562)
			(xy 78.5561 -47.011992) (xy 78.56423 -47.063327) (xy 78.56474 -47.089314) (xy 78.56423 -47.115301)
			(xy 78.558478 -47.151623) (xy 78.703934 -47.151623) (xy 78.703934 -47.099649) (xy 78.712064 -47.048314)
			(xy 78.728125 -46.998884) (xy 78.751721 -46.952574) (xy 78.782271 -46.910526) (xy 78.819022 -46.873775)
			(xy 78.86107 -46.843225) (xy 78.90738 -46.819629) (xy 78.95681 -46.803568) (xy 79.008145 -46.795438)
			(xy 79.060119 -46.795438) (xy 79.111454 -46.803568) (xy 79.160884 -46.819629) (xy 79.207194 -46.843225)
			(xy 79.249242 -46.873775) (xy 79.285993 -46.910526) (xy 79.316543 -46.952574) (xy 79.340139 -46.998884)
			(xy 79.3562 -47.048314) (xy 79.36433 -47.099649) (xy 79.36484 -47.125636) (xy 79.36433 -47.151623)
			(xy 79.50378 -47.151623) (xy 79.50378 -47.099649) (xy 79.51191 -47.048314) (xy 79.527971 -46.998884)
			(xy 79.551567 -46.952574) (xy 79.582117 -46.910526) (xy 79.618868 -46.873775) (xy 79.660916 -46.843225)
			(xy 79.707226 -46.819629) (xy 79.756656 -46.803568) (xy 79.807991 -46.795438) (xy 79.859965 -46.795438)
			(xy 79.9113 -46.803568) (xy 79.96073 -46.819629) (xy 80.00704 -46.843225) (xy 80.049088 -46.873775)
			(xy 80.085839 -46.910526) (xy 80.116389 -46.952574) (xy 80.139985 -46.998884) (xy 80.156046 -47.048314)
			(xy 80.164176 -47.099649) (xy 80.164686 -47.125636) (xy 80.164176 -47.151623) (xy 80.156046 -47.202958)
			(xy 80.139985 -47.252388) (xy 80.116389 -47.298698) (xy 80.085839 -47.340746) (xy 80.049088 -47.377497)
			(xy 80.00704 -47.408047) (xy 79.96073 -47.431643) (xy 79.9113 -47.447704) (xy 79.859965 -47.455834)
			(xy 79.807991 -47.455834) (xy 79.756656 -47.447704) (xy 79.707226 -47.431643) (xy 79.660916 -47.408047)
			(xy 79.618868 -47.377497) (xy 79.582117 -47.340746) (xy 79.551567 -47.298698) (xy 79.527971 -47.252388)
			(xy 79.51191 -47.202958) (xy 79.50378 -47.151623) (xy 79.36433 -47.151623) (xy 79.3562 -47.202958)
			(xy 79.340139 -47.252388) (xy 79.316543 -47.298698) (xy 79.285993 -47.340746) (xy 79.249242 -47.377497)
			(xy 79.207194 -47.408047) (xy 79.160884 -47.431643) (xy 79.111454 -47.447704) (xy 79.060119 -47.455834)
			(xy 79.008145 -47.455834) (xy 78.95681 -47.447704) (xy 78.90738 -47.431643) (xy 78.86107 -47.408047)
			(xy 78.819022 -47.377497) (xy 78.782271 -47.340746) (xy 78.751721 -47.298698) (xy 78.728125 -47.252388)
			(xy 78.712064 -47.202958) (xy 78.703934 -47.151623) (xy 78.558478 -47.151623) (xy 78.5561 -47.166636)
			(xy 78.540039 -47.216066) (xy 78.516443 -47.262376) (xy 78.485893 -47.304424) (xy 78.449142 -47.341175)
			(xy 78.407094 -47.371725) (xy 78.360784 -47.395321) (xy 78.311354 -47.411382) (xy 78.260019 -47.419512)
			(xy 78.208045 -47.419512) (xy 78.15671 -47.411382) (xy 78.10728 -47.395321) (xy 78.06097 -47.371725)
			(xy 78.018922 -47.341175) (xy 77.982171 -47.304424) (xy 77.951621 -47.262376) (xy 77.928025 -47.216066)
			(xy 77.911964 -47.166636) (xy 77.903834 -47.115301) (xy 75.364899 -47.115301) (xy 75.365102 -47.125636)
			(xy 75.364592 -47.151623) (xy 75.356462 -47.202958) (xy 75.340401 -47.252388) (xy 75.316805 -47.298698)
			(xy 75.286255 -47.340746) (xy 75.249504 -47.377497) (xy 75.207456 -47.408047) (xy 75.161146 -47.431643)
			(xy 75.111716 -47.447704) (xy 75.060381 -47.455834) (xy 75.008407 -47.455834) (xy 74.957072 -47.447704)
			(xy 74.907642 -47.431643) (xy 74.861332 -47.408047) (xy 74.819284 -47.377497) (xy 74.782533 -47.340746)
			(xy 74.751983 -47.298698) (xy 74.728387 -47.252388) (xy 74.712326 -47.202958) (xy 74.704196 -47.151623)
			(xy 74.600814 -47.151623) (xy 74.592684 -47.202958) (xy 74.576623 -47.252388) (xy 74.553027 -47.298698)
			(xy 74.522477 -47.340746) (xy 74.485726 -47.377497) (xy 74.443678 -47.408047) (xy 74.397368 -47.431643)
			(xy 74.347938 -47.447704) (xy 74.296603 -47.455834) (xy 74.244629 -47.455834) (xy 74.193294 -47.447704)
			(xy 74.143864 -47.431643) (xy 74.097554 -47.408047) (xy 74.055506 -47.377497) (xy 74.018755 -47.340746)
			(xy 73.988205 -47.298698) (xy 73.964609 -47.252388) (xy 73.948548 -47.202958) (xy 73.940418 -47.151623)
			(xy 73.800714 -47.151623) (xy 73.792584 -47.202958) (xy 73.776523 -47.252388) (xy 73.752927 -47.298698)
			(xy 73.722377 -47.340746) (xy 73.685626 -47.377497) (xy 73.643578 -47.408047) (xy 73.597268 -47.431643)
			(xy 73.547838 -47.447704) (xy 73.496503 -47.455834) (xy 73.444529 -47.455834) (xy 73.393194 -47.447704)
			(xy 73.343764 -47.431643) (xy 73.297454 -47.408047) (xy 73.255406 -47.377497) (xy 73.218655 -47.340746)
			(xy 73.188105 -47.298698) (xy 73.164509 -47.252388) (xy 73.148448 -47.202958) (xy 73.140318 -47.151623)
			(xy 73.000868 -47.151623) (xy 72.992738 -47.202958) (xy 72.976677 -47.252388) (xy 72.953081 -47.298698)
			(xy 72.922531 -47.340746) (xy 72.88578 -47.377497) (xy 72.843732 -47.408047) (xy 72.797422 -47.431643)
			(xy 72.747992 -47.447704) (xy 72.696657 -47.455834) (xy 72.644683 -47.455834) (xy 72.593348 -47.447704)
			(xy 72.543918 -47.431643) (xy 72.497608 -47.408047) (xy 72.45556 -47.377497) (xy 72.418809 -47.340746)
			(xy 72.388259 -47.298698) (xy 72.364663 -47.252388) (xy 72.348602 -47.202958) (xy 72.340472 -47.151623)
			(xy 71.733664 -47.151623) (xy 71.733664 -47.915147) (xy 77.903834 -47.915147) (xy 77.903834 -47.863173)
			(xy 77.911964 -47.811838) (xy 77.928025 -47.762408) (xy 77.951621 -47.716098) (xy 77.982171 -47.67405)
			(xy 78.018922 -47.637299) (xy 78.06097 -47.606749) (xy 78.10728 -47.583153) (xy 78.15671 -47.567092)
			(xy 78.208045 -47.558962) (xy 78.260019 -47.558962) (xy 78.311354 -47.567092) (xy 78.360784 -47.583153)
			(xy 78.407094 -47.606749) (xy 78.449142 -47.637299) (xy 78.485893 -47.67405) (xy 78.516443 -47.716098)
			(xy 78.540039 -47.762408) (xy 78.5561 -47.811838) (xy 78.56423 -47.863173) (xy 78.56474 -47.88916)
			(xy 78.56423 -47.915147) (xy 78.703934 -47.915147) (xy 78.703934 -47.863173) (xy 78.712064 -47.811838)
			(xy 78.728125 -47.762408) (xy 78.751721 -47.716098) (xy 78.782271 -47.67405) (xy 78.819022 -47.637299)
			(xy 78.86107 -47.606749) (xy 78.90738 -47.583153) (xy 78.95681 -47.567092) (xy 79.008145 -47.558962)
			(xy 79.060119 -47.558962) (xy 79.111454 -47.567092) (xy 79.160884 -47.583153) (xy 79.207194 -47.606749)
			(xy 79.249242 -47.637299) (xy 79.285993 -47.67405) (xy 79.316543 -47.716098) (xy 79.340139 -47.762408)
			(xy 79.3562 -47.811838) (xy 79.36433 -47.863173) (xy 79.36484 -47.88916) (xy 79.36433 -47.915147)
			(xy 79.3562 -47.966482) (xy 79.340139 -48.015912) (xy 79.316543 -48.062222) (xy 79.285993 -48.10427)
			(xy 79.249242 -48.141021) (xy 79.207194 -48.171571) (xy 79.160884 -48.195167) (xy 79.111454 -48.211228)
			(xy 79.060119 -48.219358) (xy 79.008145 -48.219358) (xy 78.95681 -48.211228) (xy 78.90738 -48.195167)
			(xy 78.86107 -48.171571) (xy 78.819022 -48.141021) (xy 78.782271 -48.10427) (xy 78.751721 -48.062222)
			(xy 78.728125 -48.015912) (xy 78.712064 -47.966482) (xy 78.703934 -47.915147) (xy 78.56423 -47.915147)
			(xy 78.5561 -47.966482) (xy 78.540039 -48.015912) (xy 78.516443 -48.062222) (xy 78.485893 -48.10427)
			(xy 78.449142 -48.141021) (xy 78.407094 -48.171571) (xy 78.360784 -48.195167) (xy 78.311354 -48.211228)
			(xy 78.260019 -48.219358) (xy 78.208045 -48.219358) (xy 78.15671 -48.211228) (xy 78.10728 -48.195167)
			(xy 78.06097 -48.171571) (xy 78.018922 -48.141021) (xy 77.982171 -48.10427) (xy 77.951621 -48.062222)
			(xy 77.928025 -48.015912) (xy 77.911964 -47.966482) (xy 77.903834 -47.915147) (xy 71.733664 -47.915147)
			(xy 71.733664 -48.333485) (xy 72.18223 -48.333485) (xy 72.18223 -48.281511) (xy 72.19036 -48.230176)
			(xy 72.206421 -48.180746) (xy 72.230017 -48.134436) (xy 72.260567 -48.092388) (xy 72.297318 -48.055637)
			(xy 72.339366 -48.025087) (xy 72.385676 -48.001491) (xy 72.435106 -47.98543) (xy 72.486441 -47.9773)
			(xy 72.538415 -47.9773) (xy 72.58975 -47.98543) (xy 72.63918 -48.001491) (xy 72.68549 -48.025087)
			(xy 72.727538 -48.055637) (xy 72.764289 -48.092388) (xy 72.794839 -48.134436) (xy 72.818435 -48.180746)
			(xy 72.834496 -48.230176) (xy 72.842626 -48.281511) (xy 72.843136 -48.307498) (xy 72.842626 -48.333485)
			(xy 72.834496 -48.38482) (xy 72.818435 -48.43425) (xy 72.794839 -48.48056) (xy 72.764289 -48.522608)
			(xy 72.727538 -48.559359) (xy 72.68549 -48.589909) (xy 72.63918 -48.613505) (xy 72.58975 -48.629566)
			(xy 72.538415 -48.637696) (xy 72.486441 -48.637696) (xy 72.435106 -48.629566) (xy 72.385676 -48.613505)
			(xy 72.339366 -48.589909) (xy 72.297318 -48.559359) (xy 72.260567 -48.522608) (xy 72.230017 -48.48056)
			(xy 72.206421 -48.43425) (xy 72.19036 -48.38482) (xy 72.18223 -48.333485) (xy 71.733664 -48.333485)
			(xy 71.733664 -48.715247) (xy 73.140318 -48.715247) (xy 73.140318 -48.663273) (xy 73.148448 -48.611938)
			(xy 73.164509 -48.562508) (xy 73.188105 -48.516198) (xy 73.218655 -48.47415) (xy 73.255406 -48.437399)
			(xy 73.297454 -48.406849) (xy 73.343764 -48.383253) (xy 73.393194 -48.367192) (xy 73.444529 -48.359062)
			(xy 73.496503 -48.359062) (xy 73.547838 -48.367192) (xy 73.597268 -48.383253) (xy 73.643578 -48.406849)
			(xy 73.685626 -48.437399) (xy 73.722377 -48.47415) (xy 73.752927 -48.516198) (xy 73.776523 -48.562508)
			(xy 73.792584 -48.611938) (xy 73.800714 -48.663273) (xy 73.801224 -48.68926) (xy 73.800714 -48.715247)
			(xy 73.940418 -48.715247) (xy 73.940418 -48.663273) (xy 73.948548 -48.611938) (xy 73.964609 -48.562508)
			(xy 73.988205 -48.516198) (xy 74.018755 -48.47415) (xy 74.055506 -48.437399) (xy 74.097554 -48.406849)
			(xy 74.143864 -48.383253) (xy 74.193294 -48.367192) (xy 74.244629 -48.359062) (xy 74.296603 -48.359062)
			(xy 74.347938 -48.367192) (xy 74.397368 -48.383253) (xy 74.443678 -48.406849) (xy 74.485726 -48.437399)
			(xy 74.522477 -48.47415) (xy 74.553027 -48.516198) (xy 74.576623 -48.562508) (xy 74.592684 -48.611938)
			(xy 74.600814 -48.663273) (xy 74.601324 -48.68926) (xy 74.600814 -48.715247) (xy 77.903834 -48.715247)
			(xy 77.903834 -48.663273) (xy 77.911964 -48.611938) (xy 77.928025 -48.562508) (xy 77.951621 -48.516198)
			(xy 77.982171 -48.47415) (xy 78.018922 -48.437399) (xy 78.06097 -48.406849) (xy 78.10728 -48.383253)
			(xy 78.15671 -48.367192) (xy 78.208045 -48.359062) (xy 78.260019 -48.359062) (xy 78.311354 -48.367192)
			(xy 78.360784 -48.383253) (xy 78.407094 -48.406849) (xy 78.449142 -48.437399) (xy 78.485893 -48.47415)
			(xy 78.516443 -48.516198) (xy 78.540039 -48.562508) (xy 78.5561 -48.611938) (xy 78.56423 -48.663273)
			(xy 78.56474 -48.68926) (xy 78.56423 -48.715247) (xy 78.703934 -48.715247) (xy 78.703934 -48.663273)
			(xy 78.712064 -48.611938) (xy 78.728125 -48.562508) (xy 78.751721 -48.516198) (xy 78.782271 -48.47415)
			(xy 78.819022 -48.437399) (xy 78.86107 -48.406849) (xy 78.90738 -48.383253) (xy 78.95681 -48.367192)
			(xy 79.008145 -48.359062) (xy 79.060119 -48.359062) (xy 79.111454 -48.367192) (xy 79.160884 -48.383253)
			(xy 79.207194 -48.406849) (xy 79.249242 -48.437399) (xy 79.285993 -48.47415) (xy 79.316543 -48.516198)
			(xy 79.340139 -48.562508) (xy 79.3562 -48.611938) (xy 79.36433 -48.663273) (xy 79.36484 -48.68926)
			(xy 79.36433 -48.715247) (xy 79.50378 -48.715247) (xy 79.50378 -48.663273) (xy 79.51191 -48.611938)
			(xy 79.527971 -48.562508) (xy 79.551567 -48.516198) (xy 79.582117 -48.47415) (xy 79.618868 -48.437399)
			(xy 79.660916 -48.406849) (xy 79.707226 -48.383253) (xy 79.756656 -48.367192) (xy 79.807991 -48.359062)
			(xy 79.859965 -48.359062) (xy 79.9113 -48.367192) (xy 79.96073 -48.383253) (xy 80.00704 -48.406849)
			(xy 80.049088 -48.437399) (xy 80.085839 -48.47415) (xy 80.116389 -48.516198) (xy 80.139985 -48.562508)
			(xy 80.156046 -48.611938) (xy 80.164176 -48.663273) (xy 80.164686 -48.68926) (xy 80.164176 -48.715247)
			(xy 80.156046 -48.766582) (xy 80.139985 -48.816012) (xy 80.116389 -48.862322) (xy 80.085839 -48.90437)
			(xy 80.049088 -48.941121) (xy 80.00704 -48.971671) (xy 79.96073 -48.995267) (xy 79.9113 -49.011328)
			(xy 79.859965 -49.019458) (xy 79.807991 -49.019458) (xy 79.756656 -49.011328) (xy 79.707226 -48.995267)
			(xy 79.660916 -48.971671) (xy 79.618868 -48.941121) (xy 79.582117 -48.90437) (xy 79.551567 -48.862322)
			(xy 79.527971 -48.816012) (xy 79.51191 -48.766582) (xy 79.50378 -48.715247) (xy 79.36433 -48.715247)
			(xy 79.3562 -48.766582) (xy 79.340139 -48.816012) (xy 79.316543 -48.862322) (xy 79.285993 -48.90437)
			(xy 79.249242 -48.941121) (xy 79.207194 -48.971671) (xy 79.160884 -48.995267) (xy 79.111454 -49.011328)
			(xy 79.060119 -49.019458) (xy 79.008145 -49.019458) (xy 78.95681 -49.011328) (xy 78.90738 -48.995267)
			(xy 78.86107 -48.971671) (xy 78.819022 -48.941121) (xy 78.782271 -48.90437) (xy 78.751721 -48.862322)
			(xy 78.728125 -48.816012) (xy 78.712064 -48.766582) (xy 78.703934 -48.715247) (xy 78.56423 -48.715247)
			(xy 78.5561 -48.766582) (xy 78.540039 -48.816012) (xy 78.516443 -48.862322) (xy 78.485893 -48.90437)
			(xy 78.449142 -48.941121) (xy 78.407094 -48.971671) (xy 78.360784 -48.995267) (xy 78.311354 -49.011328)
			(xy 78.260019 -49.019458) (xy 78.208045 -49.019458) (xy 78.15671 -49.011328) (xy 78.10728 -48.995267)
			(xy 78.06097 -48.971671) (xy 78.018922 -48.941121) (xy 77.982171 -48.90437) (xy 77.951621 -48.862322)
			(xy 77.928025 -48.816012) (xy 77.911964 -48.766582) (xy 77.903834 -48.715247) (xy 74.600814 -48.715247)
			(xy 74.592684 -48.766582) (xy 74.576623 -48.816012) (xy 74.553027 -48.862322) (xy 74.522477 -48.90437)
			(xy 74.485726 -48.941121) (xy 74.443678 -48.971671) (xy 74.397368 -48.995267) (xy 74.347938 -49.011328)
			(xy 74.296603 -49.019458) (xy 74.244629 -49.019458) (xy 74.193294 -49.011328) (xy 74.143864 -48.995267)
			(xy 74.097554 -48.971671) (xy 74.055506 -48.941121) (xy 74.018755 -48.90437) (xy 73.988205 -48.862322)
			(xy 73.964609 -48.816012) (xy 73.948548 -48.766582) (xy 73.940418 -48.715247) (xy 73.800714 -48.715247)
			(xy 73.792584 -48.766582) (xy 73.776523 -48.816012) (xy 73.752927 -48.862322) (xy 73.722377 -48.90437)
			(xy 73.685626 -48.941121) (xy 73.643578 -48.971671) (xy 73.597268 -48.995267) (xy 73.547838 -49.011328)
			(xy 73.496503 -49.019458) (xy 73.444529 -49.019458) (xy 73.393194 -49.011328) (xy 73.343764 -48.995267)
			(xy 73.297454 -48.971671) (xy 73.255406 -48.941121) (xy 73.218655 -48.90437) (xy 73.188105 -48.862322)
			(xy 73.164509 -48.816012) (xy 73.148448 -48.766582) (xy 73.140318 -48.715247) (xy 71.733664 -48.715247)
			(xy 71.733664 -49.515093) (xy 72.340472 -49.515093) (xy 72.340472 -49.463119) (xy 72.348602 -49.411784)
			(xy 72.364663 -49.362354) (xy 72.388259 -49.316044) (xy 72.418809 -49.273996) (xy 72.45556 -49.237245)
			(xy 72.497608 -49.206695) (xy 72.543918 -49.183099) (xy 72.593348 -49.167038) (xy 72.644683 -49.158908)
			(xy 72.696657 -49.158908) (xy 72.747992 -49.167038) (xy 72.797422 -49.183099) (xy 72.843732 -49.206695)
			(xy 72.88578 -49.237245) (xy 72.922531 -49.273996) (xy 72.953081 -49.316044) (xy 72.976677 -49.362354)
			(xy 72.992738 -49.411784) (xy 73.000868 -49.463119) (xy 73.001378 -49.489106) (xy 73.000868 -49.515093)
			(xy 73.140318 -49.515093) (xy 73.140318 -49.463119) (xy 73.148448 -49.411784) (xy 73.164509 -49.362354)
			(xy 73.188105 -49.316044) (xy 73.218655 -49.273996) (xy 73.255406 -49.237245) (xy 73.297454 -49.206695)
			(xy 73.343764 -49.183099) (xy 73.393194 -49.167038) (xy 73.444529 -49.158908) (xy 73.496503 -49.158908)
			(xy 73.547838 -49.167038) (xy 73.597268 -49.183099) (xy 73.643578 -49.206695) (xy 73.685626 -49.237245)
			(xy 73.722377 -49.273996) (xy 73.752927 -49.316044) (xy 73.776523 -49.362354) (xy 73.792584 -49.411784)
			(xy 73.800714 -49.463119) (xy 73.801224 -49.489106) (xy 73.800714 -49.515093) (xy 73.792584 -49.566428)
			(xy 73.776523 -49.615858) (xy 73.752927 -49.662168) (xy 73.722377 -49.704216) (xy 73.685626 -49.740967)
			(xy 73.643578 -49.771517) (xy 73.597268 -49.795113) (xy 73.547838 -49.811174) (xy 73.496503 -49.819304)
			(xy 73.444529 -49.819304) (xy 73.393194 -49.811174) (xy 73.343764 -49.795113) (xy 73.297454 -49.771517)
			(xy 73.255406 -49.740967) (xy 73.218655 -49.704216) (xy 73.188105 -49.662168) (xy 73.164509 -49.615858)
			(xy 73.148448 -49.566428) (xy 73.140318 -49.515093) (xy 73.000868 -49.515093) (xy 72.992738 -49.566428)
			(xy 72.976677 -49.615858) (xy 72.953081 -49.662168) (xy 72.922531 -49.704216) (xy 72.88578 -49.740967)
			(xy 72.843732 -49.771517) (xy 72.797422 -49.795113) (xy 72.747992 -49.811174) (xy 72.696657 -49.819304)
			(xy 72.644683 -49.819304) (xy 72.593348 -49.811174) (xy 72.543918 -49.795113) (xy 72.497608 -49.771517)
			(xy 72.45556 -49.740967) (xy 72.418809 -49.704216) (xy 72.388259 -49.662168) (xy 72.364663 -49.615858)
			(xy 72.348602 -49.566428) (xy 72.340472 -49.515093) (xy 71.733664 -49.515093) (xy 71.733664 -50.315193)
			(xy 72.340472 -50.315193) (xy 72.340472 -50.263219) (xy 72.348602 -50.211884) (xy 72.364663 -50.162454)
			(xy 72.388259 -50.116144) (xy 72.418809 -50.074096) (xy 72.45556 -50.037345) (xy 72.497608 -50.006795)
			(xy 72.543918 -49.983199) (xy 72.593348 -49.967138) (xy 72.644683 -49.959008) (xy 72.696657 -49.959008)
			(xy 72.747992 -49.967138) (xy 72.797422 -49.983199) (xy 72.843732 -50.006795) (xy 72.88578 -50.037345)
			(xy 72.922531 -50.074096) (xy 72.953081 -50.116144) (xy 72.976677 -50.162454) (xy 72.992738 -50.211884)
			(xy 73.000868 -50.263219) (xy 73.001378 -50.289206) (xy 73.000868 -50.315193) (xy 73.140318 -50.315193)
			(xy 73.140318 -50.263219) (xy 73.148448 -50.211884) (xy 73.164509 -50.162454) (xy 73.188105 -50.116144)
			(xy 73.218655 -50.074096) (xy 73.255406 -50.037345) (xy 73.297454 -50.006795) (xy 73.343764 -49.983199)
			(xy 73.393194 -49.967138) (xy 73.444529 -49.959008) (xy 73.496503 -49.959008) (xy 73.547838 -49.967138)
			(xy 73.597268 -49.983199) (xy 73.643578 -50.006795) (xy 73.685626 -50.037345) (xy 73.722377 -50.074096)
			(xy 73.752927 -50.116144) (xy 73.776523 -50.162454) (xy 73.792584 -50.211884) (xy 73.800714 -50.263219)
			(xy 73.801129 -50.28438) (xy 73.928986 -50.28438) (xy 73.929491 -50.258728) (xy 73.937397 -50.208037)
			(xy 73.953032 -50.159174) (xy 73.976022 -50.11331) (xy 74.005815 -50.071544) (xy 74.041698 -50.034877)
			(xy 74.08281 -50.004187) (xy 74.105262 -49.991772) (xy 74.117132 -49.985107) (xy 74.13698 -49.966482)
			(xy 74.151193 -49.94327) (xy 74.158761 -49.917126) (xy 74.159143 -49.889911) (xy 74.152312 -49.863564)
			(xy 74.138755 -49.839963) (xy 74.119438 -49.820788) (xy 74.107802 -49.813718) (xy 74.086275 -49.801057)
			(xy 74.047014 -49.770189) (xy 74.012835 -49.733775) (xy 73.984512 -49.692641) (xy 73.962688 -49.647719)
			(xy 73.947859 -49.600029) (xy 73.940361 -49.550653) (xy 73.939908 -49.525682) (xy 73.940418 -49.499695)
			(xy 73.948548 -49.44836) (xy 73.964609 -49.39893) (xy 73.988205 -49.35262) (xy 74.018755 -49.310572)
			(xy 74.055506 -49.273821) (xy 74.097554 -49.243271) (xy 74.143864 -49.219675) (xy 74.193294 -49.203614)
			(xy 74.244629 -49.195484) (xy 74.296603 -49.195484) (xy 74.347938 -49.203614) (xy 74.397368 -49.219675)
			(xy 74.443678 -49.243271) (xy 74.485726 -49.273821) (xy 74.522477 -49.310572) (xy 74.553027 -49.35262)
			(xy 74.576623 -49.39893) (xy 74.592684 -49.44836) (xy 74.595023 -49.463131) (xy 74.703833 -49.463131)
			(xy 74.711962 -49.411785) (xy 74.728024 -49.362342) (xy 74.751622 -49.31602) (xy 74.782177 -49.27396)
			(xy 74.818935 -49.237199) (xy 74.860991 -49.20664) (xy 74.90731 -49.183037) (xy 74.956751 -49.16697)
			(xy 75.008098 -49.158836) (xy 75.060084 -49.158835) (xy 75.11143 -49.166966) (xy 75.160873 -49.18303)
			(xy 75.207193 -49.20663) (xy 75.249251 -49.237187) (xy 75.286011 -49.273946) (xy 75.316568 -49.316004)
			(xy 75.340169 -49.362324) (xy 75.356233 -49.411766) (xy 75.364365 -49.463113) (xy 75.364848 -49.489106)
			(xy 75.36434 -49.507648) (xy 75.364093 -49.522781) (xy 75.371249 -49.552164) (xy 75.386704 -49.578159)
			(xy 75.409101 -49.598481) (xy 75.436471 -49.611344) (xy 75.46641 -49.615618) (xy 75.481434 -49.61382)
			(xy 75.494114 -49.611934) (xy 75.51967 -49.609897) (xy 75.532488 -49.609756) (xy 75.558479 -49.610262)
			(xy 75.609821 -49.618392) (xy 75.65926 -49.634454) (xy 75.705576 -49.658053) (xy 75.718083 -49.667139)
			(xy 76.227168 -49.667139) (xy 76.227168 -49.613841) (xy 76.235111 -49.561137) (xy 76.250821 -49.510207)
			(xy 76.273947 -49.462186) (xy 76.303971 -49.418149) (xy 76.340223 -49.379078) (xy 76.381894 -49.345847)
			(xy 76.428052 -49.319198) (xy 76.477666 -49.299726) (xy 76.529628 -49.287866) (xy 76.582778 -49.283883)
			(xy 76.635928 -49.287866) (xy 76.68789 -49.299726) (xy 76.737504 -49.319198) (xy 76.783662 -49.345847)
			(xy 76.825333 -49.379078) (xy 76.861585 -49.418149) (xy 76.891609 -49.462186) (xy 76.914735 -49.510207)
			(xy 76.916242 -49.515093) (xy 77.903834 -49.515093) (xy 77.903834 -49.463119) (xy 77.911964 -49.411784)
			(xy 77.928025 -49.362354) (xy 77.951621 -49.316044) (xy 77.982171 -49.273996) (xy 78.018922 -49.237245)
			(xy 78.06097 -49.206695) (xy 78.10728 -49.183099) (xy 78.15671 -49.167038) (xy 78.208045 -49.158908)
			(xy 78.260019 -49.158908) (xy 78.311354 -49.167038) (xy 78.360784 -49.183099) (xy 78.407094 -49.206695)
			(xy 78.449142 -49.237245) (xy 78.485893 -49.273996) (xy 78.516443 -49.316044) (xy 78.540039 -49.362354)
			(xy 78.5561 -49.411784) (xy 78.56423 -49.463119) (xy 78.56474 -49.489106) (xy 78.56423 -49.515093)
			(xy 78.703934 -49.515093) (xy 78.703934 -49.463119) (xy 78.712064 -49.411784) (xy 78.728125 -49.362354)
			(xy 78.751721 -49.316044) (xy 78.782271 -49.273996) (xy 78.819022 -49.237245) (xy 78.86107 -49.206695)
			(xy 78.90738 -49.183099) (xy 78.95681 -49.167038) (xy 79.008145 -49.158908) (xy 79.060119 -49.158908)
			(xy 79.111454 -49.167038) (xy 79.160884 -49.183099) (xy 79.207194 -49.206695) (xy 79.249242 -49.237245)
			(xy 79.285993 -49.273996) (xy 79.316543 -49.316044) (xy 79.340139 -49.362354) (xy 79.3562 -49.411784)
			(xy 79.36433 -49.463119) (xy 79.36484 -49.489106) (xy 79.36433 -49.515093) (xy 79.50378 -49.515093)
			(xy 79.50378 -49.463119) (xy 79.51191 -49.411784) (xy 79.527971 -49.362354) (xy 79.551567 -49.316044)
			(xy 79.582117 -49.273996) (xy 79.618868 -49.237245) (xy 79.660916 -49.206695) (xy 79.707226 -49.183099)
			(xy 79.756656 -49.167038) (xy 79.807991 -49.158908) (xy 79.859965 -49.158908) (xy 79.9113 -49.167038)
			(xy 79.96073 -49.183099) (xy 80.00704 -49.206695) (xy 80.049088 -49.237245) (xy 80.085839 -49.273996)
			(xy 80.116389 -49.316044) (xy 80.139985 -49.362354) (xy 80.156046 -49.411784) (xy 80.164176 -49.463119)
			(xy 80.164686 -49.489106) (xy 80.164176 -49.515093) (xy 80.156046 -49.566428) (xy 80.15443 -49.571402)
			(xy 80.911698 -49.571402) (xy 80.915769 -49.51578) (xy 80.927895 -49.461343) (xy 80.947818 -49.409252)
			(xy 80.975114 -49.360617) (xy 81.0092 -49.316474) (xy 81.049349 -49.277765) (xy 81.094707 -49.245314)
			(xy 81.144307 -49.219813) (xy 81.197091 -49.201806) (xy 81.251934 -49.191676) (xy 81.307668 -49.189639)
			(xy 81.363105 -49.195739) (xy 81.417062 -49.209845) (xy 81.468391 -49.231657) (xy 81.515997 -49.260711)
			(xy 81.558865 -49.296386) (xy 81.596082 -49.337923) (xy 81.626855 -49.384436) (xy 81.650527 -49.434933)
			(xy 81.666595 -49.48834) (xy 81.674715 -49.543516) (xy 81.675224 -49.571402) (xy 81.674715 -49.599288)
			(xy 81.666595 -49.654464) (xy 81.650527 -49.707871) (xy 81.626855 -49.758368) (xy 81.596082 -49.804881)
			(xy 81.558865 -49.846418) (xy 81.515997 -49.882093) (xy 81.468391 -49.911147) (xy 81.417062 -49.932959)
			(xy 81.363105 -49.947065) (xy 81.307668 -49.953165) (xy 81.251934 -49.951128) (xy 81.197091 -49.940998)
			(xy 81.144307 -49.922991) (xy 81.094707 -49.89749) (xy 81.049349 -49.865039) (xy 81.0092 -49.82633)
			(xy 80.975114 -49.782187) (xy 80.947818 -49.733552) (xy 80.927895 -49.681461) (xy 80.915769 -49.627024)
			(xy 80.911698 -49.571402) (xy 80.15443 -49.571402) (xy 80.139985 -49.615858) (xy 80.116389 -49.662168)
			(xy 80.085839 -49.704216) (xy 80.049088 -49.740967) (xy 80.00704 -49.771517) (xy 79.96073 -49.795113)
			(xy 79.9113 -49.811174) (xy 79.859965 -49.819304) (xy 79.807991 -49.819304) (xy 79.756656 -49.811174)
			(xy 79.707226 -49.795113) (xy 79.660916 -49.771517) (xy 79.618868 -49.740967) (xy 79.582117 -49.704216)
			(xy 79.551567 -49.662168) (xy 79.527971 -49.615858) (xy 79.51191 -49.566428) (xy 79.50378 -49.515093)
			(xy 79.36433 -49.515093) (xy 79.3562 -49.566428) (xy 79.340139 -49.615858) (xy 79.316543 -49.662168)
			(xy 79.285993 -49.704216) (xy 79.249242 -49.740967) (xy 79.207194 -49.771517) (xy 79.160884 -49.795113)
			(xy 79.111454 -49.811174) (xy 79.060119 -49.819304) (xy 79.008145 -49.819304) (xy 78.95681 -49.811174)
			(xy 78.90738 -49.795113) (xy 78.86107 -49.771517) (xy 78.819022 -49.740967) (xy 78.782271 -49.704216)
			(xy 78.751721 -49.662168) (xy 78.728125 -49.615858) (xy 78.712064 -49.566428) (xy 78.703934 -49.515093)
			(xy 78.56423 -49.515093) (xy 78.5561 -49.566428) (xy 78.540039 -49.615858) (xy 78.516443 -49.662168)
			(xy 78.485893 -49.704216) (xy 78.449142 -49.740967) (xy 78.407094 -49.771517) (xy 78.360784 -49.795113)
			(xy 78.311354 -49.811174) (xy 78.260019 -49.819304) (xy 78.208045 -49.819304) (xy 78.15671 -49.811174)
			(xy 78.10728 -49.795113) (xy 78.06097 -49.771517) (xy 78.018922 -49.740967) (xy 77.982171 -49.704216)
			(xy 77.951621 -49.662168) (xy 77.928025 -49.615858) (xy 77.911964 -49.566428) (xy 77.903834 -49.515093)
			(xy 76.916242 -49.515093) (xy 76.930445 -49.561137) (xy 76.938388 -49.613841) (xy 76.938886 -49.64049)
			(xy 76.938388 -49.667139) (xy 76.930445 -49.719843) (xy 76.914735 -49.770773) (xy 76.891609 -49.818794)
			(xy 76.861585 -49.862831) (xy 76.825333 -49.901902) (xy 76.783662 -49.935133) (xy 76.737504 -49.961782)
			(xy 76.68789 -49.981254) (xy 76.635928 -49.993114) (xy 76.582778 -49.997098) (xy 76.529628 -49.993114)
			(xy 76.477666 -49.981254) (xy 76.428052 -49.961782) (xy 76.381894 -49.935133) (xy 76.340223 -49.901902)
			(xy 76.303971 -49.862831) (xy 76.273947 -49.818794) (xy 76.250821 -49.770773) (xy 76.235111 -49.719843)
			(xy 76.227168 -49.667139) (xy 75.718083 -49.667139) (xy 75.747631 -49.688606) (xy 75.784388 -49.725363)
			(xy 75.814943 -49.767417) (xy 75.838542 -49.813733) (xy 75.854606 -49.863171) (xy 75.862737 -49.914513)
			(xy 75.862736 -49.966495) (xy 75.854604 -50.017837) (xy 75.838539 -50.067274) (xy 75.814939 -50.11359)
			(xy 75.784383 -50.155643) (xy 75.747625 -50.192399) (xy 75.70557 -50.222951) (xy 75.659252 -50.246549)
			(xy 75.609814 -50.262609) (xy 75.558471 -50.270738) (xy 75.506489 -50.270735) (xy 75.455148 -50.2626)
			(xy 75.405711 -50.246533) (xy 75.359396 -50.22293) (xy 75.317344 -50.192373) (xy 75.280591 -50.155613)
			(xy 75.25004 -50.113556) (xy 75.226445 -50.067237) (xy 75.210387 -50.017798) (xy 75.20226 -49.966455)
			(xy 75.20178 -49.940464) (xy 75.202288 -49.921922) (xy 75.202645 -49.906786) (xy 75.195475 -49.877387)
			(xy 75.18 -49.851382) (xy 75.15758 -49.831058) (xy 75.130186 -49.818201) (xy 75.100226 -49.813942)
			(xy 75.085194 -49.81575) (xy 75.072515 -49.817644) (xy 75.046959 -49.819676) (xy 75.03414 -49.819814)
			(xy 75.008147 -49.819368) (xy 74.9568 -49.811241) (xy 74.907356 -49.795182) (xy 74.861033 -49.771586)
			(xy 74.818972 -49.741033) (xy 74.782209 -49.704277) (xy 74.751648 -49.662222) (xy 74.728043 -49.615904)
			(xy 74.711974 -49.566463) (xy 74.703837 -49.515118) (xy 74.703833 -49.463131) (xy 74.595023 -49.463131)
			(xy 74.600814 -49.499695) (xy 74.601324 -49.525682) (xy 74.600864 -49.551335) (xy 74.592949 -49.602028)
			(xy 74.577305 -49.650892) (xy 74.554308 -49.696756) (xy 74.524508 -49.738521) (xy 74.48862 -49.775187)
			(xy 74.447503 -49.805876) (xy 74.425048 -49.81829) (xy 74.413211 -49.825009) (xy 74.393365 -49.843624)
			(xy 74.37915 -49.866825) (xy 74.37158 -49.892961) (xy 74.371193 -49.920168) (xy 74.378017 -49.946508)
			(xy 74.391567 -49.970104) (xy 74.410876 -49.989275) (xy 74.422508 -49.996344) (xy 74.444021 -50.009028)
			(xy 74.483281 -50.039893) (xy 74.517461 -50.076303) (xy 74.545785 -50.117433) (xy 74.56761 -50.162351)
			(xy 74.582443 -50.210037) (xy 74.589946 -50.25941) (xy 74.590402 -50.28438) (xy 74.589892 -50.310367)
			(xy 74.583335 -50.351769) (xy 77.903834 -50.351769) (xy 77.903834 -50.299795) (xy 77.911964 -50.24846)
			(xy 77.928025 -50.19903) (xy 77.951621 -50.15272) (xy 77.982171 -50.110672) (xy 78.018922 -50.073921)
			(xy 78.06097 -50.043371) (xy 78.10728 -50.019775) (xy 78.15671 -50.003714) (xy 78.208045 -49.995584)
			(xy 78.260019 -49.995584) (xy 78.311354 -50.003714) (xy 78.360784 -50.019775) (xy 78.407094 -50.043371)
			(xy 78.449142 -50.073921) (xy 78.485893 -50.110672) (xy 78.516443 -50.15272) (xy 78.540039 -50.19903)
			(xy 78.5561 -50.24846) (xy 78.56423 -50.299795) (xy 78.564532 -50.315193) (xy 78.703934 -50.315193)
			(xy 78.703934 -50.263219) (xy 78.712064 -50.211884) (xy 78.728125 -50.162454) (xy 78.751721 -50.116144)
			(xy 78.782271 -50.074096) (xy 78.819022 -50.037345) (xy 78.86107 -50.006795) (xy 78.90738 -49.983199)
			(xy 78.95681 -49.967138) (xy 79.008145 -49.959008) (xy 79.060119 -49.959008) (xy 79.111454 -49.967138)
			(xy 79.160884 -49.983199) (xy 79.207194 -50.006795) (xy 79.249242 -50.037345) (xy 79.285993 -50.074096)
			(xy 79.316543 -50.116144) (xy 79.340139 -50.162454) (xy 79.3562 -50.211884) (xy 79.36433 -50.263219)
			(xy 79.36484 -50.289206) (xy 79.36433 -50.315193) (xy 79.50378 -50.315193) (xy 79.50378 -50.263219)
			(xy 79.51191 -50.211884) (xy 79.527971 -50.162454) (xy 79.551567 -50.116144) (xy 79.582117 -50.074096)
			(xy 79.618868 -50.037345) (xy 79.660916 -50.006795) (xy 79.707226 -49.983199) (xy 79.756656 -49.967138)
			(xy 79.807991 -49.959008) (xy 79.859965 -49.959008) (xy 79.9113 -49.967138) (xy 79.96073 -49.983199)
			(xy 80.00704 -50.006795) (xy 80.049088 -50.037345) (xy 80.085839 -50.074096) (xy 80.116389 -50.116144)
			(xy 80.139985 -50.162454) (xy 80.156046 -50.211884) (xy 80.164176 -50.263219) (xy 80.164686 -50.289206)
			(xy 80.164176 -50.315193) (xy 80.156046 -50.366528) (xy 80.139985 -50.415958) (xy 80.116389 -50.462268)
			(xy 80.085839 -50.504316) (xy 80.049088 -50.541067) (xy 80.00704 -50.571617) (xy 79.96073 -50.595213)
			(xy 79.9113 -50.611274) (xy 79.859965 -50.619404) (xy 79.807991 -50.619404) (xy 79.756656 -50.611274)
			(xy 79.707226 -50.595213) (xy 79.660916 -50.571617) (xy 79.618868 -50.541067) (xy 79.582117 -50.504316)
			(xy 79.551567 -50.462268) (xy 79.527971 -50.415958) (xy 79.51191 -50.366528) (xy 79.50378 -50.315193)
			(xy 79.36433 -50.315193) (xy 79.3562 -50.366528) (xy 79.340139 -50.415958) (xy 79.316543 -50.462268)
			(xy 79.285993 -50.504316) (xy 79.249242 -50.541067) (xy 79.207194 -50.571617) (xy 79.160884 -50.595213)
			(xy 79.111454 -50.611274) (xy 79.060119 -50.619404) (xy 79.008145 -50.619404) (xy 78.95681 -50.611274)
			(xy 78.90738 -50.595213) (xy 78.86107 -50.571617) (xy 78.819022 -50.541067) (xy 78.782271 -50.504316)
			(xy 78.751721 -50.462268) (xy 78.728125 -50.415958) (xy 78.712064 -50.366528) (xy 78.703934 -50.315193)
			(xy 78.564532 -50.315193) (xy 78.56474 -50.325782) (xy 78.56423 -50.351769) (xy 78.5561 -50.403104)
			(xy 78.540039 -50.452534) (xy 78.516443 -50.498844) (xy 78.485893 -50.540892) (xy 78.449142 -50.577643)
			(xy 78.407094 -50.608193) (xy 78.360784 -50.631789) (xy 78.311354 -50.64785) (xy 78.260019 -50.65598)
			(xy 78.208045 -50.65598) (xy 78.15671 -50.64785) (xy 78.10728 -50.631789) (xy 78.06097 -50.608193)
			(xy 78.018922 -50.577643) (xy 77.982171 -50.540892) (xy 77.951621 -50.498844) (xy 77.928025 -50.452534)
			(xy 77.911964 -50.403104) (xy 77.903834 -50.351769) (xy 74.583335 -50.351769) (xy 74.581762 -50.361702)
			(xy 74.565701 -50.411132) (xy 74.542105 -50.457442) (xy 74.511555 -50.49949) (xy 74.474804 -50.536241)
			(xy 74.432756 -50.566791) (xy 74.386446 -50.590387) (xy 74.337016 -50.606448) (xy 74.285681 -50.614578)
			(xy 74.233707 -50.614578) (xy 74.182372 -50.606448) (xy 74.132942 -50.590387) (xy 74.086632 -50.566791)
			(xy 74.044584 -50.536241) (xy 74.007833 -50.49949) (xy 73.977283 -50.457442) (xy 73.953687 -50.411132)
			(xy 73.937626 -50.361702) (xy 73.929496 -50.310367) (xy 73.928986 -50.28438) (xy 73.801129 -50.28438)
			(xy 73.801224 -50.289206) (xy 73.800714 -50.315193) (xy 73.792584 -50.366528) (xy 73.776523 -50.415958)
			(xy 73.752927 -50.462268) (xy 73.722377 -50.504316) (xy 73.685626 -50.541067) (xy 73.643578 -50.571617)
			(xy 73.597268 -50.595213) (xy 73.547838 -50.611274) (xy 73.496503 -50.619404) (xy 73.444529 -50.619404)
			(xy 73.393194 -50.611274) (xy 73.343764 -50.595213) (xy 73.297454 -50.571617) (xy 73.255406 -50.541067)
			(xy 73.218655 -50.504316) (xy 73.188105 -50.462268) (xy 73.164509 -50.415958) (xy 73.148448 -50.366528)
			(xy 73.140318 -50.315193) (xy 73.000868 -50.315193) (xy 72.992738 -50.366528) (xy 72.976677 -50.415958)
			(xy 72.953081 -50.462268) (xy 72.922531 -50.504316) (xy 72.88578 -50.541067) (xy 72.843732 -50.571617)
			(xy 72.797422 -50.595213) (xy 72.747992 -50.611274) (xy 72.696657 -50.619404) (xy 72.644683 -50.619404)
			(xy 72.593348 -50.611274) (xy 72.543918 -50.595213) (xy 72.497608 -50.571617) (xy 72.45556 -50.541067)
			(xy 72.418809 -50.504316) (xy 72.388259 -50.462268) (xy 72.364663 -50.415958) (xy 72.348602 -50.366528)
			(xy 72.340472 -50.315193) (xy 71.733664 -50.315193) (xy 71.733664 -50.804064) (xy 72.044893 -51.115293)
			(xy 72.340472 -51.115293) (xy 72.340472 -51.063319) (xy 72.348602 -51.011984) (xy 72.364663 -50.962554)
			(xy 72.388259 -50.916244) (xy 72.418809 -50.874196) (xy 72.45556 -50.837445) (xy 72.497608 -50.806895)
			(xy 72.543918 -50.783299) (xy 72.593348 -50.767238) (xy 72.644683 -50.759108) (xy 72.696657 -50.759108)
			(xy 72.747992 -50.767238) (xy 72.797422 -50.783299) (xy 72.843732 -50.806895) (xy 72.88578 -50.837445)
			(xy 72.922531 -50.874196) (xy 72.953081 -50.916244) (xy 72.976677 -50.962554) (xy 72.992738 -51.011984)
			(xy 73.000868 -51.063319) (xy 73.001378 -51.089306) (xy 73.000868 -51.115293) (xy 73.140318 -51.115293)
			(xy 73.140318 -51.063319) (xy 73.148448 -51.011984) (xy 73.164509 -50.962554) (xy 73.188105 -50.916244)
			(xy 73.218655 -50.874196) (xy 73.255406 -50.837445) (xy 73.297454 -50.806895) (xy 73.343764 -50.783299)
			(xy 73.393194 -50.767238) (xy 73.444529 -50.759108) (xy 73.496503 -50.759108) (xy 73.547838 -50.767238)
			(xy 73.597268 -50.783299) (xy 73.643578 -50.806895) (xy 73.685626 -50.837445) (xy 73.722377 -50.874196)
			(xy 73.752927 -50.916244) (xy 73.776523 -50.962554) (xy 73.792584 -51.011984) (xy 73.800714 -51.063319)
			(xy 73.801224 -51.089306) (xy 73.800714 -51.115293) (xy 73.794962 -51.151615) (xy 73.940418 -51.151615)
			(xy 73.940418 -51.099641) (xy 73.948548 -51.048306) (xy 73.964609 -50.998876) (xy 73.988205 -50.952566)
			(xy 74.018755 -50.910518) (xy 74.055506 -50.873767) (xy 74.097554 -50.843217) (xy 74.143864 -50.819621)
			(xy 74.193294 -50.80356) (xy 74.244629 -50.79543) (xy 74.296603 -50.79543) (xy 74.347938 -50.80356)
			(xy 74.397368 -50.819621) (xy 74.443678 -50.843217) (xy 74.485726 -50.873767) (xy 74.522477 -50.910518)
			(xy 74.553027 -50.952566) (xy 74.576623 -50.998876) (xy 74.592684 -51.048306) (xy 74.600814 -51.099641)
			(xy 74.601324 -51.125628) (xy 74.600814 -51.151615) (xy 74.598722 -51.164823) (xy 75.78522 -51.164823)
			(xy 75.78522 -51.112849) (xy 75.79335 -51.061514) (xy 75.809411 -51.012084) (xy 75.833007 -50.965774)
			(xy 75.863557 -50.923726) (xy 75.900308 -50.886975) (xy 75.942356 -50.856425) (xy 75.988666 -50.832829)
			(xy 76.038096 -50.816768) (xy 76.089431 -50.808638) (xy 76.141405 -50.808638) (xy 76.19274 -50.816768)
			(xy 76.24217 -50.832829) (xy 76.28848 -50.856425) (xy 76.330528 -50.886975) (xy 76.367279 -50.923726)
			(xy 76.397829 -50.965774) (xy 76.421425 -51.012084) (xy 76.437486 -51.061514) (xy 76.445616 -51.112849)
			(xy 76.445664 -51.115293) (xy 78.703934 -51.115293) (xy 78.703934 -51.063319) (xy 78.712064 -51.011984)
			(xy 78.728125 -50.962554) (xy 78.751721 -50.916244) (xy 78.782271 -50.874196) (xy 78.819022 -50.837445)
			(xy 78.86107 -50.806895) (xy 78.90738 -50.783299) (xy 78.95681 -50.767238) (xy 79.008145 -50.759108)
			(xy 79.060119 -50.759108) (xy 79.111454 -50.767238) (xy 79.160884 -50.783299) (xy 79.207194 -50.806895)
			(xy 79.249242 -50.837445) (xy 79.285993 -50.874196) (xy 79.316543 -50.916244) (xy 79.340139 -50.962554)
			(xy 79.3562 -51.011984) (xy 79.36433 -51.063319) (xy 79.36484 -51.089306) (xy 79.36433 -51.115293)
			(xy 79.50378 -51.115293) (xy 79.50378 -51.063319) (xy 79.51191 -51.011984) (xy 79.527971 -50.962554)
			(xy 79.551567 -50.916244) (xy 79.582117 -50.874196) (xy 79.618868 -50.837445) (xy 79.660916 -50.806895)
			(xy 79.707226 -50.783299) (xy 79.756656 -50.767238) (xy 79.807991 -50.759108) (xy 79.859965 -50.759108)
			(xy 79.9113 -50.767238) (xy 79.96073 -50.783299) (xy 80.00704 -50.806895) (xy 80.049088 -50.837445)
			(xy 80.085839 -50.874196) (xy 80.116389 -50.916244) (xy 80.139985 -50.962554) (xy 80.156046 -51.011984)
			(xy 80.164176 -51.063319) (xy 80.164686 -51.089306) (xy 80.164681 -51.08956) (xy 80.797146 -51.08956)
			(xy 80.797615 -51.060789) (xy 80.806243 -51.003898) (xy 80.823313 -50.948946) (xy 80.848438 -50.89718)
			(xy 80.881048 -50.849771) (xy 80.920405 -50.807794) (xy 80.942688 -50.789586) (xy 80.953994 -50.780153)
			(xy 80.97103 -50.756151) (xy 80.980494 -50.72828) (xy 80.981595 -50.698867) (xy 80.974243 -50.670367)
			(xy 80.967072 -50.657506) (xy 80.954061 -50.635105) (xy 80.933544 -50.587537) (xy 80.919652 -50.537631)
			(xy 80.912642 -50.486304) (xy 80.912208 -50.460402) (xy 80.912694 -50.433151) (xy 80.92045 -50.379203)
			(xy 80.935805 -50.326908) (xy 80.958447 -50.277331) (xy 80.987913 -50.231481) (xy 81.023604 -50.19029)
			(xy 81.064795 -50.154599) (xy 81.110645 -50.125133) (xy 81.160222 -50.102491) (xy 81.212517 -50.087136)
			(xy 81.266465 -50.07938) (xy 81.320967 -50.07938) (xy 81.374915 -50.087136) (xy 81.42721 -50.102491)
			(xy 81.476787 -50.125133) (xy 81.522637 -50.154599) (xy 81.563828 -50.19029) (xy 81.599519 -50.231481)
			(xy 81.628985 -50.277331) (xy 81.651627 -50.326908) (xy 81.666982 -50.379203) (xy 81.674738 -50.433151)
			(xy 81.675224 -50.460402) (xy 81.674701 -50.489171) (xy 81.666081 -50.546058) (xy 81.64902 -50.601007)
			(xy 81.623905 -50.652774) (xy 81.591305 -50.700184) (xy 81.551959 -50.742165) (xy 81.529682 -50.760376)
			(xy 81.518405 -50.76984) (xy 81.501371 -50.793834) (xy 81.491905 -50.821695) (xy 81.490795 -50.8511)
			(xy 81.498134 -50.879595) (xy 81.505298 -50.892456) (xy 81.518291 -50.914867) (xy 81.538813 -50.962431)
			(xy 81.55271 -51.012334) (xy 81.559725 -51.063659) (xy 81.560162 -51.08956) (xy 81.559676 -51.116811)
			(xy 81.55192 -51.170759) (xy 81.536565 -51.223054) (xy 81.513923 -51.272631) (xy 81.484457 -51.318481)
			(xy 81.448766 -51.359672) (xy 81.407575 -51.395363) (xy 81.361725 -51.424829) (xy 81.312148 -51.447471)
			(xy 81.259853 -51.462826) (xy 81.205905 -51.470582) (xy 81.151403 -51.470582) (xy 81.097455 -51.462826)
			(xy 81.04516 -51.447471) (xy 80.995583 -51.424829) (xy 80.949733 -51.395363) (xy 80.908542 -51.359672)
			(xy 80.872851 -51.318481) (xy 80.843385 -51.272631) (xy 80.820743 -51.223054) (xy 80.805388 -51.170759)
			(xy 80.797632 -51.116811) (xy 80.797146 -51.08956) (xy 80.164681 -51.08956) (xy 80.164176 -51.115293)
			(xy 80.156046 -51.166628) (xy 80.139985 -51.216058) (xy 80.116389 -51.262368) (xy 80.085839 -51.304416)
			(xy 80.049088 -51.341167) (xy 80.00704 -51.371717) (xy 79.96073 -51.395313) (xy 79.9113 -51.411374)
			(xy 79.859965 -51.419504) (xy 79.807991 -51.419504) (xy 79.756656 -51.411374) (xy 79.707226 -51.395313)
			(xy 79.660916 -51.371717) (xy 79.618868 -51.341167) (xy 79.582117 -51.304416) (xy 79.551567 -51.262368)
			(xy 79.527971 -51.216058) (xy 79.51191 -51.166628) (xy 79.50378 -51.115293) (xy 79.36433 -51.115293)
			(xy 79.3562 -51.166628) (xy 79.340139 -51.216058) (xy 79.316543 -51.262368) (xy 79.285993 -51.304416)
			(xy 79.249242 -51.341167) (xy 79.207194 -51.371717) (xy 79.160884 -51.395313) (xy 79.111454 -51.411374)
			(xy 79.060119 -51.419504) (xy 79.008145 -51.419504) (xy 78.95681 -51.411374) (xy 78.90738 -51.395313)
			(xy 78.86107 -51.371717) (xy 78.819022 -51.341167) (xy 78.782271 -51.304416) (xy 78.751721 -51.262368)
			(xy 78.728125 -51.216058) (xy 78.712064 -51.166628) (xy 78.703934 -51.115293) (xy 76.445664 -51.115293)
			(xy 76.446126 -51.138836) (xy 76.445616 -51.164823) (xy 76.437486 -51.216158) (xy 76.421425 -51.265588)
			(xy 76.397829 -51.311898) (xy 76.367279 -51.353946) (xy 76.330528 -51.390697) (xy 76.28848 -51.421247)
			(xy 76.24217 -51.444843) (xy 76.19274 -51.460904) (xy 76.141405 -51.469034) (xy 76.089431 -51.469034)
			(xy 76.038096 -51.460904) (xy 75.988666 -51.444843) (xy 75.942356 -51.421247) (xy 75.900308 -51.390697)
			(xy 75.863557 -51.353946) (xy 75.833007 -51.311898) (xy 75.809411 -51.265588) (xy 75.79335 -51.216158)
			(xy 75.78522 -51.164823) (xy 74.598722 -51.164823) (xy 74.592684 -51.20295) (xy 74.576623 -51.25238)
			(xy 74.553027 -51.29869) (xy 74.522477 -51.340738) (xy 74.485726 -51.377489) (xy 74.443678 -51.408039)
			(xy 74.397368 -51.431635) (xy 74.347938 -51.447696) (xy 74.296603 -51.455826) (xy 74.244629 -51.455826)
			(xy 74.193294 -51.447696) (xy 74.143864 -51.431635) (xy 74.097554 -51.408039) (xy 74.055506 -51.377489)
			(xy 74.018755 -51.340738) (xy 73.988205 -51.29869) (xy 73.964609 -51.25238) (xy 73.948548 -51.20295)
			(xy 73.940418 -51.151615) (xy 73.794962 -51.151615) (xy 73.792584 -51.166628) (xy 73.776523 -51.216058)
			(xy 73.752927 -51.262368) (xy 73.722377 -51.304416) (xy 73.685626 -51.341167) (xy 73.643578 -51.371717)
			(xy 73.597268 -51.395313) (xy 73.547838 -51.411374) (xy 73.496503 -51.419504) (xy 73.444529 -51.419504)
			(xy 73.393194 -51.411374) (xy 73.343764 -51.395313) (xy 73.297454 -51.371717) (xy 73.255406 -51.341167)
			(xy 73.218655 -51.304416) (xy 73.188105 -51.262368) (xy 73.164509 -51.216058) (xy 73.148448 -51.166628)
			(xy 73.140318 -51.115293) (xy 73.000868 -51.115293) (xy 72.992738 -51.166628) (xy 72.976677 -51.216058)
			(xy 72.953081 -51.262368) (xy 72.922531 -51.304416) (xy 72.88578 -51.341167) (xy 72.843732 -51.371717)
			(xy 72.797422 -51.395313) (xy 72.747992 -51.411374) (xy 72.696657 -51.419504) (xy 72.644683 -51.419504)
			(xy 72.593348 -51.411374) (xy 72.543918 -51.395313) (xy 72.497608 -51.371717) (xy 72.45556 -51.341167)
			(xy 72.418809 -51.304416) (xy 72.388259 -51.262368) (xy 72.364663 -51.216058) (xy 72.348602 -51.166628)
			(xy 72.340472 -51.115293) (xy 72.044893 -51.115293) (xy 72.521572 -51.591972) (xy 72.55256 -51.580288)
			(xy 72.581025 -51.570125) (xy 72.640453 -51.559137) (xy 72.67067 -51.558444) (xy 72.696306 -51.558932)
			(xy 72.746962 -51.566857) (xy 72.795787 -51.582506) (xy 72.841612 -51.605504) (xy 72.883338 -51.6353)
			(xy 72.919964 -51.67118) (xy 72.950613 -51.712283) (xy 72.963024 -51.73472) (xy 72.969768 -51.746568)
			(xy 72.988409 -51.766449) (xy 73.011645 -51.78069) (xy 73.03782 -51.788276) (xy 73.06507 -51.788668)
			(xy 73.091453 -51.781837) (xy 73.115089 -51.76827) (xy 73.134293 -51.748934) (xy 73.141332 -51.73726)
			(xy 73.154016 -51.715765) (xy 73.184839 -51.676512) (xy 73.221207 -51.642334) (xy 73.262296 -51.614006)
			(xy 73.307174 -51.59217) (xy 73.354822 -51.577321) (xy 73.40416 -51.569798) (xy 73.429114 -51.569366)
			(xy 73.455101 -51.569877) (xy 73.506436 -51.578009) (xy 73.555866 -51.594071) (xy 73.602175 -51.617667)
			(xy 73.644224 -51.648216) (xy 73.680976 -51.684967) (xy 73.711527 -51.727014) (xy 73.735125 -51.773323)
			(xy 73.751188 -51.822753) (xy 73.759322 -51.874087) (xy 73.759822 -51.900074) (xy 73.7593 -51.926931)
			(xy 73.755242 -51.951715) (xy 77.14031 -51.951715) (xy 77.14031 -51.899741) (xy 77.14844 -51.848406)
			(xy 77.164501 -51.798976) (xy 77.188097 -51.752666) (xy 77.218647 -51.710618) (xy 77.255398 -51.673867)
			(xy 77.297446 -51.643317) (xy 77.343756 -51.619721) (xy 77.393186 -51.60366) (xy 77.444521 -51.59553)
			(xy 77.496495 -51.59553) (xy 77.54783 -51.60366) (xy 77.59726 -51.619721) (xy 77.64357 -51.643317)
			(xy 77.685618 -51.673867) (xy 77.722369 -51.710618) (xy 77.752919 -51.752666) (xy 77.776515 -51.798976)
			(xy 77.792576 -51.848406) (xy 77.800706 -51.899741) (xy 77.801216 -51.925728) (xy 77.800706 -51.951715)
			(xy 77.94041 -51.951715) (xy 77.94041 -51.899741) (xy 77.94854 -51.848406) (xy 77.964601 -51.798976)
			(xy 77.988197 -51.752666) (xy 78.018747 -51.710618) (xy 78.055498 -51.673867) (xy 78.097546 -51.643317)
			(xy 78.143856 -51.619721) (xy 78.193286 -51.60366) (xy 78.244621 -51.59553) (xy 78.296595 -51.59553)
			(xy 78.34793 -51.60366) (xy 78.39736 -51.619721) (xy 78.44367 -51.643317) (xy 78.485718 -51.673867)
			(xy 78.522469 -51.710618) (xy 78.553019 -51.752666) (xy 78.576615 -51.798976) (xy 78.592676 -51.848406)
			(xy 78.600806 -51.899741) (xy 78.601108 -51.915139) (xy 78.703934 -51.915139) (xy 78.703934 -51.863165)
			(xy 78.712064 -51.81183) (xy 78.728125 -51.7624) (xy 78.751721 -51.71609) (xy 78.782271 -51.674042)
			(xy 78.819022 -51.637291) (xy 78.86107 -51.606741) (xy 78.90738 -51.583145) (xy 78.95681 -51.567084)
			(xy 79.008145 -51.558954) (xy 79.060119 -51.558954) (xy 79.111454 -51.567084) (xy 79.160884 -51.583145)
			(xy 79.207194 -51.606741) (xy 79.249242 -51.637291) (xy 79.285993 -51.674042) (xy 79.316543 -51.71609)
			(xy 79.340139 -51.7624) (xy 79.3562 -51.81183) (xy 79.36433 -51.863165) (xy 79.36484 -51.889152)
			(xy 79.36433 -51.915139) (xy 79.50378 -51.915139) (xy 79.50378 -51.863165) (xy 79.51191 -51.81183)
			(xy 79.527971 -51.7624) (xy 79.551567 -51.71609) (xy 79.582117 -51.674042) (xy 79.618868 -51.637291)
			(xy 79.660916 -51.606741) (xy 79.707226 -51.583145) (xy 79.756656 -51.567084) (xy 79.807991 -51.558954)
			(xy 79.859965 -51.558954) (xy 79.9113 -51.567084) (xy 79.96073 -51.583145) (xy 80.00704 -51.606741)
			(xy 80.049088 -51.637291) (xy 80.085839 -51.674042) (xy 80.116389 -51.71609) (xy 80.139985 -51.7624)
			(xy 80.156046 -51.81183) (xy 80.164176 -51.863165) (xy 80.164686 -51.889152) (xy 80.164176 -51.915139)
			(xy 80.156046 -51.966474) (xy 80.139985 -52.015904) (xy 80.116389 -52.062214) (xy 80.085839 -52.104262)
			(xy 80.049088 -52.141013) (xy 80.00704 -52.171563) (xy 79.96073 -52.195159) (xy 79.9113 -52.21122)
			(xy 79.859965 -52.21935) (xy 79.807991 -52.21935) (xy 79.756656 -52.21122) (xy 79.707226 -52.195159)
			(xy 79.660916 -52.171563) (xy 79.618868 -52.141013) (xy 79.582117 -52.104262) (xy 79.551567 -52.062214)
			(xy 79.527971 -52.015904) (xy 79.51191 -51.966474) (xy 79.50378 -51.915139) (xy 79.36433 -51.915139)
			(xy 79.3562 -51.966474) (xy 79.340139 -52.015904) (xy 79.316543 -52.062214) (xy 79.285993 -52.104262)
			(xy 79.249242 -52.141013) (xy 79.207194 -52.171563) (xy 79.160884 -52.195159) (xy 79.111454 -52.21122)
			(xy 79.060119 -52.21935) (xy 79.008145 -52.21935) (xy 78.95681 -52.21122) (xy 78.90738 -52.195159)
			(xy 78.86107 -52.171563) (xy 78.819022 -52.141013) (xy 78.782271 -52.104262) (xy 78.751721 -52.062214)
			(xy 78.728125 -52.015904) (xy 78.712064 -51.966474) (xy 78.703934 -51.915139) (xy 78.601108 -51.915139)
			(xy 78.601316 -51.925728) (xy 78.600806 -51.951715) (xy 78.592676 -52.00305) (xy 78.576615 -52.05248)
			(xy 78.553019 -52.09879) (xy 78.522469 -52.140838) (xy 78.485718 -52.177589) (xy 78.44367 -52.208139)
			(xy 78.39736 -52.231735) (xy 78.34793 -52.247796) (xy 78.296595 -52.255926) (xy 78.244621 -52.255926)
			(xy 78.193286 -52.247796) (xy 78.143856 -52.231735) (xy 78.097546 -52.208139) (xy 78.055498 -52.177589)
			(xy 78.018747 -52.140838) (xy 77.988197 -52.09879) (xy 77.964601 -52.05248) (xy 77.94854 -52.00305)
			(xy 77.94041 -51.951715) (xy 77.800706 -51.951715) (xy 77.792576 -52.00305) (xy 77.776515 -52.05248)
			(xy 77.752919 -52.09879) (xy 77.722369 -52.140838) (xy 77.685618 -52.177589) (xy 77.64357 -52.208139)
			(xy 77.59726 -52.231735) (xy 77.54783 -52.247796) (xy 77.496495 -52.255926) (xy 77.444521 -52.255926)
			(xy 77.393186 -52.247796) (xy 77.343756 -52.231735) (xy 77.297446 -52.208139) (xy 77.255398 -52.177589)
			(xy 77.218647 -52.140838) (xy 77.188097 -52.09879) (xy 77.164501 -52.05248) (xy 77.14844 -52.00305)
			(xy 77.14031 -51.951715) (xy 73.755242 -51.951715) (xy 73.750621 -51.97994) (xy 73.733487 -52.030849)
			(xy 73.708349 -52.078318) (xy 73.675868 -52.121099) (xy 73.636899 -52.158067) (xy 73.592466 -52.188249)
			(xy 73.543738 -52.210852) (xy 73.518014 -52.21859) (xy 73.50358 -52.223217) (xy 73.47809 -52.239591)
			(xy 73.458516 -52.262715) (xy 73.446576 -52.290558) (xy 73.443316 -52.320678) (xy 73.449024 -52.350431)
			(xy 73.463198 -52.377207) (xy 73.473564 -52.388262) (xy 73.800678 -52.715239) (xy 77.903834 -52.715239)
			(xy 77.903834 -52.663265) (xy 77.911964 -52.61193) (xy 77.928025 -52.5625) (xy 77.951621 -52.51619)
			(xy 77.982171 -52.474142) (xy 78.018922 -52.437391) (xy 78.06097 -52.406841) (xy 78.10728 -52.383245)
			(xy 78.15671 -52.367184) (xy 78.208045 -52.359054) (xy 78.260019 -52.359054) (xy 78.311354 -52.367184)
			(xy 78.360784 -52.383245) (xy 78.407094 -52.406841) (xy 78.449142 -52.437391) (xy 78.485893 -52.474142)
			(xy 78.516443 -52.51619) (xy 78.540039 -52.5625) (xy 78.5561 -52.61193) (xy 78.56423 -52.663265)
			(xy 78.56474 -52.689252) (xy 78.56423 -52.715239) (xy 79.50378 -52.715239) (xy 79.50378 -52.663265)
			(xy 79.51191 -52.61193) (xy 79.527971 -52.5625) (xy 79.551567 -52.51619) (xy 79.582117 -52.474142)
			(xy 79.618868 -52.437391) (xy 79.660916 -52.406841) (xy 79.707226 -52.383245) (xy 79.756656 -52.367184)
			(xy 79.807991 -52.359054) (xy 79.859965 -52.359054) (xy 79.9113 -52.367184) (xy 79.96073 -52.383245)
			(xy 80.00704 -52.406841) (xy 80.049088 -52.437391) (xy 80.085839 -52.474142) (xy 80.116389 -52.51619)
			(xy 80.139985 -52.5625) (xy 80.156046 -52.61193) (xy 80.164176 -52.663265) (xy 80.164686 -52.689252)
			(xy 80.164176 -52.715239) (xy 80.156046 -52.766574) (xy 80.139985 -52.816004) (xy 80.116389 -52.862314)
			(xy 80.085839 -52.904362) (xy 80.049088 -52.941113) (xy 80.00704 -52.971663) (xy 79.96073 -52.995259)
			(xy 79.9113 -53.01132) (xy 79.859965 -53.01945) (xy 79.807991 -53.01945) (xy 79.756656 -53.01132)
			(xy 79.707226 -52.995259) (xy 79.660916 -52.971663) (xy 79.618868 -52.941113) (xy 79.582117 -52.904362)
			(xy 79.551567 -52.862314) (xy 79.527971 -52.816004) (xy 79.51191 -52.766574) (xy 79.50378 -52.715239)
			(xy 78.56423 -52.715239) (xy 78.5561 -52.766574) (xy 78.540039 -52.816004) (xy 78.516443 -52.862314)
			(xy 78.485893 -52.904362) (xy 78.449142 -52.941113) (xy 78.407094 -52.971663) (xy 78.360784 -52.995259)
			(xy 78.311354 -53.01132) (xy 78.260019 -53.01945) (xy 78.208045 -53.01945) (xy 78.15671 -53.01132)
			(xy 78.10728 -52.995259) (xy 78.06097 -52.971663) (xy 78.018922 -52.941113) (xy 77.982171 -52.904362)
			(xy 77.951621 -52.862314) (xy 77.928025 -52.816004) (xy 77.911964 -52.766574) (xy 77.903834 -52.715239)
			(xy 73.800678 -52.715239) (xy 74.080878 -52.995322) (xy 74.098726 -53.01395) (xy 74.128557 -53.056036)
			(xy 74.150939 -53.102514) (xy 74.158602 -53.127148) (xy 74.161574 -53.135923) (xy 74.172727 -53.150697)
			(xy 74.188409 -53.160534) (xy 74.206565 -53.164145) (xy 74.215752 -53.162962) (xy 74.229366 -53.160816)
			(xy 74.256834 -53.15853) (xy 74.270616 -53.15839) (xy 74.296602 -53.158901) (xy 74.347935 -53.167033)
			(xy 74.397364 -53.183096) (xy 74.443671 -53.206692) (xy 74.485717 -53.237242) (xy 74.522467 -53.273993)
			(xy 74.553015 -53.316041) (xy 74.57661 -53.362349) (xy 74.59267 -53.411779) (xy 74.6008 -53.463112)
			(xy 74.601324 -53.489098) (xy 74.600749 -53.515085) (xy 74.703942 -53.515085) (xy 74.703942 -53.463111)
			(xy 74.712072 -53.411776) (xy 74.728133 -53.362346) (xy 74.751729 -53.316036) (xy 74.782279 -53.273988)
			(xy 74.81903 -53.237237) (xy 74.861078 -53.206687) (xy 74.907388 -53.183091) (xy 74.956818 -53.16703)
			(xy 75.008153 -53.1589) (xy 75.060127 -53.1589) (xy 75.111462 -53.16703) (xy 75.160892 -53.183091)
			(xy 75.207202 -53.206687) (xy 75.24925 -53.237237) (xy 75.286001 -53.273988) (xy 75.316551 -53.316036)
			(xy 75.340147 -53.362346) (xy 75.356208 -53.411776) (xy 75.364338 -53.463111) (xy 75.36481 -53.487145)
			(xy 75.543158 -53.487145) (xy 75.543158 -53.435171) (xy 75.551288 -53.383836) (xy 75.567349 -53.334406)
			(xy 75.590945 -53.288096) (xy 75.621495 -53.246048) (xy 75.658246 -53.209297) (xy 75.700294 -53.178747)
			(xy 75.746604 -53.155151) (xy 75.796034 -53.13909) (xy 75.847369 -53.13096) (xy 75.899343 -53.13096)
			(xy 75.950678 -53.13909) (xy 76.000108 -53.155151) (xy 76.046418 -53.178747) (xy 76.088466 -53.209297)
			(xy 76.125217 -53.246048) (xy 76.155767 -53.288096) (xy 76.179363 -53.334406) (xy 76.195424 -53.383836)
			(xy 76.203554 -53.435171) (xy 76.204064 -53.461158) (xy 76.203554 -53.487145) (xy 76.195424 -53.53848)
			(xy 76.179363 -53.58791) (xy 76.155767 -53.63422) (xy 76.125217 -53.676268) (xy 76.088466 -53.713019)
			(xy 76.046418 -53.743569) (xy 76.000108 -53.767165) (xy 75.950678 -53.783226) (xy 75.899343 -53.791356)
			(xy 75.847369 -53.791356) (xy 75.796034 -53.783226) (xy 75.746604 -53.767165) (xy 75.700294 -53.743569)
			(xy 75.658246 -53.713019) (xy 75.621495 -53.676268) (xy 75.590945 -53.63422) (xy 75.567349 -53.58791)
			(xy 75.551288 -53.53848) (xy 75.543158 -53.487145) (xy 75.36481 -53.487145) (xy 75.364848 -53.489098)
			(xy 75.364338 -53.515085) (xy 75.356208 -53.56642) (xy 75.340147 -53.61585) (xy 75.316551 -53.66216)
			(xy 75.286001 -53.704208) (xy 75.24925 -53.740959) (xy 75.207202 -53.771509) (xy 75.160892 -53.795105)
			(xy 75.111462 -53.811166) (xy 75.060127 -53.819296) (xy 75.008153 -53.819296) (xy 74.956818 -53.811166)
			(xy 74.907388 -53.795105) (xy 74.861078 -53.771509) (xy 74.81903 -53.740959) (xy 74.782279 -53.704208)
			(xy 74.751729 -53.66216) (xy 74.728133 -53.61585) (xy 74.712072 -53.56642) (xy 74.703942 -53.515085)
			(xy 74.600749 -53.515085) (xy 74.600655 -53.519318) (xy 74.589665 -53.578749) (xy 74.57948 -53.607208)
			(xy 74.567796 -53.638196) (xy 74.946256 -54.016656) (xy 76.870052 -54.016656) (xy 76.870531 -53.991269)
			(xy 76.878298 -53.941092) (xy 76.893642 -53.892691) (xy 76.916203 -53.847205) (xy 76.94545 -53.8057)
			(xy 76.980698 -53.769153) (xy 77.021116 -53.738423) (xy 77.065757 -53.714231) (xy 77.089508 -53.705252)
			(xy 77.103819 -53.699596) (xy 77.128401 -53.681108) (xy 77.146379 -53.656149) (xy 77.156127 -53.626975)
			(xy 77.156765 -53.596223) (xy 77.153008 -53.5813) (xy 77.146853 -53.558747) (xy 77.140222 -53.512472)
			(xy 77.1398 -53.489098) (xy 77.14031 -53.463111) (xy 77.14844 -53.411776) (xy 77.164501 -53.362346)
			(xy 77.188097 -53.316036) (xy 77.218647 -53.273988) (xy 77.255398 -53.237237) (xy 77.297446 -53.206687)
			(xy 77.343756 -53.183091) (xy 77.393186 -53.16703) (xy 77.444521 -53.1589) (xy 77.496495 -53.1589)
			(xy 77.54783 -53.16703) (xy 77.59726 -53.183091) (xy 77.64357 -53.206687) (xy 77.685618 -53.237237)
			(xy 77.722369 -53.273988) (xy 77.752919 -53.316036) (xy 77.776515 -53.362346) (xy 77.792576 -53.411776)
			(xy 77.800706 -53.463111) (xy 77.801216 -53.489098) (xy 77.800805 -53.514488) (xy 77.795045 -53.551661)
			(xy 77.903834 -53.551661) (xy 77.903834 -53.499687) (xy 77.911964 -53.448352) (xy 77.928025 -53.398922)
			(xy 77.951621 -53.352612) (xy 77.982171 -53.310564) (xy 78.018922 -53.273813) (xy 78.06097 -53.243263)
			(xy 78.10728 -53.219667) (xy 78.15671 -53.203606) (xy 78.208045 -53.195476) (xy 78.260019 -53.195476)
			(xy 78.311354 -53.203606) (xy 78.360784 -53.219667) (xy 78.407094 -53.243263) (xy 78.449142 -53.273813)
			(xy 78.485893 -53.310564) (xy 78.516443 -53.352612) (xy 78.540039 -53.398922) (xy 78.5561 -53.448352)
			(xy 78.56423 -53.499687) (xy 78.564532 -53.515085) (xy 78.703934 -53.515085) (xy 78.703934 -53.463111)
			(xy 78.712064 -53.411776) (xy 78.728125 -53.362346) (xy 78.751721 -53.316036) (xy 78.782271 -53.273988)
			(xy 78.819022 -53.237237) (xy 78.86107 -53.206687) (xy 78.90738 -53.183091) (xy 78.95681 -53.16703)
			(xy 79.008145 -53.1589) (xy 79.060119 -53.1589) (xy 79.111454 -53.16703) (xy 79.160884 -53.183091)
			(xy 79.207194 -53.206687) (xy 79.249242 -53.237237) (xy 79.285993 -53.273988) (xy 79.316543 -53.316036)
			(xy 79.340139 -53.362346) (xy 79.3562 -53.411776) (xy 79.36433 -53.463111) (xy 79.36484 -53.489098)
			(xy 79.36433 -53.515085) (xy 79.50378 -53.515085) (xy 79.50378 -53.463111) (xy 79.51191 -53.411776)
			(xy 79.527971 -53.362346) (xy 79.551567 -53.316036) (xy 79.582117 -53.273988) (xy 79.618868 -53.237237)
			(xy 79.660916 -53.206687) (xy 79.707226 -53.183091) (xy 79.756656 -53.16703) (xy 79.807991 -53.1589)
			(xy 79.859965 -53.1589) (xy 79.9113 -53.16703) (xy 79.96073 -53.183091) (xy 80.00704 -53.206687)
			(xy 80.049088 -53.237237) (xy 80.085839 -53.273988) (xy 80.116389 -53.316036) (xy 80.139985 -53.362346)
			(xy 80.156046 -53.411776) (xy 80.164176 -53.463111) (xy 80.164686 -53.489098) (xy 80.164176 -53.515085)
			(xy 80.156046 -53.56642) (xy 80.139985 -53.61585) (xy 80.116389 -53.66216) (xy 80.085839 -53.704208)
			(xy 80.049088 -53.740959) (xy 80.00704 -53.771509) (xy 79.96073 -53.795105) (xy 79.9113 -53.811166)
			(xy 79.859965 -53.819296) (xy 79.807991 -53.819296) (xy 79.756656 -53.811166) (xy 79.707226 -53.795105)
			(xy 79.660916 -53.771509) (xy 79.618868 -53.740959) (xy 79.582117 -53.704208) (xy 79.551567 -53.66216)
			(xy 79.527971 -53.61585) (xy 79.51191 -53.56642) (xy 79.50378 -53.515085) (xy 79.36433 -53.515085)
			(xy 79.3562 -53.56642) (xy 79.340139 -53.61585) (xy 79.316543 -53.66216) (xy 79.285993 -53.704208)
			(xy 79.249242 -53.740959) (xy 79.207194 -53.771509) (xy 79.160884 -53.795105) (xy 79.111454 -53.811166)
			(xy 79.060119 -53.819296) (xy 79.008145 -53.819296) (xy 78.95681 -53.811166) (xy 78.90738 -53.795105)
			(xy 78.86107 -53.771509) (xy 78.819022 -53.740959) (xy 78.782271 -53.704208) (xy 78.751721 -53.66216)
			(xy 78.728125 -53.61585) (xy 78.712064 -53.56642) (xy 78.703934 -53.515085) (xy 78.564532 -53.515085)
			(xy 78.56474 -53.525674) (xy 78.56423 -53.551661) (xy 78.5561 -53.602996) (xy 78.540039 -53.652426)
			(xy 78.516443 -53.698736) (xy 78.485893 -53.740784) (xy 78.449142 -53.777535) (xy 78.407094 -53.808085)
			(xy 78.360784 -53.831681) (xy 78.311354 -53.847742) (xy 78.260019 -53.855872) (xy 78.208045 -53.855872)
			(xy 78.15671 -53.847742) (xy 78.10728 -53.831681) (xy 78.06097 -53.808085) (xy 78.018922 -53.777535)
			(xy 77.982171 -53.740784) (xy 77.951621 -53.698736) (xy 77.928025 -53.652426) (xy 77.911964 -53.602996)
			(xy 77.903834 -53.551661) (xy 77.795045 -53.551661) (xy 77.793029 -53.564669) (xy 77.777676 -53.613072)
			(xy 77.755105 -53.65856) (xy 77.725848 -53.700065) (xy 77.690591 -53.73661) (xy 77.650164 -53.767338)
			(xy 77.605515 -53.791526) (xy 77.58176 -53.800502) (xy 77.567465 -53.806192) (xy 77.54289 -53.824676)
			(xy 77.524914 -53.849626) (xy 77.515161 -53.878789) (xy 77.514511 -53.909533) (xy 77.51826 -53.924454)
			(xy 77.524428 -53.947004) (xy 77.53105 -53.993282) (xy 77.531468 -54.016656) (xy 77.530958 -54.042643)
			(xy 77.522828 -54.093978) (xy 77.506767 -54.143408) (xy 77.483171 -54.189718) (xy 77.452621 -54.231766)
			(xy 77.41587 -54.268517) (xy 77.373822 -54.299067) (xy 77.327512 -54.322663) (xy 77.278082 -54.338724)
			(xy 77.226747 -54.346854) (xy 77.174773 -54.346854) (xy 77.123438 -54.338724) (xy 77.074008 -54.322663)
			(xy 77.027698 -54.299067) (xy 76.98565 -54.268517) (xy 76.948899 -54.231766) (xy 76.918349 -54.189718)
			(xy 76.894753 -54.143408) (xy 76.878692 -54.093978) (xy 76.870562 -54.042643) (xy 76.870052 -54.016656)
			(xy 74.946256 -54.016656) (xy 75.35679 -54.42719) (xy 78.018587 -54.42719) (xy 78.018587 -54.37521)
			(xy 78.026719 -54.323869) (xy 78.042784 -54.274433) (xy 78.066384 -54.228119) (xy 78.096939 -54.186067)
			(xy 78.133697 -54.149313) (xy 78.175753 -54.118763) (xy 78.22207 -54.095168) (xy 78.271508 -54.07911)
			(xy 78.32285 -54.070984) (xy 78.34884 -54.070504) (xy 78.374341 -54.070995) (xy 78.424738 -54.07883)
			(xy 78.473335 -54.094307) (xy 78.518981 -54.11706) (xy 78.560593 -54.14655) (xy 78.579218 -54.163976)
			(xy 78.589257 -54.173111) (xy 78.612999 -54.18624) (xy 78.639364 -54.192639) (xy 78.666483 -54.191853)
			(xy 78.692434 -54.183939) (xy 78.715376 -54.169458) (xy 78.733683 -54.149435) (xy 78.740254 -54.13756)
			(xy 78.752522 -54.114782) (xy 78.783117 -54.073063) (xy 78.819836 -54.036616) (xy 78.861781 -54.006333)
			(xy 78.907931 -53.98295) (xy 78.957159 -53.967039) (xy 79.008264 -53.958988) (xy 79.034132 -53.95849)
			(xy 79.060117 -53.959006) (xy 79.111448 -53.96714) (xy 79.160874 -53.983204) (xy 79.207178 -54.006802)
			(xy 79.249222 -54.037352) (xy 79.285969 -54.074102) (xy 79.316515 -54.116149) (xy 79.340108 -54.162456)
			(xy 79.356167 -54.211883) (xy 79.364297 -54.263215) (xy 79.364297 -54.315185) (xy 79.50378 -54.315185)
			(xy 79.50378 -54.263211) (xy 79.51191 -54.211876) (xy 79.527971 -54.162446) (xy 79.551567 -54.116136)
			(xy 79.582117 -54.074088) (xy 79.618868 -54.037337) (xy 79.660916 -54.006787) (xy 79.707226 -53.983191)
			(xy 79.756656 -53.96713) (xy 79.807991 -53.959) (xy 79.859965 -53.959) (xy 79.9113 -53.96713) (xy 79.96073 -53.983191)
			(xy 80.00704 -54.006787) (xy 80.049088 -54.037337) (xy 80.085839 -54.074088) (xy 80.116389 -54.116136)
			(xy 80.139985 -54.162446) (xy 80.156046 -54.211876) (xy 80.164176 -54.263211) (xy 80.164686 -54.289198)
			(xy 80.164176 -54.315185) (xy 80.156046 -54.36652) (xy 80.139985 -54.41595) (xy 80.116389 -54.46226)
			(xy 80.085839 -54.504308) (xy 80.049088 -54.541059) (xy 80.00704 -54.571609) (xy 79.96073 -54.595205)
			(xy 79.9113 -54.611266) (xy 79.859965 -54.619396) (xy 79.807991 -54.619396) (xy 79.756656 -54.611266)
			(xy 79.707226 -54.595205) (xy 79.660916 -54.571609) (xy 79.618868 -54.541059) (xy 79.582117 -54.504308)
			(xy 79.551567 -54.46226) (xy 79.527971 -54.41595) (xy 79.51191 -54.36652) (xy 79.50378 -54.315185)
			(xy 79.364297 -54.315185) (xy 79.356167 -54.366517) (xy 79.340108 -54.415944) (xy 79.316515 -54.462251)
			(xy 79.285969 -54.504298) (xy 79.249222 -54.541048) (xy 79.207178 -54.571598) (xy 79.160874 -54.595196)
			(xy 79.111448 -54.61126) (xy 79.060117 -54.619394) (xy 79.034132 -54.619906) (xy 79.00863 -54.61943)
			(xy 78.958233 -54.611591) (xy 78.909636 -54.59611) (xy 78.86399 -54.573354) (xy 78.822378 -54.543861)
			(xy 78.803754 -54.526434) (xy 78.793744 -54.517264) (xy 78.769994 -54.504135) (xy 78.743622 -54.497739)
			(xy 78.716496 -54.498529) (xy 78.690541 -54.50645) (xy 78.667595 -54.520939) (xy 78.649287 -54.54097)
			(xy 78.642718 -54.55285) (xy 78.630433 -54.575619) (xy 78.599845 -54.617343) (xy 78.563131 -54.653793)
			(xy 78.521188 -54.68408) (xy 78.47504 -54.707464) (xy 78.425812 -54.723375) (xy 78.374708 -54.731424)
			(xy 78.34884 -54.73192) (xy 78.32285 -54.731416) (xy 78.271508 -54.72329) (xy 78.22207 -54.707232)
			(xy 78.175753 -54.683637) (xy 78.133697 -54.653087) (xy 78.096939 -54.616333) (xy 78.066384 -54.574281)
			(xy 78.042784 -54.527967) (xy 78.026719 -54.478531) (xy 78.018587 -54.42719) (xy 75.35679 -54.42719)
			(xy 75.437746 -54.508146) (xy 75.452478 -54.511448) (xy 75.478874 -54.51775) (xy 75.529682 -54.536813)
			(xy 75.577276 -54.562882) (xy 75.620698 -54.595431) (xy 75.65907 -54.633804) (xy 75.691619 -54.677226)
			(xy 75.717688 -54.724821) (xy 75.73675 -54.775629) (xy 75.743054 -54.802024) (xy 75.746356 -54.816756)
			(xy 76.710654 -55.781054) (xy 77.08564 -55.781054) (xy 77.08564 -55.726546) (xy 77.093397 -55.672593)
			(xy 77.108754 -55.620293) (xy 77.131397 -55.570711) (xy 77.160866 -55.524857) (xy 77.196561 -55.483662)
			(xy 77.237755 -55.447967) (xy 77.28361 -55.418498) (xy 77.333192 -55.395854) (xy 77.385491 -55.380498)
			(xy 77.439444 -55.37274) (xy 77.466698 -55.372254) (xy 77.494069 -55.372708) (xy 77.548249 -55.380527)
			(xy 77.600753 -55.396018) (xy 77.650499 -55.418863) (xy 77.696465 -55.448591) (xy 77.717396 -55.466234)
			(xy 77.728724 -55.47547) (xy 77.755281 -55.487646) (xy 77.784198 -55.491819) (xy 77.813115 -55.487646)
			(xy 77.839672 -55.47547) (xy 77.851 -55.466234) (xy 77.871926 -55.448587) (xy 77.9179 -55.418875)
			(xy 77.967649 -55.39604) (xy 78.020151 -55.380551) (xy 78.074328 -55.372726) (xy 78.101698 -55.372254)
			(xy 78.126826 -55.372672) (xy 78.176647 -55.37927) (xy 78.225171 -55.392352) (xy 78.271557 -55.411691)
			(xy 78.315003 -55.436953) (xy 78.335124 -55.45201) (xy 78.346298 -55.460109) (xy 78.371875 -55.470454)
			(xy 78.399287 -55.473589) (xy 78.426539 -55.469286) (xy 78.451651 -55.457857) (xy 78.472796 -55.440133)
			(xy 78.488436 -55.417404) (xy 78.493366 -55.404512) (xy 78.502326 -55.379808) (xy 78.526084 -55.332936)
			(xy 78.556051 -55.289769) (xy 78.591662 -55.251125) (xy 78.63224 -55.217736) (xy 78.677018 -55.190235)
			(xy 78.725148 -55.169141) (xy 78.775719 -55.154855) (xy 78.827771 -55.147646) (xy 78.854046 -55.14721)
			(xy 78.881296 -55.147663) (xy 78.935242 -55.155425) (xy 78.987533 -55.170785) (xy 79.037107 -55.19343)
			(xy 79.082954 -55.222899) (xy 79.124141 -55.258592) (xy 79.159829 -55.299783) (xy 79.189292 -55.345633)
			(xy 79.211931 -55.39521) (xy 79.227285 -55.447503) (xy 79.23504 -55.50145) (xy 79.23504 -55.55595)
			(xy 79.227285 -55.609897) (xy 79.212116 -55.66156) (xy 80.163922 -55.66156) (xy 80.167993 -55.605938)
			(xy 80.180119 -55.551501) (xy 80.200042 -55.49941) (xy 80.227338 -55.450775) (xy 80.261424 -55.406632)
			(xy 80.301573 -55.367923) (xy 80.346931 -55.335472) (xy 80.396531 -55.309971) (xy 80.449315 -55.291964)
			(xy 80.504158 -55.281834) (xy 80.559892 -55.279797) (xy 80.615329 -55.285897) (xy 80.669286 -55.300003)
			(xy 80.720615 -55.321815) (xy 80.768221 -55.350869) (xy 80.811089 -55.386544) (xy 80.848306 -55.428081)
			(xy 80.879079 -55.474594) (xy 80.902751 -55.525091) (xy 80.918819 -55.578498) (xy 80.926939 -55.633674)
			(xy 80.927448 -55.66156) (xy 80.926939 -55.689446) (xy 80.918819 -55.744622) (xy 80.902751 -55.798029)
			(xy 80.879079 -55.848526) (xy 80.848306 -55.895039) (xy 80.811089 -55.936576) (xy 80.768221 -55.972251)
			(xy 80.720615 -56.001305) (xy 80.669286 -56.023117) (xy 80.615329 -56.037223) (xy 80.559892 -56.043323)
			(xy 80.504158 -56.041286) (xy 80.449315 -56.031156) (xy 80.396531 -56.013149) (xy 80.346931 -55.987648)
			(xy 80.301573 -55.955197) (xy 80.261424 -55.916488) (xy 80.227338 -55.872345) (xy 80.200042 -55.82371)
			(xy 80.180119 -55.771619) (xy 80.167993 -55.717182) (xy 80.163922 -55.66156) (xy 79.212116 -55.66156)
			(xy 79.211931 -55.66219) (xy 79.189292 -55.711767) (xy 79.159829 -55.757617) (xy 79.124141 -55.798808)
			(xy 79.082954 -55.834501) (xy 79.037107 -55.86397) (xy 78.987533 -55.886615) (xy 78.935242 -55.901975)
			(xy 78.881296 -55.909737) (xy 78.854046 -55.910226) (xy 78.828917 -55.909843) (xy 78.779094 -55.903237)
			(xy 78.73057 -55.890148) (xy 78.684184 -55.8708) (xy 78.64074 -55.845531) (xy 78.62062 -55.83047)
			(xy 78.609405 -55.822433) (xy 78.58384 -55.812086) (xy 78.556441 -55.808945) (xy 78.529198 -55.81324)
			(xy 78.504093 -55.824657) (xy 78.482951 -55.842367) (xy 78.46731 -55.865082) (xy 78.462378 -55.877968)
			(xy 78.453369 -55.902653) (xy 78.429617 -55.949524) (xy 78.399656 -55.99269) (xy 78.364052 -56.031334)
			(xy 78.32348 -56.064725) (xy 78.278708 -56.092229) (xy 78.230584 -56.113326) (xy 78.180019 -56.127617)
			(xy 78.127971 -56.134831) (xy 78.101698 -56.13527) (xy 78.074327 -56.134812) (xy 78.020148 -56.126994)
			(xy 77.967644 -56.111503) (xy 77.917897 -56.088659) (xy 77.871931 -56.058932) (xy 77.851 -56.04129)
			(xy 77.839672 -56.032054) (xy 77.813115 -56.019878) (xy 77.784198 -56.015705) (xy 77.755281 -56.019878)
			(xy 77.728724 -56.032054) (xy 77.717396 -56.04129) (xy 77.696475 -56.058943) (xy 77.650499 -56.088653)
			(xy 77.600749 -56.111486) (xy 77.548246 -56.126974) (xy 77.494068 -56.134798) (xy 77.466698 -56.13527)
			(xy 77.439444 -56.13486) (xy 77.385491 -56.127102) (xy 77.333192 -56.111746) (xy 77.28361 -56.089102)
			(xy 77.237755 -56.059633) (xy 77.196561 -56.023938) (xy 77.160866 -55.982743) (xy 77.131397 -55.936889)
			(xy 77.108754 -55.887307) (xy 77.093397 -55.835007) (xy 77.08564 -55.781054) (xy 76.710654 -55.781054)
			(xy 77.7748 -56.8452) (xy 77.7748 -58.365644) (xy 78.236826 -58.365644) (xy 78.237277 -58.339422)
			(xy 78.244479 -58.287474) (xy 78.258725 -58.237001) (xy 78.279748 -58.188955) (xy 78.307152 -58.144239)
			(xy 78.34042 -58.103696) (xy 78.378925 -58.068091) (xy 78.421943 -58.038092) (xy 78.445106 -58.025792)
			(xy 78.457353 -58.018994) (xy 78.47793 -58.000013) (xy 78.492575 -57.976155) (xy 78.500186 -57.949216)
			(xy 78.500191 -57.921221) (xy 78.49259 -57.894279) (xy 78.477953 -57.870415) (xy 78.457383 -57.851427)
			(xy 78.445106 -57.84469) (xy 78.421919 -57.832429) (xy 78.378885 -57.80244) (xy 78.340367 -57.766836)
			(xy 78.307092 -57.726289) (xy 78.279687 -57.681565) (xy 78.25867 -57.633508) (xy 78.244438 -57.583023)
			(xy 78.237258 -57.531064) (xy 78.236826 -57.504838) (xy 78.237312 -57.477587) (xy 78.245068 -57.423639)
			(xy 78.260423 -57.371344) (xy 78.283065 -57.321767) (xy 78.312531 -57.275917) (xy 78.348222 -57.234726)
			(xy 78.389413 -57.199035) (xy 78.435263 -57.169569) (xy 78.48484 -57.146927) (xy 78.537135 -57.131572)
			(xy 78.591083 -57.123816) (xy 78.645585 -57.123816) (xy 78.699533 -57.131572) (xy 78.751828 -57.146927)
			(xy 78.801405 -57.169569) (xy 78.847255 -57.199035) (xy 78.888446 -57.234726) (xy 78.924137 -57.275917)
			(xy 78.953603 -57.321767) (xy 78.976245 -57.371344) (xy 78.9916 -57.423639) (xy 78.999356 -57.477587)
			(xy 78.999842 -57.504838) (xy 78.999394 -57.53106) (xy 78.992194 -57.583009) (xy 78.977948 -57.633483)
			(xy 78.956925 -57.68153) (xy 78.929521 -57.726246) (xy 78.896252 -57.766789) (xy 78.857745 -57.802394)
			(xy 78.814725 -57.832391) (xy 78.791562 -57.84469) (xy 78.779284 -57.851398) (xy 78.758784 -57.870431)
			(xy 78.744204 -57.894303) (xy 78.736634 -57.921232) (xy 78.736639 -57.949205) (xy 78.744219 -57.976131)
			(xy 78.758808 -57.999998) (xy 78.779315 -58.019023) (xy 78.791562 -58.025792) (xy 78.814734 -58.03808)
			(xy 78.857769 -58.068064) (xy 78.896288 -58.103664) (xy 78.929565 -58.144206) (xy 78.956972 -58.188926)
			(xy 78.977991 -58.236981) (xy 78.992226 -58.287462) (xy 78.999409 -58.339419) (xy 78.999741 -58.359548)
			(xy 80.37068 -58.359548) (xy 80.371105 -58.333325) (xy 80.378307 -58.281374) (xy 80.392556 -58.2309)
			(xy 80.413582 -58.182852) (xy 80.440989 -58.138135) (xy 80.474261 -58.097593) (xy 80.512772 -58.061989)
			(xy 80.555795 -58.031994) (xy 80.57896 -58.019696) (xy 80.591198 -58.012889) (xy 80.611764 -57.993905)
			(xy 80.6264 -57.970049) (xy 80.634008 -57.943114) (xy 80.634013 -57.915126) (xy 80.626417 -57.888189)
			(xy 80.61179 -57.864327) (xy 80.591231 -57.845335) (xy 80.57896 -57.838594) (xy 80.555787 -57.826307)
			(xy 80.512751 -57.796323) (xy 80.474231 -57.760725) (xy 80.440953 -57.720182) (xy 80.413546 -57.675462)
			(xy 80.392527 -57.627407) (xy 80.378293 -57.576924) (xy 80.371112 -57.524967) (xy 80.37068 -57.498742)
			(xy 80.371166 -57.471491) (xy 80.378922 -57.417543) (xy 80.394277 -57.365248) (xy 80.416919 -57.315671)
			(xy 80.446385 -57.269821) (xy 80.482076 -57.22863) (xy 80.523267 -57.192939) (xy 80.569117 -57.163473)
			(xy 80.618694 -57.140831) (xy 80.670989 -57.125476) (xy 80.724937 -57.11772) (xy 80.779439 -57.11772)
			(xy 80.833387 -57.125476) (xy 80.885682 -57.140831) (xy 80.935259 -57.163473) (xy 80.981109 -57.192939)
			(xy 81.0223 -57.22863) (xy 81.057991 -57.269821) (xy 81.087457 -57.315671) (xy 81.110099 -57.365248)
			(xy 81.125454 -57.417543) (xy 81.13321 -57.471491) (xy 81.133696 -57.498742) (xy 81.133276 -57.524966)
			(xy 81.126074 -57.576917) (xy 81.111826 -57.627392) (xy 81.0908 -57.675441) (xy 81.063392 -57.720157)
			(xy 81.030118 -57.760699) (xy 80.991607 -57.796303) (xy 80.948582 -57.826297) (xy 80.925416 -57.838594)
			(xy 80.913139 -57.8453) (xy 80.892647 -57.864336) (xy 80.878074 -57.888209) (xy 80.870508 -57.915136)
			(xy 80.870514 -57.943105) (xy 80.878091 -57.970029) (xy 80.892674 -57.993896) (xy 80.913173 -58.012924)
			(xy 80.925416 -58.019696) (xy 80.948579 -58.032001) (xy 80.991616 -58.061981) (xy 81.030137 -58.097576)
			(xy 81.063416 -58.138116) (xy 81.090824 -58.182834) (xy 81.111845 -58.230887) (xy 81.126081 -58.281368)
			(xy 81.133263 -58.333323) (xy 81.133595 -58.353452) (xy 82.504534 -58.353452) (xy 82.504987 -58.32723)
			(xy 82.512188 -58.275282) (xy 82.526434 -58.224809) (xy 82.547457 -58.176762) (xy 82.57486 -58.132046)
			(xy 82.608128 -58.091504) (xy 82.646633 -58.055898) (xy 82.689651 -58.0259) (xy 82.712814 -58.0136)
			(xy 82.725053 -58.00679) (xy 82.745627 -57.987811) (xy 82.760271 -57.963955) (xy 82.767882 -57.937018)
			(xy 82.767889 -57.909026) (xy 82.760289 -57.882086) (xy 82.745656 -57.858224) (xy 82.725089 -57.839235)
			(xy 82.712814 -57.832498) (xy 82.689632 -57.820227) (xy 82.646598 -57.79024) (xy 82.60808 -57.754638)
			(xy 82.574804 -57.714093) (xy 82.547399 -57.66937) (xy 82.526381 -57.621313) (xy 82.512147 -57.57083)
			(xy 82.504967 -57.518872) (xy 82.504534 -57.492646) (xy 82.50502 -57.465395) (xy 82.512776 -57.411447)
			(xy 82.528131 -57.359152) (xy 82.550773 -57.309575) (xy 82.580239 -57.263725) (xy 82.61593 -57.222534)
			(xy 82.657121 -57.186843) (xy 82.702971 -57.157377) (xy 82.752548 -57.134735) (xy 82.804843 -57.11938)
			(xy 82.858791 -57.111624) (xy 82.913293 -57.111624) (xy 82.967241 -57.11938) (xy 83.019536 -57.134735)
			(xy 83.069113 -57.157377) (xy 83.114963 -57.186843) (xy 83.156154 -57.222534) (xy 83.191845 -57.263725)
			(xy 83.221311 -57.309575) (xy 83.243953 -57.359152) (xy 83.259308 -57.411447) (xy 83.267064 -57.465395)
			(xy 83.26755 -57.492646) (xy 83.267104 -57.518869) (xy 83.259903 -57.570817) (xy 83.245656 -57.62129)
			(xy 83.224633 -57.669338) (xy 83.197229 -57.714054) (xy 83.16396 -57.754596) (xy 83.125453 -57.790201)
			(xy 83.082433 -57.820199) (xy 83.05927 -57.832498) (xy 83.046984 -57.839194) (xy 83.026482 -57.858228)
			(xy 83.0119 -57.882103) (xy 83.00433 -57.909034) (xy 83.004336 -57.93701) (xy 83.011918 -57.963938)
			(xy 83.02651 -57.987807) (xy 83.047021 -58.006832) (xy 83.05927 -58.0136) (xy 83.082447 -58.025879)
			(xy 83.125482 -58.055865) (xy 83.164001 -58.091465) (xy 83.197277 -58.132009) (xy 83.224683 -58.176731)
			(xy 83.245702 -58.224786) (xy 83.259936 -58.275269) (xy 83.267117 -58.327226) (xy 83.26755 -58.353452)
			(xy 83.267064 -58.380703) (xy 83.259308 -58.434651) (xy 83.243953 -58.486946) (xy 83.221311 -58.536523)
			(xy 83.191845 -58.582373) (xy 83.156154 -58.623564) (xy 83.114963 -58.659255) (xy 83.069113 -58.688721)
			(xy 83.019536 -58.711363) (xy 82.967241 -58.726718) (xy 82.913293 -58.734474) (xy 82.858791 -58.734474)
			(xy 82.804843 -58.726718) (xy 82.752548 -58.711363) (xy 82.702971 -58.688721) (xy 82.657121 -58.659255)
			(xy 82.61593 -58.623564) (xy 82.580239 -58.582373) (xy 82.550773 -58.536523) (xy 82.528131 -58.486946)
			(xy 82.512776 -58.434651) (xy 82.50502 -58.380703) (xy 82.504534 -58.353452) (xy 81.133595 -58.353452)
			(xy 81.133696 -58.359548) (xy 81.13321 -58.386799) (xy 81.125454 -58.440747) (xy 81.110099 -58.493042)
			(xy 81.087457 -58.542619) (xy 81.057991 -58.588469) (xy 81.0223 -58.62966) (xy 80.981109 -58.665351)
			(xy 80.935259 -58.694817) (xy 80.885682 -58.717459) (xy 80.833387 -58.732814) (xy 80.779439 -58.74057)
			(xy 80.724937 -58.74057) (xy 80.670989 -58.732814) (xy 80.618694 -58.717459) (xy 80.569117 -58.694817)
			(xy 80.523267 -58.665351) (xy 80.482076 -58.62966) (xy 80.446385 -58.588469) (xy 80.416919 -58.542619)
			(xy 80.394277 -58.493042) (xy 80.378922 -58.440747) (xy 80.371166 -58.386799) (xy 80.37068 -58.359548)
			(xy 78.999741 -58.359548) (xy 78.999842 -58.365644) (xy 78.999356 -58.392895) (xy 78.9916 -58.446843)
			(xy 78.976245 -58.499138) (xy 78.953603 -58.548715) (xy 78.924137 -58.594565) (xy 78.888446 -58.635756)
			(xy 78.847255 -58.671447) (xy 78.801405 -58.700913) (xy 78.751828 -58.723555) (xy 78.699533 -58.73891)
			(xy 78.645585 -58.746666) (xy 78.591083 -58.746666) (xy 78.537135 -58.73891) (xy 78.48484 -58.723555)
			(xy 78.435263 -58.700913) (xy 78.389413 -58.671447) (xy 78.348222 -58.635756) (xy 78.312531 -58.594565)
			(xy 78.283065 -58.548715) (xy 78.260423 -58.499138) (xy 78.245068 -58.446843) (xy 78.237312 -58.392895)
			(xy 78.236826 -58.365644) (xy 77.7748 -58.365644) (xy 77.7748 -60.640214) (xy 78.236826 -60.640214)
			(xy 78.237252 -60.613991) (xy 78.244458 -60.562042) (xy 78.258709 -60.511569) (xy 78.279735 -60.463522)
			(xy 78.307142 -60.418807) (xy 78.340413 -60.378264) (xy 78.378922 -60.342659) (xy 78.421942 -60.312662)
			(xy 78.445106 -60.300362) (xy 78.457379 -60.293609) (xy 78.477959 -60.27462) (xy 78.492605 -60.250754)
			(xy 78.500215 -60.223806) (xy 78.500216 -60.195804) (xy 78.492609 -60.168855) (xy 78.477965 -60.144988)
			(xy 78.457387 -60.125997) (xy 78.445106 -60.11926) (xy 78.421906 -60.107021) (xy 78.378872 -60.077029)
			(xy 78.340354 -60.041422) (xy 78.30708 -60.000872) (xy 78.279677 -59.956145) (xy 78.258662 -59.908084)
			(xy 78.244432 -59.857597) (xy 78.237256 -59.805635) (xy 78.236826 -59.779408) (xy 78.237312 -59.752157)
			(xy 78.245068 -59.698209) (xy 78.260423 -59.645914) (xy 78.283065 -59.596337) (xy 78.312531 -59.550487)
			(xy 78.348222 -59.509296) (xy 78.389413 -59.473605) (xy 78.435263 -59.444139) (xy 78.48484 -59.421497)
			(xy 78.537135 -59.406142) (xy 78.591083 -59.398386) (xy 78.645585 -59.398386) (xy 78.699533 -59.406142)
			(xy 78.751828 -59.421497) (xy 78.801405 -59.444139) (xy 78.847255 -59.473605) (xy 78.888446 -59.509296)
			(xy 78.924137 -59.550487) (xy 78.953603 -59.596337) (xy 78.976245 -59.645914) (xy 78.9916 -59.698209)
			(xy 78.999356 -59.752157) (xy 78.999842 -59.779408) (xy 78.999369 -59.80563) (xy 78.992173 -59.857577)
			(xy 78.977931 -59.90805) (xy 78.956912 -59.956097) (xy 78.929511 -60.000814) (xy 78.896246 -60.041357)
			(xy 78.857741 -60.076963) (xy 78.814724 -60.10696) (xy 78.791562 -60.11926) (xy 78.779311 -60.126012)
			(xy 78.758813 -60.145037) (xy 78.744234 -60.168901) (xy 78.736662 -60.195822) (xy 78.736663 -60.223788)
			(xy 78.744238 -60.250708) (xy 78.75882 -60.274571) (xy 78.779319 -60.293593) (xy 78.791562 -60.300362)
			(xy 78.814722 -60.312673) (xy 78.857756 -60.342654) (xy 78.896275 -60.37825) (xy 78.929553 -60.418789)
			(xy 78.956962 -60.463506) (xy 78.977983 -60.511557) (xy 78.992221 -60.562036) (xy 78.999407 -60.61399)
			(xy 78.999741 -60.634118) (xy 80.37068 -60.634118) (xy 80.37108 -60.607894) (xy 80.378287 -60.555942)
			(xy 80.392539 -60.505467) (xy 80.413569 -60.457419) (xy 80.440979 -60.412703) (xy 80.474255 -60.372161)
			(xy 80.512768 -60.336558) (xy 80.555794 -60.306564) (xy 80.57896 -60.294266) (xy 80.591225 -60.287503)
			(xy 80.611793 -60.268512) (xy 80.626431 -60.244647) (xy 80.634036 -60.217705) (xy 80.634038 -60.189709)
			(xy 80.626436 -60.162765) (xy 80.611802 -60.138899) (xy 80.591236 -60.119905) (xy 80.57896 -60.113164)
			(xy 80.555775 -60.100899) (xy 80.512738 -60.070913) (xy 80.474218 -60.035311) (xy 80.440941 -59.994765)
			(xy 80.413536 -59.950041) (xy 80.392519 -59.901983) (xy 80.378288 -59.851498) (xy 80.37111 -59.799539)
			(xy 80.37068 -59.773312) (xy 80.371166 -59.746061) (xy 80.378922 -59.692113) (xy 80.394277 -59.639818)
			(xy 80.416919 -59.590241) (xy 80.446385 -59.544391) (xy 80.482076 -59.5032) (xy 80.523267 -59.467509)
			(xy 80.569117 -59.438043) (xy 80.618694 -59.415401) (xy 80.670989 -59.400046) (xy 80.724937 -59.39229)
			(xy 80.779439 -59.39229) (xy 80.833387 -59.400046) (xy 80.885682 -59.415401) (xy 80.935259 -59.438043)
			(xy 80.981109 -59.467509) (xy 81.0223 -59.5032) (xy 81.057991 -59.544391) (xy 81.087457 -59.590241)
			(xy 81.110099 -59.639818) (xy 81.125454 -59.692113) (xy 81.13321 -59.746061) (xy 81.133696 -59.773312)
			(xy 81.133251 -59.799535) (xy 81.126054 -59.851485) (xy 81.111809 -59.90196) (xy 81.090787 -59.950008)
			(xy 81.063382 -59.994725) (xy 81.030112 -60.035267) (xy 80.991603 -60.070871) (xy 80.948581 -60.100866)
			(xy 80.925416 -60.113164) (xy 80.913166 -60.119914) (xy 80.892677 -60.138943) (xy 80.878104 -60.162807)
			(xy 80.870537 -60.189726) (xy 80.870538 -60.217688) (xy 80.87811 -60.244605) (xy 80.892686 -60.268468)
			(xy 80.913177 -60.287494) (xy 80.925416 -60.294266) (xy 80.948567 -60.306593) (xy 80.991603 -60.33657)
			(xy 81.030124 -60.372163) (xy 81.063404 -60.412699) (xy 81.090814 -60.457414) (xy 81.111836 -60.505464)
			(xy 81.126075 -60.555941) (xy 81.133261 -60.607894) (xy 81.133595 -60.628022) (xy 82.504534 -60.628022)
			(xy 82.504962 -60.601799) (xy 82.512167 -60.54985) (xy 82.526417 -60.499377) (xy 82.547444 -60.45133)
			(xy 82.57485 -60.406614) (xy 82.608121 -60.366072) (xy 82.646629 -60.330467) (xy 82.68965 -60.30047)
			(xy 82.712814 -60.28817) (xy 82.725079 -60.281404) (xy 82.745657 -60.262417) (xy 82.760301 -60.238553)
			(xy 82.767911 -60.211608) (xy 82.767913 -60.183609) (xy 82.760308 -60.156663) (xy 82.745668 -60.132796)
			(xy 82.725093 -60.113806) (xy 82.712814 -60.107068) (xy 82.68962 -60.09482) (xy 82.646585 -60.064829)
			(xy 82.608067 -60.029224) (xy 82.574792 -59.988676) (xy 82.547388 -59.943949) (xy 82.526373 -59.89589)
			(xy 82.512142 -59.845403) (xy 82.504965 -59.793443) (xy 82.504534 -59.767216) (xy 82.50502 -59.739965)
			(xy 82.512776 -59.686017) (xy 82.528131 -59.633722) (xy 82.550773 -59.584145) (xy 82.580239 -59.538295)
			(xy 82.61593 -59.497104) (xy 82.657121 -59.461413) (xy 82.702971 -59.431947) (xy 82.752548 -59.409305)
			(xy 82.804843 -59.39395) (xy 82.858791 -59.386194) (xy 82.913293 -59.386194) (xy 82.967241 -59.39395)
			(xy 83.019536 -59.409305) (xy 83.069113 -59.431947) (xy 83.114963 -59.461413) (xy 83.156154 -59.497104)
			(xy 83.191845 -59.538295) (xy 83.221311 -59.584145) (xy 83.243953 -59.633722) (xy 83.259308 -59.686017)
			(xy 83.267064 -59.739965) (xy 83.26755 -59.767216) (xy 83.267079 -59.793438) (xy 83.259882 -59.845385)
			(xy 83.24564 -59.895858) (xy 83.22462 -59.943905) (xy 83.197219 -59.988621) (xy 83.163953 -60.029164)
			(xy 83.125449 -60.06477) (xy 83.082432 -60.094768) (xy 83.05927 -60.107068) (xy 83.047011 -60.113808)
			(xy 83.026511 -60.132834) (xy 83.01193 -60.156701) (xy 83.004358 -60.183625) (xy 83.00436 -60.211593)
			(xy 83.011937 -60.238515) (xy 83.026522 -60.262379) (xy 83.047025 -60.281402) (xy 83.05927 -60.28817)
			(xy 83.082435 -60.300471) (xy 83.125469 -60.330454) (xy 83.163988 -60.366052) (xy 83.197265 -60.406592)
			(xy 83.224673 -60.45131) (xy 83.245694 -60.499363) (xy 83.259931 -60.549843) (xy 83.267115 -60.601797)
			(xy 83.26755 -60.628022) (xy 83.267064 -60.655273) (xy 83.259308 -60.709221) (xy 83.243953 -60.761516)
			(xy 83.221311 -60.811093) (xy 83.191845 -60.856943) (xy 83.156154 -60.898134) (xy 83.114963 -60.933825)
			(xy 83.069113 -60.963291) (xy 83.019536 -60.985933) (xy 82.967241 -61.001288) (xy 82.913293 -61.009044)
			(xy 82.858791 -61.009044) (xy 82.804843 -61.001288) (xy 82.752548 -60.985933) (xy 82.702971 -60.963291)
			(xy 82.657121 -60.933825) (xy 82.61593 -60.898134) (xy 82.580239 -60.856943) (xy 82.550773 -60.811093)
			(xy 82.528131 -60.761516) (xy 82.512776 -60.709221) (xy 82.50502 -60.655273) (xy 82.504534 -60.628022)
			(xy 81.133595 -60.628022) (xy 81.133696 -60.634118) (xy 81.13321 -60.661369) (xy 81.125454 -60.715317)
			(xy 81.110099 -60.767612) (xy 81.087457 -60.817189) (xy 81.057991 -60.863039) (xy 81.0223 -60.90423)
			(xy 80.981109 -60.939921) (xy 80.935259 -60.969387) (xy 80.885682 -60.992029) (xy 80.833387 -61.007384)
			(xy 80.779439 -61.01514) (xy 80.724937 -61.01514) (xy 80.670989 -61.007384) (xy 80.618694 -60.992029)
			(xy 80.569117 -60.969387) (xy 80.523267 -60.939921) (xy 80.482076 -60.90423) (xy 80.446385 -60.863039)
			(xy 80.416919 -60.817189) (xy 80.394277 -60.767612) (xy 80.378922 -60.715317) (xy 80.371166 -60.661369)
			(xy 80.37068 -60.634118) (xy 78.999741 -60.634118) (xy 78.999842 -60.640214) (xy 78.999356 -60.667465)
			(xy 78.9916 -60.721413) (xy 78.976245 -60.773708) (xy 78.953603 -60.823285) (xy 78.924137 -60.869135)
			(xy 78.888446 -60.910326) (xy 78.847255 -60.946017) (xy 78.801405 -60.975483) (xy 78.751828 -60.998125)
			(xy 78.699533 -61.01348) (xy 78.645585 -61.021236) (xy 78.591083 -61.021236) (xy 78.537135 -61.01348)
			(xy 78.48484 -60.998125) (xy 78.435263 -60.975483) (xy 78.389413 -60.946017) (xy 78.348222 -60.910326)
			(xy 78.312531 -60.869135) (xy 78.283065 -60.823285) (xy 78.260423 -60.773708) (xy 78.245068 -60.721413)
			(xy 78.237312 -60.667465) (xy 78.236826 -60.640214) (xy 77.7748 -60.640214) (xy 77.7748 -62.5094)
			(xy 76.835 -63.4492) (xy 76.835 -64.117474) (xy 77.1906 -64.473074) (xy 78.238096 -64.473074)
		)
		(stroke
			(width 0)
			(type solid)
		)
		(fill yes)
		(layer "In4.Cu")
		(net "P0V6_DDR_VREF_AUX")
	)
	(gr_line
		(start 0 -112.300004)
		(end 0 -85.25002)
		(stroke
			(width 2.032)
			(type default)
		)
		(layer "In5.Cu")
	)
	(gr_arc
		(start 0 -112.300004)
		(mid 0.585785 -113.714215)
		(end 1.999996 -114.3)
		(stroke
			(width 2.032)
			(type default)
		)
		(layer "In5.Cu")
	)
	(gr_line
		(start 0 -81.250028)
		(end 0 -1.999996)
		(stroke
			(width 2.032)
			(type default)
		)
		(layer "In5.Cu")
	)
	(gr_arc
		(start 0 -81.250028)
		(mid 0.073204 -81.426762)
		(end 0.249936 -81.499964)
		(stroke
			(width 2.032)
			(type default)
		)
		(layer "In5.Cu")
	)
	(gr_poly
		(pts
			(xy -3.999992 -119.892064) (xy -3.944185 -119.891542) (xy -3.832883 -119.883201) (xy -3.722516 -119.866566)
			(xy -3.6137 -119.841729) (xy -3.507045 -119.80883) (xy -3.403146 -119.768053) (xy -3.302586 -119.719626)
			(xy -3.205925 -119.663818) (xy -3.113705 -119.600944) (xy -3.026442 -119.531354) (xy -2.944623 -119.455437)
			(xy -2.868706 -119.373618) (xy -2.799116 -119.286355) (xy -2.736242 -119.194135) (xy -2.680434 -119.097474)
			(xy -2.632007 -118.996914) (xy -2.59123 -118.893015) (xy -2.558331 -118.78636) (xy -2.533494 -118.677544)
			(xy -2.516859 -118.567177) (xy -2.508518 -118.455875) (xy -2.507996 -118.400068) (xy -2.507996 -6.59003)
			(xy -2.508518 -6.534223) (xy -2.516859 -6.422921) (xy -2.533494 -6.312554) (xy -2.558331 -6.203738)
			(xy -2.59123 -6.097083) (xy -2.632007 -5.993184) (xy -2.680434 -5.892624) (xy -2.736242 -5.795963)
			(xy -2.799116 -5.703743) (xy -2.868706 -5.61648) (xy -2.944623 -5.534661) (xy -3.026442 -5.458744)
			(xy -3.113705 -5.389154) (xy -3.205925 -5.32628) (xy -3.302586 -5.270472) (xy -3.403146 -5.222045)
			(xy -3.507045 -5.181268) (xy -3.6137 -5.148369) (xy -3.722516 -5.123532) (xy -3.832883 -5.106897)
			(xy -3.944185 -5.098556) (xy -3.999992 -5.098034) (xy -17.78 -5.098034) (xy -17.835807 -5.098556)
			(xy -17.947109 -5.106897) (xy -18.057476 -5.123532) (xy -18.166292 -5.148369) (xy -18.272947 -5.181268)
			(xy -18.376846 -5.222045) (xy -18.477406 -5.270472) (xy -18.574067 -5.32628) (xy -18.666287 -5.389154)
			(xy -18.75355 -5.458744) (xy -18.835369 -5.534661) (xy -18.911286 -5.61648) (xy -18.980876 -5.703743)
			(xy -19.04375 -5.795963) (xy -19.099558 -5.892624) (xy -19.147985 -5.993184) (xy -19.188762 -6.097083)
			(xy -19.221661 -6.203738) (xy -19.246498 -6.312554) (xy -19.263133 -6.422921) (xy -19.271474 -6.534223)
			(xy -19.271996 -6.59003) (xy -19.271996 -115.464644) (xy -16.875771 -115.464644) (xy -16.875771 -115.335504)
			(xy -16.867821 -115.206609) (xy -16.851951 -115.078449) (xy -16.828222 -114.951508) (xy -16.796723 -114.826269)
			(xy -16.757574 -114.703206) (xy -16.710923 -114.582787) (xy -16.656948 -114.465468) (xy -16.595853 -114.351694)
			(xy -16.52787 -114.241897) (xy -16.453256 -114.136494) (xy -16.372295 -114.035884) (xy -16.285295 -113.940449)
			(xy -16.192584 -113.85055) (xy -16.094514 -113.766529) (xy -15.991459 -113.688705) (xy -15.883808 -113.617373)
			(xy -15.771969 -113.552803) (xy -15.656368 -113.495241) (xy -15.537443 -113.444904) (xy -15.415644 -113.401984)
			(xy -15.291434 -113.366643) (xy -15.165285 -113.339016) (xy -15.037673 -113.319207) (xy -14.909084 -113.307291)
			(xy -14.780006 -113.303315) (xy -14.650928 -113.307291) (xy -14.522339 -113.319207) (xy -14.394727 -113.339016)
			(xy -14.268578 -113.366643) (xy -14.144368 -113.401984) (xy -14.022569 -113.444904) (xy -13.903644 -113.495241)
			(xy -13.788043 -113.552803) (xy -13.676204 -113.617373) (xy -13.568553 -113.688705) (xy -13.465498 -113.766529)
			(xy -13.367428 -113.85055) (xy -13.274717 -113.940449) (xy -13.187717 -114.035884) (xy -13.106756 -114.136494)
			(xy -13.032142 -114.241897) (xy -12.964159 -114.351694) (xy -12.903064 -114.465468) (xy -12.849089 -114.582787)
			(xy -12.802438 -114.703206) (xy -12.763289 -114.826269) (xy -12.73179 -114.951508) (xy -12.708061 -115.078449)
			(xy -12.692191 -115.206609) (xy -12.684241 -115.335504) (xy -12.683744 -115.400074) (xy -12.684241 -115.464644)
			(xy -12.692191 -115.593539) (xy -12.708061 -115.721699) (xy -12.73179 -115.84864) (xy -12.763289 -115.973879)
			(xy -12.802438 -116.096942) (xy -12.849089 -116.217361) (xy -12.903064 -116.33468) (xy -12.964159 -116.448454)
			(xy -13.032142 -116.558251) (xy -13.106756 -116.663654) (xy -13.187717 -116.764264) (xy -13.274717 -116.859699)
			(xy -13.367428 -116.949598) (xy -13.465498 -117.033619) (xy -13.568553 -117.111443) (xy -13.676204 -117.182775)
			(xy -13.788043 -117.247345) (xy -13.903644 -117.304907) (xy -14.022569 -117.355244) (xy -14.144368 -117.398164)
			(xy -14.268578 -117.433505) (xy -14.394727 -117.461132) (xy -14.522339 -117.480941) (xy -14.650928 -117.492857)
			(xy -14.780006 -117.496834) (xy -14.909084 -117.492857) (xy -15.037673 -117.480941) (xy -15.165285 -117.461132)
			(xy -15.291434 -117.433505) (xy -15.415644 -117.398164) (xy -15.537443 -117.355244) (xy -15.656368 -117.304907)
			(xy -15.771969 -117.247345) (xy -15.883808 -117.182775) (xy -15.991459 -117.111443) (xy -16.094514 -117.033619)
			(xy -16.192584 -116.949598) (xy -16.285295 -116.859699) (xy -16.372295 -116.764264) (xy -16.453256 -116.663654)
			(xy -16.52787 -116.558251) (xy -16.595853 -116.448454) (xy -16.656948 -116.33468) (xy -16.710923 -116.217361)
			(xy -16.757574 -116.096942) (xy -16.796723 -115.973879) (xy -16.828222 -115.84864) (xy -16.851951 -115.721699)
			(xy -16.867821 -115.593539) (xy -16.875771 -115.464644) (xy -19.271996 -115.464644) (xy -19.271996 -118.400068)
			(xy -19.271474 -118.455875) (xy -19.263133 -118.567177) (xy -19.246498 -118.677544) (xy -19.221661 -118.78636)
			(xy -19.188762 -118.893015) (xy -19.147985 -118.996914) (xy -19.099558 -119.097474) (xy -19.04375 -119.194135)
			(xy -18.980876 -119.286355) (xy -18.911286 -119.373618) (xy -18.835369 -119.455437) (xy -18.75355 -119.531354)
			(xy -18.666287 -119.600944) (xy -18.574067 -119.663818) (xy -18.477406 -119.719626) (xy -18.376846 -119.768053)
			(xy -18.272947 -119.80883) (xy -18.166292 -119.841729) (xy -18.057476 -119.866566) (xy -17.947109 -119.883201)
			(xy -17.835807 -119.891542) (xy -17.78 -119.892064)
		)
		(stroke
			(width 0)
			(type solid)
		)
		(fill yes)
		(layer "In5.Cu")
		(net "T_GND")
	)
	(gr_poly
		(pts
			(arc
				(start 56.489092 -73.64476)
				(mid 56.812688 -73.465139)
				(end 57.136284 -73.64476)
			)
			(xy 66.059812 -73.64476)
			(arc
				(start 66.073274 -73.614788)
				(mid 66.421 -73.390245)
				(end 66.768726 -73.614788)
			)
			(xy 66.782188 -73.64476) (xy 80.63992 -73.64476)
			(arc
				(start 80.642968 -73.644506)
				(mid 80.665533 -73.642445)
				(end 80.68818 -73.641712)
			)
			(arc
				(start 80.68818 -73.641712)
				(mid 80.710828 -73.64243)
				(end 80.733392 -73.644506)
			)
			(xy 80.73644 -73.64476) (xy 88.562434 -73.64476)
			(arc
				(start 88.952324 -73.25487)
				(mid 88.967646 -73.240756)
				(end 88.984074 -73.227946)
			)
			(arc
				(start 88.984074 -71.604886)
				(mid 88.856597 -71.320152)
				(end 88.984074 -71.035418)
			)
			(arc
				(start 88.984074 -66.524886)
				(mid 88.856597 -66.240152)
				(end 88.984074 -65.955418)
			)
			(arc
				(start 88.984074 -61.444886)
				(mid 88.856597 -61.160152)
				(end 88.984074 -60.875418)
			)
			(arc
				(start 88.984074 -56.364886)
				(mid 88.856597 -56.080152)
				(end 88.984074 -55.795418)
			)
			(arc
				(start 88.984074 -51.284886)
				(mid 88.856597 -51.000152)
				(end 88.984074 -50.715418)
			)
			(arc
				(start 88.984074 -46.204886)
				(mid 88.856597 -45.920152)
				(end 88.984074 -45.635418)
			)
			(arc
				(start 88.984074 -41.124886)
				(mid 88.856597 -40.840152)
				(end 88.984074 -40.555418)
			)
			(arc
				(start 88.984074 -36.044886)
				(mid 88.856597 -35.760152)
				(end 88.984074 -35.475418)
			)
			(xy 88.984074 -34.552636) (xy 88.584786 -34.153348)
			(arc
				(start 83.440778 -34.153348)
				(mid 83.343591 -34.133998)
				(end 83.2612 -34.078926)
			)
			(arc
				(start 82.362802 -33.180528)
				(mid 82.307696 -33.098151)
				(end 82.28838 -33.00095)
			)
			(arc
				(start 82.28838 -33.00095)
				(mid 82.295201 -32.942482)
				(end 82.315304 -32.887158)
			)
			(xy 82.320638 -32.87649) (xy 82.320638 -29.892752) (xy 82.152236 -29.72435)
			(arc
				(start 82.143854 -29.72054)
				(mid 82.067787 -29.674615)
				(end 82.004408 -29.612336)
			)
			(xy 80.416146 -29.612336)
			(arc
				(start 80.407002 -29.651706)
				(mid 80.0354 -29.947048)
				(end 79.663798 -29.651706)
			)
			(xy 79.654654 -29.612336) (xy 77.599286 -29.612336)
			(arc
				(start 77.592174 -29.654754)
				(mid 77.216 -29.972538)
				(end 76.839826 -29.654754)
			)
			(xy 76.832714 -29.612336)
			(arc
				(start 49.334674 -29.612336)
				(mid 49.046384 -29.743948)
				(end 48.758094 -29.612336)
			)
			(arc
				(start 47.249588 -29.612336)
				(mid 46.921166 -29.799749)
				(end 46.592744 -29.612336)
			)
			(xy 41.290494 -29.612336) (xy 40.16883 -30.734) (xy 40.16883 -34.48812) (xy 42.7863 -37.10559) (xy 43.33367 -37.10559)
			(arc
				(start 43.343322 -37.067236)
				(mid 43.7134 -36.778624)
				(end 44.083478 -37.067236)
			)
			(xy 44.09313 -37.10559) (xy 65.284096 -37.10559)
			(arc
				(start 65.295272 -37.070284)
				(mid 65.659 -36.80403)
				(end 66.022728 -37.070284)
			)
			(xy 66.033904 -37.10559)
			(arc
				(start 68.887086 -37.10559)
				(mid 68.984273 -37.12494)
				(end 69.066664 -37.180012)
			)
			(arc
				(start 69.780658 -37.894006)
				(mid 69.835764 -37.976383)
				(end 69.85508 -38.073584)
			)
			(xy 69.85508 -44.195492)
			(arc
				(start 69.855842 -44.19981)
				(mid 69.860212 -44.231682)
				(end 69.861684 -44.263818)
			)
			(arc
				(start 69.861684 -44.263818)
				(mid 69.860208 -44.295954)
				(end 69.855842 -44.327826)
			)
			(xy 69.85508 -44.332144)
			(arc
				(start 69.85508 -68.784216)
				(mid 69.83573 -68.881403)
				(end 69.780658 -68.963794)
			)
			(arc
				(start 68.561712 -70.18274)
				(mid 68.479335 -70.237846)
				(end 68.382134 -70.257162)
			)
			(xy 59.257438 -70.257162) (xy 58.6994 -70.8152) (xy 56.793638 -70.8152) (xy 56.2356 -70.257162) (xy 54.833774 -70.257162)
			(xy 54.10581 -70.985126) (xy 54.10581 -73.3933) (xy 54.35727 -73.64476)
		)
		(stroke
			(width 0)
			(type solid)
		)
		(fill yes)
		(layer "In5.Cu")
		(net "P2V5_AUX")
	)
	(gr_poly
		(pts
			(xy 38.8366 -85.467444) (xy 38.8366 -74.549254) (xy 38.837216 -74.524299) (xy 38.846961 -74.47535)
			(xy 38.866068 -74.429242) (xy 38.893802 -74.387748) (xy 38.911022 -74.369676) (xy 39.561516 -73.719182)
			(xy 39.579556 -73.701919) (xy 39.621048 -73.674154) (xy 39.667166 -73.655034) (xy 39.716131 -73.645295)
			(xy 39.741094 -73.64476) (xy 53.294534 -73.64476) (xy 53.59781 -73.341484) (xy 53.59781 -70.87997)
			(xy 53.598424 -70.855015) (xy 53.608167 -70.806064) (xy 53.627273 -70.759955) (xy 53.655006 -70.718459)
			(xy 53.672232 -70.700392) (xy 54.54904 -69.823584) (xy 54.56708 -69.806322) (xy 54.608573 -69.778562)
			(xy 54.654691 -69.759445) (xy 54.703656 -69.749711) (xy 54.728618 -69.749162) (xy 56.439562 -69.749162)
			(xy 56.9976 -70.3072) (xy 58.496962 -70.3072) (xy 59.055 -69.749162) (xy 68.276978 -69.749162) (xy 69.34708 -68.67906)
			(xy 69.34708 -44.582588) (xy 69.323688 -44.570446) (xy 69.280453 -44.540311) (xy 69.242134 -44.50413)
			(xy 69.20957 -44.462693) (xy 69.183472 -44.416907) (xy 69.164412 -44.367773) (xy 69.152806 -44.316365)
			(xy 69.148909 -44.263808) (xy 69.152804 -44.211251) (xy 69.164408 -44.159843) (xy 69.183465 -44.110708)
			(xy 69.209561 -44.06492) (xy 69.242123 -44.023482) (xy 69.28044 -43.987299) (xy 69.323675 -43.957162)
			(xy 69.34708 -43.945048) (xy 69.34708 -38.17874) (xy 68.78193 -37.61359) (xy 42.681144 -37.61359)
			(xy 42.65619 -37.612973) (xy 42.607242 -37.603226) (xy 42.561136 -37.584117) (xy 42.519644 -37.556382)
			(xy 42.501566 -37.539168) (xy 39.735252 -34.772854) (xy 39.717993 -34.754813) (xy 39.690236 -34.713319)
			(xy 39.671124 -34.667201) (xy 39.661392 -34.618237) (xy 39.66083 -34.593276) (xy 39.66083 -33.714182)
			(xy 39.429182 -33.482534) (xy 38.088316 -33.482534) (xy 37.808154 -33.762696) (xy 37.808154 -37.143436)
			(xy 37.840412 -37.156136) (xy 37.865249 -37.166381) (xy 37.91201 -37.19284) (xy 37.954595 -37.225599)
			(xy 37.992161 -37.26401) (xy 38.023967 -37.307312) (xy 38.049381 -37.354648) (xy 38.067902 -37.405082)
			(xy 38.079162 -37.457616) (xy 38.08294 -37.51121) (xy 38.079159 -37.564804) (xy 38.067896 -37.617338)
			(xy 38.049373 -37.667771) (xy 38.023956 -37.715106) (xy 37.992148 -37.758406) (xy 37.954579 -37.796814)
			(xy 37.911993 -37.829571) (xy 37.865231 -37.856028) (xy 37.840412 -37.86632) (xy 37.808154 -37.87902)
			(xy 37.808154 -39.198804) (xy 37.839396 -39.211758) (xy 37.865188 -39.222967) (xy 37.913437 -39.251854)
			(xy 37.956923 -39.287511) (xy 37.994703 -39.329166) (xy 38.025959 -39.375916) (xy 38.050013 -39.426747)
			(xy 38.066344 -39.480559) (xy 38.074599 -39.536186) (xy 38.074599 -39.592422) (xy 38.066343 -39.648048)
			(xy 38.05001 -39.70186) (xy 38.025955 -39.752691) (xy 37.994698 -39.79944) (xy 37.956917 -39.841094)
			(xy 37.913431 -39.87675) (xy 37.865181 -39.905637) (xy 37.839396 -39.916862) (xy 37.808154 -39.929816)
			(xy 37.808154 -44.932168) (xy 66.731138 -44.932168) (xy 66.731138 -44.877632) (xy 66.738899 -44.823652)
			(xy 66.754264 -44.771325) (xy 66.776918 -44.721717) (xy 66.806402 -44.675839) (xy 66.842114 -44.634623)
			(xy 66.883329 -44.598909) (xy 66.929207 -44.569424) (xy 66.978814 -44.546768) (xy 67.03114 -44.531402)
			(xy 67.08512 -44.523639) (xy 67.112388 -44.523152) (xy 68.001388 -44.523152) (xy 68.028661 -44.523587)
			(xy 68.082651 -44.531348) (xy 68.134987 -44.546714) (xy 68.184603 -44.569371) (xy 68.23049 -44.59886)
			(xy 68.271713 -44.634578) (xy 68.307433 -44.6758) (xy 68.336923 -44.721686) (xy 68.359582 -44.771302)
			(xy 68.37495 -44.823638) (xy 68.382712 -44.877627) (xy 68.382712 -44.932173) (xy 68.37495 -44.986162)
			(xy 68.359582 -45.038498) (xy 68.336923 -45.088114) (xy 68.307433 -45.134) (xy 68.271713 -45.175222)
			(xy 68.23049 -45.21094) (xy 68.184603 -45.240429) (xy 68.134987 -45.263086) (xy 68.082651 -45.278452)
			(xy 68.028661 -45.286213) (xy 68.001388 -45.286676) (xy 67.112388 -45.286676) (xy 67.08512 -45.286161)
			(xy 67.03114 -45.278398) (xy 66.978814 -45.263032) (xy 66.929207 -45.240376) (xy 66.883329 -45.210891)
			(xy 66.842114 -45.175177) (xy 66.806402 -45.133961) (xy 66.776918 -45.088083) (xy 66.754264 -45.038475)
			(xy 66.738899 -44.986148) (xy 66.731138 -44.932168) (xy 37.808154 -44.932168) (xy 37.808154 -50.727864)
			(xy 37.827537 -50.747534) (xy 37.861003 -50.79146) (xy 37.887786 -50.839752) (xy 37.907327 -50.8914)
			(xy 37.919217 -50.945327) (xy 37.923207 -51.000404) (xy 37.919216 -51.055481) (xy 37.907324 -51.109408)
			(xy 37.887782 -51.161056) (xy 37.860998 -51.209347) (xy 37.827531 -51.253272) (xy 37.808154 -51.272948)
			(xy 37.808154 -52.67175) (xy 66.314303 -52.67175) (xy 66.314303 -52.61725) (xy 66.32206 -52.563304)
			(xy 66.337415 -52.511011) (xy 66.360056 -52.461436) (xy 66.389522 -52.415587) (xy 66.425214 -52.374399)
			(xy 66.466403 -52.33871) (xy 66.512253 -52.309246) (xy 66.56183 -52.286608) (xy 66.614123 -52.271256)
			(xy 66.66807 -52.263502) (xy 66.69532 -52.26304) (xy 67.58432 -52.26304) (xy 67.611574 -52.263431)
			(xy 67.665526 -52.271191) (xy 67.717825 -52.28655) (xy 67.767406 -52.309195) (xy 67.81326 -52.338666)
			(xy 67.854453 -52.374362) (xy 67.890146 -52.415556) (xy 67.919615 -52.461412) (xy 67.942257 -52.510994)
			(xy 67.957613 -52.563293) (xy 67.96537 -52.617246) (xy 67.96537 -52.671754) (xy 67.957613 -52.725707)
			(xy 67.942257 -52.778006) (xy 67.919615 -52.827588) (xy 67.890146 -52.873444) (xy 67.854453 -52.914638)
			(xy 67.81326 -52.950334) (xy 67.767406 -52.979805) (xy 67.717825 -53.00245) (xy 67.665526 -53.017809)
			(xy 67.611574 -53.025569) (xy 67.58432 -53.026056) (xy 66.69532 -53.026056) (xy 66.66807 -53.025498)
			(xy 66.614123 -53.017744) (xy 66.56183 -53.002392) (xy 66.512253 -52.979754) (xy 66.466403 -52.95029)
			(xy 66.425214 -52.914601) (xy 66.389522 -52.873413) (xy 66.360056 -52.827564) (xy 66.337415 -52.777989)
			(xy 66.32206 -52.725696) (xy 66.314303 -52.67175) (xy 37.808154 -52.67175) (xy 37.808154 -54.53387)
			(xy 66.568023 -54.53387) (xy 66.568023 -54.47933) (xy 66.575786 -54.425344) (xy 66.591152 -54.373013)
			(xy 66.61381 -54.323401) (xy 66.643298 -54.277519) (xy 66.679015 -54.236301) (xy 66.720235 -54.200586)
			(xy 66.766119 -54.1711) (xy 66.815732 -54.148445) (xy 66.868064 -54.133081) (xy 66.92205 -54.125322)
			(xy 66.94932 -54.12486) (xy 67.83832 -54.12486) (xy 67.86559 -54.125304) (xy 67.919575 -54.133068)
			(xy 67.971905 -54.148436) (xy 68.021515 -54.171095) (xy 68.067396 -54.200583) (xy 68.108614 -54.2363)
			(xy 68.144329 -54.27752) (xy 68.173815 -54.323402) (xy 68.196471 -54.373014) (xy 68.211836 -54.425345)
			(xy 68.219598 -54.47933) (xy 68.219598 -54.53387) (xy 68.211836 -54.587855) (xy 68.196471 -54.640186)
			(xy 68.173815 -54.689798) (xy 68.144329 -54.73568) (xy 68.108614 -54.7769) (xy 68.067396 -54.812617)
			(xy 68.021515 -54.842105) (xy 67.971905 -54.864764) (xy 67.919575 -54.880132) (xy 67.86559 -54.887896)
			(xy 67.83832 -54.888384) (xy 66.94932 -54.888384) (xy 66.92205 -54.887878) (xy 66.868064 -54.880119)
			(xy 66.815732 -54.864755) (xy 66.766119 -54.8421) (xy 66.720235 -54.812614) (xy 66.679015 -54.776899)
			(xy 66.643298 -54.735681) (xy 66.61381 -54.689799) (xy 66.591152 -54.640187) (xy 66.575786 -54.587856)
			(xy 66.568023 -54.53387) (xy 37.808154 -54.53387) (xy 37.808154 -56.035702) (xy 37.808408 -56.036464)
			(xy 37.811286 -56.050189) (xy 37.814346 -56.078067) (xy 37.814504 -56.09209) (xy 37.814324 -56.106112)
			(xy 37.811271 -56.133989) (xy 37.808408 -56.147716) (xy 37.808154 -56.148478) (xy 37.808154 -58.166508)
			(xy 60.959492 -58.166508) (xy 60.959492 -57.366662) (xy 60.959966 -57.340674) (xy 60.968103 -57.289338)
			(xy 60.984169 -57.239907) (xy 61.007769 -57.193597) (xy 61.038323 -57.15155) (xy 61.075078 -57.114799)
			(xy 61.11713 -57.08425) (xy 61.163442 -57.060654) (xy 61.212875 -57.044594) (xy 61.264212 -57.036464)
			(xy 61.2902 -57.035954) (xy 61.317668 -57.036479) (xy 61.371851 -57.04555) (xy 61.423791 -57.063444)
			(xy 61.472065 -57.089668) (xy 61.515345 -57.123503) (xy 61.534294 -57.143396) (xy 61.55212 -57.162087)
			(xy 61.582322 -57.203984) (xy 61.605643 -57.250068) (xy 61.621515 -57.299217) (xy 61.629551 -57.350236)
			(xy 61.630052 -57.37606) (xy 61.629773 -57.39555) (xy 61.625189 -57.43426) (xy 61.620908 -57.453276)
			(xy 61.620908 -58.166508) (xy 61.620398 -58.192491) (xy 63.359983 -58.192491) (xy 63.359983 -58.140509)
			(xy 63.368116 -58.089167) (xy 63.38418 -58.03973) (xy 63.407782 -57.993415) (xy 63.438338 -57.951362)
			(xy 63.475097 -57.914608) (xy 63.517154 -57.884058) (xy 63.563473 -57.860463) (xy 63.612912 -57.844405)
			(xy 63.664255 -57.83628) (xy 63.690246 -57.8358) (xy 64.490092 -57.8358) (xy 64.516082 -57.836267)
			(xy 64.567423 -57.844397) (xy 64.61686 -57.860459) (xy 64.663175 -57.884057) (xy 64.705229 -57.91461)
			(xy 64.741985 -57.951365) (xy 64.772539 -57.993418) (xy 64.796138 -58.039733) (xy 64.812201 -58.089169)
			(xy 64.820333 -58.14051) (xy 64.820333 -58.19249) (xy 64.812201 -58.243831) (xy 64.796138 -58.293267)
			(xy 64.772539 -58.339582) (xy 64.741985 -58.381635) (xy 64.705229 -58.41839) (xy 64.663175 -58.448943)
			(xy 64.61686 -58.472541) (xy 64.567423 -58.488603) (xy 64.516082 -58.496733) (xy 64.490092 -58.497216)
			(xy 63.690246 -58.497216) (xy 63.664255 -58.49672) (xy 63.612912 -58.488595) (xy 63.563473 -58.472537)
			(xy 63.517154 -58.448942) (xy 63.475097 -58.418392) (xy 63.438338 -58.381638) (xy 63.407782 -58.339585)
			(xy 63.38418 -58.29327) (xy 63.368116 -58.243833) (xy 63.359983 -58.192491) (xy 61.620398 -58.192491)
			(xy 61.620398 -58.192495) (xy 61.612268 -58.24383) (xy 61.596207 -58.29326) (xy 61.572611 -58.33957)
			(xy 61.542061 -58.381618) (xy 61.50531 -58.418369) (xy 61.463262 -58.448919) (xy 61.416952 -58.472515)
			(xy 61.367522 -58.488576) (xy 61.316187 -58.496706) (xy 61.264213 -58.496706) (xy 61.212878 -58.488576)
			(xy 61.163448 -58.472515) (xy 61.117138 -58.448919) (xy 61.07509 -58.418369) (xy 61.038339 -58.381618)
			(xy 61.007789 -58.33957) (xy 60.984193 -58.29326) (xy 60.968132 -58.24383) (xy 60.960002 -58.192495)
			(xy 60.959492 -58.166508) (xy 37.808154 -58.166508) (xy 37.808154 -58.992411) (xy 61.759802 -58.992411)
			(xy 61.759802 -58.940389) (xy 61.76794 -58.889008) (xy 61.784015 -58.839533) (xy 61.807633 -58.793181)
			(xy 61.83821 -58.751095) (xy 61.874995 -58.71431) (xy 61.917081 -58.683733) (xy 61.963433 -58.660115)
			(xy 62.012908 -58.64404) (xy 62.064289 -58.635902) (xy 62.0903 -58.635392) (xy 62.890146 -58.635392)
			(xy 62.916147 -58.635998) (xy 62.967508 -58.644139) (xy 63.016964 -58.660214) (xy 63.063296 -58.683827)
			(xy 63.105364 -58.714397) (xy 63.142133 -58.751171) (xy 63.172697 -58.793243) (xy 63.196303 -58.839579)
			(xy 63.212372 -58.889036) (xy 63.220506 -58.940399) (xy 63.220506 -58.992401) (xy 63.220505 -58.99241)
			(xy 64.159602 -58.99241) (xy 64.159602 -58.94039) (xy 64.16774 -58.889009) (xy 64.183815 -58.839535)
			(xy 64.207431 -58.793184) (xy 64.238008 -58.751098) (xy 64.274792 -58.714313) (xy 64.316877 -58.683735)
			(xy 64.363227 -58.660118) (xy 64.412702 -58.644042) (xy 64.464082 -58.635903) (xy 64.490092 -58.635392)
			(xy 65.289938 -58.635392) (xy 65.31594 -58.635997) (xy 65.367302 -58.644137) (xy 65.416758 -58.660212)
			(xy 65.463091 -58.683825) (xy 65.505161 -58.714394) (xy 65.541931 -58.751168) (xy 65.572495 -58.793241)
			(xy 65.596103 -58.839577) (xy 65.612171 -58.889035) (xy 65.620306 -58.940398) (xy 65.620306 -58.992402)
			(xy 65.612171 -59.043765) (xy 65.596103 -59.093223) (xy 65.572495 -59.139559) (xy 65.541931 -59.181632)
			(xy 65.505161 -59.218406) (xy 65.463091 -59.248975) (xy 65.416758 -59.272588) (xy 65.367302 -59.288663)
			(xy 65.31594 -59.296803) (xy 65.289938 -59.297316) (xy 64.490092 -59.297316) (xy 64.464082 -59.296897)
			(xy 64.412702 -59.288758) (xy 64.363227 -59.272682) (xy 64.316877 -59.249065) (xy 64.274792 -59.218487)
			(xy 64.238008 -59.181702) (xy 64.207431 -59.139616) (xy 64.183815 -59.093265) (xy 64.16774 -59.043791)
			(xy 64.159602 -58.99241) (xy 63.220505 -58.99241) (xy 63.212372 -59.043763) (xy 63.196303 -59.093221)
			(xy 63.172697 -59.139557) (xy 63.142133 -59.181629) (xy 63.105364 -59.218403) (xy 63.063296 -59.248973)
			(xy 63.016964 -59.272586) (xy 62.967508 -59.288661) (xy 62.916147 -59.296802) (xy 62.890146 -59.297316)
			(xy 62.0903 -59.297316) (xy 62.064289 -59.296898) (xy 62.012908 -59.28876) (xy 61.963433 -59.272685)
			(xy 61.917081 -59.249067) (xy 61.874995 -59.21849) (xy 61.83821 -59.181705) (xy 61.807633 -59.139619)
			(xy 61.784015 -59.093267) (xy 61.76794 -59.043792) (xy 61.759802 -58.992411) (xy 37.808154 -58.992411)
			(xy 37.808154 -59.792515) (xy 63.359676 -59.792515) (xy 63.359676 -59.740485) (xy 63.367816 -59.689095)
			(xy 63.383895 -59.639612) (xy 63.407519 -59.593254) (xy 63.438104 -59.551162) (xy 63.474897 -59.514374)
			(xy 63.516993 -59.483794) (xy 63.563355 -59.460178) (xy 63.61284 -59.444105) (xy 63.664231 -59.435972)
			(xy 63.690246 -59.435492) (xy 64.490092 -59.435492) (xy 64.516098 -59.436067) (xy 64.56747 -59.444202)
			(xy 64.616937 -59.460274) (xy 64.66328 -59.483886) (xy 64.705359 -59.514457) (xy 64.742138 -59.551235)
			(xy 64.77271 -59.593313) (xy 64.796323 -59.639656) (xy 64.812396 -59.689122) (xy 64.820533 -59.740494)
			(xy 64.820533 -59.792506) (xy 64.812396 -59.843878) (xy 64.796323 -59.893344) (xy 64.77271 -59.939687)
			(xy 64.742138 -59.981765) (xy 64.705359 -60.018543) (xy 64.66328 -60.049114) (xy 64.616937 -60.072726)
			(xy 64.56747 -60.088798) (xy 64.516098 -60.096933) (xy 64.490092 -60.097416) (xy 63.690246 -60.097416)
			(xy 63.664231 -60.097028) (xy 63.61284 -60.088895) (xy 63.563355 -60.072822) (xy 63.516993 -60.049206)
			(xy 63.474897 -60.018626) (xy 63.438104 -59.981838) (xy 63.407519 -59.939746) (xy 63.383895 -59.893388)
			(xy 63.367816 -59.843905) (xy 63.359676 -59.792515) (xy 37.808154 -59.792515) (xy 37.808154 -60.3494)
			(xy 60.569868 -60.3494) (xy 60.573857 -60.296174) (xy 60.585733 -60.244137) (xy 60.605233 -60.194451)
			(xy 60.631919 -60.148227) (xy 60.665197 -60.106496) (xy 60.704323 -60.07019) (xy 60.748422 -60.040121)
			(xy 60.796511 -60.016961) (xy 60.847514 -60.001226) (xy 60.900292 -59.993268) (xy 60.92698 -59.992768)
			(xy 60.949767 -59.993141) (xy 60.994967 -59.998968) (xy 61.03906 -60.010491) (xy 61.06033 -60.018676)
			(xy 61.555376 -60.018676) (xy 61.564012 -60.015374) (xy 61.594178 -60.00485) (xy 61.657039 -59.993478)
			(xy 61.68898 -59.992768) (xy 61.717333 -59.993267) (xy 61.773326 -60.002234) (xy 61.827196 -60.019945)
			(xy 61.877586 -60.045954) (xy 61.923227 -60.079606) (xy 61.943488 -60.099448) (xy 61.962622 -60.116719)
			(xy 61.995857 -60.156112) (xy 62.022581 -60.200183) (xy 62.042146 -60.247865) (xy 62.054078 -60.298005)
			(xy 62.058089 -60.34939) (xy 62.054081 -60.400774) (xy 62.042152 -60.450915) (xy 62.022591 -60.498599)
			(xy 61.99587 -60.542671) (xy 61.962636 -60.582066) (xy 61.943488 -60.59932) (xy 61.923242 -60.619175)
			(xy 61.877589 -60.652806) (xy 61.827194 -60.678797) (xy 61.773323 -60.696496) (xy 61.717332 -60.705456)
			(xy 61.68898 -60.706) (xy 61.657039 -60.705289) (xy 61.594177 -60.693921) (xy 61.564012 -60.683394)
			(xy 61.555376 -60.680092) (xy 61.06033 -60.680092) (xy 61.039069 -60.688303) (xy 60.994975 -60.699837)
			(xy 60.949769 -60.705644) (xy 60.92698 -60.706) (xy 60.900292 -60.705532) (xy 60.847514 -60.697574)
			(xy 60.796511 -60.681839) (xy 60.748422 -60.658679) (xy 60.704323 -60.62861) (xy 60.665197 -60.592304)
			(xy 60.631919 -60.550573) (xy 60.605233 -60.504349) (xy 60.585733 -60.454663) (xy 60.573857 -60.402626)
			(xy 60.569868 -60.3494) (xy 37.808154 -60.3494) (xy 37.808154 -63.791846) (xy 37.807578 -63.816804)
			(xy 37.79783 -63.86576) (xy 37.778718 -63.911873) (xy 37.750976 -63.953371) (xy 37.733732 -63.971424)
			(xy 35.155378 -66.549778) (xy 35.137339 -66.567043) (xy 35.095848 -66.594811) (xy 35.04973 -66.613933)
			(xy 35.000763 -66.623673) (xy 34.9758 -66.6242) (xy 30.026356 -66.6242) (xy 29.3878 -67.262756) (xy 29.3878 -69.182234)
			(xy 29.412023 -69.195547) (xy 29.456697 -69.228091) (xy 29.496207 -69.266741) (xy 29.529727 -69.310688)
			(xy 29.556555 -69.359012) (xy 29.57613 -69.410701) (xy 29.58804 -69.464674) (xy 29.592039 -69.5198)
			(xy 29.58804 -69.574926) (xy 29.57613 -69.628899) (xy 29.556555 -69.680588) (xy 29.529727 -69.728912)
			(xy 29.496207 -69.772859) (xy 29.456697 -69.811509) (xy 29.412023 -69.844053) (xy 29.3878 -69.857366)
			(xy 29.3878 -75.635104) (xy 35.491176 -75.635104) (xy 35.495155 -75.535091) (xy 35.507068 -75.43571)
			(xy 35.526839 -75.33759) (xy 35.554343 -75.241351) (xy 35.589406 -75.147602) (xy 35.631807 -75.056934)
			(xy 35.681278 -74.969922) (xy 35.737505 -74.887115) (xy 35.800133 -74.809038) (xy 35.868767 -74.736183)
			(xy 35.942972 -74.669011) (xy 36.02228 -74.607948) (xy 36.106188 -74.553378) (xy 36.194166 -74.505647)
			(xy 36.285659 -74.465057) (xy 36.380087 -74.431865) (xy 36.476854 -74.40628) (xy 36.575348 -74.388463)
			(xy 36.674946 -74.378529) (xy 36.775018 -74.376539) (xy 36.874932 -74.382506) (xy 36.974056 -74.396392)
			(xy 37.071764 -74.41811) (xy 37.167437 -74.447522) (xy 37.260471 -74.484443) (xy 37.350277 -74.528638)
			(xy 37.436289 -74.579828) (xy 37.517961 -74.637691) (xy 37.594778 -74.701859) (xy 37.666254 -74.771928)
			(xy 37.731937 -74.847454) (xy 37.791412 -74.92796) (xy 37.844303 -75.012936) (xy 37.890275 -75.101846)
			(xy 37.929037 -75.194128) (xy 37.960346 -75.289197) (xy 37.984002 -75.386454) (xy 37.999856 -75.485282)
			(xy 38.007809 -75.585058) (xy 38.008306 -75.635104) (xy 38.007809 -75.68515) (xy 37.999856 -75.784926)
			(xy 37.984002 -75.883754) (xy 37.960346 -75.981011) (xy 37.929037 -76.07608) (xy 37.890275 -76.168362)
			(xy 37.844303 -76.257272) (xy 37.791412 -76.342248) (xy 37.731937 -76.422754) (xy 37.666254 -76.49828)
			(xy 37.594778 -76.568349) (xy 37.517961 -76.632517) (xy 37.436289 -76.69038) (xy 37.350277 -76.74157)
			(xy 37.260471 -76.785765) (xy 37.167437 -76.822686) (xy 37.071764 -76.852098) (xy 36.974056 -76.873816)
			(xy 36.874932 -76.887702) (xy 36.775018 -76.893669) (xy 36.674946 -76.891679) (xy 36.575348 -76.881745)
			(xy 36.476854 -76.863928) (xy 36.380087 -76.838343) (xy 36.285659 -76.805151) (xy 36.194166 -76.764561)
			(xy 36.106188 -76.71683) (xy 36.02228 -76.66226) (xy 35.942972 -76.601197) (xy 35.868767 -76.534025)
			(xy 35.800133 -76.46117) (xy 35.737505 -76.383093) (xy 35.681278 -76.300286) (xy 35.631807 -76.213274)
			(xy 35.589406 -76.122606) (xy 35.554343 -76.028857) (xy 35.526839 -75.932618) (xy 35.507068 -75.834498)
			(xy 35.495155 -75.735117) (xy 35.491176 -75.635104) (xy 29.3878 -75.635104) (xy 29.3878 -83.816444)
			(xy 31.728156 -86.1568) (xy 38.147244 -86.1568)
		)
		(stroke
			(width 0)
			(type solid)
		)
		(fill yes)
		(layer "In5.Cu")
		(net "P1V8_AUX")
	)
	(gr_poly
		(pts
			(xy 28.776676 -89.070434) (xy 28.786702 -89.045154) (xy 28.812885 -88.99749) (xy 28.84557 -88.954026)
			(xy 28.884095 -88.915643) (xy 28.92768 -88.883119) (xy 28.975441 -88.857113) (xy 29.02641 -88.838151)
			(xy 29.079556 -88.826618) (xy 29.1338 -88.822748) (xy 29.188044 -88.826618) (xy 29.24119 -88.838151)
			(xy 29.292159 -88.857113) (xy 29.33992 -88.883119) (xy 29.383505 -88.915643) (xy 29.42203 -88.954026)
			(xy 29.454715 -88.99749) (xy 29.480898 -89.045154) (xy 29.490924 -89.070434) (xy 29.503116 -89.1032)
			(xy 42.316146 -89.1032) (xy 42.601134 -88.818212) (xy 42.598086 -88.793828) (xy 42.596786 -88.782379)
			(xy 42.595386 -88.759376) (xy 42.595292 -88.747854) (xy 42.595292 -88.7476) (xy 42.595778 -88.720349)
			(xy 42.603534 -88.666401) (xy 42.618889 -88.614106) (xy 42.641531 -88.564529) (xy 42.670997 -88.518679)
			(xy 42.706688 -88.477488) (xy 42.747879 -88.441797) (xy 42.793729 -88.412331) (xy 42.843306 -88.389689)
			(xy 42.895601 -88.374334) (xy 42.949549 -88.366578) (xy 42.9768 -88.366092) (xy 42.977054 -88.366092)
			(xy 42.988577 -88.366175) (xy 43.01158 -88.367571) (xy 43.023028 -88.368886) (xy 43.047412 -88.371934)
			(xy 46.1772 -85.242146) (xy 46.1772 -83.14817) (xy 46.149514 -83.1342) (xy 46.124778 -83.121066)
			(xy 46.079107 -83.088651) (xy 46.038664 -83.049909) (xy 46.00432 -83.00567) (xy 45.976811 -82.956887)
			(xy 45.956728 -82.904606) (xy 45.944504 -82.849952) (xy 45.9404 -82.794097) (xy 45.944504 -82.738243)
			(xy 45.95673 -82.683588) (xy 45.976813 -82.631308) (xy 46.004323 -82.582525) (xy 46.038668 -82.538287)
			(xy 46.079111 -82.499545) (xy 46.124782 -82.467131) (xy 46.149514 -82.453988) (xy 46.1772 -82.440018)
			(xy 46.1772 -79.0194) (xy 46.177812 -78.994443) (xy 46.187549 -78.945489) (xy 46.20665 -78.899376)
			(xy 46.23438 -78.857874) (xy 46.251622 -78.839822) (xy 46.810422 -78.281022) (xy 46.828461 -78.263757)
			(xy 46.869952 -78.235989) (xy 46.91607 -78.216867) (xy 46.965037 -78.207127) (xy 46.99 -78.2066)
			(xy 48.513492 -78.2066) (xy 48.525938 -78.174088) (xy 48.536109 -78.149091) (xy 48.562477 -78.102007)
			(xy 48.595217 -78.059107) (xy 48.633675 -78.021249) (xy 48.677083 -77.989187) (xy 48.724576 -77.963562)
			(xy 48.775205 -77.944883) (xy 48.827962 -77.933525) (xy 48.881792 -77.929714) (xy 48.935622 -77.933525)
			(xy 48.988379 -77.944883) (xy 49.039008 -77.963562) (xy 49.086501 -77.989187) (xy 49.129909 -78.021249)
			(xy 49.168367 -78.059107) (xy 49.201107 -78.102007) (xy 49.227475 -78.149091) (xy 49.237646 -78.174088)
			(xy 49.250092 -78.2066) (xy 53.951632 -78.2066) (xy 53.968323 -78.185058) (xy 54.006842 -78.146511)
			(xy 54.050458 -78.11384) (xy 54.098281 -78.087713) (xy 54.149336 -78.06866) (xy 54.202584 -78.057071)
			(xy 54.25694 -78.053182) (xy 54.311296 -78.057071) (xy 54.364544 -78.06866) (xy 54.415599 -78.087713)
			(xy 54.463422 -78.11384) (xy 54.507038 -78.146511) (xy 54.545557 -78.185058) (xy 54.562248 -78.2066)
			(xy 56.968644 -78.2066) (xy 57.820306 -77.354938) (xy 57.831986 -77.341076) (xy 57.857555 -77.315378)
			(xy 57.87136 -77.30363) (xy 57.873138 -77.302106) (xy 57.936892 -77.238352) (xy 57.89803 -77.19949)
			(xy 57.894474 -77.19695) (xy 57.873522 -77.181546) (xy 57.835589 -77.145975) (xy 57.802837 -77.105582)
			(xy 57.775873 -77.061116) (xy 57.755198 -77.013401) (xy 57.741192 -76.96332) (xy 57.734118 -76.911801)
			(xy 57.733692 -76.8858) (xy 57.734139 -76.859325) (xy 57.741451 -76.806883) (xy 57.755949 -76.755956)
			(xy 57.777354 -76.707526) (xy 57.805253 -76.662523) (xy 57.839111 -76.621813) (xy 57.878276 -76.586179)
			(xy 57.921995 -76.556306) (xy 57.945528 -76.54417) (xy 57.973722 -76.5302) (xy 57.973722 -74.413364)
			(xy 57.713118 -74.15276) (xy 57.040526 -74.15276) (xy 57.018465 -74.168574) (xy 56.970765 -74.194471)
			(xy 56.919877 -74.213352) (xy 56.866828 -74.224835) (xy 56.812688 -74.228689) (xy 56.758548 -74.224835)
			(xy 56.705499 -74.213352) (xy 56.654611 -74.194471) (xy 56.606911 -74.168574) (xy 56.58485 -74.15276)
			(xy 49.248314 -74.15276) (xy 49.242218 -74.196448) (xy 49.237908 -74.223386) (xy 49.222595 -74.275744)
			(xy 49.19998 -74.325388) (xy 49.170525 -74.371305) (xy 49.13483 -74.412558) (xy 49.093624 -74.448307)
			(xy 49.047745 -74.477822) (xy 48.998131 -74.500501) (xy 48.945792 -74.515883) (xy 48.891796 -74.523653)
			(xy 48.837244 -74.523653) (xy 48.783248 -74.515883) (xy 48.730909 -74.500501) (xy 48.681295 -74.477822)
			(xy 48.635416 -74.448307) (xy 48.59421 -74.412558) (xy 48.558515 -74.371305) (xy 48.52906 -74.325388)
			(xy 48.506445 -74.275744) (xy 48.491132 -74.223386) (xy 48.486822 -74.196448) (xy 48.480726 -74.15276)
			(xy 41.54678 -74.15276) (xy 41.535096 -74.187558) (xy 41.525733 -74.213958) (xy 41.500364 -74.263899)
			(xy 41.467965 -74.309593) (xy 41.429232 -74.350058) (xy 41.384997 -74.384422) (xy 41.336212 -74.411949)
			(xy 41.283927 -74.432044) (xy 41.229264 -74.444277) (xy 41.1734 -74.448384) (xy 41.117536 -74.444277)
			(xy 41.062873 -74.432044) (xy 41.010588 -74.411949) (xy 40.961803 -74.384422) (xy 40.917568 -74.350058)
			(xy 40.878835 -74.309593) (xy 40.846436 -74.263899) (xy 40.821067 -74.213958) (xy 40.811704 -74.187558)
			(xy 40.80002 -74.15276) (xy 39.84625 -74.15276) (xy 39.3446 -74.65441) (xy 39.3446 -85.5726) (xy 39.343988 -85.597557)
			(xy 39.334251 -85.646511) (xy 39.31515 -85.692624) (xy 39.28742 -85.734126) (xy 39.270178 -85.752178)
			(xy 38.431978 -86.590378) (xy 38.413939 -86.607643) (xy 38.372448 -86.635411) (xy 38.32633 -86.654533)
			(xy 38.277363 -86.664273) (xy 38.2524 -86.6648) (xy 34.924238 -86.6648) (xy 34.91484 -86.703662)
			(xy 34.907695 -86.731029) (xy 34.886433 -86.78344) (xy 34.857665 -86.832138) (xy 34.822024 -86.876055)
			(xy 34.78029 -86.914229) (xy 34.733377 -86.945823) (xy 34.682314 -86.970145) (xy 34.62822 -86.986662)
			(xy 34.57228 -86.995012) (xy 34.51572 -86.995012) (xy 34.45978 -86.986662) (xy 34.405686 -86.970145)
			(xy 34.354623 -86.945823) (xy 34.30771 -86.914229) (xy 34.265976 -86.876055) (xy 34.230335 -86.832138)
			(xy 34.201567 -86.78344) (xy 34.180305 -86.731029) (xy 34.17316 -86.703662) (xy 34.163762 -86.6648)
			(xy 31.623 -86.6648) (xy 31.598043 -86.664188) (xy 31.549089 -86.654451) (xy 31.502976 -86.63535)
			(xy 31.461474 -86.60762) (xy 31.443422 -86.590378) (xy 28.954222 -84.101178) (xy 28.936957 -84.083139)
			(xy 28.909189 -84.041648) (xy 28.890067 -83.99553) (xy 28.880327 -83.946563) (xy 28.8798 -83.9216)
			(xy 28.8798 -69.710808) (xy 28.865914 -69.685804) (xy 28.844973 -69.632584) (xy 28.832217 -69.576832)
			(xy 28.827933 -69.5198) (xy 28.832217 -69.462768) (xy 28.844973 -69.407016) (xy 28.865914 -69.353796)
			(xy 28.8798 -69.328792) (xy 28.8798 -67.1576) (xy 28.880412 -67.132643) (xy 28.890149 -67.083689)
			(xy 28.90925 -67.037576) (xy 28.93698 -66.996074) (xy 28.954222 -66.978022) (xy 29.741622 -66.190622)
			(xy 29.759661 -66.173357) (xy 29.801152 -66.145589) (xy 29.84727 -66.126467) (xy 29.896237 -66.116727)
			(xy 29.9212 -66.1162) (xy 34.870644 -66.1162) (xy 35.614864 -65.37198) (xy 35.594171 -65.350381)
			(xy 35.559086 -65.30194) (xy 35.531986 -65.248618) (xy 35.513535 -65.191723) (xy 35.504184 -65.132646)
			(xy 35.503612 -65.10274) (xy 35.504073 -65.075486) (xy 35.511825 -65.021532) (xy 35.527178 -64.96923)
			(xy 35.549818 -64.919646) (xy 35.579286 -64.87379) (xy 35.61498 -64.832594) (xy 35.656173 -64.796898)
			(xy 35.702029 -64.767428) (xy 35.751611 -64.744785) (xy 35.803912 -64.729429) (xy 35.857866 -64.721674)
			(xy 35.88512 -64.721232) (xy 35.915029 -64.721809) (xy 35.974114 -64.731136) (xy 36.031019 -64.749573)
			(xy 36.084347 -64.776668) (xy 36.132792 -64.811757) (xy 36.15436 -64.832484) (xy 37.300154 -63.68669)
			(xy 37.300154 -56.238902) (xy 37.295582 -56.228996) (xy 37.28723 -56.209269) (xy 37.276519 -56.167793)
			(xy 37.272914 -56.125109) (xy 37.276516 -56.082425) (xy 37.287224 -56.040949) (xy 37.295582 -56.021224)
			(xy 37.300154 -56.011318) (xy 37.300154 -51.296062) (xy 37.278615 -51.277847) (xy 37.24062 -51.236153)
			(xy 37.20918 -51.189318) (xy 37.184979 -51.138364) (xy 37.168546 -51.084402) (xy 37.160238 -51.028608)
			(xy 37.160238 -50.972199) (xy 37.168544 -50.916405) (xy 37.184976 -50.862443) (xy 37.209176 -50.811488)
			(xy 37.240615 -50.764653) (xy 37.278609 -50.722959) (xy 37.300154 -50.70475) (xy 37.300154 -45.469302)
			(xy 37.256212 -45.463206) (xy 37.229156 -45.459022) (xy 37.176534 -45.44391) (xy 37.126614 -45.42143)
			(xy 37.080421 -45.392044) (xy 37.038903 -45.356356) (xy 37.002915 -45.315098) (xy 36.973195 -45.26912)
			(xy 36.950353 -45.219364) (xy 36.93486 -45.166854) (xy 36.927034 -45.112668) (xy 36.927035 -45.05792)
			(xy 36.934863 -45.003734) (xy 36.950358 -44.951224) (xy 36.973201 -44.90147) (xy 37.002922 -44.855492)
			(xy 37.038912 -44.814235) (xy 37.080431 -44.778548) (xy 37.126625 -44.749164) (xy 37.176546 -44.726686)
			(xy 37.229168 -44.711576) (xy 37.256212 -44.707302) (xy 37.300154 -44.701206) (xy 37.300154 -33.65754)
			(xy 37.300731 -33.632582) (xy 37.310482 -33.583628) (xy 37.329596 -33.537517) (xy 37.35734 -33.496022)
			(xy 37.374576 -33.477962) (xy 37.803582 -33.048956) (xy 37.821624 -33.031699) (xy 37.863119 -33.003948)
			(xy 37.909237 -32.984842) (xy 37.9582 -32.975117) (xy 37.98316 -32.974534) (xy 39.247318 -32.974534)
			(xy 39.261619 -32.974059) (xy 39.2891 -32.966138) (xy 39.3133 -32.950895) (xy 39.332315 -32.929531)
			(xy 39.344647 -32.903726) (xy 39.349327 -32.875511) (xy 39.348156 -32.86125) (xy 39.346974 -32.850367)
			(xy 39.345705 -32.828509) (xy 39.345616 -32.817562) (xy 39.346098 -32.790072) (xy 39.353995 -32.73566)
			(xy 39.369619 -32.682946) (xy 39.392646 -32.63302) (xy 39.422601 -32.586915) (xy 39.458862 -32.545587)
			(xy 39.50068 -32.509891) (xy 39.547188 -32.480566) (xy 39.597423 -32.45822) (xy 39.623746 -32.450278)
			(xy 39.66083 -32.439864) (xy 39.66083 -32.107378) (xy 39.62019 -32.09925) (xy 39.593348 -32.093252)
			(xy 39.541616 -32.074578) (xy 39.4931 -32.048671) (xy 39.448806 -32.016067) (xy 39.409651 -31.977444)
			(xy 39.376445 -31.933599) (xy 39.349877 -31.885442) (xy 39.330498 -31.83397) (xy 39.318707 -31.780249)
			(xy 39.314751 -31.725392) (xy 39.31871 -31.670536) (xy 39.330502 -31.616815) (xy 39.349884 -31.565344)
			(xy 39.376454 -31.517188) (xy 39.409661 -31.473345) (xy 39.448818 -31.434723) (xy 39.493113 -31.402121)
			(xy 39.54163 -31.376216) (xy 39.593363 -31.357544) (xy 39.62019 -31.351474) (xy 39.66083 -31.343346)
			(xy 39.66083 -30.628844) (xy 39.661407 -30.603886) (xy 39.671156 -30.554931) (xy 39.690269 -30.508818)
			(xy 39.718011 -30.467321) (xy 39.735252 -30.449266) (xy 41.00576 -29.178758) (xy 41.023801 -29.161499)
			(xy 41.065296 -29.133745) (xy 41.111414 -29.114634) (xy 41.160377 -29.104905) (xy 41.185338 -29.104336)
			(xy 46.704504 -29.104336) (xy 46.728518 -29.088392) (xy 46.780335 -29.063148) (xy 46.835363 -29.045991)
			(xy 46.892346 -29.037314) (xy 46.949986 -29.037314) (xy 47.006969 -29.045991) (xy 47.061997 -29.063148)
			(xy 47.113814 -29.088392) (xy 47.137828 -29.104336) (xy 48.76546 -29.104336) (xy 48.785267 -29.083524)
			(xy 48.830023 -29.047503) (xy 48.879677 -29.018604) (xy 48.933104 -28.997482) (xy 48.989096 -28.984614)
			(xy 49.046384 -28.980292) (xy 49.103672 -28.984614) (xy 49.159664 -28.997482) (xy 49.213091 -29.018604)
			(xy 49.262745 -29.047503) (xy 49.307501 -29.083524) (xy 49.327308 -29.104336) (xy 60.30087 -29.104336)
			(xy 60.310776 -29.065982) (xy 60.318104 -29.038877) (xy 60.339629 -28.987019) (xy 60.368527 -28.938878)
			(xy 60.404171 -28.895495) (xy 60.445791 -28.857808) (xy 60.492488 -28.826631) (xy 60.543252 -28.802639)
			(xy 60.596985 -28.78635) (xy 60.652526 -28.778116) (xy 60.708674 -28.778116) (xy 60.764215 -28.78635)
			(xy 60.817948 -28.802639) (xy 60.868712 -28.826631) (xy 60.915409 -28.857808) (xy 60.957029 -28.895495)
			(xy 60.992673 -28.938878) (xy 61.021571 -28.987019) (xy 61.043096 -29.038877) (xy 61.050424 -29.065982)
			(xy 61.06033 -29.104336) (xy 82.031332 -29.104336) (xy 82.052951 -29.083405) (xy 82.101556 -29.047934)
			(xy 82.155125 -29.02053) (xy 82.212331 -29.001871) (xy 82.271756 -28.99242) (xy 82.301842 -28.991814)
			(xy 82.329091 -28.992303) (xy 82.383033 -29.000065) (xy 82.435321 -29.015424) (xy 82.484891 -29.038067)
			(xy 82.530735 -29.067535) (xy 82.571918 -29.103227) (xy 82.607603 -29.144416) (xy 82.637063 -29.190265)
			(xy 82.659699 -29.239839) (xy 82.675049 -29.29213) (xy 82.682801 -29.346073) (xy 82.68335 -29.373322)
			(xy 82.68281 -29.401164) (xy 82.674657 -29.45625) (xy 82.667094 -29.48305) (xy 82.658458 -29.51226)
			(xy 82.754216 -29.608018) (xy 82.771479 -29.626058) (xy 82.799244 -29.66755) (xy 82.818364 -29.713668)
			(xy 82.828102 -29.762634) (xy 82.828638 -29.787596) (xy 82.828638 -32.928052) (xy 83.545934 -33.645348)
			(xy 88.547194 -33.645348) (xy 88.95334 -33.239202) (xy 88.960549 -33.232124) (xy 88.975935 -33.219026)
			(xy 88.984074 -33.21304) (xy 88.984074 -30.964886) (xy 88.964392 -30.946703) (xy 88.929811 -30.905774)
			(xy 88.901293 -30.86041) (xy 88.879401 -30.811504) (xy 88.864564 -30.760016) (xy 88.857074 -30.706959)
			(xy 88.857078 -30.653377) (xy 88.864577 -30.600321) (xy 88.879423 -30.548836) (xy 88.901323 -30.499933)
			(xy 88.929848 -30.454574) (xy 88.964437 -30.413651) (xy 88.984074 -30.395418) (xy 88.984074 -25.884886)
			(xy 88.964392 -25.866703) (xy 88.929811 -25.825774) (xy 88.901293 -25.78041) (xy 88.879401 -25.731504)
			(xy 88.864564 -25.680016) (xy 88.857074 -25.626959) (xy 88.857078 -25.573377) (xy 88.864577 -25.520321)
			(xy 88.879423 -25.468836) (xy 88.901323 -25.419933) (xy 88.929848 -25.374574) (xy 88.964437 -25.333651)
			(xy 88.984074 -25.315418) (xy 88.984074 -23.993348) (xy 88.744552 -23.753826) (xy 86.864952 -23.753826)
			(xy 86.837872 -23.827873) (xy 86.777274 -23.973448) (xy 86.709467 -24.115808) (xy 86.634622 -24.254597)
			(xy 86.552927 -24.389467) (xy 86.464585 -24.520081) (xy 86.369819 -24.646111) (xy 86.268865 -24.767241)
			(xy 86.161977 -24.883168) (xy 86.049422 -24.993602) (xy 85.931483 -25.098265) (xy 85.808454 -25.196896)
			(xy 85.680644 -25.289248) (xy 85.548374 -25.375089) (xy 85.411974 -25.454204) (xy 85.271786 -25.526395)
			(xy 85.128161 -25.591481) (xy 84.98146 -25.649299) (xy 84.83205 -25.699704) (xy 84.680304 -25.74257)
			(xy 84.526604 -25.77779) (xy 84.371334 -25.805275) (xy 84.214884 -25.824957) (xy 84.057644 -25.836786)
			(xy 83.90001 -25.840732) (xy 83.742376 -25.836786) (xy 83.585136 -25.824957) (xy 83.428686 -25.805275)
			(xy 83.273416 -25.77779) (xy 83.119716 -25.74257) (xy 82.96797 -25.699704) (xy 82.81856 -25.649299)
			(xy 82.671859 -25.591481) (xy 82.528234 -25.526395) (xy 82.388046 -25.454204) (xy 82.251646 -25.375089)
			(xy 82.119376 -25.289248) (xy 81.991566 -25.196896) (xy 81.868537 -25.098265) (xy 81.750598 -24.993602)
			(xy 81.638043 -24.883168) (xy 81.531155 -24.767241) (xy 81.430201 -24.646111) (xy 81.335435 -24.520081)
			(xy 81.247093 -24.389467) (xy 81.165398 -24.254597) (xy 81.090553 -24.115808) (xy 81.022746 -23.973448)
			(xy 80.962148 -23.827873) (xy 80.935068 -23.753826) (xy 70.428612 -23.753826) (xy 70.404111 -23.770779)
			(xy 70.350948 -23.797669) (xy 70.294246 -23.815952) (xy 70.235389 -23.825183) (xy 70.2056 -23.825708)
			(xy 70.175816 -23.825131) (xy 70.116972 -23.815874) (xy 70.060276 -23.7976) (xy 70.007102 -23.770752)
			(xy 69.982588 -23.753826) (xy 69.778626 -23.753826) (xy 69.765164 -23.777552) (xy 69.7325 -23.821243)
			(xy 69.693947 -23.859837) (xy 69.650291 -23.892547) (xy 69.602421 -23.918706) (xy 69.551314 -23.937782)
			(xy 69.498012 -23.949385) (xy 69.4436 -23.95328) (xy 69.389188 -23.949385) (xy 69.335886 -23.937782)
			(xy 69.284779 -23.918706) (xy 69.236909 -23.892547) (xy 69.193253 -23.859837) (xy 69.1547 -23.821243)
			(xy 69.122036 -23.777552) (xy 69.108574 -23.753826) (xy 60.439554 -23.753826) (xy 60.414599 -23.75321)
			(xy 60.365649 -23.743466) (xy 60.31954 -23.724361) (xy 60.278044 -23.696628) (xy 60.259976 -23.679404)
			(xy 57.918096 -21.337524) (xy 57.893712 -21.340318) (xy 57.883078 -21.341411) (xy 57.86173 -21.342554)
			(xy 57.85104 -21.342604) (xy 57.823785 -21.342143) (xy 57.76983 -21.334391) (xy 57.717528 -21.319038)
			(xy 57.667943 -21.296398) (xy 57.622085 -21.266931) (xy 57.580888 -21.231237) (xy 57.54519 -21.190044)
			(xy 57.515719 -21.144189) (xy 57.493074 -21.094606) (xy 57.477717 -21.042305) (xy 57.469959 -20.988351)
			(xy 57.469532 -20.961096) (xy 57.469576 -20.950406) (xy 57.470718 -20.929057) (xy 57.471818 -20.918424)
			(xy 57.474612 -20.89404) (xy 56.727852 -20.14728) (xy 49.99482 -20.14728) (xy 48.901096 -21.241004)
			(xy 48.918418 -21.265642) (xy 48.945905 -21.319229) (xy 48.964636 -21.376467) (xy 48.974147 -21.435936)
			(xy 48.974756 -21.466048) (xy 48.974267 -21.493298) (xy 48.966505 -21.547243) (xy 48.951146 -21.599535)
			(xy 48.928503 -21.649109) (xy 48.899036 -21.694957) (xy 48.863346 -21.736146) (xy 48.822157 -21.771836)
			(xy 48.776309 -21.801303) (xy 48.726735 -21.823946) (xy 48.674443 -21.839305) (xy 48.620498 -21.847067)
			(xy 48.593248 -21.847556) (xy 48.567974 -21.847142) (xy 48.517871 -21.840457) (xy 48.469089 -21.827212)
			(xy 48.422485 -21.807639) (xy 48.400462 -21.795232) (xy 48.36668 -21.77542) (xy 46.462696 -23.679404)
			(xy 46.444654 -23.696661) (xy 46.40316 -23.724413) (xy 46.357041 -23.743518) (xy 46.308078 -23.753241)
			(xy 46.283118 -23.753826) (xy 38.243256 -23.75154) (xy 35.53714 -23.75154) (xy 35.512182 -23.750963)
			(xy 35.463228 -23.741212) (xy 35.417118 -23.722097) (xy 35.375623 -23.694353) (xy 35.357562 -23.677118)
			(xy 33.015174 -21.33473) (xy 32.984186 -21.347176) (xy 32.961532 -21.355855) (xy 32.914579 -21.36806)
			(xy 32.866457 -21.374212) (xy 32.8422 -21.374608) (xy 32.814949 -21.374122) (xy 32.761001 -21.366366)
			(xy 32.708706 -21.351011) (xy 32.659129 -21.328369) (xy 32.613279 -21.298903) (xy 32.572088 -21.263212)
			(xy 32.536397 -21.222021) (xy 32.506931 -21.176171) (xy 32.484289 -21.126594) (xy 32.468934 -21.074299)
			(xy 32.461178 -21.020351) (xy 32.460692 -20.9931) (xy 32.461071 -20.968843) (xy 32.467229 -20.92072)
			(xy 32.479443 -20.873768) (xy 32.488124 -20.851114) (xy 32.50057 -20.820126) (xy 27.481022 -15.800578)
			(xy 27.463757 -15.782539) (xy 27.435989 -15.741048) (xy 27.416867 -15.69493) (xy 27.407127 -15.645963)
			(xy 27.4066 -15.621) (xy 27.4066 -14.430756) (xy 25.142444 -12.1666) (xy 16.894556 -12.1666) (xy 15.454376 -13.60678)
			(xy 15.450312 -13.61694) (xy 15.44066 -13.641091) (xy 15.415742 -13.686741) (xy 15.384845 -13.728576)
			(xy 15.367 -13.747496) (xy 15.367 -16.871696) (xy 15.381565 -16.895) (xy 15.404571 -16.944907) (xy 15.405531 -16.94815)
			(xy 25.574752 -16.94815) (xy 25.574752 -16.05915) (xy 25.575238 -16.031899) (xy 25.582994 -15.977951)
			(xy 25.598349 -15.925656) (xy 25.620991 -15.876079) (xy 25.650457 -15.830229) (xy 25.686148 -15.789038)
			(xy 25.727339 -15.753347) (xy 25.773189 -15.723881) (xy 25.822766 -15.701239) (xy 25.875061 -15.685884)
			(xy 25.929009 -15.678128) (xy 25.983511 -15.678128) (xy 26.037459 -15.685884) (xy 26.089754 -15.701239)
			(xy 26.139331 -15.723881) (xy 26.185181 -15.753347) (xy 26.226372 -15.789038) (xy 26.262063 -15.830229)
			(xy 26.291529 -15.876079) (xy 26.314171 -15.925656) (xy 26.329526 -15.977951) (xy 26.337282 -16.031899)
			(xy 26.337768 -16.05915) (xy 26.337768 -16.94815) (xy 26.337282 -16.975401) (xy 26.329526 -17.029349)
			(xy 26.314171 -17.081644) (xy 26.291529 -17.131221) (xy 26.262063 -17.177071) (xy 26.226372 -17.218262)
			(xy 26.185181 -17.253953) (xy 26.139331 -17.283419) (xy 26.089754 -17.306061) (xy 26.037459 -17.321416)
			(xy 25.983511 -17.329172) (xy 25.929009 -17.329172) (xy 25.875061 -17.321416) (xy 25.822766 -17.306061)
			(xy 25.773189 -17.283419) (xy 25.727339 -17.253953) (xy 25.686148 -17.218262) (xy 25.650457 -17.177071)
			(xy 25.620991 -17.131221) (xy 25.598349 -17.081644) (xy 25.582994 -17.029349) (xy 25.575238 -16.975401)
			(xy 25.574752 -16.94815) (xy 15.405531 -16.94815) (xy 15.420165 -16.997602) (xy 15.428024 -17.051991)
			(xy 15.428468 -17.079468) (xy 15.427987 -17.106942) (xy 15.42011 -17.161324) (xy 15.404527 -17.214017)
			(xy 15.38156 -17.263936) (xy 15.367 -17.28724) (xy 15.367 -18.815812) (xy 15.396972 -18.829274) (xy 15.421713 -18.840959)
			(xy 15.467854 -18.870364) (xy 15.509321 -18.906059) (xy 15.545264 -18.947311) (xy 15.574945 -18.993276)
			(xy 15.597756 -19.043008) (xy 15.613228 -19.09549) (xy 15.621044 -19.149643) (xy 15.621044 -19.204357)
			(xy 15.613228 -19.25851) (xy 15.597756 -19.310992) (xy 15.574945 -19.360724) (xy 15.545264 -19.406689)
			(xy 15.509321 -19.447941) (xy 15.467854 -19.483636) (xy 15.421713 -19.513041) (xy 15.396972 -19.524726)
			(xy 15.367 -19.538188) (xy 15.367 -20.574) (xy 15.366388 -20.598957) (xy 15.356651 -20.647911) (xy 15.33755 -20.694024)
			(xy 15.30982 -20.735526) (xy 15.292578 -20.753578) (xy 12.366752 -23.679404) (xy 12.348712 -23.696666)
			(xy 12.307219 -23.724427) (xy 12.261101 -23.743542) (xy 12.212136 -23.753275) (xy 12.187174 -23.753826)
			(xy 11.837162 -23.753826) (xy 11.817371 -23.774513) (xy 11.772689 -23.810304) (xy 11.723159 -23.839012)
			(xy 11.669892 -23.859991) (xy 11.614088 -23.872771) (xy 11.557 -23.877063) (xy 11.499912 -23.872771)
			(xy 11.444108 -23.859991) (xy 11.390841 -23.839012) (xy 11.341311 -23.810304) (xy 11.296629 -23.774513)
			(xy 11.276838 -23.753826) (xy 9.065006 -23.753826) (xy 9.037357 -23.829414) (xy 8.975343 -23.977958)
			(xy 8.905822 -24.12314) (xy 8.828977 -24.264582) (xy 8.745006 -24.401914) (xy 8.689767 -24.482675)
			(xy 40.239076 -24.482675) (xy 40.239076 -24.428125) (xy 40.246839 -24.374131) (xy 40.262209 -24.321791)
			(xy 40.284871 -24.272172) (xy 40.314365 -24.226283) (xy 40.350089 -24.185059) (xy 40.391317 -24.149339)
			(xy 40.437209 -24.119851) (xy 40.486831 -24.097194) (xy 40.539172 -24.08183) (xy 40.593167 -24.074073)
			(xy 40.620442 -24.073612) (xy 41.509442 -24.073612) (xy 41.536708 -24.074153) (xy 41.590683 -24.081919)
			(xy 41.643004 -24.097287) (xy 41.692605 -24.119944) (xy 41.738478 -24.149429) (xy 41.779688 -24.185142)
			(xy 41.815396 -24.226356) (xy 41.844876 -24.272232) (xy 41.867528 -24.321836) (xy 41.88289 -24.374158)
			(xy 41.89065 -24.428134) (xy 41.89065 -24.482666) (xy 41.890649 -24.482675) (xy 42.632776 -24.482675)
			(xy 42.632776 -24.428125) (xy 42.640539 -24.374132) (xy 42.655909 -24.321792) (xy 42.67857 -24.272173)
			(xy 42.708064 -24.226285) (xy 42.743788 -24.185061) (xy 42.785015 -24.149341) (xy 42.830907 -24.119852)
			(xy 42.880528 -24.097195) (xy 42.932869 -24.081831) (xy 42.986863 -24.074073) (xy 43.014138 -24.073612)
			(xy 43.903138 -24.073612) (xy 43.930404 -24.074153) (xy 43.98438 -24.081918) (xy 44.036701 -24.097286)
			(xy 44.086303 -24.119943) (xy 44.132176 -24.149428) (xy 44.173386 -24.185141) (xy 44.209095 -24.226354)
			(xy 44.238575 -24.27223) (xy 44.261227 -24.321835) (xy 44.27659 -24.374158) (xy 44.28435 -24.428134)
			(xy 44.28435 -24.482666) (xy 44.27659 -24.536642) (xy 44.261227 -24.588965) (xy 44.238575 -24.63857)
			(xy 44.209095 -24.684446) (xy 44.173386 -24.725659) (xy 44.132176 -24.761372) (xy 44.086303 -24.790857)
			(xy 44.036701 -24.813514) (xy 43.98438 -24.828882) (xy 43.930404 -24.836647) (xy 43.903138 -24.837136)
			(xy 43.014138 -24.837136) (xy 42.986863 -24.836727) (xy 42.932869 -24.828969) (xy 42.880528 -24.813605)
			(xy 42.830907 -24.790948) (xy 42.785015 -24.761459) (xy 42.743788 -24.725739) (xy 42.708064 -24.684515)
			(xy 42.67857 -24.638627) (xy 42.655909 -24.589008) (xy 42.640539 -24.536668) (xy 42.632776 -24.482675)
			(xy 41.890649 -24.482675) (xy 41.88289 -24.536642) (xy 41.867528 -24.588964) (xy 41.844876 -24.638568)
			(xy 41.815396 -24.684444) (xy 41.779688 -24.725658) (xy 41.738478 -24.761371) (xy 41.692605 -24.790856)
			(xy 41.643004 -24.813513) (xy 41.590683 -24.828881) (xy 41.536708 -24.836647) (xy 41.509442 -24.837136)
			(xy 40.620442 -24.837136) (xy 40.593167 -24.836727) (xy 40.539172 -24.82897) (xy 40.486831 -24.813606)
			(xy 40.437209 -24.790949) (xy 40.391317 -24.761461) (xy 40.350089 -24.725741) (xy 40.314365 -24.684517)
			(xy 40.284871 -24.638628) (xy 40.262209 -24.589009) (xy 40.246839 -24.536669) (xy 40.239076 -24.482675)
			(xy 8.689767 -24.482675) (xy 8.654131 -24.534777) (xy 8.556587 -24.662825) (xy 8.45263 -24.785723)
			(xy 8.342531 -24.903151) (xy 8.226578 -25.014802) (xy 8.105073 -25.120383) (xy 7.978333 -25.219621)
			(xy 7.84669 -25.312255) (xy 7.710487 -25.398044) (xy 7.570079 -25.476764) (xy 7.425834 -25.548209)
			(xy 7.278128 -25.612193) (xy 7.127347 -25.668548) (xy 6.973883 -25.717128) (xy 6.818138 -25.757805)
			(xy 6.660519 -25.790474) (xy 6.501437 -25.81505) (xy 6.341308 -25.831467) (xy 6.180549 -25.839683)
			(xy 6.100064 -25.840182) (xy 6.098032 -25.840182) (xy 6.033441 -25.839831) (xy 5.904368 -25.834495)
			(xy 5.839968 -25.829514) (xy 5.82597 -25.828815) (xy 5.798476 -25.834203) (xy 5.773477 -25.846851)
			(xy 5.752849 -25.86581) (xy 5.738142 -25.889656) (xy 5.73046 -25.916599) (xy 5.729986 -25.930606)
			(xy 5.729986 -26.898451) (xy 62.226946 -26.898451) (xy 62.226946 -26.843949) (xy 62.234702 -26.790001)
			(xy 62.250056 -26.737705) (xy 62.272695 -26.688127) (xy 62.302159 -26.642275) (xy 62.337849 -26.601083)
			(xy 62.379037 -26.565388) (xy 62.424885 -26.535918) (xy 62.47446 -26.513272) (xy 62.526754 -26.497912)
			(xy 62.580701 -26.490149) (xy 62.607952 -26.48966) (xy 63.496952 -26.48966) (xy 63.524205 -26.490184)
			(xy 63.578156 -26.497935) (xy 63.630456 -26.513285) (xy 63.680038 -26.535923) (xy 63.725893 -26.565387)
			(xy 63.767088 -26.601078) (xy 63.802784 -26.642269) (xy 63.832254 -26.68812) (xy 63.854898 -26.737699)
			(xy 63.870255 -26.789997) (xy 63.878013 -26.843947) (xy 63.878013 -26.898453) (xy 63.870255 -26.952403)
			(xy 63.863218 -26.976368) (xy 64.442847 -26.976368) (xy 64.442847 -26.921832) (xy 64.450609 -26.867852)
			(xy 64.465973 -26.815525) (xy 64.488628 -26.765918) (xy 64.518112 -26.72004) (xy 64.553826 -26.678824)
			(xy 64.595041 -26.643111) (xy 64.64092 -26.613627) (xy 64.690527 -26.590972) (xy 64.742854 -26.575608)
			(xy 64.796834 -26.567847) (xy 64.824102 -26.567384) (xy 65.713102 -26.567384) (xy 65.740375 -26.567779)
			(xy 65.794364 -26.575542) (xy 65.8467 -26.590909) (xy 65.896316 -26.613568) (xy 65.942202 -26.643057)
			(xy 65.983424 -26.678777) (xy 66.019144 -26.72) (xy 66.048633 -26.765886) (xy 66.071292 -26.815502)
			(xy 66.086659 -26.867838) (xy 66.094421 -26.921827) (xy 66.094421 -26.976373) (xy 66.086659 -27.030362)
			(xy 66.071292 -27.082698) (xy 66.048633 -27.132314) (xy 66.019144 -27.1782) (xy 65.983424 -27.219423)
			(xy 65.942202 -27.255143) (xy 65.896316 -27.284632) (xy 65.8467 -27.307291) (xy 65.794364 -27.322658)
			(xy 65.740375 -27.330421) (xy 65.713102 -27.330908) (xy 64.824102 -27.330908) (xy 64.796834 -27.330353)
			(xy 64.742854 -27.322592) (xy 64.690527 -27.307228) (xy 64.64092 -27.284573) (xy 64.595041 -27.255089)
			(xy 64.553826 -27.219376) (xy 64.518112 -27.17816) (xy 64.488628 -27.132282) (xy 64.465973 -27.082675)
			(xy 64.450609 -27.030348) (xy 64.442847 -26.976368) (xy 63.863218 -26.976368) (xy 63.854898 -27.004701)
			(xy 63.832254 -27.05428) (xy 63.802784 -27.100131) (xy 63.767088 -27.141322) (xy 63.725893 -27.177013)
			(xy 63.680038 -27.206477) (xy 63.630456 -27.229115) (xy 63.578156 -27.244465) (xy 63.524205 -27.252216)
			(xy 63.496952 -27.252676) (xy 62.607952 -27.252676) (xy 62.580701 -27.252251) (xy 62.526754 -27.244488)
			(xy 62.47446 -27.229128) (xy 62.424885 -27.206482) (xy 62.379037 -27.177012) (xy 62.337849 -27.141317)
			(xy 62.302159 -27.100125) (xy 62.272695 -27.054273) (xy 62.250056 -27.004695) (xy 62.234702 -26.952399)
			(xy 62.226946 -26.898451) (xy 5.729986 -26.898451) (xy 5.729986 -34.872422) (xy 6.60146 -35.743896)
			(xy 17.012666 -35.743896) (xy 17.024613 -35.719813) (xy 17.054268 -35.674974) (xy 17.089926 -35.634745)
			(xy 17.130882 -35.599923) (xy 17.176323 -35.571198) (xy 17.225348 -35.549142) (xy 17.276985 -35.534189)
			(xy 17.330211 -35.526639) (xy 17.383969 -35.526639) (xy 17.437195 -35.534189) (xy 17.488832 -35.549142)
			(xy 17.537857 -35.571198) (xy 17.583298 -35.599923) (xy 17.624254 -35.634745) (xy 17.659912 -35.674974)
			(xy 17.689567 -35.719813) (xy 17.701514 -35.743896) (xy 22.328886 -35.743896) (xy 22.344047 -35.72135)
			(xy 22.379737 -35.680384) (xy 22.420877 -35.644897) (xy 22.466636 -35.615605) (xy 22.516088 -35.593102)
			(xy 22.568233 -35.577842) (xy 22.622014 -35.570134) (xy 22.676346 -35.570134) (xy 22.730127 -35.577842)
			(xy 22.782272 -35.593102) (xy 22.831724 -35.615605) (xy 22.877483 -35.644897) (xy 22.918623 -35.680384)
			(xy 22.954313 -35.72135) (xy 22.969474 -35.743896) (xy 25.863296 -35.743896) (xy 25.888249 -35.744517)
			(xy 25.937193 -35.75427) (xy 25.983294 -35.773383) (xy 26.024782 -35.801121) (xy 26.042874 -35.818318)
			(xy 28.094178 -37.869622) (xy 28.111443 -37.887661) (xy 28.139211 -37.929152) (xy 28.158333 -37.97527)
			(xy 28.168073 -38.024237) (xy 28.1686 -38.0492) (xy 28.1686 -40.409114) (xy 32.292544 -44.533058)
			(xy 32.296354 -44.535598) (xy 32.316396 -44.549847) (xy 32.353005 -44.582682) (xy 32.385105 -44.619936)
			(xy 32.39897 -44.640246) (xy 32.413412 -44.657706) (xy 32.436514 -44.696682) (xy 32.452359 -44.739129)
			(xy 32.460448 -44.783709) (xy 32.460946 -44.806362) (xy 32.460946 -44.827444) (xy 32.461708 -44.85005)
			(xy 32.460946 -44.872656) (xy 32.460946 -61.569854) (xy 32.460369 -61.594812) (xy 32.45062 -61.643767)
			(xy 32.431506 -61.689878) (xy 32.403762 -61.731374) (xy 32.386524 -61.749432) (xy 31.650178 -62.485778)
			(xy 31.634502 -62.500848) (xy 31.598987 -62.525935) (xy 31.559717 -62.544603) (xy 31.51784 -62.556307)
			(xy 31.496254 -62.55893) (xy 31.478068 -62.578794) (xy 31.437071 -62.613717) (xy 31.391571 -62.64253)
			(xy 31.342472 -62.664659) (xy 31.29075 -62.679666) (xy 31.237432 -62.687252) (xy 31.210504 -62.687708)
			(xy 31.183709 -62.687255) (xy 31.130647 -62.679758) (xy 31.079156 -62.664912) (xy 31.030248 -62.643007)
			(xy 30.984886 -62.614475) (xy 30.943962 -62.579878) (xy 30.92577 -62.5602) (xy 29.103066 -62.5602)
			(xy 29.082112 -62.577921) (xy 29.036075 -62.607789) (xy 28.98623 -62.630748) (xy 28.933609 -62.646322)
			(xy 28.879299 -62.654191) (xy 28.824421 -62.654191) (xy 28.770111 -62.646322) (xy 28.71749 -62.630748)
			(xy 28.667645 -62.607789) (xy 28.621608 -62.577921) (xy 28.600654 -62.5602) (xy 27.232356 -62.5602)
			(xy 25.6032 -64.189356) (xy 25.6032 -74.191368) (xy 25.64511 -74.198988) (xy 25.672584 -74.204393)
			(xy 25.725673 -74.222186) (xy 25.77559 -74.247551) (xy 25.821262 -74.279943) (xy 25.861706 -74.318665)
			(xy 25.896053 -74.362885) (xy 25.923564 -74.411652) (xy 25.943649 -74.463918) (xy 25.955875 -74.518559)
			(xy 25.95998 -74.5744) (xy 25.955875 -74.630241) (xy 25.943649 -74.684882) (xy 25.923564 -74.737148)
			(xy 25.896053 -74.785915) (xy 25.861706 -74.830135) (xy 25.821262 -74.868857) (xy 25.77559 -74.901249)
			(xy 25.725673 -74.926614) (xy 25.672584 -74.944407) (xy 25.64511 -74.949812) (xy 25.6032 -74.957432)
			(xy 25.6032 -77.88529) (xy 25.625941 -77.900403) (xy 25.66726 -77.936097) (xy 25.703068 -77.977318)
			(xy 25.732634 -78.023222) (xy 25.755353 -78.072873) (xy 25.770763 -78.125255) (xy 25.778547 -78.179299)
			(xy 25.778547 -78.233901) (xy 25.770763 -78.287945) (xy 25.755353 -78.340327) (xy 25.732634 -78.389978)
			(xy 25.703068 -78.435882) (xy 25.66726 -78.477103) (xy 25.625941 -78.512797) (xy 25.6032 -78.52791)
			(xy 25.6032 -78.72349) (xy 25.625941 -78.738603) (xy 25.66726 -78.774297) (xy 25.703068 -78.815518)
			(xy 25.732634 -78.861422) (xy 25.755353 -78.911073) (xy 25.770763 -78.963455) (xy 25.778547 -79.017499)
			(xy 25.778547 -79.072101) (xy 25.770763 -79.126145) (xy 25.755353 -79.178527) (xy 25.732634 -79.228178)
			(xy 25.703068 -79.274082) (xy 25.66726 -79.315303) (xy 25.625941 -79.350997) (xy 25.6032 -79.36611)
			(xy 25.6032 -83.075272) (xy 25.639014 -83.086194) (xy 25.664678 -83.094565) (xy 25.71353 -83.117529)
			(xy 25.758659 -83.14715) (xy 25.799161 -83.182836) (xy 25.834229 -83.223875) (xy 25.863162 -83.269447)
			(xy 25.885382 -83.318642) (xy 25.900446 -83.370479) (xy 25.908054 -83.423921) (xy 25.908052 -83.477902)
			(xy 25.900442 -83.531343) (xy 25.885374 -83.583179) (xy 25.863151 -83.632373) (xy 25.834215 -83.677943)
			(xy 25.799145 -83.71898) (xy 25.758641 -83.754664) (xy 25.713511 -83.784282) (xy 25.664657 -83.807243)
			(xy 25.639014 -83.815682) (xy 25.6032 -83.826604) (xy 25.6032 -86.000844) (xy 28.705556 -89.1032)
			(xy 28.764484 -89.1032)
		)
		(stroke
			(width 0)
			(type solid)
		)
		(fill yes)
		(layer "In5.Cu")
		(net "P5V_AUX")
	)
	(gr_poly
		(pts
			(xy 9.749028 -114.799872) (xy 9.749526 -114.744681) (xy 9.757554 -114.634591) (xy 9.773568 -114.525376)
			(xy 9.797484 -114.417615) (xy 9.829176 -114.31188) (xy 9.868475 -114.20873) (xy 9.915173 -114.108712)
			(xy 9.969022 -114.012356) (xy 9.998964 -113.96599) (xy 9.996593 -113.950606) (xy 9.994051 -113.919579)
			(xy 9.993884 -113.904014) (xy 9.993884 -113.90376) (xy 9.994347 -113.876507) (xy 10.002104 -113.822556)
			(xy 10.01746 -113.770259) (xy 10.040103 -113.720679) (xy 10.069571 -113.674826) (xy 10.105265 -113.633633)
			(xy 10.146457 -113.59794) (xy 10.19231 -113.568472) (xy 10.241891 -113.54583) (xy 10.294188 -113.530474)
			(xy 10.348139 -113.522717) (xy 10.375392 -113.522252) (xy 10.39173 -113.522426) (xy 10.424287 -113.525226)
			(xy 10.440416 -113.52784) (xy 10.486395 -113.498623) (xy 10.581842 -113.446092) (xy 10.680812 -113.400546)
			(xy 10.782796 -113.362219) (xy 10.887268 -113.331309) (xy 10.993688 -113.307977) (xy 11.101508 -113.292341)
			(xy 11.210172 -113.284483) (xy 11.264646 -113.284) (xy 12.765278 -113.284) (xy 12.818115 -113.284465)
			(xy 12.923533 -113.29184) (xy 13.02818 -113.30654) (xy 13.13155 -113.328495) (xy 13.233138 -113.357598)
			(xy 13.332452 -113.393708) (xy 13.42901 -113.436648) (xy 13.522341 -113.486211) (xy 13.611992 -113.542156)
			(xy 13.65504 -113.572798) (xy 13.67633 -113.568172) (xy 13.719616 -113.563212) (xy 13.7414 -113.562892)
			(xy 13.768651 -113.563378) (xy 13.822599 -113.571134) (xy 13.874894 -113.586489) (xy 13.924471 -113.609131)
			(xy 13.970321 -113.638597) (xy 14.011512 -113.674288) (xy 14.047203 -113.715479) (xy 14.076669 -113.761329)
			(xy 14.099311 -113.810906) (xy 14.108106 -113.840859) (xy 20.444184 -113.840859) (xy 20.444184 -113.786321)
			(xy 20.451946 -113.732337) (xy 20.467311 -113.680007) (xy 20.489968 -113.630397) (xy 20.519454 -113.584516)
			(xy 20.555169 -113.543299) (xy 20.596386 -113.507584) (xy 20.642267 -113.478098) (xy 20.691877 -113.455441)
			(xy 20.744207 -113.440076) (xy 20.798191 -113.432314) (xy 20.82546 -113.431828) (xy 21.71446 -113.431828)
			(xy 21.741732 -113.432309) (xy 21.795722 -113.440066) (xy 21.848058 -113.455428) (xy 21.897675 -113.478083)
			(xy 21.943562 -113.507569) (xy 21.984786 -113.543285) (xy 22.020507 -113.584506) (xy 22.049998 -113.63039)
			(xy 22.072658 -113.680004) (xy 22.088025 -113.732339) (xy 22.095788 -113.786328) (xy 22.095788 -113.840872)
			(xy 22.088025 -113.894861) (xy 22.072658 -113.947196) (xy 22.049998 -113.99681) (xy 22.020507 -114.042694)
			(xy 21.984786 -114.083915) (xy 21.943562 -114.119631) (xy 21.897675 -114.149117) (xy 21.848058 -114.171772)
			(xy 21.795722 -114.187134) (xy 21.741732 -114.194891) (xy 21.71446 -114.195352) (xy 20.82546 -114.195352)
			(xy 20.798191 -114.194866) (xy 20.744207 -114.187104) (xy 20.691877 -114.171739) (xy 20.642267 -114.149082)
			(xy 20.596386 -114.119596) (xy 20.555169 -114.083881) (xy 20.519454 -114.042664) (xy 20.489968 -113.996783)
			(xy 20.467311 -113.947173) (xy 20.451946 -113.894843) (xy 20.444184 -113.840859) (xy 14.108106 -113.840859)
			(xy 14.114666 -113.863201) (xy 14.122422 -113.917149) (xy 14.122908 -113.9444) (xy 14.122221 -113.978818)
			(xy 14.109953 -114.046548) (xy 14.098524 -114.07902) (xy 14.124683 -114.12847) (xy 14.170503 -114.230538)
			(xy 14.208672 -114.335706) (xy 14.238981 -114.443404) (xy 14.261266 -114.553043) (xy 14.275404 -114.664026)
			(xy 14.278864 -114.719862) (xy 14.279834 -114.729744) (xy 14.288276 -114.747695) (xy 14.302897 -114.7611)
			(xy 14.321511 -114.767956) (xy 14.331442 -114.768122) (xy 14.346428 -114.767868) (xy 14.373679 -114.768356)
			(xy 14.427625 -114.776115) (xy 14.479917 -114.791473) (xy 14.529493 -114.814115) (xy 14.575341 -114.843582)
			(xy 14.61653 -114.879273) (xy 14.652221 -114.920462) (xy 14.681687 -114.966311) (xy 14.704329 -115.015886)
			(xy 14.719686 -115.068179) (xy 14.727445 -115.122125) (xy 14.727936 -115.149376) (xy 14.727936 -116.038376)
			(xy 15.764764 -116.038376) (xy 15.764764 -115.149376) (xy 15.76525 -115.122107) (xy 15.773012 -115.068123)
			(xy 15.788377 -115.015793) (xy 15.811034 -114.966183) (xy 15.84052 -114.920302) (xy 15.876235 -114.879085)
			(xy 15.917452 -114.84337) (xy 15.963333 -114.813884) (xy 16.012943 -114.791227) (xy 16.065273 -114.775862)
			(xy 16.119257 -114.7681) (xy 16.173795 -114.7681) (xy 16.227779 -114.775862) (xy 16.280109 -114.791227)
			(xy 16.329719 -114.813884) (xy 16.3756 -114.84337) (xy 16.416817 -114.879085) (xy 16.452532 -114.920302)
			(xy 16.482018 -114.966183) (xy 16.504675 -115.015793) (xy 16.510811 -115.036691) (xy 23.190153 -115.036691)
			(xy 23.190153 -114.982149) (xy 23.197916 -114.928162) (xy 23.213282 -114.875829) (xy 23.23594 -114.826216)
			(xy 23.265428 -114.780333) (xy 23.301145 -114.739113) (xy 23.342366 -114.703395) (xy 23.38825 -114.673908)
			(xy 23.437863 -114.651251) (xy 23.490196 -114.635885) (xy 23.544183 -114.628123) (xy 23.571454 -114.62766)
			(xy 24.460454 -114.62766) (xy 24.487723 -114.628143) (xy 24.541707 -114.635905) (xy 24.594036 -114.651271)
			(xy 24.643646 -114.673927) (xy 24.689527 -114.703413) (xy 24.730744 -114.739129) (xy 24.766459 -114.780347)
			(xy 24.795945 -114.826227) (xy 24.818601 -114.875838) (xy 24.833966 -114.928167) (xy 24.841728 -114.982151)
			(xy 24.841728 -115.036689) (xy 24.833966 -115.090673) (xy 24.818601 -115.143002) (xy 24.795945 -115.192613)
			(xy 24.766459 -115.238493) (xy 24.730744 -115.279711) (xy 24.689527 -115.315427) (xy 24.643646 -115.344913)
			(xy 24.594036 -115.367569) (xy 24.541707 -115.382935) (xy 24.487723 -115.390697) (xy 24.460454 -115.391184)
			(xy 23.571454 -115.391184) (xy 23.544183 -115.390717) (xy 23.490196 -115.382955) (xy 23.437863 -115.367589)
			(xy 23.38825 -115.344932) (xy 23.342366 -115.315445) (xy 23.301145 -115.279727) (xy 23.265428 -115.238507)
			(xy 23.23594 -115.192624) (xy 23.213282 -115.143011) (xy 23.197916 -115.090678) (xy 23.190153 -115.036691)
			(xy 16.510811 -115.036691) (xy 16.52004 -115.068123) (xy 16.527802 -115.122107) (xy 16.528288 -115.149376)
			(xy 16.528288 -116.038376) (xy 16.527802 -116.065645) (xy 16.52004 -116.119629) (xy 16.504675 -116.171959)
			(xy 16.482018 -116.221569) (xy 16.452532 -116.26745) (xy 16.416817 -116.308667) (xy 16.3756 -116.344382)
			(xy 16.329719 -116.373868) (xy 16.280109 -116.396525) (xy 16.227779 -116.41189) (xy 16.173795 -116.419652)
			(xy 16.119257 -116.419652) (xy 16.065273 -116.41189) (xy 16.012943 -116.396525) (xy 15.963333 -116.373868)
			(xy 15.917452 -116.344382) (xy 15.876235 -116.308667) (xy 15.84052 -116.26745) (xy 15.811034 -116.221569)
			(xy 15.788377 -116.171959) (xy 15.773012 -116.119629) (xy 15.76525 -116.065645) (xy 15.764764 -116.038376)
			(xy 14.727936 -116.038376) (xy 14.727397 -116.066929) (xy 14.718877 -116.123396) (xy 14.702037 -116.177963)
			(xy 14.677255 -116.229411) (xy 14.645083 -116.276593) (xy 14.60624 -116.318453) (xy 14.561593 -116.354059)
			(xy 14.512139 -116.382614) (xy 14.458982 -116.403481) (xy 14.403309 -116.416195) (xy 14.374876 -116.418868)
			(xy 14.359732 -116.420576) (xy 14.331382 -116.431712) (xy 14.307573 -116.450708) (xy 14.29042 -116.475877)
			(xy 14.281447 -116.504985) (xy 14.280896 -116.520214) (xy 14.280896 -117.3734) (xy 30.609032 -117.3734)
			(xy 30.609032 -114.77498) (xy 30.609527 -114.705883) (xy 30.617514 -114.567919) (xy 30.633457 -114.430646)
			(xy 30.657302 -114.294524) (xy 30.68897 -114.160006) (xy 30.728355 -114.027543) (xy 30.775326 -113.897575)
			(xy 30.829726 -113.770537) (xy 30.891372 -113.646854) (xy 30.96006 -113.526938) (xy 31.03556 -113.41119)
			(xy 31.11762 -113.299996) (xy 31.205965 -113.193728) (xy 31.300301 -113.09274) (xy 31.400313 -112.99737)
			(xy 31.505667 -112.907936) (xy 31.616011 -112.824737) (xy 31.730976 -112.74805) (xy 31.850179 -112.678132)
			(xy 31.973221 -112.615216) (xy 32.099692 -112.559512) (xy 32.22917 -112.511206) (xy 32.361221 -112.47046)
			(xy 32.495406 -112.43741) (xy 32.631276 -112.412165) (xy 32.768377 -112.394811) (xy 32.906251 -112.385405)
			(xy 33.044439 -112.383979) (xy 33.182478 -112.390536) (xy 33.319908 -112.405057) (xy 33.45627 -112.427491)
			(xy 33.591108 -112.457765) (xy 33.723973 -112.495776) (xy 33.85442 -112.541398) (xy 33.982014 -112.59448)
			(xy 34.106329 -112.654842) (xy 34.22695 -112.722285) (xy 34.343474 -112.796582) (xy 34.455511 -112.877486)
			(xy 34.562689 -112.964726) (xy 34.664648 -113.058011) (xy 34.761049 -113.15703) (xy 34.851569 -113.261452)
			(xy 34.935907 -113.370928) (xy 35.01378 -113.485093) (xy 35.084929 -113.603565) (xy 35.149115 -113.72595)
			(xy 35.206126 -113.851837) (xy 35.25577 -113.980808) (xy 35.297881 -114.11243) (xy 35.332319 -114.246265)
			(xy 35.346132 -114.31397) (xy 35.372445 -114.321878) (xy 35.422644 -114.34421) (xy 35.469118 -114.373517)
			(xy 35.510903 -114.409192) (xy 35.547133 -114.450496) (xy 35.577058 -114.496574) (xy 35.600058 -114.546471)
			(xy 35.615656 -114.599153) (xy 35.62353 -114.653529) (xy 35.624008 -114.681) (xy 35.623474 -114.709917)
			(xy 35.614747 -114.767088) (xy 35.597493 -114.822288) (xy 35.572108 -114.874252) (xy 35.539171 -114.921791)
			(xy 35.499439 -114.963815) (xy 35.476942 -114.98199) (xy 35.465134 -114.991886) (xy 35.447612 -115.017209)
			(xy 35.438433 -115.046603) (xy 35.438433 -115.077397) (xy 35.447612 -115.106791) (xy 35.465134 -115.132114)
			(xy 35.476942 -115.14201) (xy 35.499432 -115.160197) (xy 35.539181 -115.202211) (xy 35.572133 -115.249744)
			(xy 35.597531 -115.301706) (xy 35.614793 -115.356907) (xy 35.623525 -115.414081) (xy 35.624008 -115.443)
			(xy 35.623488 -115.471719) (xy 35.614873 -115.528507) (xy 35.597838 -115.583361) (xy 35.572768 -115.635039)
			(xy 35.540231 -115.682373) (xy 35.500962 -115.724291) (xy 35.47872 -115.742466) (xy 35.468178 -115.751378)
			(xy 35.451892 -115.773652) (xy 35.442156 -115.79947) (xy 35.43968 -115.826951) (xy 35.444644 -115.854094)
			(xy 35.456687 -115.87892) (xy 35.465512 -115.889532) (xy 35.483322 -115.910534) (xy 35.513349 -115.956693)
			(xy 35.536434 -116.006685) (xy 35.552101 -116.059475) (xy 35.560023 -116.113967) (xy 35.560508 -116.1415)
			(xy 35.560057 -116.168261) (xy 35.552581 -116.221258) (xy 35.537774 -116.272691) (xy 35.515928 -116.321551)
			(xy 35.48747 -116.36688) (xy 35.452959 -116.407789) (xy 35.413072 -116.443477) (xy 35.39109 -116.458746)
			(xy 35.39109 -117.3734) (xy 43.318938 -117.3734) (xy 43.318938 -114.766344) (xy 43.297493 -114.75102)
			(xy 43.258633 -114.715412) (xy 43.225052 -114.674788) (xy 43.197389 -114.629923) (xy 43.176174 -114.581674)
			(xy 43.161812 -114.530962) (xy 43.154575 -114.478754) (xy 43.154092 -114.4524) (xy 43.154573 -114.425208)
			(xy 43.162294 -114.371375) (xy 43.17758 -114.319183) (xy 43.20012 -114.26969) (xy 43.229458 -114.223899)
			(xy 43.265 -114.182736) (xy 43.306027 -114.147036) (xy 43.32859 -114.131852) (xy 43.335256 -114.070124)
			(xy 43.355477 -113.947611) (xy 43.383487 -113.826642) (xy 43.419173 -113.70771) (xy 43.462387 -113.591303)
			(xy 43.512954 -113.477896) (xy 43.570666 -113.367952) (xy 43.635288 -113.261923) (xy 43.706554 -113.160241)
			(xy 43.784174 -113.063322) (xy 43.867831 -112.971562) (xy 43.957182 -112.885338) (xy 44.051861 -112.805001)
			(xy 44.151481 -112.73088) (xy 44.255636 -112.663278) (xy 44.363899 -112.602472) (xy 44.475827 -112.54871)
			(xy 44.590962 -112.502212) (xy 44.708834 -112.463169) (xy 44.828961 -112.43174) (xy 44.950851 -112.408053)
			(xy 45.074005 -112.392206) (xy 45.197921 -112.384264) (xy 45.260006 -112.383824) (xy 45.323533 -112.384344)
			(xy 45.450315 -112.392654) (xy 45.576282 -112.409238) (xy 45.700894 -112.434025) (xy 45.823619 -112.466909)
			(xy 45.94393 -112.50775) (xy 46.061312 -112.556371) (xy 46.175263 -112.612566) (xy 46.285295 -112.676093)
			(xy 46.390937 -112.74668) (xy 46.491735 -112.824026) (xy 46.58726 -112.907798) (xy 46.6771 -112.997639)
			(xy 46.760873 -113.093163) (xy 46.838218 -113.193962) (xy 46.908806 -113.299603) (xy 46.972333 -113.409635)
			(xy 47.028528 -113.523586) (xy 47.07715 -113.640968) (xy 47.11799 -113.761279) (xy 47.150874 -113.884004)
			(xy 47.175662 -114.008616) (xy 47.192246 -114.134583) (xy 47.200556 -114.261365) (xy 47.201074 -114.324892)
			(xy 47.201074 -114.36223) (xy 47.22114 -114.37747) (xy 47.244101 -114.395624) (xy 47.284705 -114.43778)
			(xy 47.318394 -114.485643) (xy 47.344378 -114.53809) (xy 47.362047 -114.593891) (xy 47.370986 -114.651735)
			(xy 47.371508 -114.681) (xy 47.371036 -114.70837) (xy 47.363213 -114.762548) (xy 47.347726 -114.815052)
			(xy 47.324894 -114.864804) (xy 47.295186 -114.910781) (xy 47.277528 -114.931698) (xy 47.268289 -114.943024)
			(xy 47.256108 -114.969582) (xy 47.251934 -114.9985) (xy 47.256108 -115.027418) (xy 47.268289 -115.053976)
			(xy 47.277528 -115.065302) (xy 47.295171 -115.086234) (xy 47.324899 -115.132201) (xy 47.347747 -115.181947)
			(xy 47.363245 -115.234449) (xy 47.371075 -115.288629) (xy 47.371075 -115.343371) (xy 47.363245 -115.397551)
			(xy 47.347747 -115.450053) (xy 47.324899 -115.499799) (xy 47.295171 -115.545766) (xy 47.277528 -115.566698)
			(xy 47.268289 -115.578024) (xy 47.256108 -115.604582) (xy 47.251934 -115.6335) (xy 47.256108 -115.662418)
			(xy 47.268289 -115.688976) (xy 47.277528 -115.700302) (xy 47.295169 -115.721234) (xy 47.324892 -115.767201)
			(xy 47.347734 -115.816948) (xy 47.363222 -115.869451) (xy 47.37104 -115.92363) (xy 47.371508 -115.951)
			(xy 47.371051 -115.977837) (xy 47.363524 -116.03098) (xy 47.348618 -116.082543) (xy 47.32663 -116.131506)
			(xy 47.297992 -116.176902) (xy 47.263271 -116.217833) (xy 47.223153 -116.25349) (xy 47.201074 -116.268754)
			(xy 47.201074 -117.3734) (xy 63.51905 -117.3734) (xy 63.51905 -114.525044) (xy 63.519529 -114.460365)
			(xy 63.527339 -114.331244) (xy 63.542931 -114.20283) (xy 63.566248 -114.075591) (xy 63.597205 -113.949992)
			(xy 63.63569 -113.826492) (xy 63.68156 -113.705541) (xy 63.73465 -113.58758) (xy 63.794765 -113.47304)
			(xy 63.861687 -113.362338) (xy 63.93517 -113.255879) (xy 64.014947 -113.154051) (xy 64.100727 -113.057225)
			(xy 64.192197 -112.965756) (xy 64.289022 -112.879976) (xy 64.39085 -112.800199) (xy 64.49731 -112.726716)
			(xy 64.608011 -112.659794) (xy 64.722552 -112.599679) (xy 64.840513 -112.546589) (xy 64.961464 -112.500719)
			(xy 65.084964 -112.462235) (xy 65.210563 -112.431278) (xy 65.337802 -112.407961) (xy 65.466216 -112.392369)
			(xy 65.595337 -112.384559) (xy 65.660016 -112.384078) (xy 65.66027 -112.384078) (xy 65.720289 -112.384488)
			(xy 65.84014 -112.391214) (xy 65.959424 -112.404652) (xy 66.018664 -112.414304) (xy 66.036855 -112.391861)
			(xy 66.078856 -112.352198) (xy 66.126356 -112.319319) (xy 66.178269 -112.293975) (xy 66.233409 -112.276744)
			(xy 66.290516 -112.268022) (xy 66.3194 -112.267492) (xy 66.346651 -112.267978) (xy 66.400599 -112.275734)
			(xy 66.452894 -112.291089) (xy 66.502471 -112.313731) (xy 66.548321 -112.343197) (xy 66.589512 -112.378888)
			(xy 66.625203 -112.420079) (xy 66.654669 -112.465929) (xy 66.677311 -112.515506) (xy 66.692666 -112.567801)
			(xy 66.700422 -112.621749) (xy 66.700908 -112.649) (xy 66.700908 -112.65408) (xy 66.759163 -112.68708)
			(xy 66.87188 -112.759359) (xy 66.979859 -112.838542) (xy 67.082678 -112.924319) (xy 67.179934 -113.016354)
			(xy 67.271249 -113.114288) (xy 67.356263 -113.217738) (xy 67.434646 -113.326299) (xy 67.506091 -113.439547)
			(xy 67.570317 -113.557039) (xy 67.627075 -113.678315) (xy 67.676142 -113.802902) (xy 67.717326 -113.930311)
			(xy 67.750467 -114.060046) (xy 67.775434 -114.191599) (xy 67.79213 -114.324454) (xy 67.80049 -114.458094)
			(xy 67.800982 -114.525044) (xy 67.800982 -117.3734) (xy 75.724004 -117.3734) (xy 75.724004 -114.799872)
			(xy 75.72447 -114.745753) (xy 75.732179 -114.637791) (xy 75.747571 -114.530654) (xy 75.770568 -114.424888)
			(xy 75.801051 -114.321033) (xy 75.838866 -114.219616) (xy 75.88382 -114.121156) (xy 75.935683 -114.026154)
			(xy 75.994192 -113.935094) (xy 76.059049 -113.84844) (xy 76.129922 -113.766634) (xy 76.206451 -113.690092)
			(xy 76.288245 -113.619206) (xy 76.374888 -113.554335) (xy 76.465939 -113.495811) (xy 76.560932 -113.443931)
			(xy 76.659385 -113.398961) (xy 76.760795 -113.36113) (xy 76.864646 -113.330629) (xy 76.970408 -113.307616)
			(xy 77.077543 -113.292206) (xy 77.185504 -113.284478) (xy 77.239622 -113.284) (xy 78.74 -113.284)
			(xy 78.794131 -113.284472) (xy 78.902118 -113.292195) (xy 79.009279 -113.307603) (xy 79.115068 -113.330616)
			(xy 79.218945 -113.361118) (xy 79.320382 -113.398952) (xy 79.418861 -113.443926) (xy 79.51388 -113.495812)
			(xy 79.604956 -113.554344) (xy 79.691625 -113.619224) (xy 79.773444 -113.690121) (xy 79.849996 -113.766675)
			(xy 79.920893 -113.848495) (xy 79.985771 -113.935165) (xy 80.044302 -114.026242) (xy 80.096185 -114.121263)
			(xy 80.141158 -114.219742) (xy 80.178991 -114.32118) (xy 80.20949 -114.425058) (xy 80.232502 -114.530846)
			(xy 80.247907 -114.638008) (xy 80.255629 -114.745995) (xy 80.256126 -114.800126) (xy 80.256126 -115.673124)
			(xy 80.275814 -115.691307) (xy 80.310408 -115.732238) (xy 80.338938 -115.777605) (xy 80.360842 -115.826517)
			(xy 80.375689 -115.878011) (xy 80.383189 -115.931076) (xy 80.383193 -115.984668) (xy 80.375701 -116.037734)
			(xy 80.360861 -116.089231) (xy 80.338964 -116.138145) (xy 80.310441 -116.183517) (xy 80.275853 -116.224453)
			(xy 80.256126 -116.242592) (xy 80.256126 -118.720616) (xy 83.769962 -118.720616) (xy 83.785387 -118.720026)
			(xy 83.814807 -118.710726) (xy 83.840119 -118.69308) (xy 83.859022 -118.668694) (xy 83.869798 -118.639782)
			(xy 83.871468 -118.608972) (xy 83.86826 -118.59387) (xy 83.862789 -118.570826) (xy 83.856924 -118.523826)
			(xy 83.856576 -118.500144) (xy 83.857026 -118.473348) (xy 83.864518 -118.420283) (xy 83.87936 -118.368788)
			(xy 83.90126 -118.319875) (xy 83.929789 -118.274508) (xy 83.964384 -118.233578) (xy 83.984084 -118.21541)
			(xy 83.984084 -114.799872) (xy 83.984551 -114.747028) (xy 83.991928 -114.641597) (xy 84.006631 -114.536936)
			(xy 84.028587 -114.433553) (xy 84.057692 -114.331951) (xy 84.093802 -114.232623) (xy 84.136742 -114.13605)
			(xy 84.186305 -114.042704) (xy 84.24225 -113.953036) (xy 84.304303 -113.867482) (xy 84.372165 -113.786459)
			(xy 84.445506 -113.710358) (xy 84.484464 -113.674652) (xy 84.487437 -113.646488) (xy 84.500641 -113.591417)
			(xy 84.52184 -113.538903) (xy 84.550567 -113.490099) (xy 84.586191 -113.446076) (xy 84.627931 -113.407802)
			(xy 84.67487 -113.376118) (xy 84.725976 -113.351718) (xy 84.780126 -113.335141) (xy 84.836133 -113.326748)
			(xy 84.864448 -113.326164) (xy 84.891798 -113.326657) (xy 84.945932 -113.334505) (xy 84.998393 -113.349993)
			(xy 85.023452 -113.360962) (xy 85.081131 -113.342462) (xy 85.198793 -113.313639) (xy 85.318381 -113.29431)
			(xy 85.439132 -113.284598) (xy 85.499702 -113.284) (xy 88.000078 -113.284) (xy 88.045548 -113.283492)
			(xy 88.1361 -113.275103) (xy 88.225492 -113.258395) (xy 88.312961 -113.233509) (xy 88.397761 -113.200659)
			(xy 88.479168 -113.160125) (xy 88.556488 -113.112253) (xy 88.62906 -113.05745) (xy 88.696267 -112.996185)
			(xy 88.757534 -112.92898) (xy 88.812338 -112.856409) (xy 88.860213 -112.779091) (xy 88.900749 -112.697685)
			(xy 88.933601 -112.612886) (xy 88.958489 -112.525418) (xy 88.975199 -112.436026) (xy 88.983591 -112.345474)
			(xy 88.984074 -112.300004) (xy 88.984074 -111.417608) (xy 88.964391 -111.399425) (xy 88.929806 -111.358495)
			(xy 88.901286 -111.313131) (xy 88.87939 -111.264223) (xy 88.864551 -111.212734) (xy 88.857059 -111.159675)
			(xy 88.857061 -111.10609) (xy 88.864558 -111.053032) (xy 88.879402 -111.001544) (xy 88.901302 -110.952639)
			(xy 88.929826 -110.907277) (xy 88.964415 -110.86635) (xy 88.984074 -110.84814) (xy 88.984074 -106.337608)
			(xy 88.964391 -106.319425) (xy 88.929806 -106.278495) (xy 88.901286 -106.233131) (xy 88.87939 -106.184223)
			(xy 88.864551 -106.132734) (xy 88.857059 -106.079675) (xy 88.857061 -106.02609) (xy 88.864558 -105.973032)
			(xy 88.879402 -105.921544) (xy 88.901302 -105.872639) (xy 88.929826 -105.827277) (xy 88.964415 -105.78635)
			(xy 88.984074 -105.76814) (xy 88.984074 -101.257608) (xy 88.964391 -101.239425) (xy 88.929806 -101.198495)
			(xy 88.901286 -101.153131) (xy 88.87939 -101.104223) (xy 88.864551 -101.052734) (xy 88.857059 -100.999675)
			(xy 88.857061 -100.94609) (xy 88.864558 -100.893032) (xy 88.879402 -100.841544) (xy 88.901302 -100.792639)
			(xy 88.929826 -100.747277) (xy 88.964415 -100.70635) (xy 88.984074 -100.68814) (xy 88.984074 -96.177608)
			(xy 88.964391 -96.159425) (xy 88.929806 -96.118495) (xy 88.901286 -96.073131) (xy 88.87939 -96.024223)
			(xy 88.864551 -95.972734) (xy 88.857059 -95.919675) (xy 88.857061 -95.86609) (xy 88.864558 -95.813032)
			(xy 88.879402 -95.761544) (xy 88.901302 -95.712639) (xy 88.929826 -95.667277) (xy 88.964415 -95.62635)
			(xy 88.984074 -95.60814) (xy 88.984074 -91.097608) (xy 88.964391 -91.079425) (xy 88.929806 -91.038495)
			(xy 88.901286 -90.993131) (xy 88.87939 -90.944223) (xy 88.864551 -90.892734) (xy 88.857059 -90.839675)
			(xy 88.857061 -90.78609) (xy 88.864558 -90.733032) (xy 88.879402 -90.681544) (xy 88.901302 -90.632639)
			(xy 88.929826 -90.587277) (xy 88.964415 -90.54635) (xy 88.984074 -90.52814) (xy 88.984074 -86.216744)
			(xy 88.983555 -86.202844) (xy 88.975972 -86.176096) (xy 88.961463 -86.152379) (xy 88.941103 -86.133446)
			(xy 88.916395 -86.120699) (xy 88.889166 -86.115078) (xy 88.86143 -86.116999) (xy 88.848184 -86.12124)
			(xy 88.817082 -86.131673) (xy 88.752458 -86.142917) (xy 88.71966 -86.143592) (xy 88.692864 -86.143143)
			(xy 88.639798 -86.135653) (xy 88.588302 -86.120811) (xy 88.53939 -86.098911) (xy 88.494022 -86.070382)
			(xy 88.453093 -86.035786) (xy 88.434926 -86.016084) (xy 87.749634 -86.016084) (xy 87.695522 -86.015578)
			(xy 87.587576 -86.007814) (xy 87.480458 -85.992371) (xy 87.374714 -85.96933) (xy 87.270883 -85.938808)
			(xy 87.169492 -85.900959) (xy 87.071058 -85.855976) (xy 86.976082 -85.804089) (xy 86.885048 -85.745562)
			(xy 86.798419 -85.680692) (xy 86.716636 -85.609811) (xy 86.640116 -85.533278) (xy 86.569248 -85.451483)
			(xy 86.504393 -85.364843) (xy 86.445881 -85.273799) (xy 86.39401 -85.178815) (xy 86.349044 -85.080374)
			(xy 86.311212 -84.978976) (xy 86.280707 -84.87514) (xy 86.257683 -84.769392) (xy 86.242259 -84.662272)
			(xy 86.234513 -84.554324) (xy 86.234016 -84.500212) (xy 86.234016 -81.999836) (xy 86.234549 -81.943052)
			(xy 86.243072 -81.829805) (xy 86.260043 -81.717513) (xy 86.285368 -81.606805) (xy 86.318903 -81.498302)
			(xy 86.360461 -81.392611) (xy 86.409809 -81.290326) (xy 86.466671 -81.192019) (xy 86.530729 -81.098241)
			(xy 86.601621 -81.009518) (xy 86.639908 -80.96758) (xy 86.640443 -80.940363) (xy 86.648283 -80.886494)
			(xy 86.663701 -80.834287) (xy 86.686383 -80.784801) (xy 86.715869 -80.739042) (xy 86.75156 -80.697939)
			(xy 86.792732 -80.662327) (xy 86.838548 -80.632929) (xy 86.888077 -80.610343) (xy 86.940314 -80.595026)
			(xy 86.994198 -80.58729) (xy 87.021416 -80.586834) (xy 87.021924 -80.586834) (xy 87.054114 -80.587523)
			(xy 87.117573 -80.598376) (xy 87.148162 -80.608424) (xy 87.195651 -80.588374) (xy 87.292843 -80.553998)
			(xy 87.392144 -80.526299) (xy 87.493097 -80.505406) (xy 87.595235 -80.491416) (xy 87.698088 -80.484392)
			(xy 87.749634 -80.483964) (xy 88.984074 -80.483964) (xy 88.984074 -79.182722) (xy 88.629236 -78.827884)
			(xy 82.953098 -78.827884) (xy 82.14106 -79.639922) (xy 82.14106 -101.037644) (xy 82.140575 -101.062595)
			(xy 82.132778 -101.111885) (xy 82.117367 -101.159349) (xy 82.094722 -101.203818) (xy 82.0654 -101.244197)
			(xy 82.048096 -101.26218) (xy 79.788004 -103.522272) (xy 79.770006 -103.539559) (xy 79.729625 -103.568875)
			(xy 79.68516 -103.591523) (xy 79.637702 -103.606947) (xy 79.588418 -103.614768) (xy 79.563468 -103.615236)
			(xy 65.782952 -103.615236) (xy 64.473836 -104.924352) (xy 64.470788 -104.939338) (xy 64.464496 -104.967738)
			(xy 64.444464 -105.022346) (xy 64.416378 -105.073282) (xy 64.380887 -105.119367) (xy 64.338814 -105.159532)
			(xy 64.291134 -105.192847) (xy 64.23895 -105.218542) (xy 64.183471 -105.23602) (xy 64.125983 -105.244876)
			(xy 64.0969 -105.245408) (xy 64.068797 -105.244908) (xy 64.0132 -105.236664) (xy 63.959413 -105.220354)
			(xy 63.908601 -105.196331) (xy 63.861862 -105.165114) (xy 63.820207 -105.12738) (xy 63.802006 -105.105962)
			(xy 52.650898 -105.105962) (xy 52.632686 -105.126314) (xy 52.591446 -105.162117) (xy 52.545524 -105.191677)
			(xy 52.495858 -105.214392) (xy 52.443463 -105.229798) (xy 52.389407 -105.23758) (xy 52.334793 -105.23758)
			(xy 52.280737 -105.229798) (xy 52.228342 -105.214392) (xy 52.178676 -105.191677) (xy 52.132754 -105.162117)
			(xy 52.091514 -105.126314) (xy 52.073302 -105.105962) (xy 28.835858 -105.105962) (xy 28.824936 -105.11155)
			(xy 28.801678 -105.123053) (xy 28.752762 -105.140363) (xy 28.701952 -105.150878) (xy 28.650184 -105.154405)
			(xy 28.598416 -105.150878) (xy 28.547606 -105.140363) (xy 28.49869 -105.123053) (xy 28.475432 -105.11155)
			(xy 28.46451 -105.105962) (xy 25.053798 -105.105962) (xy 25.04567 -105.10901) (xy 25.014618 -105.119356)
			(xy 24.950123 -105.13047) (xy 24.9174 -105.131108) (xy 24.884678 -105.130455) (xy 24.820184 -105.119345)
			(xy 24.78913 -105.10901) (xy 24.781002 -105.105962) (xy 24.391366 -105.105962) (xy 24.38019 -105.111804)
			(xy 24.352452 -105.12585) (xy 24.29355 -105.14575) (xy 24.232206 -105.155859) (xy 24.20112 -105.156508)
			(xy 24.17003 -105.1559) (xy 24.108676 -105.14581) (xy 24.049778 -105.125878) (xy 24.02205 -105.111804)
			(xy 24.010874 -105.105962) (xy 20.080224 -105.105962) (xy 20.068286 -105.139744) (xy 20.059204 -105.164251)
			(xy 20.035282 -105.21072) (xy 20.005239 -105.253487) (xy 19.969638 -105.291752) (xy 19.929146 -105.324798)
			(xy 19.884521 -105.352005) (xy 19.836599 -105.372865) (xy 19.786278 -105.386986) (xy 19.734501 -105.394104)
			(xy 19.708368 -105.394506) (xy 19.6812 -105.394023) (xy 19.627416 -105.386303) (xy 19.575273 -105.371024)
			(xy 19.525827 -105.348496) (xy 19.480081 -105.319176) (xy 19.459194 -105.301796) (xy 19.448077 -105.292855)
			(xy 19.422164 -105.28095) (xy 19.39397 -105.276674) (xy 19.365693 -105.280359) (xy 19.339536 -105.291718)
			(xy 19.31754 -105.309866) (xy 19.30908 -105.321354) (xy 19.293739 -105.342851) (xy 19.258086 -105.381811)
			(xy 19.217404 -105.415487) (xy 19.17247 -105.443237) (xy 19.124141 -105.46453) (xy 19.073339 -105.478962)
			(xy 19.021034 -105.486256) (xy 18.994628 -105.486708) (xy 18.966932 -105.486214) (xy 18.912122 -105.478206)
			(xy 18.859047 -105.462353) (xy 18.808823 -105.438989) (xy 18.762507 -105.408606) (xy 18.721074 -105.371842)
			(xy 18.685394 -105.329472) (xy 18.656219 -105.282386) (xy 18.634162 -105.231575) (xy 18.619686 -105.178108)
			(xy 18.615914 -105.150666) (xy 18.61058 -105.105962) (xy 17.933924 -105.105962) (xy 17.92224 -105.140252)
			(xy 17.913302 -105.165007) (xy 17.889579 -105.21199) (xy 17.859624 -105.255266) (xy 17.824007 -105.294015)
			(xy 17.783402 -105.327501) (xy 17.73858 -105.355089) (xy 17.690392 -105.376256) (xy 17.639752 -105.390599)
			(xy 17.587622 -105.397847) (xy 17.561306 -105.398316) (xy 17.5352 -105.39789) (xy 17.483477 -105.390775)
			(xy 17.433205 -105.376676) (xy 17.385324 -105.355857) (xy 17.340728 -105.328707) (xy 17.300247 -105.295732)
			(xy 17.28216 -105.276904) (xy 17.27218 -105.266835) (xy 17.247931 -105.25217) (xy 17.220583 -105.244744)
			(xy 17.192248 -105.245133) (xy 17.165113 -105.253305) (xy 17.141276 -105.268631) (xy 17.131538 -105.278936)
			(xy 17.113341 -105.298914) (xy 17.072283 -105.334046) (xy 17.026676 -105.36303) (xy 16.977435 -105.385285)
			(xy 16.925545 -105.400366) (xy 16.872045 -105.40797) (xy 16.845026 -105.408476) (xy 16.818184 -105.408014)
			(xy 16.76503 -105.400481) (xy 16.713456 -105.385574) (xy 16.66448 -105.363587) (xy 16.619068 -105.334954)
			(xy 16.578117 -105.300239) (xy 16.542434 -105.260129) (xy 16.512724 -105.215415) (xy 16.489573 -105.166978)
			(xy 16.481044 -105.141522) (xy 16.469868 -105.105962) (xy 14.089888 -105.105962) (xy 14.064936 -105.10548)
			(xy 14.015643 -105.097687) (xy 13.968176 -105.08228) (xy 13.923704 -105.059637) (xy 13.883321 -105.030317)
			(xy 13.865352 -105.012998) (xy 11.848846 -102.996492) (xy 11.831559 -102.978495) (xy 11.802243 -102.938113)
			(xy 11.779595 -102.893648) (xy 11.764172 -102.84619) (xy 11.756352 -102.796906) (xy 11.755882 -102.771956)
			(xy 11.755882 -99.823524) (xy 11.732627 -99.808509) (xy 11.69031 -99.772826) (xy 11.653594 -99.731402)
			(xy 11.62325 -99.685106) (xy 11.599917 -99.63491) (xy 11.584084 -99.581869) (xy 11.576084 -99.527097)
			(xy 11.576084 -99.471743) (xy 11.584084 -99.416971) (xy 11.599917 -99.36393) (xy 11.62325 -99.313734)
			(xy 11.653594 -99.267438) (xy 11.69031 -99.226014) (xy 11.732627 -99.190331) (xy 11.755882 -99.175316)
			(xy 11.755882 -79.511652) (xy 11.739399 -79.49103) (xy 11.71167 -79.446105) (xy 11.690397 -79.397788)
			(xy 11.675984 -79.347001) (xy 11.668707 -79.294712) (xy 11.668705 -79.241919) (xy 11.675978 -79.189629)
			(xy 11.690386 -79.138841) (xy 11.711656 -79.090522) (xy 11.739381 -79.045595) (xy 11.755882 -79.024988)
			(xy 11.755882 -78.651354) (xy 11.230864 -78.126336) (xy 11.213579 -78.108338) (xy 11.184268 -78.067956)
			(xy 11.161627 -78.02349) (xy 11.146212 -77.976032) (xy 11.1384 -77.926749) (xy 11.1379 -77.9018)
			(xy 11.1379 -72.6186) (xy 11.138389 -72.593651) (xy 11.146195 -72.544366) (xy 11.161615 -72.49691)
			(xy 11.184268 -72.45245) (xy 11.213598 -72.412081) (xy 11.230864 -72.394064) (xy 11.755882 -71.869046)
			(xy 11.755882 -62.99073) (xy 11.756369 -62.96578) (xy 11.76417 -62.916493) (xy 11.779586 -62.869033)
			(xy 11.802236 -62.824569) (xy 11.831562 -62.784195) (xy 11.848846 -62.766194) (xy 14.84249 -59.77255)
			(xy 14.8463 -59.762644) (xy 14.856271 -59.738212) (xy 14.881979 -59.692127) (xy 14.913792 -59.650025)
			(xy 14.951105 -59.612709) (xy 14.993205 -59.580893) (xy 15.039288 -59.555182) (xy 15.063724 -59.54522)
			(xy 15.07363 -59.54141) (xy 16.194278 -58.420762) (xy 16.194278 -53.156612) (xy 15.774924 -52.737258)
			(xy 5.531358 -52.737258) (xy 5.52323 -52.740052) (xy 5.492752 -52.749994) (xy 5.429552 -52.760719)
			(xy 5.3975 -52.761388) (xy 5.365446 -52.760736) (xy 5.302242 -52.750017) (xy 5.27177 -52.740052)
			(xy 5.263642 -52.737258) (xy 1.230376 -52.737258) (xy 1.214945 -52.737799) (xy 1.185489 -52.747012)
			(xy 1.160124 -52.764593) (xy 1.141157 -52.78894) (xy 1.130317 -52.817837) (xy 1.12859 -52.848651)
			(xy 1.131824 -52.86375) (xy 1.137294 -52.886794) (xy 1.143157 -52.933794) (xy 1.143508 -52.957476)
			(xy 1.143058 -52.984271) (xy 1.135565 -53.037336) (xy 1.120722 -53.08883) (xy 1.09882 -53.137741)
			(xy 1.070289 -53.183105) (xy 1.035692 -53.224032) (xy 1.016 -53.24221) (xy 1.016 -57.752742) (xy 1.035684 -57.770926)
			(xy 1.07027 -57.811857) (xy 1.098792 -57.857223) (xy 1.120688 -57.906132) (xy 1.13553 -57.957622)
			(xy 1.143024 -58.010683) (xy 1.143024 -58.064269) (xy 1.13553 -58.11733) (xy 1.120688 -58.16882)
			(xy 1.098792 -58.217729) (xy 1.07027 -58.263095) (xy 1.035684 -58.304026) (xy 1.016 -58.32221) (xy 1.016 -62.832742)
			(xy 1.035684 -62.850926) (xy 1.07027 -62.891857) (xy 1.098792 -62.937223) (xy 1.120688 -62.986132)
			(xy 1.13553 -63.037622) (xy 1.143024 -63.090683) (xy 1.143024 -63.144269) (xy 1.13553 -63.19733)
			(xy 1.120688 -63.24882) (xy 1.098792 -63.297729) (xy 1.07027 -63.343095) (xy 1.035684 -63.384026)
			(xy 1.016 -63.40221) (xy 1.016 -67.912742) (xy 1.035684 -67.930926) (xy 1.07027 -67.971857) (xy 1.098792 -68.017223)
			(xy 1.120688 -68.066132) (xy 1.13553 -68.117622) (xy 1.143024 -68.170683) (xy 1.143024 -68.224269)
			(xy 1.13553 -68.27733) (xy 1.120688 -68.32882) (xy 1.098792 -68.377729) (xy 1.07027 -68.423095) (xy 1.035684 -68.464026)
			(xy 1.016 -68.48221) (xy 1.016 -72.992742) (xy 1.035684 -73.010926) (xy 1.07027 -73.051857) (xy 1.098792 -73.097223)
			(xy 1.120688 -73.146132) (xy 1.13553 -73.197622) (xy 1.143024 -73.250683) (xy 1.143024 -73.304269)
			(xy 1.13553 -73.35733) (xy 1.120688 -73.40882) (xy 1.098792 -73.457729) (xy 1.07027 -73.503095) (xy 1.035684 -73.544026)
			(xy 1.016 -73.56221) (xy 1.016 -78.072742) (xy 1.035684 -78.090926) (xy 1.07027 -78.131857) (xy 1.098792 -78.177223)
			(xy 1.120688 -78.226132) (xy 1.13553 -78.277622) (xy 1.143024 -78.330683) (xy 1.143024 -78.384269)
			(xy 1.13553 -78.43733) (xy 1.120688 -78.48882) (xy 1.098792 -78.537729) (xy 1.07027 -78.583095) (xy 1.035684 -78.624026)
			(xy 1.016 -78.64221) (xy 1.016 -80.483964) (xy 2.249932 -80.483964) (xy 2.304063 -80.484447) (xy 2.41205 -80.49217)
			(xy 2.519211 -80.507578) (xy 2.624999 -80.530591) (xy 2.728876 -80.561092) (xy 2.830313 -80.598926)
			(xy 2.928792 -80.6439) (xy 3.023812 -80.695785) (xy 3.114888 -80.754316) (xy 3.201556 -80.819196)
			(xy 3.283376 -80.890093) (xy 3.359929 -80.966646) (xy 3.430826 -81.048465) (xy 3.495705 -81.135134)
			(xy 3.554236 -81.22621) (xy 3.606121 -81.32123) (xy 3.651095 -81.419709) (xy 3.688929 -81.521146)
			(xy 3.71943 -81.625023) (xy 3.742442 -81.730811) (xy 3.75785 -81.837972) (xy 3.765573 -81.945959)
			(xy 3.766058 -82.00009) (xy 3.766058 -82.344006) (xy 3.785742 -82.36219) (xy 3.820327 -82.403121)
			(xy 3.848849 -82.448487) (xy 3.870745 -82.497396) (xy 3.885587 -82.548886) (xy 3.893081 -82.601947)
			(xy 3.893081 -82.655533) (xy 3.885587 -82.708594) (xy 3.870745 -82.760084) (xy 3.848849 -82.808993)
			(xy 3.820327 -82.854359) (xy 3.785742 -82.89529) (xy 3.766058 -82.913474) (xy 3.766058 -84.499958)
			(xy 3.765575 -84.554089) (xy 3.757852 -84.662076) (xy 3.742445 -84.769237) (xy 3.719432 -84.875026)
			(xy 3.688931 -84.978903) (xy 3.651097 -85.08034) (xy 3.606123 -85.17882) (xy 3.554239 -85.27384)
			(xy 3.495707 -85.364916) (xy 3.430828 -85.451585) (xy 3.359931 -85.533405) (xy 3.283378 -85.609958)
			(xy 3.201558 -85.680855) (xy 3.11489 -85.745735) (xy 3.023813 -85.804266) (xy 2.928793 -85.856151)
			(xy 2.830314 -85.901126) (xy 2.728877 -85.93896) (xy 2.625 -85.969461) (xy 2.519211 -85.992474) (xy 2.41205 -86.007882)
			(xy 2.304063 -86.015605) (xy 2.249932 -86.016084) (xy 1.016 -86.016084) (xy 1.016 -86.61527) (xy 1.035684 -86.633454)
			(xy 1.07027 -86.674385) (xy 1.098792 -86.719751) (xy 1.120688 -86.76866) (xy 1.13553 -86.82015) (xy 1.143024 -86.873211)
			(xy 1.143024 -86.926797) (xy 1.13553 -86.979858) (xy 1.120688 -87.031348) (xy 1.098792 -87.080257)
			(xy 1.07027 -87.125623) (xy 1.035684 -87.166554) (xy 1.016 -87.184738) (xy 1.016 -91.69527) (xy 1.035684 -91.713454)
			(xy 1.07027 -91.754385) (xy 1.098792 -91.799751) (xy 1.120688 -91.84866) (xy 1.13553 -91.90015) (xy 1.143024 -91.953211)
			(xy 1.143024 -92.006797) (xy 1.13553 -92.059858) (xy 1.120688 -92.111348) (xy 1.098792 -92.160257)
			(xy 1.07027 -92.205623) (xy 1.035684 -92.246554) (xy 1.016 -92.264738) (xy 1.016 -96.77527) (xy 1.035684 -96.793454)
			(xy 1.07027 -96.834385) (xy 1.098792 -96.879751) (xy 1.120688 -96.92866) (xy 1.13553 -96.98015) (xy 1.143024 -97.033211)
			(xy 1.143024 -97.086797) (xy 1.13553 -97.139858) (xy 1.120688 -97.191348) (xy 1.098792 -97.240257)
			(xy 1.07027 -97.285623) (xy 1.035684 -97.326554) (xy 1.016 -97.344738) (xy 1.016 -101.85527) (xy 1.035684 -101.873454)
			(xy 1.07027 -101.914385) (xy 1.098792 -101.959751) (xy 1.120688 -102.00866) (xy 1.13553 -102.06015)
			(xy 1.143024 -102.113211) (xy 1.143024 -102.166797) (xy 1.13553 -102.219858) (xy 1.120688 -102.271348)
			(xy 1.098792 -102.320257) (xy 1.07027 -102.365623) (xy 1.035684 -102.406554) (xy 1.016 -102.424738)
			(xy 1.016 -106.93527) (xy 1.035684 -106.953454) (xy 1.07027 -106.994385) (xy 1.098792 -107.039751)
			(xy 1.120688 -107.08866) (xy 1.13553 -107.14015) (xy 1.143024 -107.193211) (xy 1.143024 -107.246797)
			(xy 1.13553 -107.299858) (xy 1.120688 -107.351348) (xy 1.098792 -107.400257) (xy 1.07027 -107.445623)
			(xy 1.035684 -107.486554) (xy 1.016 -107.504738) (xy 1.016 -107.774051) (xy 13.017478 -107.774051)
			(xy 13.017478 -107.719549) (xy 13.025234 -107.665601) (xy 13.040589 -107.613306) (xy 13.063231 -107.563729)
			(xy 13.092697 -107.517879) (xy 13.128388 -107.476688) (xy 13.169579 -107.440997) (xy 13.215429 -107.411531)
			(xy 13.265006 -107.388889) (xy 13.317301 -107.373534) (xy 13.371249 -107.365778) (xy 13.3985 -107.365292)
			(xy 14.2875 -107.365292) (xy 14.314751 -107.365778) (xy 14.368699 -107.373534) (xy 14.420994 -107.388889)
			(xy 14.470571 -107.411531) (xy 14.516421 -107.440997) (xy 14.557612 -107.476688) (xy 14.593303 -107.517879)
			(xy 14.622769 -107.563729) (xy 14.645411 -107.613306) (xy 14.660766 -107.665601) (xy 14.668522 -107.719549)
			(xy 14.668522 -107.77382) (xy 17.94482 -107.77382) (xy 17.94482 -107.71928) (xy 17.952582 -107.665296)
			(xy 17.967948 -107.612966) (xy 17.990604 -107.563355) (xy 18.02009 -107.517474) (xy 18.055806 -107.476256)
			(xy 18.097024 -107.44054) (xy 18.142905 -107.411054) (xy 18.192516 -107.388398) (xy 18.244846 -107.373032)
			(xy 18.29883 -107.36527) (xy 18.3261 -107.364784) (xy 19.2151 -107.364784) (xy 19.242369 -107.365278)
			(xy 19.296352 -107.37304) (xy 19.348681 -107.388405) (xy 19.398291 -107.411061) (xy 19.444171 -107.440547)
			(xy 19.485388 -107.476262) (xy 19.521103 -107.517479) (xy 19.550589 -107.563359) (xy 19.573245 -107.612969)
			(xy 19.58861 -107.665298) (xy 19.596372 -107.719281) (xy 19.596372 -107.773819) (xy 19.58861 -107.827802)
			(xy 19.573245 -107.880131) (xy 19.550589 -107.929741) (xy 19.521103 -107.975621) (xy 19.485388 -108.016838)
			(xy 19.444171 -108.052553) (xy 19.398291 -108.082039) (xy 19.348681 -108.104695) (xy 19.296352 -108.12006)
			(xy 19.242369 -108.127822) (xy 19.2151 -108.128308) (xy 18.3261 -108.128308) (xy 18.29883 -108.12783)
			(xy 18.244846 -108.120068) (xy 18.192516 -108.104702) (xy 18.142905 -108.082046) (xy 18.097024 -108.05256)
			(xy 18.055806 -108.016844) (xy 18.02009 -107.975626) (xy 17.990604 -107.929745) (xy 17.967948 -107.880134)
			(xy 17.952582 -107.827804) (xy 17.94482 -107.77382) (xy 14.668522 -107.77382) (xy 14.668522 -107.774051)
			(xy 14.660766 -107.827999) (xy 14.645411 -107.880294) (xy 14.622769 -107.929871) (xy 14.593303 -107.975721)
			(xy 14.557612 -108.016912) (xy 14.516421 -108.052603) (xy 14.470571 -108.082069) (xy 14.420994 -108.104711)
			(xy 14.368699 -108.120066) (xy 14.314751 -108.127822) (xy 14.2875 -108.128308) (xy 13.3985 -108.128308)
			(xy 13.371249 -108.127822) (xy 13.317301 -108.120066) (xy 13.265006 -108.104711) (xy 13.215429 -108.082069)
			(xy 13.169579 -108.052603) (xy 13.128388 -108.016912) (xy 13.092697 -107.975721) (xy 13.063231 -107.929871)
			(xy 13.040589 -107.880294) (xy 13.025234 -107.827999) (xy 13.017478 -107.774051) (xy 1.016 -107.774051)
			(xy 1.016 -109.570609) (xy 15.016716 -109.570609) (xy 15.016716 -109.516071) (xy 15.024478 -109.462088)
			(xy 15.039843 -109.409759) (xy 15.062499 -109.360149) (xy 15.091985 -109.314268) (xy 15.127699 -109.273051)
			(xy 15.168917 -109.237336) (xy 15.214797 -109.20785) (xy 15.264407 -109.185194) (xy 15.316736 -109.169828)
			(xy 15.370719 -109.162067) (xy 15.397988 -109.16158) (xy 16.286988 -109.16158) (xy 16.314259 -109.162039)
			(xy 16.368247 -109.169801) (xy 16.42058 -109.185167) (xy 16.470193 -109.207825) (xy 16.516078 -109.237313)
			(xy 16.557298 -109.27303) (xy 16.593016 -109.314251) (xy 16.622504 -109.360135) (xy 16.645162 -109.409748)
			(xy 16.660528 -109.462081) (xy 16.668291 -109.516069) (xy 16.668291 -109.570611) (xy 16.660528 -109.624599)
			(xy 16.645162 -109.676932) (xy 16.622504 -109.726545) (xy 16.593016 -109.772429) (xy 16.557298 -109.81365)
			(xy 16.516078 -109.849367) (xy 16.470193 -109.878855) (xy 16.42058 -109.901513) (xy 16.368247 -109.916879)
			(xy 16.314259 -109.924641) (xy 16.286988 -109.925104) (xy 15.397988 -109.925104) (xy 15.370719 -109.924613)
			(xy 15.316736 -109.916852) (xy 15.264407 -109.901486) (xy 15.214797 -109.87883) (xy 15.168917 -109.849344)
			(xy 15.127699 -109.813629) (xy 15.091985 -109.772412) (xy 15.062499 -109.726531) (xy 15.039843 -109.676921)
			(xy 15.024478 -109.624592) (xy 15.016716 -109.570609) (xy 1.016 -109.570609) (xy 1.016 -109.998056)
			(xy 84.426541 -109.998056) (xy 84.426541 -109.868916) (xy 84.434491 -109.740021) (xy 84.450361 -109.611861)
			(xy 84.47409 -109.48492) (xy 84.505589 -109.359681) (xy 84.544738 -109.236618) (xy 84.591389 -109.116199)
			(xy 84.645364 -108.99888) (xy 84.706459 -108.885106) (xy 84.774442 -108.775309) (xy 84.849056 -108.669906)
			(xy 84.930017 -108.569296) (xy 85.017017 -108.473861) (xy 85.109728 -108.383962) (xy 85.207798 -108.299941)
			(xy 85.310853 -108.222117) (xy 85.418504 -108.150785) (xy 85.530343 -108.086215) (xy 85.645944 -108.028653)
			(xy 85.764869 -107.978316) (xy 85.886668 -107.935396) (xy 86.010878 -107.900055) (xy 86.137027 -107.872428)
			(xy 86.264639 -107.852619) (xy 86.393228 -107.840703) (xy 86.522306 -107.836727) (xy 86.651384 -107.840703)
			(xy 86.779973 -107.852619) (xy 86.907585 -107.872428) (xy 87.033734 -107.900055) (xy 87.157944 -107.935396)
			(xy 87.279743 -107.978316) (xy 87.398668 -108.028653) (xy 87.514269 -108.086215) (xy 87.626108 -108.150785)
			(xy 87.733759 -108.222117) (xy 87.836814 -108.299941) (xy 87.934884 -108.383962) (xy 88.027595 -108.473861)
			(xy 88.114595 -108.569296) (xy 88.195556 -108.669906) (xy 88.27017 -108.775309) (xy 88.338153 -108.885106)
			(xy 88.399248 -108.99888) (xy 88.453223 -109.116199) (xy 88.499874 -109.236618) (xy 88.539023 -109.359681)
			(xy 88.570522 -109.48492) (xy 88.594251 -109.611861) (xy 88.610121 -109.740021) (xy 88.618071 -109.868916)
			(xy 88.618568 -109.933486) (xy 88.618071 -109.998056) (xy 88.610121 -110.126951) (xy 88.594251 -110.255111)
			(xy 88.570522 -110.382052) (xy 88.539023 -110.507291) (xy 88.499874 -110.630354) (xy 88.453223 -110.750773)
			(xy 88.399248 -110.868092) (xy 88.338153 -110.981866) (xy 88.27017 -111.091663) (xy 88.195556 -111.197066)
			(xy 88.114595 -111.297676) (xy 88.027595 -111.393111) (xy 87.934884 -111.48301) (xy 87.836814 -111.567031)
			(xy 87.733759 -111.644855) (xy 87.626108 -111.716187) (xy 87.514269 -111.780757) (xy 87.398668 -111.838319)
			(xy 87.279743 -111.888656) (xy 87.157944 -111.931576) (xy 87.033734 -111.966917) (xy 86.907585 -111.994544)
			(xy 86.779973 -112.014353) (xy 86.651384 -112.026269) (xy 86.522306 -112.030246) (xy 86.393228 -112.026269)
			(xy 86.264639 -112.014353) (xy 86.137027 -111.994544) (xy 86.010878 -111.966917) (xy 85.886668 -111.931576)
			(xy 85.764869 -111.888656) (xy 85.645944 -111.838319) (xy 85.530343 -111.780757) (xy 85.418504 -111.716187)
			(xy 85.310853 -111.644855) (xy 85.207798 -111.567031) (xy 85.109728 -111.48301) (xy 85.017017 -111.393111)
			(xy 84.930017 -111.297676) (xy 84.849056 -111.197066) (xy 84.774442 -111.091663) (xy 84.706459 -110.981866)
			(xy 84.645364 -110.868092) (xy 84.591389 -110.750773) (xy 84.544738 -110.630354) (xy 84.505589 -110.507291)
			(xy 84.47409 -110.382052) (xy 84.450361 -110.255111) (xy 84.434491 -110.126951) (xy 84.426541 -109.998056)
			(xy 1.016 -109.998056) (xy 1.016 -112.01527) (xy 1.035682 -112.033455) (xy 1.070266 -112.074389)
			(xy 1.098788 -112.119755) (xy 1.120689 -112.168662) (xy 1.135537 -112.220151) (xy 1.143041 -112.273211)
			(xy 1.143508 -112.300004) (xy 1.143029 -112.327502) (xy 1.1396 -112.35115) (xy 53.778158 -112.35115)
			(xy 53.778158 -112.29665) (xy 53.785913 -112.242703) (xy 53.801267 -112.19041) (xy 53.823905 -112.140833)
			(xy 53.853369 -112.094983) (xy 53.889057 -112.053792) (xy 53.930243 -112.018099) (xy 53.976089 -111.988629)
			(xy 54.025663 -111.965984) (xy 54.077955 -111.950624) (xy 54.1319 -111.942861) (xy 54.15915 -111.942372)
			(xy 55.04815 -111.942372) (xy 55.075404 -111.942872) (xy 55.129357 -111.950623) (xy 55.181658 -111.965974)
			(xy 55.231242 -111.988612) (xy 55.277099 -112.018077) (xy 55.318296 -112.053769) (xy 55.353993 -112.094961)
			(xy 55.383464 -112.140814) (xy 55.406109 -112.190395) (xy 55.421467 -112.242694) (xy 55.429225 -112.296646)
			(xy 55.429225 -112.351154) (xy 55.421467 -112.405106) (xy 55.406109 -112.457405) (xy 55.383464 -112.506986)
			(xy 55.353993 -112.552839) (xy 55.318296 -112.594031) (xy 55.277099 -112.629723) (xy 55.231242 -112.659188)
			(xy 55.181658 -112.681826) (xy 55.129357 -112.697177) (xy 55.075404 -112.704928) (xy 55.04815 -112.705388)
			(xy 54.15915 -112.705388) (xy 54.1319 -112.704939) (xy 54.077955 -112.697176) (xy 54.025663 -112.681816)
			(xy 53.976089 -112.659171) (xy 53.930243 -112.629701) (xy 53.889057 -112.594008) (xy 53.853369 -112.552817)
			(xy 53.823905 -112.506967) (xy 53.801267 -112.45739) (xy 53.785913 -112.405097) (xy 53.778158 -112.35115)
			(xy 1.1396 -112.35115) (xy 1.135137 -112.381929) (xy 1.119517 -112.434661) (xy 1.096492 -112.484605)
			(xy 1.066537 -112.530728) (xy 1.048766 -112.551718) (xy 1.060222 -112.593211) (xy 1.089432 -112.674191)
			(xy 1.125604 -112.75231) (xy 1.168462 -112.82697) (xy 1.217678 -112.8976) (xy 1.272877 -112.963661)
			(xy 1.333635 -113.024648) (xy 1.399489 -113.080094) (xy 1.469934 -113.129575) (xy 1.544433 -113.172713)
			(xy 1.559952 -113.17997) (xy 23.969706 -113.17997) (xy 23.969706 -113.12543) (xy 23.977468 -113.071446)
			(xy 23.992833 -113.019115) (xy 24.015489 -112.969504) (xy 24.044974 -112.923622) (xy 24.080689 -112.882403)
			(xy 24.121906 -112.846686) (xy 24.167787 -112.817198) (xy 24.217397 -112.79454) (xy 24.269726 -112.779172)
			(xy 24.32371 -112.771408) (xy 24.35098 -112.77092) (xy 25.23998 -112.77092) (xy 25.267251 -112.771418)
			(xy 25.321237 -112.779178) (xy 25.37357 -112.794541) (xy 25.423183 -112.817197) (xy 25.469067 -112.846682)
			(xy 25.510288 -112.882398) (xy 25.546006 -112.923617) (xy 25.575494 -112.969499) (xy 25.598152 -113.019111)
			(xy 25.613518 -113.071443) (xy 25.62128 -113.125429) (xy 25.62128 -113.179971) (xy 25.613518 -113.233957)
			(xy 25.598152 -113.286289) (xy 25.575494 -113.335901) (xy 25.546006 -113.381783) (xy 25.510288 -113.423002)
			(xy 25.469067 -113.458718) (xy 25.423183 -113.488203) (xy 25.37357 -113.510859) (xy 25.321237 -113.526222)
			(xy 25.267251 -113.533982) (xy 25.23998 -113.534444) (xy 24.35098 -113.534444) (xy 24.32371 -113.533992)
			(xy 24.269726 -113.526228) (xy 24.217397 -113.51086) (xy 24.167787 -113.488202) (xy 24.121906 -113.458714)
			(xy 24.080689 -113.422997) (xy 24.044974 -113.381778) (xy 24.015489 -113.335896) (xy 23.992833 -113.286285)
			(xy 23.977468 -113.233954) (xy 23.969706 -113.17997) (xy 1.559952 -113.17997) (xy 1.622415 -113.209178)
			(xy 1.703285 -113.238691) (xy 1.786423 -113.261027) (xy 1.871195 -113.276015) (xy 1.956953 -113.28354)
			(xy 1.999996 -113.284) (xy 4.500372 -113.284) (xy 4.561173 -113.284629) (xy 4.682381 -113.294415)
			(xy 4.802417 -113.313869) (xy 4.920511 -113.342868) (xy 4.9784 -113.36147) (xy 5.003378 -113.350547)
			(xy 5.055677 -113.335157) (xy 5.109638 -113.32739) (xy 5.136896 -113.326926) (xy 5.13715 -113.326926)
			(xy 5.165504 -113.327441) (xy 5.221589 -113.335826) (xy 5.275815 -113.35242) (xy 5.326988 -113.376856)
			(xy 5.373981 -113.408596) (xy 5.415759 -113.446943) (xy 5.451401 -113.491049) (xy 5.480124 -113.539946)
			(xy 5.501293 -113.592554) (xy 5.514443 -113.647716) (xy 5.517388 -113.675922) (xy 5.559695 -113.714947)
			(xy 5.638923 -113.798452) (xy 5.71159 -113.887724) (xy 5.777278 -113.982251) (xy 5.835607 -114.081486)
			(xy 5.886243 -114.18486) (xy 5.928894 -114.291776) (xy 5.963313 -114.401619) (xy 5.989304 -114.513755)
			(xy 6.006715 -114.62754) (xy 6.015446 -114.742317) (xy 6.01599 -114.799872) (xy 6.01599 -118.209314)
			(xy 6.035929 -118.227508) (xy 6.07099 -118.268546) (xy 6.099917 -118.314117) (xy 6.12213 -118.363311)
			(xy 6.137186 -118.415145) (xy 6.144785 -118.468584) (xy 6.145276 -118.495572) (xy 6.144877 -118.520176)
			(xy 6.138507 -118.568972) (xy 6.132576 -118.592854) (xy 6.129529 -118.605826) (xy 6.129567 -118.632465)
			(xy 6.1365 -118.658185) (xy 6.149854 -118.681235) (xy 6.16872 -118.700041) (xy 6.191812 -118.713323)
			(xy 6.217554 -118.720175) (xy 6.230874 -118.720616) (xy 9.749028 -118.720616)
		)
		(stroke
			(width 0)
			(type solid)
		)
		(fill yes)
		(layer "In5.Cu")
		(net "P12V_AUX")
	)
	(gr_poly
		(pts
			(xy 23.970742 -104.470962) (xy 23.992944 -104.45473) (xy 24.041086 -104.428138) (xy 24.092549 -104.408741)
			(xy 24.146265 -104.396938) (xy 24.20112 -104.392977) (xy 24.255975 -104.396938) (xy 24.309691 -104.408741)
			(xy 24.361154 -104.428138) (xy 24.409296 -104.45473) (xy 24.431498 -104.470962) (xy 24.656796 -104.470962)
			(xy 24.678114 -104.451734) (xy 24.725443 -104.419244) (xy 24.777106 -104.394213) (xy 24.831936 -104.377204)
			(xy 24.888696 -104.368603) (xy 24.946104 -104.368603) (xy 25.002864 -104.377204) (xy 25.057694 -104.394213)
			(xy 25.109357 -104.419244) (xy 25.156686 -104.451734) (xy 25.178004 -104.470962) (xy 27.138884 -104.470962)
			(xy 27.149044 -104.43337) (xy 27.156754 -104.406749) (xy 27.178806 -104.355905) (xy 27.207983 -104.308786)
			(xy 27.24367 -104.266384) (xy 27.285116 -104.229592) (xy 27.33145 -104.199183) (xy 27.381695 -104.175799)
			(xy 27.434796 -104.15993) (xy 27.489634 -104.151912) (xy 27.545054 -104.151912) (xy 27.599892 -104.15993)
			(xy 27.652993 -104.175799) (xy 27.703238 -104.199183) (xy 27.749572 -104.229592) (xy 27.791018 -104.266384)
			(xy 27.826705 -104.308786) (xy 27.855882 -104.355905) (xy 27.877934 -104.406749) (xy 27.885644 -104.43337)
			(xy 27.895804 -104.470962) (xy 28.416504 -104.470962) (xy 28.438899 -104.454211) (xy 28.487621 -104.426756)
			(xy 28.539831 -104.406714) (xy 28.594409 -104.394514) (xy 28.650184 -104.390418) (xy 28.705959 -104.394514)
			(xy 28.760537 -104.406714) (xy 28.812747 -104.426756) (xy 28.861469 -104.454211) (xy 28.883864 -104.470962)
			(xy 29.244036 -104.470962) (xy 29.253434 -104.4321) (xy 29.260536 -104.404671) (xy 29.281738 -104.352128)
			(xy 29.310476 -104.303299) (xy 29.346118 -104.259255) (xy 29.387881 -104.220965) (xy 29.434846 -104.189272)
			(xy 29.485982 -104.164872) (xy 29.540163 -104.1483) (xy 29.596199 -104.139923) (xy 29.652857 -104.139923)
			(xy 29.708893 -104.1483) (xy 29.763074 -104.164872) (xy 29.81421 -104.189272) (xy 29.861175 -104.220965)
			(xy 29.902938 -104.259255) (xy 29.93858 -104.303299) (xy 29.967318 -104.352128) (xy 29.98852 -104.404671)
			(xy 29.995622 -104.4321) (xy 30.00502 -104.470962) (xy 30.141926 -104.470962) (xy 30.160094 -104.451205)
			(xy 30.20102 -104.41648) (xy 30.246413 -104.387839) (xy 30.295374 -104.365848) (xy 30.346935 -104.350941)
			(xy 30.400078 -104.343413) (xy 30.45375 -104.343413) (xy 30.506893 -104.350941) (xy 30.558454 -104.365848)
			(xy 30.607415 -104.387839) (xy 30.652808 -104.41648) (xy 30.693734 -104.451205) (xy 30.711902 -104.470962)
			(xy 35.427158 -104.470962) (xy 35.44533 -104.451166) (xy 35.486277 -104.416369) (xy 35.531704 -104.387666)
			(xy 35.580712 -104.365626) (xy 35.632329 -104.350685) (xy 35.685532 -104.34314) (xy 35.739268 -104.34314)
			(xy 35.792471 -104.350685) (xy 35.844088 -104.365626) (xy 35.893096 -104.387666) (xy 35.938523 -104.416369)
			(xy 35.97947 -104.451166) (xy 35.997642 -104.470962) (xy 38.544246 -104.470962) (xy 38.557521 -104.446662)
			(xy 38.590021 -104.401832) (xy 38.628663 -104.362174) (xy 38.672635 -104.328523) (xy 38.721012 -104.301587)
			(xy 38.772777 -104.281931) (xy 38.826841 -104.26997) (xy 38.882066 -104.265955) (xy 38.937291 -104.26997)
			(xy 38.991355 -104.281931) (xy 39.04312 -104.301587) (xy 39.091497 -104.328523) (xy 39.135469 -104.362174)
			(xy 39.174111 -104.401832) (xy 39.206611 -104.446662) (xy 39.219886 -104.470962) (xy 54.858412 -104.470962)
			(xy 54.872786 -104.470478) (xy 54.900399 -104.462479) (xy 54.924682 -104.447092) (xy 54.943706 -104.42554)
			(xy 54.95596 -104.399535) (xy 54.96047 -104.371143) (xy 54.956878 -104.342621) (xy 54.95163 -104.32923)
			(xy 54.941771 -104.305266) (xy 54.927871 -104.255347) (xy 54.920829 -104.204009) (xy 54.920388 -104.1781)
			(xy 54.920873 -104.15086) (xy 54.928623 -104.096935) (xy 54.943965 -104.04466) (xy 54.966588 -103.995099)
			(xy 54.99603 -103.949261) (xy 55.031694 -103.908077) (xy 55.072854 -103.872385) (xy 55.118673 -103.842912)
			(xy 55.168218 -103.820255) (xy 55.220482 -103.804878) (xy 55.274403 -103.797091) (xy 55.301642 -103.796592)
			(xy 56.19115 -103.796592) (xy 56.218407 -103.797081) (xy 56.272365 -103.804842) (xy 56.324671 -103.820198)
			(xy 56.374261 -103.842838) (xy 56.420126 -103.872301) (xy 56.461335 -103.907988) (xy 56.497049 -103.949173)
			(xy 56.526542 -103.99502) (xy 56.549214 -104.044595) (xy 56.564605 -104.09689) (xy 56.572401 -104.150844)
			(xy 56.572912 -104.1781) (xy 56.572481 -104.204011) (xy 56.565464 -104.255354) (xy 56.551545 -104.305271)
			(xy 56.54167 -104.32923) (xy 56.536443 -104.342623) (xy 56.532885 -104.371138) (xy 56.537411 -104.399515)
			(xy 56.549663 -104.425509) (xy 56.568671 -104.44706) (xy 56.592931 -104.462463) (xy 56.62052 -104.470499)
			(xy 56.634888 -104.470962) (xy 64.029082 -104.470962) (xy 65.426844 -103.0732) (xy 65.444843 -103.055917)
			(xy 65.485227 -103.02661) (xy 65.529693 -103.00397) (xy 65.577149 -102.988555) (xy 65.626431 -102.980742)
			(xy 65.65138 -102.980236) (xy 70.193916 -102.980236) (xy 70.206915 -102.955122) (xy 70.239201 -102.908696)
			(xy 70.277987 -102.867545) (xy 70.322423 -102.832572) (xy 70.371536 -102.804542) (xy 70.424249 -102.78407)
			(xy 70.479407 -102.771605) (xy 70.5358 -102.767419) (xy 70.592193 -102.771605) (xy 70.647351 -102.78407)
			(xy 70.700064 -102.804542) (xy 70.749177 -102.832572) (xy 70.793613 -102.867545) (xy 70.832399 -102.908696)
			(xy 70.864685 -102.955122) (xy 70.877684 -102.980236) (xy 79.431896 -102.980236) (xy 81.50606 -100.906072)
			(xy 81.50606 -79.50835) (xy 81.506545 -79.483399) (xy 81.514344 -79.43411) (xy 81.529756 -79.386647)
			(xy 81.552403 -79.34218) (xy 81.581727 -79.301803) (xy 81.599024 -79.283814) (xy 82.59699 -78.285848)
			(xy 82.614989 -78.268565) (xy 82.655373 -78.23926) (xy 82.699839 -78.216623) (xy 82.747296 -78.201212)
			(xy 82.796578 -78.193405) (xy 82.821526 -78.192884) (xy 88.7095 -78.192884) (xy 88.984074 -77.91831)
			(xy 88.984074 -76.684886) (xy 88.964392 -76.666703) (xy 88.929811 -76.625774) (xy 88.901293 -76.58041)
			(xy 88.879401 -76.531504) (xy 88.864564 -76.480016) (xy 88.857074 -76.426959) (xy 88.857078 -76.373377)
			(xy 88.864577 -76.320321) (xy 88.879423 -76.268836) (xy 88.901323 -76.219933) (xy 88.929848 -76.174574)
			(xy 88.964437 -76.133651) (xy 88.984074 -76.115418) (xy 88.984074 -74.56932) (xy 88.567514 -74.15276)
			(xy 81.048606 -74.15276) (xy 81.03489 -74.182478) (xy 81.023098 -74.206995) (xy 80.993598 -74.252704)
			(xy 80.957905 -74.29376) (xy 80.916741 -74.32933) (xy 80.870943 -74.358692) (xy 80.821439 -74.38125)
			(xy 80.769232 -74.396549) (xy 80.715381 -74.404276) (xy 80.660979 -74.404276) (xy 80.607128 -74.396549)
			(xy 80.554921 -74.38125) (xy 80.505417 -74.358692) (xy 80.459619 -74.32933) (xy 80.418455 -74.29376)
			(xy 80.382762 -74.252704) (xy 80.353262 -74.206995) (xy 80.34147 -74.182478) (xy 80.327754 -74.15276)
			(xy 66.438272 -74.15276) (xy 66.421 -74.153268) (xy 66.403728 -74.15276) (xy 58.750962 -74.15276)
			(xy 58.481722 -74.422) (xy 58.481722 -76.779628) (xy 58.4835 -76.786232) (xy 58.489682 -76.810658)
			(xy 58.496303 -76.860607) (xy 58.496708 -76.8858) (xy 58.496299 -76.910992) (xy 58.489668 -76.960939)
			(xy 58.4835 -76.985368) (xy 58.481722 -76.991972) (xy 58.481722 -77.306678) (xy 58.481313 -77.326595)
			(xy 58.475057 -77.365937) (xy 58.46274 -77.403821) (xy 58.454036 -77.42174) (xy 58.467471 -77.448981)
			(xy 58.486484 -77.506664) (xy 58.496112 -77.566632) (xy 58.496708 -77.597) (xy 58.496222 -77.624251)
			(xy 58.488466 -77.678199) (xy 58.473111 -77.730494) (xy 58.450469 -77.780071) (xy 58.421003 -77.825921)
			(xy 58.385312 -77.867112) (xy 58.344121 -77.902803) (xy 58.298271 -77.932269) (xy 58.248694 -77.954911)
			(xy 58.196399 -77.970266) (xy 58.142451 -77.978022) (xy 58.1152 -77.978508) (xy 58.114438 -77.978508)
			(xy 58.08042 -77.977717) (xy 58.013472 -77.965582) (xy 57.981342 -77.954378) (xy 57.950608 -77.942948)
			(xy 57.253378 -78.640178) (xy 57.235339 -78.657443) (xy 57.193848 -78.685211) (xy 57.14773 -78.704333)
			(xy 57.098763 -78.714073) (xy 57.0738 -78.7146) (xy 54.516782 -78.7146) (xy 54.495486 -78.733691)
			(xy 54.448251 -78.765934) (xy 54.396733 -78.79077) (xy 54.342087 -78.807643) (xy 54.285536 -78.816174)
			(xy 54.228344 -78.816174) (xy 54.171793 -78.807643) (xy 54.117147 -78.79077) (xy 54.065629 -78.765934)
			(xy 54.018394 -78.733691) (xy 53.997098 -78.7146) (xy 47.095156 -78.7146) (xy 46.6852 -79.124556)
			(xy 46.6852 -82.675476) (xy 46.687486 -82.682842) (xy 46.6952 -82.709941) (xy 46.703491 -82.765669)
			(xy 46.703996 -82.79384) (xy 46.703996 -82.794348) (xy 46.703494 -82.822519) (xy 46.69521 -82.87825)
			(xy 46.687486 -82.905346) (xy 46.6852 -82.912712) (xy 46.6852 -85.347302) (xy 46.684588 -85.372259)
			(xy 46.67485 -85.421212) (xy 46.655749 -85.467326) (xy 46.628019 -85.508827) (xy 46.610778 -85.52688)
			(xy 43.357292 -88.780366) (xy 43.355006 -88.797384) (xy 43.350888 -88.824836) (xy 43.335744 -88.87824)
			(xy 43.31302 -88.928884) (xy 43.283195 -88.9757) (xy 43.2469 -89.0177) (xy 43.2049 -89.053995) (xy 43.158084 -89.08382)
			(xy 43.10744 -89.106544) (xy 43.054036 -89.121688) (xy 43.026584 -89.125806) (xy 43.009566 -89.128092)
			(xy 42.60088 -89.536778) (xy 42.582841 -89.554043) (xy 42.54135 -89.581812) (xy 42.495232 -89.600934)
			(xy 42.446265 -89.610674) (xy 42.421302 -89.6112) (xy 31.957772 -89.6112) (xy 31.945834 -89.64549)
			(xy 31.945834 -89.645744) (xy 31.936349 -89.671958) (xy 31.910854 -89.721532) (xy 31.878413 -89.766866)
			(xy 31.839718 -89.806994) (xy 31.795592 -89.841062) (xy 31.746978 -89.868342) (xy 31.69491 -89.888254)
			(xy 31.640497 -89.900373) (xy 31.5849 -89.904442) (xy 31.529303 -89.900373) (xy 31.47489 -89.888254)
			(xy 31.422822 -89.868342) (xy 31.374208 -89.841062) (xy 31.330082 -89.806994) (xy 31.291387 -89.766866)
			(xy 31.258946 -89.721532) (xy 31.233451 -89.671958) (xy 31.223966 -89.645744) (xy 31.223966 -89.64549)
			(xy 31.212028 -89.6112) (xy 28.6004 -89.6112) (xy 28.575443 -89.610588) (xy 28.526489 -89.600851)
			(xy 28.480376 -89.58175) (xy 28.438874 -89.55402) (xy 28.420822 -89.536778) (xy 27.181302 -88.297258)
			(xy 27.152854 -88.304878) (xy 27.13185 -88.310173) (xy 27.088914 -88.315904) (xy 27.067256 -88.316308)
			(xy 27.041271 -88.315795) (xy 26.989942 -88.307659) (xy 26.940517 -88.291594) (xy 26.894214 -88.267996)
			(xy 26.852172 -88.237446) (xy 26.815426 -88.200695) (xy 26.784881 -88.158649) (xy 26.761289 -88.112342)
			(xy 26.745231 -88.062915) (xy 26.737101 -88.011585) (xy 26.736548 -87.9856) (xy 26.736918 -87.96394)
			(xy 26.74265 -87.921) (xy 26.747978 -87.900002) (xy 26.755598 -87.871554) (xy 25.207722 -86.323678)
			(xy 25.184354 -86.32571) (xy 25.152604 -86.32698) (xy 25.125352 -86.326517) (xy 25.071402 -86.31876)
			(xy 25.019105 -86.303404) (xy 24.969526 -86.280762) (xy 24.923675 -86.251293) (xy 24.882484 -86.215599)
			(xy 24.846792 -86.174406) (xy 24.817327 -86.128553) (xy 24.794687 -86.078972) (xy 24.779335 -86.026675)
			(xy 24.771581 -85.972724) (xy 24.771096 -85.945472) (xy 24.77158 -85.917527) (xy 24.779726 -85.862235)
			(xy 24.795854 -85.808724) (xy 24.819618 -85.758139) (xy 24.850511 -85.711564) (xy 24.88787 -85.669995)
			(xy 24.930895 -85.634324) (xy 24.978665 -85.605314) (xy 25.030158 -85.583586) (xy 25.0571 -85.576156)
			(xy 25.0952 -85.56625) (xy 25.0952 -79.277464) (xy 25.078622 -79.255119) (xy 25.051435 -79.206577)
			(xy 25.031591 -79.154599) (xy 25.019514 -79.100289) (xy 25.01546 -79.0448) (xy 25.019514 -78.989311)
			(xy 25.031591 -78.935001) (xy 25.051435 -78.883023) (xy 25.078622 -78.834481) (xy 25.0952 -78.812136)
			(xy 25.0952 -78.439264) (xy 25.078622 -78.416919) (xy 25.051435 -78.368377) (xy 25.031591 -78.316399)
			(xy 25.019514 -78.262089) (xy 25.01546 -78.2066) (xy 25.019514 -78.151111) (xy 25.031591 -78.096801)
			(xy 25.051435 -78.044823) (xy 25.078622 -77.996281) (xy 25.0952 -77.973936) (xy 25.0952 -64.0842)
			(xy 25.095812 -64.059243) (xy 25.105549 -64.010289) (xy 25.12465 -63.964176) (xy 25.15238 -63.922674)
			(xy 25.169622 -63.904622) (xy 26.947622 -62.126622) (xy 26.965661 -62.109357) (xy 27.007152 -62.081589)
			(xy 27.05327 -62.062467) (xy 27.102237 -62.052727) (xy 27.1272 -62.0522) (xy 28.540964 -62.0522)
			(xy 28.557561 -62.029672) (xy 28.596274 -61.989272) (xy 28.640475 -61.954963) (xy 28.689217 -61.927483)
			(xy 28.741451 -61.907421) (xy 28.796056 -61.895209) (xy 28.85186 -61.891109) (xy 28.907664 -61.895209)
			(xy 28.962269 -61.907421) (xy 29.014503 -61.927483) (xy 29.063245 -61.954963) (xy 29.107446 -61.989272)
			(xy 29.146159 -62.029672) (xy 29.162756 -62.0522) (xy 30.92577 -62.0522) (xy 30.943955 -62.032518)
			(xy 30.984889 -61.997934) (xy 31.030255 -61.969412) (xy 31.079162 -61.947511) (xy 31.130651 -61.932663)
			(xy 31.183711 -61.925159) (xy 31.210504 -61.924692) (xy 31.211012 -61.924692) (xy 31.242876 -61.925352)
			(xy 31.30571 -61.935985) (xy 31.365902 -61.956918) (xy 31.394146 -61.971682) (xy 31.42742 -61.990224)
			(xy 31.952946 -61.464698) (xy 31.952946 -50.938684) (xy 31.918656 -50.926746) (xy 31.892522 -50.91721)
			(xy 31.843117 -50.891643) (xy 31.797949 -50.85917) (xy 31.757977 -50.820482) (xy 31.724048 -50.776397)
			(xy 31.696883 -50.727852) (xy 31.677057 -50.675875) (xy 31.664992 -50.62157) (xy 31.660943 -50.566089)
			(xy 31.664995 -50.510608) (xy 31.677064 -50.456303) (xy 31.696892 -50.404328) (xy 31.72406 -50.355784)
			(xy 31.757991 -50.311702) (xy 31.797966 -50.273015) (xy 31.843136 -50.240546) (xy 31.892543 -50.214982)
			(xy 31.918656 -50.205386) (xy 31.952946 -50.193448) (xy 31.952946 -45.211238) (xy 31.922974 -45.197776)
			(xy 31.89826 -45.186067) (xy 31.852174 -45.156627) (xy 31.81076 -45.120912) (xy 31.774866 -45.079653)
			(xy 31.745226 -45.033695) (xy 31.722446 -44.983978) (xy 31.706993 -44.93152) (xy 31.699184 -44.877393)
			(xy 31.698692 -44.85005) (xy 31.698692 -44.849796) (xy 31.6994 -44.817002) (xy 31.710644 -44.752382)
			(xy 31.721044 -44.721272) (xy 31.731966 -44.690792) (xy 27.735022 -40.693848) (xy 27.717759 -40.675808)
			(xy 27.689997 -40.634316) (xy 27.67088 -40.588198) (xy 27.661146 -40.539232) (xy 27.6606 -40.51427)
			(xy 27.6606 -38.154356) (xy 25.75814 -36.251896) (xy 22.883876 -36.251896) (xy 22.861418 -36.268801)
			(xy 22.812519 -36.296522) (xy 22.76008 -36.316764) (xy 22.705238 -36.329087) (xy 22.64918 -36.333224)
			(xy 22.593122 -36.329087) (xy 22.53828 -36.316764) (xy 22.485841 -36.296522) (xy 22.436942 -36.268801)
			(xy 22.414484 -36.251896) (xy 17.521936 -36.251896) (xy 17.51203 -36.256214) (xy 17.487535 -36.266606)
			(xy 17.436385 -36.281263) (xy 17.383694 -36.288664) (xy 17.330486 -36.288664) (xy 17.277795 -36.281263)
			(xy 17.226645 -36.266606) (xy 17.20215 -36.256214) (xy 17.192244 -36.251896) (xy 6.496304 -36.251896)
			(xy 6.471351 -36.251275) (xy 6.422407 -36.241522) (xy 6.376307 -36.222409) (xy 6.33482 -36.19467)
			(xy 6.316726 -36.177474) (xy 5.296408 -35.157156) (xy 5.279146 -35.139116) (xy 5.251383 -35.097624)
			(xy 5.232266 -35.051506) (xy 5.222531 -35.00254) (xy 5.221986 -34.977578) (xy 5.221986 -24.777446)
			(xy 5.222603 -24.752491) (xy 5.232349 -24.703543) (xy 5.251456 -24.657435) (xy 5.27919 -24.615941)
			(xy 5.296408 -24.597868) (xy 6.574028 -23.320248) (xy 6.592069 -23.302988) (xy 6.633562 -23.275229)
			(xy 6.67968 -23.256113) (xy 6.728644 -23.246378) (xy 6.753606 -23.245826) (xy 11.268202 -23.245826)
			(xy 11.286393 -23.225439) (xy 11.327607 -23.189568) (xy 11.37352 -23.159948) (xy 11.423191 -23.137185)
			(xy 11.475602 -23.121746) (xy 11.529681 -23.113947) (xy 11.584319 -23.113947) (xy 11.638398 -23.121746)
			(xy 11.690809 -23.137185) (xy 11.74048 -23.159948) (xy 11.786393 -23.189568) (xy 11.827607 -23.225439)
			(xy 11.845798 -23.245826) (xy 12.082018 -23.245826) (xy 14.859 -20.468844) (xy 14.859 -19.194272)
			(xy 14.858492 -19.177) (xy 14.859 -19.159728) (xy 14.859 -17.411446) (xy 14.835853 -17.397814) (xy 14.793282 -17.36505)
			(xy 14.755728 -17.326639) (xy 14.723934 -17.28334) (xy 14.698528 -17.236008) (xy 14.680014 -17.185581)
			(xy 14.668757 -17.133055) (xy 14.66498 -17.079469) (xy 14.668757 -17.025883) (xy 14.680015 -16.973357)
			(xy 14.698529 -16.92293) (xy 14.723935 -16.875598) (xy 14.755729 -16.832299) (xy 14.793283 -16.793888)
			(xy 14.835854 -16.761125) (xy 14.859 -16.74749) (xy 14.859 -13.781532) (xy 14.836584 -13.763354)
			(xy 14.796971 -13.721383) (xy 14.764139 -13.67392) (xy 14.738836 -13.622051) (xy 14.721642 -13.56696)
			(xy 14.71295 -13.509906) (xy 14.712442 -13.48105) (xy 14.712902 -13.453796) (xy 14.720653 -13.399842)
			(xy 14.736006 -13.347541) (xy 14.758646 -13.297958) (xy 14.788113 -13.252102) (xy 14.823808 -13.210908)
			(xy 14.865002 -13.175213) (xy 14.910858 -13.145746) (xy 14.960441 -13.123106) (xy 15.012742 -13.107753)
			(xy 15.066696 -13.100002) (xy 15.09395 -13.099542) (xy 15.094458 -13.099542) (xy 15.119587 -13.099957)
			(xy 15.169409 -13.106577) (xy 15.193772 -13.11275) (xy 15.22222 -13.120624) (xy 16.609822 -11.733022)
			(xy 16.627861 -11.715757) (xy 16.669352 -11.687989) (xy 16.71547 -11.668867) (xy 16.764437 -11.659127)
			(xy 16.7894 -11.6586) (xy 25.2476 -11.6586) (xy 25.272557 -11.659212) (xy 25.321511 -11.668949) (xy 25.367624 -11.68805)
			(xy 25.409126 -11.71578) (xy 25.427178 -11.733022) (xy 27.111404 -13.417248) (xy 41.210697 -13.417248)
			(xy 41.210697 -13.342672) (xy 41.218492 -13.268505) (xy 41.233997 -13.195559) (xy 41.257043 -13.124633)
			(xy 41.287375 -13.056505) (xy 41.324663 -12.991921) (xy 41.368498 -12.931588) (xy 41.418399 -12.876167)
			(xy 41.473819 -12.826266) (xy 41.534152 -12.782432) (xy 41.598737 -12.745144) (xy 41.666865 -12.714812)
			(xy 41.737791 -12.691767) (xy 41.810737 -12.676262) (xy 41.884904 -12.668467) (xy 41.922192 -12.667996)
			(xy 43.922188 -12.667996) (xy 43.959474 -12.668551) (xy 44.033637 -12.676344) (xy 44.106579 -12.691848)
			(xy 44.177502 -12.714891) (xy 44.245627 -12.745221) (xy 44.310208 -12.782506) (xy 44.370538 -12.826338)
			(xy 44.425956 -12.876235) (xy 44.475855 -12.931652) (xy 44.519687 -12.991982) (xy 44.556974 -13.056563)
			(xy 44.587305 -13.124687) (xy 44.610349 -13.195609) (xy 44.625854 -13.268551) (xy 44.633649 -13.342714)
			(xy 44.633649 -13.417286) (xy 44.625854 -13.491449) (xy 44.610349 -13.564391) (xy 44.587305 -13.635313)
			(xy 44.556974 -13.703437) (xy 44.519687 -13.768018) (xy 44.475855 -13.828348) (xy 44.425956 -13.883765)
			(xy 44.370538 -13.933662) (xy 44.310208 -13.977494) (xy 44.245627 -14.014779) (xy 44.177502 -14.045109)
			(xy 44.106579 -14.068152) (xy 44.033637 -14.083656) (xy 43.959474 -14.091449) (xy 43.922188 -14.09192)
			(xy 41.922192 -14.09192) (xy 41.884904 -14.091453) (xy 41.810737 -14.083658) (xy 41.737791 -14.068153)
			(xy 41.666865 -14.045108) (xy 41.598737 -14.014776) (xy 41.534152 -13.977488) (xy 41.473819 -13.933654)
			(xy 41.418399 -13.883753) (xy 41.368498 -13.828332) (xy 41.324663 -13.767999) (xy 41.287375 -13.703415)
			(xy 41.257043 -13.635287) (xy 41.233997 -13.564361) (xy 41.218492 -13.491415) (xy 41.210697 -13.417248)
			(xy 27.111404 -13.417248) (xy 27.840178 -14.146022) (xy 27.857443 -14.164061) (xy 27.885211 -14.205552)
			(xy 27.904333 -14.25167) (xy 27.914073 -14.300637) (xy 27.9146 -14.3256) (xy 27.9146 -14.917388)
			(xy 38.210708 -14.917388) (xy 38.210708 -14.842812) (xy 38.218503 -14.768646) (xy 38.234008 -14.6957)
			(xy 38.257053 -14.624775) (xy 38.287386 -14.556647) (xy 38.324673 -14.492062) (xy 38.368507 -14.43173)
			(xy 38.418408 -14.376309) (xy 38.473828 -14.326409) (xy 38.534161 -14.282574) (xy 38.598745 -14.245287)
			(xy 38.666873 -14.214954) (xy 38.737798 -14.191909) (xy 38.810744 -14.176403) (xy 38.88491 -14.168608)
			(xy 38.922198 -14.16812) (xy 40.922194 -14.16812) (xy 40.959481 -14.168627) (xy 41.033646 -14.176422)
			(xy 41.106591 -14.191926) (xy 41.177515 -14.21497) (xy 41.245641 -14.245301) (xy 41.310224 -14.282588)
			(xy 41.370556 -14.326421) (xy 41.425975 -14.37632) (xy 41.475875 -14.431739) (xy 41.519709 -14.492071)
			(xy 41.556996 -14.556653) (xy 41.587328 -14.62478) (xy 41.610373 -14.695704) (xy 41.625877 -14.768648)
			(xy 41.633673 -14.842813) (xy 41.633673 -14.917387) (xy 44.210708 -14.917387) (xy 44.210708 -14.842813)
			(xy 44.218503 -14.768647) (xy 44.234008 -14.695702) (xy 44.257052 -14.624777) (xy 44.287384 -14.55665)
			(xy 44.324671 -14.492066) (xy 44.368504 -14.431734) (xy 44.418404 -14.376314) (xy 44.473823 -14.326413)
			(xy 44.534154 -14.282578) (xy 44.598737 -14.24529) (xy 44.666864 -14.214957) (xy 44.737788 -14.191911)
			(xy 44.810733 -14.176405) (xy 44.884899 -14.168609) (xy 44.922186 -14.16812) (xy 46.922182 -14.16812)
			(xy 46.959469 -14.168626) (xy 47.033636 -14.17642) (xy 47.106581 -14.191923) (xy 47.177506 -14.214967)
			(xy 47.245634 -14.245298) (xy 47.310218 -14.282584) (xy 47.370551 -14.326417) (xy 47.425971 -14.376316)
			(xy 47.475872 -14.431735) (xy 47.519706 -14.492067) (xy 47.556994 -14.55665) (xy 47.587327 -14.624777)
			(xy 47.610372 -14.695702) (xy 47.625877 -14.768647) (xy 47.633673 -14.842813) (xy 47.633673 -14.917387)
			(xy 47.625877 -14.991553) (xy 47.610372 -15.064498) (xy 47.587327 -15.135423) (xy 47.556994 -15.20355)
			(xy 47.519706 -15.268133) (xy 47.475872 -15.328465) (xy 47.425971 -15.383884) (xy 47.370551 -15.433783)
			(xy 47.310218 -15.477616) (xy 47.245634 -15.514902) (xy 47.177506 -15.545233) (xy 47.106581 -15.568277)
			(xy 47.033636 -15.58378) (xy 46.959469 -15.591574) (xy 46.922182 -15.592044) (xy 44.922186 -15.592044)
			(xy 44.884899 -15.591591) (xy 44.810733 -15.583795) (xy 44.737788 -15.568289) (xy 44.666864 -15.545243)
			(xy 44.598737 -15.51491) (xy 44.534154 -15.477622) (xy 44.473823 -15.433787) (xy 44.418404 -15.383886)
			(xy 44.368504 -15.328466) (xy 44.324671 -15.268134) (xy 44.287384 -15.20355) (xy 44.257052 -15.135423)
			(xy 44.234008 -15.064498) (xy 44.218503 -14.991553) (xy 44.210708 -14.917387) (xy 41.633673 -14.917387)
			(xy 41.625877 -14.991552) (xy 41.610373 -15.064496) (xy 41.587328 -15.13542) (xy 41.556996 -15.203547)
			(xy 41.519709 -15.268129) (xy 41.475875 -15.328461) (xy 41.425975 -15.38388) (xy 41.370556 -15.433779)
			(xy 41.310224 -15.477612) (xy 41.245641 -15.514899) (xy 41.177515 -15.54523) (xy 41.106591 -15.568274)
			(xy 41.033646 -15.583778) (xy 40.959481 -15.591573) (xy 40.922194 -15.592044) (xy 38.922198 -15.592044)
			(xy 38.88491 -15.591592) (xy 38.810744 -15.583797) (xy 38.737798 -15.568291) (xy 38.666873 -15.545246)
			(xy 38.598745 -15.514913) (xy 38.534161 -15.477626) (xy 38.473828 -15.433791) (xy 38.418408 -15.383891)
			(xy 38.368507 -15.32847) (xy 38.324673 -15.268138) (xy 38.287386 -15.203553) (xy 38.257053 -15.135425)
			(xy 38.234008 -15.0645) (xy 38.218503 -14.991554) (xy 38.210708 -14.917388) (xy 27.9146 -14.917388)
			(xy 27.9146 -15.515844) (xy 35.642296 -23.24354) (xy 38.243256 -23.24354) (xy 46.177962 -23.245826)
			(xy 49.710086 -19.713702) (xy 49.728127 -19.696443) (xy 49.769621 -19.668688) (xy 49.815739 -19.649579)
			(xy 49.864703 -19.639853) (xy 49.889664 -19.63928) (xy 56.833008 -19.63928) (xy 56.857964 -19.639892)
			(xy 56.906918 -19.649631) (xy 56.953032 -19.668731) (xy 56.994533 -19.696461) (xy 57.012586 -19.713702)
			(xy 57.87898 -20.580096) (xy 57.896506 -20.582382) (xy 57.924467 -20.586253) (xy 57.978907 -20.601169)
			(xy 58.030556 -20.623943) (xy 58.078286 -20.654078) (xy 58.121054 -20.690917) (xy 58.157929 -20.733654)
			(xy 58.188104 -20.781358) (xy 58.210922 -20.832987) (xy 58.225884 -20.887415) (xy 58.229754 -20.915376)
			(xy 58.229754 -20.91563) (xy 58.23204 -20.933156) (xy 60.421012 -23.122128) (xy 60.43151 -23.131928)
			(xy 60.456654 -23.145774) (xy 60.484657 -23.152083) (xy 60.51331 -23.150358) (xy 60.540353 -23.140734)
			(xy 60.563655 -23.12397) (xy 60.572904 -23.112984) (xy 60.591096 -23.090544) (xy 60.6331 -23.050887)
			(xy 60.6806 -23.018015) (xy 60.732513 -22.992678) (xy 60.787652 -22.975454) (xy 60.844757 -22.966738)
			(xy 60.87364 -22.966172) (xy 60.902505 -22.966706) (xy 60.959576 -22.975412) (xy 61.014682 -22.992619)
			(xy 61.066566 -23.017934) (xy 61.114043 -23.050779) (xy 61.156028 -23.090403) (xy 61.191562 -23.135902)
			(xy 61.219833 -23.186237) (xy 61.23051 -23.21306) (xy 61.242956 -23.245826) (xy 66.447924 -23.245826)
			(xy 66.457322 -23.207218) (xy 66.464538 -23.17994) (xy 66.485907 -23.127719) (xy 66.514734 -23.079214)
			(xy 66.550389 -23.035483) (xy 66.592094 -22.997479) (xy 66.638942 -22.966031) (xy 66.68991 -22.941825)
			(xy 66.743887 -22.925388) (xy 66.799696 -22.917079) (xy 66.85612 -22.917079) (xy 66.911929 -22.925388)
			(xy 66.965906 -22.941825) (xy 67.016874 -22.966031) (xy 67.063722 -22.997479) (xy 67.105427 -23.035483)
			(xy 67.141082 -23.079214) (xy 67.169909 -23.127719) (xy 67.191278 -23.17994) (xy 67.198494 -23.207218)
			(xy 67.207892 -23.245826) (xy 69.244464 -23.245826) (xy 69.267035 -23.232511) (xy 69.31505 -23.211518)
			(xy 69.365488 -23.197299) (xy 69.417398 -23.190122) (xy 69.469802 -23.190122) (xy 69.521712 -23.197299)
			(xy 69.57215 -23.211518) (xy 69.620165 -23.232511) (xy 69.642736 -23.245826) (xy 69.879718 -23.245826)
			(xy 69.89465 -23.222231) (xy 69.930326 -23.179277) (xy 69.971882 -23.141982) (xy 70.01843 -23.111143)
			(xy 70.068976 -23.087418) (xy 70.12244 -23.071314) (xy 70.177681 -23.063175) (xy 70.233519 -23.063175)
			(xy 70.28876 -23.071314) (xy 70.342224 -23.087418) (xy 70.39277 -23.111143) (xy 70.439318 -23.141982)
			(xy 70.480874 -23.179277) (xy 70.51655 -23.222231) (xy 70.531482 -23.245826) (xy 88.705436 -23.245826)
			(xy 88.984074 -22.967188) (xy 88.984074 -20.804886) (xy 88.964392 -20.786703) (xy 88.929811 -20.745774)
			(xy 88.901293 -20.70041) (xy 88.879401 -20.651504) (xy 88.864564 -20.600016) (xy 88.857074 -20.546959)
			(xy 88.857078 -20.493377) (xy 88.864577 -20.440321) (xy 88.879423 -20.388836) (xy 88.901323 -20.339933)
			(xy 88.929848 -20.294574) (xy 88.964437 -20.253651) (xy 88.984074 -20.235418) (xy 88.984074 -15.724886)
			(xy 88.964392 -15.706703) (xy 88.929811 -15.665774) (xy 88.901293 -15.62041) (xy 88.879401 -15.571504)
			(xy 88.864564 -15.520016) (xy 88.857074 -15.466959) (xy 88.857078 -15.413377) (xy 88.864577 -15.360321)
			(xy 88.879423 -15.308836) (xy 88.901323 -15.259933) (xy 88.929848 -15.214574) (xy 88.964437 -15.173651)
			(xy 88.984074 -15.155418) (xy 88.984074 -10.644886) (xy 88.964392 -10.626703) (xy 88.929811 -10.585774)
			(xy 88.901293 -10.54041) (xy 88.879401 -10.491504) (xy 88.864564 -10.440016) (xy 88.857074 -10.386959)
			(xy 88.857078 -10.333377) (xy 88.864577 -10.280321) (xy 88.879423 -10.228836) (xy 88.901323 -10.179933)
			(xy 88.929848 -10.134574) (xy 88.964437 -10.093651) (xy 88.984074 -10.075418) (xy 88.984074 -5.564886)
			(xy 88.964392 -5.546703) (xy 88.929811 -5.505774) (xy 88.901293 -5.46041) (xy 88.879401 -5.411504)
			(xy 88.864564 -5.360016) (xy 88.857074 -5.306959) (xy 88.857078 -5.253377) (xy 88.864577 -5.200321)
			(xy 88.879423 -5.148836) (xy 88.901323 -5.099933) (xy 88.929848 -5.054574) (xy 88.964437 -5.013651)
			(xy 88.984074 -4.995418) (xy 88.984074 -1.999996) (xy 88.983565 -1.954527) (xy 88.975174 -1.863977)
			(xy 88.958463 -1.774588) (xy 88.933576 -1.687122) (xy 88.900725 -1.602325) (xy 88.86019 -1.520922)
			(xy 88.812317 -1.443605) (xy 88.757514 -1.371036) (xy 88.696248 -1.303833) (xy 88.629044 -1.24257)
			(xy 88.556473 -1.187769) (xy 88.479156 -1.139897) (xy 88.397751 -1.099364) (xy 88.312953 -1.066515)
			(xy 88.225487 -1.041631) (xy 88.136097 -1.024923) (xy 88.045547 -1.016534) (xy 88.000078 -1.016)
			(xy 87.208106 -1.016) (xy 87.189922 -1.035684) (xy 87.148991 -1.07027) (xy 87.103625 -1.098792) (xy 87.054716 -1.120688)
			(xy 87.003226 -1.13553) (xy 86.950165 -1.143024) (xy 86.896579 -1.143024) (xy 86.843518 -1.13553)
			(xy 86.792028 -1.120688) (xy 86.743119 -1.098792) (xy 86.697753 -1.07027) (xy 86.656822 -1.035684)
			(xy 86.638638 -1.016) (xy 82.128106 -1.016) (xy 82.109922 -1.035684) (xy 82.068991 -1.07027) (xy 82.023625 -1.098792)
			(xy 81.974716 -1.120688) (xy 81.923226 -1.13553) (xy 81.870165 -1.143024) (xy 81.816579 -1.143024)
			(xy 81.763518 -1.13553) (xy 81.712028 -1.120688) (xy 81.663119 -1.098792) (xy 81.617753 -1.07027)
			(xy 81.576822 -1.035684) (xy 81.558638 -1.016) (xy 77.048106 -1.016) (xy 77.029922 -1.035684) (xy 76.988991 -1.07027)
			(xy 76.943625 -1.098792) (xy 76.894716 -1.120688) (xy 76.843226 -1.13553) (xy 76.790165 -1.143024)
			(xy 76.736579 -1.143024) (xy 76.683518 -1.13553) (xy 76.632028 -1.120688) (xy 76.583119 -1.098792)
			(xy 76.537753 -1.07027) (xy 76.496822 -1.035684) (xy 76.478638 -1.016) (xy 71.968106 -1.016) (xy 71.949922 -1.035684)
			(xy 71.908991 -1.07027) (xy 71.863625 -1.098792) (xy 71.814716 -1.120688) (xy 71.763226 -1.13553)
			(xy 71.710165 -1.143024) (xy 71.656579 -1.143024) (xy 71.603518 -1.13553) (xy 71.552028 -1.120688)
			(xy 71.503119 -1.098792) (xy 71.457753 -1.07027) (xy 71.416822 -1.035684) (xy 71.398638 -1.016) (xy 66.888106 -1.016)
			(xy 66.869922 -1.035684) (xy 66.828991 -1.07027) (xy 66.783625 -1.098792) (xy 66.734716 -1.120688)
			(xy 66.683226 -1.13553) (xy 66.630165 -1.143024) (xy 66.576579 -1.143024) (xy 66.523518 -1.13553)
			(xy 66.472028 -1.120688) (xy 66.423119 -1.098792) (xy 66.377753 -1.07027) (xy 66.336822 -1.035684)
			(xy 66.318638 -1.016) (xy 61.808106 -1.016) (xy 61.789922 -1.035684) (xy 61.748991 -1.07027) (xy 61.703625 -1.098792)
			(xy 61.654716 -1.120688) (xy 61.603226 -1.13553) (xy 61.550165 -1.143024) (xy 61.496579 -1.143024)
			(xy 61.443518 -1.13553) (xy 61.392028 -1.120688) (xy 61.343119 -1.098792) (xy 61.297753 -1.07027)
			(xy 61.256822 -1.035684) (xy 61.238638 -1.016) (xy 56.728106 -1.016) (xy 56.709922 -1.035684) (xy 56.668991 -1.07027)
			(xy 56.623625 -1.098792) (xy 56.574716 -1.120688) (xy 56.523226 -1.13553) (xy 56.470165 -1.143024)
			(xy 56.416579 -1.143024) (xy 56.363518 -1.13553) (xy 56.312028 -1.120688) (xy 56.263119 -1.098792)
			(xy 56.217753 -1.07027) (xy 56.176822 -1.035684) (xy 56.158638 -1.016) (xy 51.648106 -1.016) (xy 51.629922 -1.035684)
			(xy 51.588991 -1.07027) (xy 51.543625 -1.098792) (xy 51.494716 -1.120688) (xy 51.443226 -1.13553)
			(xy 51.390165 -1.143024) (xy 51.336579 -1.143024) (xy 51.283518 -1.13553) (xy 51.232028 -1.120688)
			(xy 51.183119 -1.098792) (xy 51.137753 -1.07027) (xy 51.096822 -1.035684) (xy 51.078638 -1.016) (xy 46.568106 -1.016)
			(xy 46.549922 -1.035684) (xy 46.508991 -1.07027) (xy 46.463625 -1.098792) (xy 46.414716 -1.120688)
			(xy 46.363226 -1.13553) (xy 46.310165 -1.143024) (xy 46.256579 -1.143024) (xy 46.203518 -1.13553)
			(xy 46.152028 -1.120688) (xy 46.103119 -1.098792) (xy 46.057753 -1.07027) (xy 46.016822 -1.035684)
			(xy 45.998638 -1.016) (xy 41.488106 -1.016) (xy 41.469922 -1.035684) (xy 41.428991 -1.07027) (xy 41.383625 -1.098792)
			(xy 41.334716 -1.120688) (xy 41.283226 -1.13553) (xy 41.230165 -1.143024) (xy 41.176579 -1.143024)
			(xy 41.123518 -1.13553) (xy 41.072028 -1.120688) (xy 41.023119 -1.098792) (xy 40.977753 -1.07027)
			(xy 40.936822 -1.035684) (xy 40.918638 -1.016) (xy 36.408106 -1.016) (xy 36.389922 -1.035684) (xy 36.348991 -1.07027)
			(xy 36.303625 -1.098792) (xy 36.254716 -1.120688) (xy 36.203226 -1.13553) (xy 36.150165 -1.143024)
			(xy 36.096579 -1.143024) (xy 36.043518 -1.13553) (xy 35.992028 -1.120688) (xy 35.943119 -1.098792)
			(xy 35.897753 -1.07027) (xy 35.856822 -1.035684) (xy 35.838638 -1.016) (xy 31.328106 -1.016) (xy 31.309922 -1.035684)
			(xy 31.268991 -1.07027) (xy 31.223625 -1.098792) (xy 31.174716 -1.120688) (xy 31.123226 -1.13553)
			(xy 31.070165 -1.143024) (xy 31.016579 -1.143024) (xy 30.963518 -1.13553) (xy 30.912028 -1.120688)
			(xy 30.863119 -1.098792) (xy 30.817753 -1.07027) (xy 30.776822 -1.035684) (xy 30.758638 -1.016) (xy 26.248106 -1.016)
			(xy 26.229922 -1.035684) (xy 26.188991 -1.07027) (xy 26.143625 -1.098792) (xy 26.094716 -1.120688)
			(xy 26.043226 -1.13553) (xy 25.990165 -1.143024) (xy 25.936579 -1.143024) (xy 25.883518 -1.13553)
			(xy 25.832028 -1.120688) (xy 25.783119 -1.098792) (xy 25.737753 -1.07027) (xy 25.696822 -1.035684)
			(xy 25.678638 -1.016) (xy 21.168106 -1.016) (xy 21.149922 -1.035684) (xy 21.108991 -1.07027) (xy 21.063625 -1.098792)
			(xy 21.014716 -1.120688) (xy 20.963226 -1.13553) (xy 20.910165 -1.143024) (xy 20.856579 -1.143024)
			(xy 20.803518 -1.13553) (xy 20.752028 -1.120688) (xy 20.703119 -1.098792) (xy 20.657753 -1.07027)
			(xy 20.616822 -1.035684) (xy 20.598638 -1.016) (xy 16.088106 -1.016) (xy 16.069922 -1.035684) (xy 16.028991 -1.07027)
			(xy 15.983625 -1.098792) (xy 15.934716 -1.120688) (xy 15.883226 -1.13553) (xy 15.830165 -1.143024)
			(xy 15.776579 -1.143024) (xy 15.723518 -1.13553) (xy 15.672028 -1.120688) (xy 15.623119 -1.098792)
			(xy 15.577753 -1.07027) (xy 15.536822 -1.035684) (xy 15.518638 -1.016) (xy 11.008106 -1.016) (xy 10.989922 -1.035684)
			(xy 10.948991 -1.07027) (xy 10.903625 -1.098792) (xy 10.854716 -1.120688) (xy 10.803226 -1.13553)
			(xy 10.750165 -1.143024) (xy 10.696579 -1.143024) (xy 10.643518 -1.13553) (xy 10.592028 -1.120688)
			(xy 10.543119 -1.098792) (xy 10.497753 -1.07027) (xy 10.456822 -1.035684) (xy 10.438638 -1.016) (xy 5.928106 -1.016)
			(xy 5.909922 -1.035684) (xy 5.868991 -1.07027) (xy 5.823625 -1.098792) (xy 5.774716 -1.120688) (xy 5.723226 -1.13553)
			(xy 5.670165 -1.143024) (xy 5.616579 -1.143024) (xy 5.563518 -1.13553) (xy 5.512028 -1.120688) (xy 5.463119 -1.098792)
			(xy 5.417753 -1.07027) (xy 5.376822 -1.035684) (xy 5.358638 -1.016) (xy 1.999996 -1.016) (xy 1.955458 -1.016498)
			(xy 1.866747 -1.024551) (xy 1.779126 -1.040589) (xy 1.693314 -1.06448) (xy 1.610012 -1.09603) (xy 1.529902 -1.134979)
			(xy 1.453641 -1.181008) (xy 1.381852 -1.233742) (xy 1.315122 -1.292749) (xy 1.253999 -1.357545) (xy 1.198983 -1.4276)
			(xy 1.150523 -1.502341) (xy 1.109016 -1.581156) (xy 1.074803 -1.6634) (xy 1.048163 -1.748399) (xy 1.029315 -1.835458)
			(xy 1.023366 -1.8796) (xy 1.041969 -1.8977) (xy 1.074605 -1.938059) (xy 1.101469 -1.982468) (xy 1.122067 -2.030109)
			(xy 1.136018 -2.080102) (xy 1.143065 -2.131525) (xy 1.143508 -2.157476) (xy 1.143058 -2.184271) (xy 1.135565 -2.237336)
			(xy 1.120722 -2.28883) (xy 1.09882 -2.337741) (xy 1.070289 -2.383105) (xy 1.035692 -2.424032) (xy 1.016 -2.44221)
			(xy 1.016 -4.69011) (xy 3.634743 -4.69011) (xy 3.638781 -4.606614) (xy 3.65086 -4.523897) (xy 3.670865 -4.442732)
			(xy 3.69861 -4.363877) (xy 3.733837 -4.288068) (xy 3.776216 -4.216013) (xy 3.825351 -4.148384) (xy 3.880784 -4.085813)
			(xy 3.941997 -4.028884) (xy 4.008419 -3.978129) (xy 4.079429 -3.934021) (xy 4.154365 -3.896973) (xy 4.232527 -3.867331)
			(xy 4.313184 -3.84537) (xy 4.395585 -3.831296) (xy 4.478959 -3.825241) (xy 4.562529 -3.827261) (xy 4.645513 -3.837337)
			(xy 4.727138 -3.855375) (xy 4.80664 -3.881207) (xy 4.883279 -3.914592) (xy 4.956337 -3.955217) (xy 5.025133 -4.002704)
			(xy 5.089025 -4.056609) (xy 5.147417 -4.116428) (xy 5.199762 -4.181604) (xy 5.245572 -4.251528) (xy 5.284421 -4.325547)
			(xy 5.315943 -4.402969) (xy 5.339847 -4.483073) (xy 5.355907 -4.565109) (xy 5.363975 -4.648313) (xy 5.36448 -4.69011)
			(xy 10.635237 -4.69011) (xy 10.639274 -4.606638) (xy 10.651349 -4.523946) (xy 10.671348 -4.442805)
			(xy 10.699086 -4.363973) (xy 10.734302 -4.288186) (xy 10.776668 -4.216152) (xy 10.825789 -4.148543)
			(xy 10.881206 -4.08599) (xy 10.942401 -4.029078) (xy 11.008803 -3.978338) (xy 11.079793 -3.934243)
			(xy 11.154707 -3.897206) (xy 11.232845 -3.867572) (xy 11.313479 -3.845618) (xy 11.395856 -3.831548)
			(xy 11.479206 -3.825495) (xy 11.562751 -3.827514) (xy 11.645711 -3.837588) (xy 11.727311 -3.85562)
			(xy 11.80679 -3.881445) (xy 11.883406 -3.914819) (xy 11.956443 -3.955433) (xy 12.025219 -4.002906)
			(xy 12.089092 -4.056795) (xy 12.147467 -4.116597) (xy 12.199797 -4.181754) (xy 12.245594 -4.251657)
			(xy 12.28443 -4.325654) (xy 12.315944 -4.403054) (xy 12.33984 -4.483134) (xy 12.355896 -4.565146)
			(xy 12.363962 -4.648325) (xy 12.364466 -4.69011) (xy 12.363962 -4.731895) (xy 12.355896 -4.815074)
			(xy 12.33984 -4.897086) (xy 12.315944 -4.977166) (xy 12.28443 -5.054566) (xy 12.265749 -5.09016)
			(xy 66.234821 -5.09016) (xy 66.238859 -5.006664) (xy 66.250938 -4.923947) (xy 66.270943 -4.842782)
			(xy 66.298688 -4.763927) (xy 66.333915 -4.688118) (xy 66.376294 -4.616063) (xy 66.425429 -4.548434)
			(xy 66.480862 -4.485863) (xy 66.542075 -4.428934) (xy 66.608497 -4.378179) (xy 66.679507 -4.334071)
			(xy 66.754443 -4.297023) (xy 66.832605 -4.267381) (xy 66.913262 -4.24542) (xy 66.995663 -4.231346)
			(xy 67.079037 -4.225291) (xy 67.162607 -4.227311) (xy 67.245591 -4.237387) (xy 67.327216 -4.255425)
			(xy 67.406718 -4.281257) (xy 67.483357 -4.314642) (xy 67.556415 -4.355267) (xy 67.625211 -4.402754)
			(xy 67.689103 -4.456659) (xy 67.747495 -4.516478) (xy 67.79984 -4.581654) (xy 67.84565 -4.651578)
			(xy 67.884499 -4.725597) (xy 67.916021 -4.803019) (xy 67.939925 -4.883123) (xy 67.955985 -4.965159)
			(xy 67.964053 -5.048363) (xy 67.964558 -5.09016) (xy 73.235315 -5.09016) (xy 73.239352 -5.006688)
			(xy 73.251427 -4.923996) (xy 73.271426 -4.842855) (xy 73.299164 -4.764023) (xy 73.33438 -4.688236)
			(xy 73.376746 -4.616202) (xy 73.425867 -4.548593) (xy 73.481284 -4.48604) (xy 73.542479 -4.429128)
			(xy 73.608881 -4.378388) (xy 73.679871 -4.334293) (xy 73.754785 -4.297256) (xy 73.832923 -4.267622)
			(xy 73.913557 -4.245668) (xy 73.995934 -4.231598) (xy 74.079284 -4.225545) (xy 74.162829 -4.227564)
			(xy 74.245789 -4.237638) (xy 74.327389 -4.25567) (xy 74.406868 -4.281495) (xy 74.483484 -4.314869)
			(xy 74.556521 -4.355483) (xy 74.625297 -4.402956) (xy 74.68917 -4.456845) (xy 74.747545 -4.516647)
			(xy 74.799875 -4.581804) (xy 74.845672 -4.651707) (xy 74.865827 -4.69011) (xy 77.634849 -4.69011)
			(xy 77.638887 -4.606614) (xy 77.650966 -4.523897) (xy 77.670971 -4.442732) (xy 77.698716 -4.363877)
			(xy 77.733943 -4.288068) (xy 77.776322 -4.216013) (xy 77.825457 -4.148384) (xy 77.88089 -4.085813)
			(xy 77.942103 -4.028884) (xy 78.008525 -3.978129) (xy 78.079535 -3.934021) (xy 78.154471 -3.896973)
			(xy 78.232633 -3.867331) (xy 78.31329 -3.84537) (xy 78.395691 -3.831296) (xy 78.479065 -3.825241)
			(xy 78.562635 -3.827261) (xy 78.645619 -3.837337) (xy 78.727244 -3.855375) (xy 78.806746 -3.881207)
			(xy 78.883385 -3.914592) (xy 78.956443 -3.955217) (xy 79.025239 -4.002704) (xy 79.089131 -4.056609)
			(xy 79.147523 -4.116428) (xy 79.199868 -4.181604) (xy 79.245678 -4.251528) (xy 79.284527 -4.325547)
			(xy 79.316049 -4.402969) (xy 79.339953 -4.483073) (xy 79.356013 -4.565109) (xy 79.364081 -4.648313)
			(xy 79.364586 -4.69011) (xy 84.635343 -4.69011) (xy 84.63938 -4.606638) (xy 84.651455 -4.523946)
			(xy 84.671454 -4.442805) (xy 84.699192 -4.363973) (xy 84.734408 -4.288186) (xy 84.776774 -4.216152)
			(xy 84.825895 -4.148543) (xy 84.881312 -4.08599) (xy 84.942507 -4.029078) (xy 85.008909 -3.978338)
			(xy 85.079899 -3.934243) (xy 85.154813 -3.897206) (xy 85.232951 -3.867572) (xy 85.313585 -3.845618)
			(xy 85.395962 -3.831548) (xy 85.479312 -3.825495) (xy 85.562857 -3.827514) (xy 85.645817 -3.837588)
			(xy 85.727417 -3.85562) (xy 85.806896 -3.881445) (xy 85.883512 -3.914819) (xy 85.956549 -3.955433)
			(xy 86.025325 -4.002906) (xy 86.089198 -4.056795) (xy 86.147573 -4.116597) (xy 86.199903 -4.181754)
			(xy 86.2457 -4.251657) (xy 86.284536 -4.325654) (xy 86.31605 -4.403054) (xy 86.339946 -4.483134)
			(xy 86.356002 -4.565146) (xy 86.364068 -4.648325) (xy 86.364572 -4.69011) (xy 86.364068 -4.731895)
			(xy 86.356002 -4.815074) (xy 86.339946 -4.897086) (xy 86.31605 -4.977166) (xy 86.284536 -5.054566)
			(xy 86.2457 -5.128563) (xy 86.199903 -5.198466) (xy 86.147573 -5.263623) (xy 86.089198 -5.323425)
			(xy 86.025325 -5.377314) (xy 85.956549 -5.424787) (xy 85.883512 -5.465401) (xy 85.806896 -5.498775)
			(xy 85.727417 -5.5246) (xy 85.645817 -5.542632) (xy 85.562857 -5.552706) (xy 85.479312 -5.554725)
			(xy 85.395962 -5.548672) (xy 85.313585 -5.534602) (xy 85.232951 -5.512648) (xy 85.154813 -5.483014)
			(xy 85.079899 -5.445977) (xy 85.008909 -5.401882) (xy 84.942507 -5.351142) (xy 84.881312 -5.29423)
			(xy 84.825895 -5.231677) (xy 84.776774 -5.164068) (xy 84.734408 -5.092034) (xy 84.699192 -5.016247)
			(xy 84.671454 -4.937415) (xy 84.651455 -4.856274) (xy 84.63938 -4.773582) (xy 84.635343 -4.69011)
			(xy 79.364586 -4.69011) (xy 79.364081 -4.731907) (xy 79.356013 -4.815111) (xy 79.339953 -4.897147)
			(xy 79.316049 -4.977251) (xy 79.284527 -5.054673) (xy 79.245678 -5.128692) (xy 79.199868 -5.198616)
			(xy 79.147523 -5.263792) (xy 79.089131 -5.323611) (xy 79.025239 -5.377516) (xy 78.956443 -5.425003)
			(xy 78.883385 -5.465628) (xy 78.806746 -5.499013) (xy 78.727244 -5.524845) (xy 78.645619 -5.542883)
			(xy 78.562635 -5.552959) (xy 78.479065 -5.554979) (xy 78.395691 -5.548924) (xy 78.31329 -5.53485)
			(xy 78.232633 -5.512889) (xy 78.154471 -5.483247) (xy 78.079535 -5.446199) (xy 78.008525 -5.402091)
			(xy 77.942103 -5.351336) (xy 77.88089 -5.294407) (xy 77.825457 -5.231836) (xy 77.776322 -5.164207)
			(xy 77.733943 -5.092152) (xy 77.698716 -5.016343) (xy 77.670971 -4.937488) (xy 77.650966 -4.856323)
			(xy 77.638887 -4.773606) (xy 77.634849 -4.69011) (xy 74.865827 -4.69011) (xy 74.884508 -4.725704)
			(xy 74.916022 -4.803104) (xy 74.939918 -4.883184) (xy 74.955974 -4.965196) (xy 74.96404 -5.048375)
			(xy 74.964544 -5.09016) (xy 74.96404 -5.131945) (xy 74.955974 -5.215124) (xy 74.939918 -5.297136)
			(xy 74.916022 -5.377216) (xy 74.884508 -5.454616) (xy 74.845672 -5.528613) (xy 74.799875 -5.598516)
			(xy 74.747545 -5.663673) (xy 74.68917 -5.723475) (xy 74.625297 -5.777364) (xy 74.556521 -5.824837)
			(xy 74.483484 -5.865451) (xy 74.406868 -5.898825) (xy 74.327389 -5.92465) (xy 74.245789 -5.942682)
			(xy 74.162829 -5.952756) (xy 74.079284 -5.954775) (xy 73.995934 -5.948722) (xy 73.913557 -5.934652)
			(xy 73.832923 -5.912698) (xy 73.754785 -5.883064) (xy 73.679871 -5.846027) (xy 73.608881 -5.801932)
			(xy 73.542479 -5.751192) (xy 73.481284 -5.69428) (xy 73.425867 -5.631727) (xy 73.376746 -5.564118)
			(xy 73.33438 -5.492084) (xy 73.299164 -5.416297) (xy 73.271426 -5.337465) (xy 73.251427 -5.256324)
			(xy 73.239352 -5.173632) (xy 73.235315 -5.09016) (xy 67.964558 -5.09016) (xy 67.964053 -5.131957)
			(xy 67.955985 -5.215161) (xy 67.939925 -5.297197) (xy 67.916021 -5.377301) (xy 67.884499 -5.454723)
			(xy 67.84565 -5.528742) (xy 67.79984 -5.598666) (xy 67.747495 -5.663842) (xy 67.689103 -5.723661)
			(xy 67.625211 -5.777566) (xy 67.556415 -5.825053) (xy 67.483357 -5.865678) (xy 67.406718 -5.899063)
			(xy 67.327216 -5.924895) (xy 67.245591 -5.942933) (xy 67.162607 -5.953009) (xy 67.079037 -5.955029)
			(xy 66.995663 -5.948974) (xy 66.913262 -5.9349) (xy 66.832605 -5.912939) (xy 66.754443 -5.883297)
			(xy 66.679507 -5.846249) (xy 66.608497 -5.802141) (xy 66.542075 -5.751386) (xy 66.480862 -5.694457)
			(xy 66.425429 -5.631886) (xy 66.376294 -5.564257) (xy 66.333915 -5.492202) (xy 66.298688 -5.416393)
			(xy 66.270943 -5.337538) (xy 66.250938 -5.256373) (xy 66.238859 -5.173656) (xy 66.234821 -5.09016)
			(xy 12.265749 -5.09016) (xy 12.245594 -5.128563) (xy 12.199797 -5.198466) (xy 12.147467 -5.263623)
			(xy 12.089092 -5.323425) (xy 12.025219 -5.377314) (xy 11.956443 -5.424787) (xy 11.883406 -5.465401)
			(xy 11.80679 -5.498775) (xy 11.727311 -5.5246) (xy 11.645711 -5.542632) (xy 11.562751 -5.552706)
			(xy 11.479206 -5.554725) (xy 11.395856 -5.548672) (xy 11.313479 -5.534602) (xy 11.232845 -5.512648)
			(xy 11.154707 -5.483014) (xy 11.079793 -5.445977) (xy 11.008803 -5.401882) (xy 10.942401 -5.351142)
			(xy 10.881206 -5.29423) (xy 10.825789 -5.231677) (xy 10.776668 -5.164068) (xy 10.734302 -5.092034)
			(xy 10.699086 -5.016247) (xy 10.671348 -4.937415) (xy 10.651349 -4.856274) (xy 10.639274 -4.773582)
			(xy 10.635237 -4.69011) (xy 5.36448 -4.69011) (xy 5.363975 -4.731907) (xy 5.355907 -4.815111) (xy 5.339847 -4.897147)
			(xy 5.315943 -4.977251) (xy 5.284421 -5.054673) (xy 5.245572 -5.128692) (xy 5.199762 -5.198616) (xy 5.147417 -5.263792)
			(xy 5.089025 -5.323611) (xy 5.025133 -5.377516) (xy 4.956337 -5.425003) (xy 4.883279 -5.465628) (xy 4.80664 -5.499013)
			(xy 4.727138 -5.524845) (xy 4.645513 -5.542883) (xy 4.562529 -5.552959) (xy 4.478959 -5.554979) (xy 4.395585 -5.548924)
			(xy 4.313184 -5.53485) (xy 4.232527 -5.512889) (xy 4.154365 -5.483247) (xy 4.079429 -5.446199) (xy 4.008419 -5.402091)
			(xy 3.941997 -5.351336) (xy 3.880784 -5.294407) (xy 3.825351 -5.231836) (xy 3.776216 -5.164207) (xy 3.733837 -5.092152)
			(xy 3.69861 -5.016343) (xy 3.670865 -4.937488) (xy 3.65086 -4.856323) (xy 3.638781 -4.773606) (xy 3.634743 -4.69011)
			(xy 1.016 -4.69011) (xy 1.016 -6.952742) (xy 1.035684 -6.970926) (xy 1.07027 -7.011857) (xy 1.098792 -7.057223)
			(xy 1.120688 -7.106132) (xy 1.13553 -7.157622) (xy 1.143024 -7.210683) (xy 1.143024 -7.264269) (xy 1.13553 -7.31733)
			(xy 1.120688 -7.36882) (xy 1.098792 -7.417729) (xy 1.07027 -7.463095) (xy 1.035684 -7.504026) (xy 1.016 -7.52221)
			(xy 1.016 -12.032742) (xy 1.035684 -12.050926) (xy 1.07027 -12.091857) (xy 1.098792 -12.137223) (xy 1.120688 -12.186132)
			(xy 1.13553 -12.237622) (xy 1.143024 -12.290683) (xy 1.143024 -12.344269) (xy 1.13553 -12.39733)
			(xy 1.120688 -12.44882) (xy 1.098792 -12.497729) (xy 1.07027 -12.543095) (xy 1.035684 -12.584026)
			(xy 1.016 -12.60221) (xy 1.016 -17.112742) (xy 1.035684 -17.130926) (xy 1.07027 -17.171857) (xy 1.098792 -17.217223)
			(xy 1.120688 -17.266132) (xy 1.13553 -17.317622) (xy 1.143024 -17.370683) (xy 1.143024 -17.38737)
			(xy 4.838435 -17.38737) (xy 4.838435 -17.25823) (xy 4.846385 -17.129335) (xy 4.862255 -17.001175)
			(xy 4.885984 -16.874234) (xy 4.917483 -16.748995) (xy 4.956632 -16.625932) (xy 5.003283 -16.505513)
			(xy 5.057258 -16.388194) (xy 5.118353 -16.27442) (xy 5.186336 -16.164623) (xy 5.26095 -16.05922)
			(xy 5.341911 -15.95861) (xy 5.428911 -15.863175) (xy 5.521622 -15.773276) (xy 5.619692 -15.689255)
			(xy 5.722747 -15.611431) (xy 5.830398 -15.540099) (xy 5.942237 -15.475529) (xy 6.057838 -15.417967)
			(xy 6.176763 -15.36763) (xy 6.298562 -15.32471) (xy 6.422772 -15.289369) (xy 6.548921 -15.261742)
			(xy 6.676533 -15.241933) (xy 6.805122 -15.230017) (xy 6.9342 -15.226041) (xy 7.063278 -15.230017)
			(xy 7.191867 -15.241933) (xy 7.319479 -15.261742) (xy 7.445628 -15.289369) (xy 7.569838 -15.32471)
			(xy 7.691637 -15.36763) (xy 7.810562 -15.417967) (xy 7.926163 -15.475529) (xy 8.038002 -15.540099)
			(xy 8.145653 -15.611431) (xy 8.248708 -15.689255) (xy 8.346778 -15.773276) (xy 8.439489 -15.863175)
			(xy 8.526489 -15.95861) (xy 8.60745 -16.05922) (xy 8.682064 -16.164623) (xy 8.750047 -16.27442) (xy 8.811142 -16.388194)
			(xy 8.865117 -16.505513) (xy 8.911768 -16.625932) (xy 8.950917 -16.748995) (xy 8.982416 -16.874234)
			(xy 9.006145 -17.001175) (xy 9.022015 -17.129335) (xy 9.029965 -17.25823) (xy 9.030462 -17.3228)
			(xy 9.029965 -17.38737) (xy 9.022015 -17.516265) (xy 9.006145 -17.644425) (xy 8.982416 -17.771366)
			(xy 8.950917 -17.896605) (xy 8.911768 -18.019668) (xy 8.865117 -18.140087) (xy 8.811142 -18.257406)
			(xy 8.750047 -18.37118) (xy 8.682064 -18.480977) (xy 8.60745 -18.58638) (xy 8.526489 -18.68699) (xy 8.439489 -18.782425)
			(xy 8.346778 -18.872324) (xy 8.248708 -18.956345) (xy 8.145653 -19.034169) (xy 8.038002 -19.105501)
			(xy 7.926163 -19.170071) (xy 7.810562 -19.227633) (xy 7.691637 -19.27797) (xy 7.569838 -19.32089)
			(xy 7.445628 -19.356231) (xy 7.319479 -19.383858) (xy 7.191867 -19.403667) (xy 7.063278 -19.415583)
			(xy 6.9342 -19.41956) (xy 6.805122 -19.415583) (xy 6.676533 -19.403667) (xy 6.548921 -19.383858)
			(xy 6.422772 -19.356231) (xy 6.298562 -19.32089) (xy 6.176763 -19.27797) (xy 6.057838 -19.227633)
			(xy 5.942237 -19.170071) (xy 5.830398 -19.105501) (xy 5.722747 -19.034169) (xy 5.619692 -18.956345)
			(xy 5.521622 -18.872324) (xy 5.428911 -18.782425) (xy 5.341911 -18.68699) (xy 5.26095 -18.58638)
			(xy 5.186336 -18.480977) (xy 5.118353 -18.37118) (xy 5.057258 -18.257406) (xy 5.003283 -18.140087)
			(xy 4.956632 -18.019668) (xy 4.917483 -17.896605) (xy 4.885984 -17.771366) (xy 4.862255 -17.644425)
			(xy 4.846385 -17.516265) (xy 4.838435 -17.38737) (xy 1.143024 -17.38737) (xy 1.143024 -17.424269)
			(xy 1.13553 -17.47733) (xy 1.120688 -17.52882) (xy 1.098792 -17.577729) (xy 1.07027 -17.623095) (xy 1.035684 -17.664026)
			(xy 1.016 -17.68221) (xy 1.016 -22.192742) (xy 1.035684 -22.210926) (xy 1.07027 -22.251857) (xy 1.098792 -22.297223)
			(xy 1.120688 -22.346132) (xy 1.13553 -22.397622) (xy 1.143024 -22.450683) (xy 1.143024 -22.504269)
			(xy 1.13553 -22.55733) (xy 1.120688 -22.60882) (xy 1.098792 -22.657729) (xy 1.07027 -22.703095) (xy 1.035684 -22.744026)
			(xy 1.016 -22.76221) (xy 1.016 -27.272742) (xy 1.035684 -27.290926) (xy 1.07027 -27.331857) (xy 1.098792 -27.377223)
			(xy 1.120688 -27.426132) (xy 1.13553 -27.477622) (xy 1.143024 -27.530683) (xy 1.143024 -27.584269)
			(xy 1.13553 -27.63733) (xy 1.120688 -27.68882) (xy 1.098792 -27.737729) (xy 1.07027 -27.783095) (xy 1.035684 -27.824026)
			(xy 1.016 -27.84221) (xy 1.016 -32.352742) (xy 1.035684 -32.370926) (xy 1.07027 -32.411857) (xy 1.098792 -32.457223)
			(xy 1.120688 -32.506132) (xy 1.13553 -32.557622) (xy 1.143024 -32.610683) (xy 1.143024 -32.664269)
			(xy 1.13553 -32.71733) (xy 1.120688 -32.76882) (xy 1.098792 -32.817729) (xy 1.07027 -32.863095) (xy 1.035684 -32.904026)
			(xy 1.016 -32.92221) (xy 1.016 -37.432742) (xy 1.035684 -37.450926) (xy 1.07027 -37.491857) (xy 1.098792 -37.537223)
			(xy 1.120688 -37.586132) (xy 1.13553 -37.637622) (xy 1.143024 -37.690683) (xy 1.143024 -37.744269)
			(xy 1.13553 -37.79733) (xy 1.120688 -37.84882) (xy 1.098792 -37.897729) (xy 1.07027 -37.943095) (xy 1.035684 -37.984026)
			(xy 1.016 -38.00221) (xy 1.016 -42.512742) (xy 1.035684 -42.530926) (xy 1.07027 -42.571857) (xy 1.098792 -42.617223)
			(xy 1.120688 -42.666132) (xy 1.13553 -42.717622) (xy 1.143024 -42.770683) (xy 1.143024 -42.824269)
			(xy 1.13553 -42.87733) (xy 1.120688 -42.92882) (xy 1.098792 -42.977729) (xy 1.07027 -43.023095) (xy 1.035684 -43.064026)
			(xy 1.016 -43.08221) (xy 1.016 -47.592742) (xy 1.035684 -47.610926) (xy 1.07027 -47.651857) (xy 1.098792 -47.697223)
			(xy 1.120688 -47.746132) (xy 1.13553 -47.797622) (xy 1.143024 -47.850683) (xy 1.143024 -47.904269)
			(xy 1.13553 -47.95733) (xy 1.120688 -48.00882) (xy 1.098792 -48.057729) (xy 1.07027 -48.103095) (xy 1.035684 -48.144026)
			(xy 1.016 -48.16221) (xy 1.016 -52.102258) (xy 5.13588 -52.102258) (xy 5.157229 -52.08285) (xy 5.204684 -52.050038)
			(xy 5.256542 -52.02475) (xy 5.311617 -52.007564) (xy 5.368653 -51.998871) (xy 5.426347 -51.998871)
			(xy 5.483383 -52.007564) (xy 5.538458 -52.02475) (xy 5.590316 -52.050038) (xy 5.637771 -52.08285)
			(xy 5.65912 -52.102258) (xy 15.906496 -52.102258) (xy 15.931446 -52.102747) (xy 15.980731 -52.110551)
			(xy 16.028189 -52.125969) (xy 16.072651 -52.14862) (xy 16.113023 -52.177947) (xy 16.131032 -52.195222)
			(xy 16.736314 -52.800504) (xy 16.753599 -52.818503) (xy 16.78291 -52.858886) (xy 16.805554 -52.903351)
			(xy 16.820974 -52.950808) (xy 16.828793 -53.000091) (xy 16.829278 -53.02504) (xy 16.829278 -54.189122)
			(xy 23.449788 -54.189122) (xy 23.450281 -54.107076) (xy 23.458429 -53.943187) (xy 23.474711 -53.779906)
			(xy 23.499087 -53.617635) (xy 23.531496 -53.456776) (xy 23.571858 -53.297726) (xy 23.620075 -53.140878)
			(xy 23.676025 -52.98662) (xy 23.739572 -52.835333) (xy 23.810559 -52.687391) (xy 23.888809 -52.543159)
			(xy 23.97413 -52.402993) (xy 24.06631 -52.267241) (xy 24.165123 -52.136237) (xy 24.270323 -52.010305)
			(xy 24.381651 -51.889756) (xy 24.498832 -51.774888) (xy 24.621576 -51.665985) (xy 24.74958 -51.563316)
			(xy 24.882528 -51.467135) (xy 25.020091 -51.377679) (xy 25.16193 -51.295169) (xy 25.307693 -51.219809)
			(xy 25.457021 -51.151786) (xy 25.533096 -51.121056) (xy 25.546771 -51.115047) (xy 25.570153 -51.096486)
			(xy 25.587163 -51.071953) (xy 25.596346 -51.043546) (xy 25.596914 -51.013698) (xy 25.58882 -50.984963)
			(xy 25.572756 -50.9598) (xy 25.550097 -50.940362) (xy 25.536652 -50.933858) (xy 25.464831 -50.901553)
			(xy 25.324313 -50.830408) (xy 25.187721 -50.75199) (xy 25.055431 -50.666514) (xy 24.927807 -50.574217)
			(xy 24.805201 -50.475351) (xy 24.68795 -50.37019) (xy 24.576376 -50.259023) (xy 24.470788 -50.142156)
			(xy 24.371476 -50.019911) (xy 24.278714 -49.892625) (xy 24.192756 -49.760648) (xy 24.11384 -49.624343)
			(xy 24.042183 -49.484086) (xy 23.977983 -49.340263) (xy 23.921415 -49.19327) (xy 23.872637 -49.043513)
			(xy 23.831781 -48.891402) (xy 23.798962 -48.737358) (xy 23.774268 -48.581804) (xy 23.757769 -48.42517)
			(xy 23.749509 -48.267885) (xy 23.749 -48.189134) (xy 23.749 -46.588934) (xy 23.749498 -46.511651)
			(xy 23.757454 -46.357291) (xy 23.773347 -46.203545) (xy 23.797133 -46.050821) (xy 23.82875 -45.899525)
			(xy 23.868113 -45.750056) (xy 23.915118 -45.602812) (xy 23.969642 -45.458182) (xy 24.031538 -45.316552)
			(xy 24.100643 -45.178295) (xy 24.176774 -45.04378) (xy 24.259728 -44.913361) (xy 24.349287 -44.787386)
			(xy 24.445211 -44.666189) (xy 24.547248 -44.55009) (xy 24.655125 -44.439398) (xy 24.768558 -44.334406)
			(xy 24.887246 -44.235393) (xy 25.010873 -44.14262) (xy 25.139112 -44.056335) (xy 25.271623 -43.976766)
			(xy 25.408055 -43.904124) (xy 25.548045 -43.838602) (xy 25.691222 -43.780373) (xy 25.837207 -43.729592)
			(xy 25.985613 -43.686393) (xy 26.136045 -43.650891) (xy 26.288106 -43.623181) (xy 26.441392 -43.603335)
			(xy 26.595496 -43.591406) (xy 26.75001 -43.587427) (xy 26.904524 -43.591406) (xy 27.058628 -43.603335)
			(xy 27.211914 -43.623181) (xy 27.363975 -43.650891) (xy 27.514407 -43.686393) (xy 27.662813 -43.729592)
			(xy 27.808798 -43.780373) (xy 27.951975 -43.838602) (xy 28.091965 -43.904124) (xy 28.228397 -43.976766)
			(xy 28.360908 -44.056335) (xy 28.489147 -44.14262) (xy 28.612774 -44.235393) (xy 28.731462 -44.334406)
			(xy 28.844895 -44.439398) (xy 28.952772 -44.55009) (xy 29.054809 -44.666189) (xy 29.150733 -44.787386)
			(xy 29.240292 -44.913361) (xy 29.323246 -45.04378) (xy 29.399377 -45.178295) (xy 29.468482 -45.316552)
			(xy 29.530378 -45.458182) (xy 29.584902 -45.602812) (xy 29.631907 -45.750056) (xy 29.67127 -45.899525)
			(xy 29.702887 -46.050821) (xy 29.726673 -46.203545) (xy 29.742566 -46.357291) (xy 29.750522 -46.511651)
			(xy 29.75102 -46.588934) (xy 29.75102 -48.189134) (xy 29.750471 -48.267875) (xy 29.742209 -48.42514)
			(xy 29.725709 -48.581755) (xy 29.701017 -48.737289) (xy 29.668201 -48.891314) (xy 29.627351 -49.043405)
			(xy 29.578579 -49.193144) (xy 29.522021 -49.340119) (xy 29.45783 -49.483925) (xy 29.386186 -49.624166)
			(xy 29.307283 -49.760456) (xy 29.221341 -49.89242) (xy 29.128595 -50.019694) (xy 29.0293 -50.141928)
			(xy 28.923731 -50.258785) (xy 28.812178 -50.369944) (xy 28.694947 -50.475099) (xy 28.572363 -50.57396)
			(xy 28.444761 -50.666255) (xy 28.312494 -50.75173) (xy 28.175926 -50.830149) (xy 28.035432 -50.901297)
			(xy 27.963622 -50.933604) (xy 27.950153 -50.940124) (xy 27.927432 -50.959576) (xy 27.911321 -50.984774)
			(xy 27.9032 -51.01356) (xy 27.903766 -51.043464) (xy 27.91297 -51.071921) (xy 27.930024 -51.096493)
			(xy 27.953464 -51.11507) (xy 27.967178 -51.121056) (xy 28.043259 -51.15178) (xy 28.192599 -51.219794)
			(xy 28.338375 -51.295145) (xy 28.480226 -51.377648) (xy 28.617801 -51.467098) (xy 28.750762 -51.563273)
			(xy 28.878778 -51.665938) (xy 29.001535 -51.774838) (xy 29.118729 -51.889703) (xy 29.230069 -52.01025)
			(xy 29.335281 -52.136181) (xy 29.434105 -52.267186) (xy 29.526297 -52.402939) (xy 29.611629 -52.543106)
			(xy 29.689889 -52.687341) (xy 29.760886 -52.835286) (xy 29.824442 -52.986577) (xy 29.880402 -53.140839)
			(xy 29.928626 -53.297692) (xy 29.968996 -53.456747) (xy 30.001412 -53.617612) (xy 30.025794 -53.779889)
			(xy 30.042081 -53.943177) (xy 30.050234 -54.107073) (xy 30.05074 -54.189122) (xy 30.050243 -54.270132)
			(xy 30.042293 -54.431957) (xy 30.026412 -54.593196) (xy 30.002639 -54.753463) (xy 29.97103 -54.912369)
			(xy 29.931663 -55.069534) (xy 29.884631 -55.224577) (xy 29.830048 -55.377126) (xy 29.768046 -55.526813)
			(xy 29.698773 -55.673277) (xy 29.622398 -55.816166) (xy 29.539103 -55.955135) (xy 29.449089 -56.089849)
			(xy 29.352574 -56.219985) (xy 29.24979 -56.345228) (xy 29.140984 -56.465277) (xy 29.026419 -56.579842)
			(xy 28.90637 -56.688648) (xy 28.781127 -56.791432) (xy 28.650991 -56.887947) (xy 28.516277 -56.977961)
			(xy 28.377308 -57.061256) (xy 28.234419 -57.137631) (xy 28.087955 -57.206904) (xy 27.938268 -57.268906)
			(xy 27.785719 -57.323489) (xy 27.630676 -57.370521) (xy 27.473511 -57.409888) (xy 27.314605 -57.441497)
			(xy 27.154338 -57.46527) (xy 26.993099 -57.481151) (xy 26.831274 -57.489101) (xy 26.669254 -57.489101)
			(xy 26.507429 -57.481151) (xy 26.34619 -57.46527) (xy 26.185923 -57.441497) (xy 26.027017 -57.409888)
			(xy 25.869852 -57.370521) (xy 25.714809 -57.323489) (xy 25.56226 -57.268906) (xy 25.412573 -57.206904)
			(xy 25.266109 -57.137631) (xy 25.12322 -57.061256) (xy 24.984251 -56.977961) (xy 24.849537 -56.887947)
			(xy 24.719401 -56.791432) (xy 24.594158 -56.688648) (xy 24.474109 -56.579842) (xy 24.359544 -56.465277)
			(xy 24.250738 -56.345228) (xy 24.147954 -56.219985) (xy 24.051439 -56.089849) (xy 23.961425 -55.955135)
			(xy 23.87813 -55.816166) (xy 23.801755 -55.673277) (xy 23.732482 -55.526813) (xy 23.67048 -55.377126)
			(xy 23.615897 -55.224577) (xy 23.568865 -55.069534) (xy 23.529498 -54.912369) (xy 23.497889 -54.753463)
			(xy 23.474116 -54.593196) (xy 23.458235 -54.431957) (xy 23.450285 -54.270132) (xy 23.449788 -54.189122)
			(xy 16.829278 -54.189122) (xy 16.829278 -58.552334) (xy 16.828794 -58.577286) (xy 16.820999 -58.626577)
			(xy 16.80559 -58.674042) (xy 16.782946 -58.718513) (xy 16.753625 -58.758894) (xy 16.736314 -58.77687)
			(xy 15.582646 -59.930538) (xy 15.580614 -59.94781) (xy 15.57666 -59.975616) (xy 15.561648 -60.029735)
			(xy 15.538866 -60.081069) (xy 15.508806 -60.12851) (xy 15.472117 -60.171033) (xy 15.429592 -60.207719)
			(xy 15.38215 -60.237776) (xy 15.330814 -60.260556) (xy 15.276694 -60.275565) (xy 15.24889 -60.279534)
			(xy 15.231618 -60.281566) (xy 12.390882 -63.122302) (xy 12.390882 -72.000618) (xy 12.390399 -72.02557)
			(xy 12.382606 -72.074863) (xy 12.367199 -72.12233) (xy 12.344557 -72.166802) (xy 12.315238 -72.207186)
			(xy 12.297918 -72.225154) (xy 11.7729 -72.750172) (xy 11.7729 -75.635104) (xy 15.73277 -75.635104)
			(xy 15.736751 -75.545198) (xy 15.748662 -75.455997) (xy 15.76841 -75.368196) (xy 15.79584 -75.282485)
			(xy 15.830739 -75.199534) (xy 15.872832 -75.119991) (xy 15.92179 -75.04448) (xy 15.977231 -74.973591)
			(xy 16.038719 -74.90788) (xy 16.105775 -74.84786) (xy 16.177873 -74.794001) (xy 16.254449 -74.746725)
			(xy 16.334903 -74.706402) (xy 16.418606 -74.673347) (xy 16.504903 -74.647819) (xy 16.593119 -74.630019)
			(xy 16.682562 -74.620084) (xy 16.772534 -74.618093) (xy 16.862329 -74.624062) (xy 16.951246 -74.637943)
			(xy 17.038588 -74.659629) (xy 17.123671 -74.688949) (xy 17.20583 -74.725673) (xy 17.284422 -74.769516)
			(xy 17.358832 -74.820133) (xy 17.428477 -74.877128) (xy 17.492812 -74.940055) (xy 17.551334 -75.008422)
			(xy 17.603584 -75.081694) (xy 17.649155 -75.159297) (xy 17.687688 -75.240623) (xy 17.718883 -75.325037)
			(xy 17.742496 -75.411878) (xy 17.758341 -75.500466) (xy 17.766294 -75.590107) (xy 17.766792 -75.635104)
			(xy 17.766294 -75.680101) (xy 17.758341 -75.769742) (xy 17.742496 -75.85833) (xy 17.718883 -75.945171)
			(xy 17.687688 -76.029585) (xy 17.649155 -76.110911) (xy 17.603584 -76.188514) (xy 17.551334 -76.261786)
			(xy 17.492812 -76.330153) (xy 17.428477 -76.39308) (xy 17.358832 -76.450075) (xy 17.284422 -76.500692)
			(xy 17.20583 -76.544535) (xy 17.123671 -76.581259) (xy 17.038588 -76.610579) (xy 16.951246 -76.632265)
			(xy 16.862329 -76.646146) (xy 16.772534 -76.652115) (xy 16.682562 -76.650124) (xy 16.593119 -76.640189)
			(xy 16.504903 -76.622389) (xy 16.418606 -76.596861) (xy 16.334903 -76.563806) (xy 16.254449 -76.523483)
			(xy 16.177873 -76.476207) (xy 16.105775 -76.422348) (xy 16.038719 -76.362328) (xy 15.977231 -76.296617)
			(xy 15.92179 -76.225728) (xy 15.872832 -76.150217) (xy 15.830739 -76.070674) (xy 15.79584 -75.987723)
			(xy 15.76841 -75.902012) (xy 15.748662 -75.814211) (xy 15.736751 -75.72501) (xy 15.73277 -75.635104)
			(xy 11.7729 -75.635104) (xy 11.7729 -77.770228) (xy 12.028678 -78.026006) (xy 12.04976 -78.026006)
			(xy 12.077014 -78.026467) (xy 12.130969 -78.034219) (xy 12.183271 -78.049572) (xy 12.232855 -78.072212)
			(xy 12.278712 -78.101679) (xy 12.319908 -78.137373) (xy 12.355605 -78.178567) (xy 12.385075 -78.224422)
			(xy 12.407719 -78.274005) (xy 12.423075 -78.326306) (xy 12.430832 -78.38026) (xy 12.431268 -78.407514)
			(xy 12.431268 -78.407768) (xy 12.430692 -78.437279) (xy 12.421566 -78.495594) (xy 12.403587 -78.551813)
			(xy 12.390882 -78.578456) (xy 12.390882 -79.097378) (xy 12.403614 -79.12401) (xy 12.42161 -79.180229)
			(xy 12.430712 -79.238552) (xy 12.431268 -79.268066) (xy 12.431268 -79.268574) (xy 12.430691 -79.298085)
			(xy 12.421564 -79.356399) (xy 12.403585 -79.412618) (xy 12.390882 -79.439262) (xy 12.390882 -81.318608)
			(xy 12.424918 -81.330546) (xy 12.450893 -81.340164) (xy 12.499974 -81.365835) (xy 12.544825 -81.398337)
			(xy 12.584501 -81.436985) (xy 12.618168 -81.480967) (xy 12.645118 -81.529358) (xy 12.664784 -81.581138)
			(xy 12.676751 -81.635218) (xy 12.680768 -81.690461) (xy 12.676751 -81.745704) (xy 12.664783 -81.799785)
			(xy 12.645117 -81.851565) (xy 12.618167 -81.899955) (xy 12.584499 -81.943937) (xy 12.544823 -81.982585)
			(xy 12.499972 -82.015087) (xy 12.450891 -82.040757) (xy 12.424918 -82.050382) (xy 12.390882 -82.06232)
			(xy 12.390882 -97.978249) (xy 45.046914 -97.978249) (xy 45.046914 -97.923751) (xy 45.05467 -97.869809)
			(xy 45.070024 -97.817519) (xy 45.092663 -97.767947) (xy 45.122126 -97.722101) (xy 45.157814 -97.680914)
			(xy 45.199001 -97.645226) (xy 45.244847 -97.615763) (xy 45.294419 -97.593124) (xy 45.346709 -97.57777)
			(xy 45.400651 -97.570014) (xy 45.4279 -97.569528) (xy 46.3169 -97.569528) (xy 46.344154 -97.569942)
			(xy 46.398107 -97.577699) (xy 46.450406 -97.593056) (xy 46.499988 -97.615699) (xy 46.545843 -97.645168)
			(xy 46.587037 -97.680863) (xy 46.622732 -97.722057) (xy 46.652201 -97.767912) (xy 46.674844 -97.817494)
			(xy 46.690201 -97.869793) (xy 46.697958 -97.923746) (xy 46.697958 -97.978254) (xy 46.690201 -98.032207)
			(xy 46.674844 -98.084506) (xy 46.652201 -98.134088) (xy 46.622732 -98.179943) (xy 46.587037 -98.221137)
			(xy 46.545843 -98.256832) (xy 46.499988 -98.286301) (xy 46.450406 -98.308944) (xy 46.398107 -98.324301)
			(xy 46.344154 -98.332058) (xy 46.3169 -98.332544) (xy 45.4279 -98.332544) (xy 45.400651 -98.331986)
			(xy 45.346709 -98.32423) (xy 45.294419 -98.308876) (xy 45.244847 -98.286237) (xy 45.199001 -98.256774)
			(xy 45.157814 -98.221086) (xy 45.122126 -98.179899) (xy 45.092663 -98.134053) (xy 45.070024 -98.084481)
			(xy 45.05467 -98.032191) (xy 45.046914 -97.978249) (xy 12.390882 -97.978249) (xy 12.390882 -98.410049)
			(xy 40.017714 -98.410049) (xy 40.017714 -98.355551) (xy 40.02547 -98.301609) (xy 40.040824 -98.249319)
			(xy 40.063463 -98.199747) (xy 40.092926 -98.153901) (xy 40.128614 -98.112714) (xy 40.169801 -98.077026)
			(xy 40.215647 -98.047563) (xy 40.265219 -98.024924) (xy 40.317509 -98.00957) (xy 40.371451 -98.001814)
			(xy 40.3987 -98.001328) (xy 41.2877 -98.001328) (xy 41.314954 -98.001742) (xy 41.368907 -98.009499)
			(xy 41.421206 -98.024856) (xy 41.470788 -98.047499) (xy 41.516643 -98.076968) (xy 41.557837 -98.112663)
			(xy 41.593532 -98.153857) (xy 41.623001 -98.199712) (xy 41.645644 -98.249294) (xy 41.661001 -98.301593)
			(xy 41.668758 -98.355546) (xy 41.668758 -98.410054) (xy 41.661001 -98.464007) (xy 41.645644 -98.516306)
			(xy 41.623001 -98.565888) (xy 41.593532 -98.611743) (xy 41.557837 -98.652937) (xy 41.516643 -98.688632)
			(xy 41.470788 -98.718101) (xy 41.421206 -98.740744) (xy 41.368907 -98.756101) (xy 41.314954 -98.763858)
			(xy 41.2877 -98.764344) (xy 40.3987 -98.764344) (xy 40.371451 -98.763786) (xy 40.317509 -98.75603)
			(xy 40.265219 -98.740676) (xy 40.215647 -98.718037) (xy 40.169801 -98.688574) (xy 40.128614 -98.652886)
			(xy 40.092926 -98.611699) (xy 40.063463 -98.565853) (xy 40.040824 -98.516281) (xy 40.02547 -98.463991)
			(xy 40.017714 -98.410049) (xy 12.390882 -98.410049) (xy 12.390882 -102.640384) (xy 14.22146 -104.470962)
		)
		(stroke
			(width 0)
			(type solid)
		)
		(fill yes)
		(layer "In5.Cu")
		(net "P3V3_AUX")
	)
	(gr_poly
		(pts
			(xy 121.000012 -119.892064) (xy 121.055819 -119.891554) (xy 121.16712 -119.883212) (xy 121.277487 -119.866576)
			(xy 121.386302 -119.841739) (xy 121.492956 -119.808839) (xy 121.596854 -119.768061) (xy 121.697414 -119.719632)
			(xy 121.794073 -119.663824) (xy 121.886292 -119.600949) (xy 121.973554 -119.531358) (xy 122.055371 -119.45544)
			(xy 122.131287 -119.373621) (xy 122.200875 -119.286356) (xy 122.263748 -119.194136) (xy 122.319553 -119.097475)
			(xy 122.367978 -118.996914) (xy 122.408754 -118.893015) (xy 122.44165 -118.786359) (xy 122.466484 -118.677544)
			(xy 122.483117 -118.567176) (xy 122.491456 -118.455875) (xy 122.492008 -118.400068) (xy 122.492008 129.499868)
			(xy 122.4915 129.555676) (xy 122.483161 129.666981) (xy 122.466528 129.777352) (xy 122.441693 129.886171)
			(xy 122.408795 129.992829) (xy 122.368019 130.096731) (xy 122.319592 130.197295) (xy 122.263785 130.293959)
			(xy 122.200911 130.386183) (xy 122.13132 130.473449) (xy 122.055402 130.555271) (xy 121.973583 130.631191)
			(xy 121.886318 130.700784) (xy 121.794097 130.763662) (xy 121.697434 130.819471) (xy 121.596872 130.867901)
			(xy 121.492971 130.908681) (xy 121.386313 130.941581) (xy 121.277495 130.96642) (xy 121.167125 130.983056)
			(xy 121.05582 130.991398) (xy 121.000012 130.991864) (xy 94.000066 130.991864) (xy 93.94426 130.991341)
			(xy 93.832961 130.982998) (xy 93.722596 130.96636) (xy 93.613784 130.941522) (xy 93.507131 130.908622)
			(xy 93.403236 130.867843) (xy 93.302679 130.819414) (xy 93.206021 130.763606) (xy 93.113805 130.700731)
			(xy 93.026545 130.631141) (xy 92.94473 130.555224) (xy 92.868816 130.473405) (xy 92.79923 130.386142)
			(xy 92.736359 130.293923) (xy 92.680555 130.197263) (xy 92.632131 130.096703) (xy 92.591357 129.992806)
			(xy 92.558461 129.886153) (xy 92.533627 129.777339) (xy 92.516995 129.666973) (xy 92.508656 129.555674)
			(xy 92.50807 129.499868) (xy 92.50807 126.435304) (xy 115.904253 126.435304) (xy 115.904253 126.564444)
			(xy 115.912203 126.693339) (xy 115.928073 126.821499) (xy 115.951802 126.94844) (xy 115.983301 127.073679)
			(xy 116.02245 127.196742) (xy 116.069101 127.317161) (xy 116.123076 127.43448) (xy 116.184171 127.548254)
			(xy 116.252154 127.658051) (xy 116.326768 127.763454) (xy 116.407729 127.864064) (xy 116.494729 127.959499)
			(xy 116.58744 128.049398) (xy 116.68551 128.133419) (xy 116.788565 128.211243) (xy 116.896216 128.282575)
			(xy 117.008055 128.347145) (xy 117.123656 128.404707) (xy 117.242581 128.455044) (xy 117.36438 128.497964)
			(xy 117.48859 128.533305) (xy 117.614739 128.560932) (xy 117.742351 128.580741) (xy 117.87094 128.592657)
			(xy 118.000018 128.596634) (xy 118.129096 128.592657) (xy 118.257685 128.580741) (xy 118.385297 128.560932)
			(xy 118.511446 128.533305) (xy 118.635656 128.497964) (xy 118.757455 128.455044) (xy 118.87638 128.404707)
			(xy 118.991981 128.347145) (xy 119.10382 128.282575) (xy 119.211471 128.211243) (xy 119.314526 128.133419)
			(xy 119.412596 128.049398) (xy 119.505307 127.959499) (xy 119.592307 127.864064) (xy 119.673268 127.763454)
			(xy 119.747882 127.658051) (xy 119.815865 127.548254) (xy 119.87696 127.43448) (xy 119.930935 127.317161)
			(xy 119.977586 127.196742) (xy 120.016735 127.073679) (xy 120.048234 126.94844) (xy 120.071963 126.821499)
			(xy 120.087833 126.693339) (xy 120.095783 126.564444) (xy 120.09628 126.499874) (xy 120.095783 126.435304)
			(xy 120.087833 126.306409) (xy 120.071963 126.178249) (xy 120.048234 126.051308) (xy 120.016735 125.926069)
			(xy 119.977586 125.803006) (xy 119.930935 125.682587) (xy 119.87696 125.565268) (xy 119.815865 125.451494)
			(xy 119.747882 125.341697) (xy 119.673268 125.236294) (xy 119.592307 125.135684) (xy 119.505307 125.040249)
			(xy 119.412596 124.95035) (xy 119.314526 124.866329) (xy 119.211471 124.788505) (xy 119.10382 124.717173)
			(xy 118.991981 124.652603) (xy 118.87638 124.595041) (xy 118.757455 124.544704) (xy 118.635656 124.501784)
			(xy 118.511446 124.466443) (xy 118.385297 124.438816) (xy 118.257685 124.419007) (xy 118.129096 124.407091)
			(xy 118.000018 124.403115) (xy 117.87094 124.407091) (xy 117.742351 124.419007) (xy 117.614739 124.438816)
			(xy 117.48859 124.466443) (xy 117.36438 124.501784) (xy 117.242581 124.544704) (xy 117.123656 124.595041)
			(xy 117.008055 124.652603) (xy 116.896216 124.717173) (xy 116.788565 124.788505) (xy 116.68551 124.866329)
			(xy 116.58744 124.95035) (xy 116.494729 125.040249) (xy 116.407729 125.135684) (xy 116.326768 125.236294)
			(xy 116.252154 125.341697) (xy 116.184171 125.451494) (xy 116.123076 125.565268) (xy 116.069101 125.682587)
			(xy 116.02245 125.803006) (xy 115.983301 125.926069) (xy 115.951802 126.051308) (xy 115.928073 126.178249)
			(xy 115.912203 126.306409) (xy 115.904253 126.435304) (xy 92.50807 126.435304) (xy 92.50807 122.226375)
			(xy 99.070401 122.226375) (xy 99.070401 122.312125) (xy 99.078313 122.397508) (xy 99.094069 122.481798)
			(xy 99.117536 122.564274) (xy 99.148512 122.644233) (xy 99.186734 122.720993) (xy 99.231875 122.793899)
			(xy 99.283551 122.862328) (xy 99.34132 122.925698) (xy 99.40469 122.983467) (xy 99.473119 123.035143)
			(xy 99.546025 123.080284) (xy 99.622785 123.118506) (xy 99.702744 123.149482) (xy 99.78522 123.172949)
			(xy 99.86951 123.188705) (xy 99.954893 123.196617) (xy 100.040643 123.196617) (xy 100.126026 123.188705)
			(xy 100.210316 123.172949) (xy 100.292792 123.149482) (xy 100.372751 123.118506) (xy 100.449511 123.080284)
			(xy 100.522417 123.035143) (xy 100.590846 122.983467) (xy 100.654216 122.925698) (xy 100.711985 122.862328)
			(xy 100.763661 122.793899) (xy 100.808802 122.720993) (xy 100.847024 122.644233) (xy 100.878 122.564274)
			(xy 100.901467 122.481798) (xy 100.917223 122.397508) (xy 100.925135 122.312125) (xy 100.92563 122.26925)
			(xy 100.925135 122.226375) (xy 101.610401 122.226375) (xy 101.610401 122.312125) (xy 101.618313 122.397508)
			(xy 101.634069 122.481798) (xy 101.657536 122.564274) (xy 101.688512 122.644233) (xy 101.726734 122.720993)
			(xy 101.771875 122.793899) (xy 101.823551 122.862328) (xy 101.88132 122.925698) (xy 101.94469 122.983467)
			(xy 102.013119 123.035143) (xy 102.086025 123.080284) (xy 102.162785 123.118506) (xy 102.242744 123.149482)
			(xy 102.32522 123.172949) (xy 102.40951 123.188705) (xy 102.494893 123.196617) (xy 102.580643 123.196617)
			(xy 102.666026 123.188705) (xy 102.750316 123.172949) (xy 102.832792 123.149482) (xy 102.912751 123.118506)
			(xy 102.989511 123.080284) (xy 103.062417 123.035143) (xy 103.130846 122.983467) (xy 103.194216 122.925698)
			(xy 103.251985 122.862328) (xy 103.303661 122.793899) (xy 103.348802 122.720993) (xy 103.387024 122.644233)
			(xy 103.418 122.564274) (xy 103.441467 122.481798) (xy 103.457223 122.397508) (xy 103.465135 122.312125)
			(xy 103.46563 122.26925) (xy 103.465135 122.226375) (xy 103.457223 122.140992) (xy 103.441467 122.056702)
			(xy 103.418 121.974226) (xy 103.387024 121.894267) (xy 103.348802 121.817507) (xy 103.303661 121.744601)
			(xy 103.251985 121.676172) (xy 103.194216 121.612802) (xy 103.130846 121.555033) (xy 103.062417 121.503357)
			(xy 102.989511 121.458216) (xy 102.912751 121.419994) (xy 102.832792 121.389018) (xy 102.750316 121.365551)
			(xy 102.666026 121.349795) (xy 102.580643 121.341883) (xy 102.494893 121.341883) (xy 102.40951 121.349795)
			(xy 102.32522 121.365551) (xy 102.242744 121.389018) (xy 102.162785 121.419994) (xy 102.086025 121.458216)
			(xy 102.013119 121.503357) (xy 101.94469 121.555033) (xy 101.88132 121.612802) (xy 101.823551 121.676172)
			(xy 101.771875 121.744601) (xy 101.726734 121.817507) (xy 101.688512 121.894267) (xy 101.657536 121.974226)
			(xy 101.634069 122.056702) (xy 101.618313 122.140992) (xy 101.610401 122.226375) (xy 100.925135 122.226375)
			(xy 100.917223 122.140992) (xy 100.901467 122.056702) (xy 100.878 121.974226) (xy 100.847024 121.894267)
			(xy 100.808802 121.817507) (xy 100.763661 121.744601) (xy 100.711985 121.676172) (xy 100.654216 121.612802)
			(xy 100.590846 121.555033) (xy 100.522417 121.503357) (xy 100.449511 121.458216) (xy 100.372751 121.419994)
			(xy 100.292792 121.389018) (xy 100.210316 121.365551) (xy 100.126026 121.349795) (xy 100.040643 121.341883)
			(xy 99.954893 121.341883) (xy 99.86951 121.349795) (xy 99.78522 121.365551) (xy 99.702744 121.389018)
			(xy 99.622785 121.419994) (xy 99.546025 121.458216) (xy 99.473119 121.503357) (xy 99.40469 121.555033)
			(xy 99.34132 121.612802) (xy 99.283551 121.676172) (xy 99.231875 121.744601) (xy 99.186734 121.817507)
			(xy 99.148512 121.894267) (xy 99.117536 121.974226) (xy 99.094069 122.056702) (xy 99.078313 122.140992)
			(xy 99.070401 122.226375) (xy 92.50807 122.226375) (xy 92.50807 117.881334) (xy 100.454746 117.881334)
			(xy 100.454746 117.935866) (xy 100.462507 117.989844) (xy 100.47787 118.042168) (xy 100.500522 118.091773)
			(xy 100.530003 118.13765) (xy 100.565713 118.178864) (xy 100.606924 118.214578) (xy 100.652799 118.244063)
			(xy 100.702402 118.266719) (xy 100.754725 118.282087) (xy 100.808702 118.289851) (xy 100.835968 118.29034)
			(xy 101.699568 118.29034) (xy 101.726842 118.289923) (xy 101.780835 118.282164) (xy 101.833175 118.266799)
			(xy 101.882795 118.244142) (xy 101.928685 118.214654) (xy 101.969912 118.178934) (xy 102.005635 118.137711)
			(xy 102.035127 118.091823) (xy 102.057788 118.042205) (xy 102.073157 117.989867) (xy 102.08092 117.935874)
			(xy 102.08092 117.881326) (xy 102.073157 117.827333) (xy 102.057788 117.774995) (xy 102.035127 117.725377)
			(xy 102.005635 117.679489) (xy 101.969912 117.638266) (xy 101.928685 117.602546) (xy 101.882795 117.573058)
			(xy 101.833175 117.550401) (xy 101.780836 117.535036) (xy 101.726842 117.527277) (xy 101.699568 117.526816)
			(xy 100.835968 117.526816) (xy 100.808702 117.527349) (xy 100.754725 117.535113) (xy 100.702402 117.550481)
			(xy 100.652799 117.573137) (xy 100.606924 117.602622) (xy 100.565713 117.638336) (xy 100.530003 117.67955)
			(xy 100.500522 117.725427) (xy 100.47787 117.775032) (xy 100.462507 117.827356) (xy 100.454746 117.881334)
			(xy 92.50807 117.881334) (xy 92.50807 115.606627) (xy 93.714049 115.606627) (xy 93.714049 115.692377)
			(xy 93.721961 115.77776) (xy 93.737717 115.86205) (xy 93.761184 115.944526) (xy 93.79216 116.024485)
			(xy 93.830382 116.101245) (xy 93.875523 116.174151) (xy 93.927199 116.24258) (xy 93.984968 116.30595)
			(xy 94.048338 116.363719) (xy 94.116767 116.415395) (xy 94.189673 116.460536) (xy 94.266433 116.498758)
			(xy 94.346392 116.529734) (xy 94.428868 116.553201) (xy 94.513158 116.568957) (xy 94.598541 116.576869)
			(xy 94.684291 116.576869) (xy 94.769674 116.568957) (xy 94.853964 116.553201) (xy 94.93644 116.529734)
			(xy 95.016399 116.498758) (xy 95.093159 116.460536) (xy 95.166065 116.415395) (xy 95.234494 116.363719)
			(xy 95.297864 116.30595) (xy 95.355633 116.24258) (xy 95.407309 116.174151) (xy 95.45245 116.101245)
			(xy 95.490672 116.024485) (xy 95.521648 115.944526) (xy 95.545115 115.86205) (xy 95.560871 115.77776)
			(xy 95.568783 115.692377) (xy 95.569278 115.649502) (xy 95.568783 115.606627) (xy 96.254049 115.606627)
			(xy 96.254049 115.692377) (xy 96.261961 115.77776) (xy 96.277717 115.86205) (xy 96.301184 115.944526)
			(xy 96.33216 116.024485) (xy 96.370382 116.101245) (xy 96.415523 116.174151) (xy 96.467199 116.24258)
			(xy 96.524968 116.30595) (xy 96.588338 116.363719) (xy 96.656767 116.415395) (xy 96.729673 116.460536)
			(xy 96.806433 116.498758) (xy 96.886392 116.529734) (xy 96.968868 116.553201) (xy 97.053158 116.568957)
			(xy 97.138541 116.576869) (xy 97.224291 116.576869) (xy 97.309674 116.568957) (xy 97.393964 116.553201)
			(xy 97.47644 116.529734) (xy 97.556399 116.498758) (xy 97.633159 116.460536) (xy 97.706065 116.415395)
			(xy 97.774494 116.363719) (xy 97.837864 116.30595) (xy 97.895633 116.24258) (xy 97.947309 116.174151)
			(xy 97.99245 116.101245) (xy 98.030672 116.024485) (xy 98.061648 115.944526) (xy 98.081039 115.876375)
			(xy 99.070401 115.876375) (xy 99.070401 115.962125) (xy 99.078313 116.047508) (xy 99.094069 116.131798)
			(xy 99.117536 116.214274) (xy 99.148512 116.294233) (xy 99.186734 116.370993) (xy 99.231875 116.443899)
			(xy 99.283551 116.512328) (xy 99.34132 116.575698) (xy 99.40469 116.633467) (xy 99.473119 116.685143)
			(xy 99.546025 116.730284) (xy 99.622785 116.768506) (xy 99.702744 116.799482) (xy 99.78522 116.822949)
			(xy 99.86951 116.838705) (xy 99.954893 116.846617) (xy 100.040643 116.846617) (xy 100.126026 116.838705)
			(xy 100.210316 116.822949) (xy 100.292792 116.799482) (xy 100.372751 116.768506) (xy 100.449511 116.730284)
			(xy 100.522417 116.685143) (xy 100.590846 116.633467) (xy 100.654216 116.575698) (xy 100.711985 116.512328)
			(xy 100.763661 116.443899) (xy 100.808802 116.370993) (xy 100.847024 116.294233) (xy 100.878 116.214274)
			(xy 100.901467 116.131798) (xy 100.917223 116.047508) (xy 100.925135 115.962125) (xy 100.92563 115.91925)
			(xy 100.925135 115.876375) (xy 101.610401 115.876375) (xy 101.610401 115.962125) (xy 101.618313 116.047508)
			(xy 101.634069 116.131798) (xy 101.657536 116.214274) (xy 101.688512 116.294233) (xy 101.726734 116.370993)
			(xy 101.771875 116.443899) (xy 101.823551 116.512328) (xy 101.88132 116.575698) (xy 101.94469 116.633467)
			(xy 102.013119 116.685143) (xy 102.086025 116.730284) (xy 102.162785 116.768506) (xy 102.242744 116.799482)
			(xy 102.32522 116.822949) (xy 102.40951 116.838705) (xy 102.494893 116.846617) (xy 102.580643 116.846617)
			(xy 102.666026 116.838705) (xy 102.750316 116.822949) (xy 102.832792 116.799482) (xy 102.912751 116.768506)
			(xy 102.989511 116.730284) (xy 103.062417 116.685143) (xy 103.130846 116.633467) (xy 103.194216 116.575698)
			(xy 103.251985 116.512328) (xy 103.303661 116.443899) (xy 103.348802 116.370993) (xy 103.387024 116.294233)
			(xy 103.418 116.214274) (xy 103.441467 116.131798) (xy 103.457223 116.047508) (xy 103.465135 115.962125)
			(xy 103.46563 115.91925) (xy 103.465135 115.876375) (xy 103.457223 115.790992) (xy 103.441467 115.706702)
			(xy 103.418 115.624226) (xy 103.387024 115.544267) (xy 103.348802 115.467507) (xy 103.303661 115.394601)
			(xy 103.251985 115.326172) (xy 103.194216 115.262802) (xy 103.130846 115.205033) (xy 103.062417 115.153357)
			(xy 102.989511 115.108216) (xy 102.912751 115.069994) (xy 102.832792 115.039018) (xy 102.750316 115.015551)
			(xy 102.666026 114.999795) (xy 102.580643 114.991883) (xy 102.494893 114.991883) (xy 102.40951 114.999795)
			(xy 102.32522 115.015551) (xy 102.242744 115.039018) (xy 102.162785 115.069994) (xy 102.086025 115.108216)
			(xy 102.013119 115.153357) (xy 101.94469 115.205033) (xy 101.88132 115.262802) (xy 101.823551 115.326172)
			(xy 101.771875 115.394601) (xy 101.726734 115.467507) (xy 101.688512 115.544267) (xy 101.657536 115.624226)
			(xy 101.634069 115.706702) (xy 101.618313 115.790992) (xy 101.610401 115.876375) (xy 100.925135 115.876375)
			(xy 100.917223 115.790992) (xy 100.901467 115.706702) (xy 100.878 115.624226) (xy 100.847024 115.544267)
			(xy 100.808802 115.467507) (xy 100.763661 115.394601) (xy 100.711985 115.326172) (xy 100.654216 115.262802)
			(xy 100.590846 115.205033) (xy 100.522417 115.153357) (xy 100.449511 115.108216) (xy 100.372751 115.069994)
			(xy 100.292792 115.039018) (xy 100.210316 115.015551) (xy 100.126026 114.999795) (xy 100.040643 114.991883)
			(xy 99.954893 114.991883) (xy 99.86951 114.999795) (xy 99.78522 115.015551) (xy 99.702744 115.039018)
			(xy 99.622785 115.069994) (xy 99.546025 115.108216) (xy 99.473119 115.153357) (xy 99.40469 115.205033)
			(xy 99.34132 115.262802) (xy 99.283551 115.326172) (xy 99.231875 115.394601) (xy 99.186734 115.467507)
			(xy 99.148512 115.544267) (xy 99.117536 115.624226) (xy 99.094069 115.706702) (xy 99.078313 115.790992)
			(xy 99.070401 115.876375) (xy 98.081039 115.876375) (xy 98.085115 115.86205) (xy 98.100871 115.77776)
			(xy 98.108783 115.692377) (xy 98.109278 115.649502) (xy 98.108783 115.606627) (xy 98.100871 115.521244)
			(xy 98.085115 115.436954) (xy 98.061648 115.354478) (xy 98.030672 115.274519) (xy 97.99245 115.197759)
			(xy 97.947309 115.124853) (xy 97.895633 115.056424) (xy 97.837864 114.993054) (xy 97.774494 114.935285)
			(xy 97.706065 114.883609) (xy 97.633159 114.838468) (xy 97.556399 114.800246) (xy 97.47644 114.76927)
			(xy 97.393964 114.745803) (xy 97.309674 114.730047) (xy 97.224291 114.722135) (xy 97.138541 114.722135)
			(xy 97.053158 114.730047) (xy 96.968868 114.745803) (xy 96.886392 114.76927) (xy 96.806433 114.800246)
			(xy 96.729673 114.838468) (xy 96.656767 114.883609) (xy 96.588338 114.935285) (xy 96.524968 114.993054)
			(xy 96.467199 115.056424) (xy 96.415523 115.124853) (xy 96.370382 115.197759) (xy 96.33216 115.274519)
			(xy 96.301184 115.354478) (xy 96.277717 115.436954) (xy 96.261961 115.521244) (xy 96.254049 115.606627)
			(xy 95.568783 115.606627) (xy 95.560871 115.521244) (xy 95.545115 115.436954) (xy 95.521648 115.354478)
			(xy 95.490672 115.274519) (xy 95.45245 115.197759) (xy 95.407309 115.124853) (xy 95.355633 115.056424)
			(xy 95.297864 114.993054) (xy 95.234494 114.935285) (xy 95.166065 114.883609) (xy 95.093159 114.838468)
			(xy 95.016399 114.800246) (xy 94.93644 114.76927) (xy 94.853964 114.745803) (xy 94.769674 114.730047)
			(xy 94.684291 114.722135) (xy 94.598541 114.722135) (xy 94.513158 114.730047) (xy 94.428868 114.745803)
			(xy 94.346392 114.76927) (xy 94.266433 114.800246) (xy 94.189673 114.838468) (xy 94.116767 114.883609)
			(xy 94.048338 114.935285) (xy 93.984968 114.993054) (xy 93.927199 115.056424) (xy 93.875523 115.124853)
			(xy 93.830382 115.197759) (xy 93.79216 115.274519) (xy 93.761184 115.354478) (xy 93.737717 115.436954)
			(xy 93.721961 115.521244) (xy 93.714049 115.606627) (xy 92.50807 115.606627) (xy 92.50807 111.261526)
			(xy 95.098272 111.261526) (xy 95.098272 111.316074) (xy 95.106035 111.370066) (xy 95.121403 111.422404)
			(xy 95.144064 111.472023) (xy 95.173555 111.517911) (xy 95.209277 111.559134) (xy 95.250502 111.594855)
			(xy 95.296392 111.624344) (xy 95.346011 111.647003) (xy 95.398349 111.662369) (xy 95.452342 111.67013)
			(xy 95.479616 111.670592) (xy 96.343216 111.670592) (xy 96.370482 111.670045) (xy 96.42446 111.662282)
			(xy 96.476784 111.646916) (xy 96.526388 111.624261) (xy 96.572263 111.594777) (xy 96.613476 111.559064)
			(xy 96.649186 111.51785) (xy 96.678668 111.471974) (xy 96.701322 111.422369) (xy 96.716685 111.370044)
			(xy 96.724446 111.316067) (xy 96.724446 111.261534) (xy 96.716685 111.207556) (xy 96.701322 111.155231)
			(xy 96.678668 111.105626) (xy 96.649186 111.05975) (xy 96.613476 111.018536) (xy 96.572263 110.982823)
			(xy 96.526388 110.953339) (xy 96.476784 110.930684) (xy 96.42446 110.915318) (xy 96.370482 110.907555)
			(xy 96.343216 110.907068) (xy 95.479616 110.907068) (xy 95.452342 110.90747) (xy 95.398349 110.915231)
			(xy 95.346011 110.930597) (xy 95.296392 110.953256) (xy 95.250502 110.982745) (xy 95.209277 111.018466)
			(xy 95.173555 111.059689) (xy 95.144064 111.105577) (xy 95.121403 111.155196) (xy 95.106035 111.207534)
			(xy 95.098272 111.261526) (xy 92.50807 111.261526) (xy 92.50807 109.256627) (xy 93.714049 109.256627)
			(xy 93.714049 109.342377) (xy 93.721961 109.42776) (xy 93.737717 109.51205) (xy 93.761184 109.594526)
			(xy 93.79216 109.674485) (xy 93.830382 109.751245) (xy 93.875523 109.824151) (xy 93.927199 109.89258)
			(xy 93.984968 109.95595) (xy 94.048338 110.013719) (xy 94.116767 110.065395) (xy 94.189673 110.110536)
			(xy 94.266433 110.148758) (xy 94.346392 110.179734) (xy 94.428868 110.203201) (xy 94.513158 110.218957)
			(xy 94.598541 110.226869) (xy 94.684291 110.226869) (xy 94.769674 110.218957) (xy 94.853964 110.203201)
			(xy 94.93644 110.179734) (xy 95.016399 110.148758) (xy 95.093159 110.110536) (xy 95.166065 110.065395)
			(xy 95.234494 110.013719) (xy 95.297864 109.95595) (xy 95.355633 109.89258) (xy 95.407309 109.824151)
			(xy 95.45245 109.751245) (xy 95.490672 109.674485) (xy 95.521648 109.594526) (xy 95.545115 109.51205)
			(xy 95.560871 109.42776) (xy 95.568783 109.342377) (xy 95.569278 109.299502) (xy 95.568783 109.256627)
			(xy 96.254049 109.256627) (xy 96.254049 109.342377) (xy 96.261961 109.42776) (xy 96.277717 109.51205)
			(xy 96.301184 109.594526) (xy 96.33216 109.674485) (xy 96.370382 109.751245) (xy 96.415523 109.824151)
			(xy 96.467199 109.89258) (xy 96.524968 109.95595) (xy 96.588338 110.013719) (xy 96.656767 110.065395)
			(xy 96.729673 110.110536) (xy 96.806433 110.148758) (xy 96.886392 110.179734) (xy 96.968868 110.203201)
			(xy 97.053158 110.218957) (xy 97.138541 110.226869) (xy 97.224291 110.226869) (xy 97.309674 110.218957)
			(xy 97.393964 110.203201) (xy 97.47644 110.179734) (xy 97.556399 110.148758) (xy 97.633159 110.110536)
			(xy 97.706065 110.065395) (xy 97.774494 110.013719) (xy 97.837864 109.95595) (xy 97.895633 109.89258)
			(xy 97.947309 109.824151) (xy 97.99245 109.751245) (xy 98.030672 109.674485) (xy 98.061648 109.594526)
			(xy 98.085115 109.51205) (xy 98.100871 109.42776) (xy 98.108783 109.342377) (xy 98.109278 109.299502)
			(xy 98.108783 109.256627) (xy 98.100871 109.171244) (xy 98.085115 109.086954) (xy 98.061648 109.004478)
			(xy 98.030672 108.924519) (xy 97.99245 108.847759) (xy 97.947309 108.774853) (xy 97.895633 108.706424)
			(xy 97.837864 108.643054) (xy 97.774494 108.585285) (xy 97.706065 108.533609) (xy 97.633159 108.488468)
			(xy 97.556399 108.450246) (xy 97.47644 108.41927) (xy 97.393964 108.395803) (xy 97.309674 108.380047)
			(xy 97.224291 108.372135) (xy 97.138541 108.372135) (xy 97.053158 108.380047) (xy 96.968868 108.395803)
			(xy 96.886392 108.41927) (xy 96.806433 108.450246) (xy 96.729673 108.488468) (xy 96.656767 108.533609)
			(xy 96.588338 108.585285) (xy 96.524968 108.643054) (xy 96.467199 108.706424) (xy 96.415523 108.774853)
			(xy 96.370382 108.847759) (xy 96.33216 108.924519) (xy 96.301184 109.004478) (xy 96.277717 109.086954)
			(xy 96.261961 109.171244) (xy 96.254049 109.256627) (xy 95.568783 109.256627) (xy 95.560871 109.171244)
			(xy 95.545115 109.086954) (xy 95.521648 109.004478) (xy 95.490672 108.924519) (xy 95.45245 108.847759)
			(xy 95.407309 108.774853) (xy 95.355633 108.706424) (xy 95.297864 108.643054) (xy 95.234494 108.585285)
			(xy 95.166065 108.533609) (xy 95.093159 108.488468) (xy 95.016399 108.450246) (xy 94.93644 108.41927)
			(xy 94.853964 108.395803) (xy 94.769674 108.380047) (xy 94.684291 108.372135) (xy 94.598541 108.372135)
			(xy 94.513158 108.380047) (xy 94.428868 108.395803) (xy 94.346392 108.41927) (xy 94.266433 108.450246)
			(xy 94.189673 108.488468) (xy 94.116767 108.533609) (xy 94.048338 108.585285) (xy 93.984968 108.643054)
			(xy 93.927199 108.706424) (xy 93.875523 108.774853) (xy 93.830382 108.847759) (xy 93.79216 108.924519)
			(xy 93.761184 109.004478) (xy 93.737717 109.086954) (xy 93.721961 109.171244) (xy 93.714049 109.256627)
			(xy 92.50807 109.256627) (xy 92.50807 56.800039) (xy 93.729289 56.800039) (xy 93.729289 56.885789)
			(xy 93.737201 56.971172) (xy 93.752957 57.055462) (xy 93.776424 57.137938) (xy 93.8074 57.217897)
			(xy 93.845622 57.294657) (xy 93.890763 57.367563) (xy 93.942439 57.435992) (xy 94.000208 57.499362)
			(xy 94.063578 57.557131) (xy 94.132007 57.608807) (xy 94.204913 57.653948) (xy 94.281673 57.69217)
			(xy 94.361632 57.723146) (xy 94.444108 57.746613) (xy 94.528398 57.762369) (xy 94.613781 57.770281)
			(xy 94.699531 57.770281) (xy 94.784914 57.762369) (xy 94.869204 57.746613) (xy 94.95168 57.723146)
			(xy 95.031639 57.69217) (xy 95.108399 57.653948) (xy 95.181305 57.608807) (xy 95.249734 57.557131)
			(xy 95.313104 57.499362) (xy 95.370873 57.435992) (xy 95.422549 57.367563) (xy 95.46769 57.294657)
			(xy 95.505912 57.217897) (xy 95.536888 57.137938) (xy 95.560355 57.055462) (xy 95.576111 56.971172)
			(xy 95.584023 56.885789) (xy 95.584518 56.842914) (xy 95.584023 56.800039) (xy 96.269289 56.800039)
			(xy 96.269289 56.885789) (xy 96.277201 56.971172) (xy 96.292957 57.055462) (xy 96.316424 57.137938)
			(xy 96.3474 57.217897) (xy 96.385622 57.294657) (xy 96.430763 57.367563) (xy 96.482439 57.435992)
			(xy 96.540208 57.499362) (xy 96.603578 57.557131) (xy 96.672007 57.608807) (xy 96.744913 57.653948)
			(xy 96.821673 57.69217) (xy 96.901632 57.723146) (xy 96.984108 57.746613) (xy 97.068398 57.762369)
			(xy 97.153781 57.770281) (xy 97.239531 57.770281) (xy 97.324914 57.762369) (xy 97.409204 57.746613)
			(xy 97.49168 57.723146) (xy 97.571639 57.69217) (xy 97.648399 57.653948) (xy 97.721305 57.608807)
			(xy 97.789734 57.557131) (xy 97.853104 57.499362) (xy 97.910873 57.435992) (xy 97.962549 57.367563)
			(xy 98.00769 57.294657) (xy 98.045912 57.217897) (xy 98.076888 57.137938) (xy 98.100355 57.055462)
			(xy 98.116111 56.971172) (xy 98.124023 56.885789) (xy 98.124518 56.842914) (xy 98.124023 56.800039)
			(xy 98.116111 56.714656) (xy 98.100355 56.630366) (xy 98.076888 56.54789) (xy 98.045912 56.467931)
			(xy 98.00769 56.391171) (xy 97.962549 56.318265) (xy 97.910873 56.249836) (xy 97.853104 56.186466)
			(xy 97.789734 56.128697) (xy 97.721305 56.077021) (xy 97.648399 56.03188) (xy 97.571639 55.993658)
			(xy 97.49168 55.962682) (xy 97.409204 55.939215) (xy 97.324914 55.923459) (xy 97.239531 55.915547)
			(xy 97.153781 55.915547) (xy 97.068398 55.923459) (xy 96.984108 55.939215) (xy 96.901632 55.962682)
			(xy 96.821673 55.993658) (xy 96.744913 56.03188) (xy 96.672007 56.077021) (xy 96.603578 56.128697)
			(xy 96.540208 56.186466) (xy 96.482439 56.249836) (xy 96.430763 56.318265) (xy 96.385622 56.391171)
			(xy 96.3474 56.467931) (xy 96.316424 56.54789) (xy 96.292957 56.630366) (xy 96.277201 56.714656)
			(xy 96.269289 56.800039) (xy 95.584023 56.800039) (xy 95.576111 56.714656) (xy 95.560355 56.630366)
			(xy 95.536888 56.54789) (xy 95.505912 56.467931) (xy 95.46769 56.391171) (xy 95.422549 56.318265)
			(xy 95.370873 56.249836) (xy 95.313104 56.186466) (xy 95.249734 56.128697) (xy 95.181305 56.077021)
			(xy 95.108399 56.03188) (xy 95.031639 55.993658) (xy 94.95168 55.962682) (xy 94.869204 55.939215)
			(xy 94.784914 55.923459) (xy 94.699531 55.915547) (xy 94.613781 55.915547) (xy 94.528398 55.923459)
			(xy 94.444108 55.939215) (xy 94.361632 55.962682) (xy 94.281673 55.993658) (xy 94.204913 56.03188)
			(xy 94.132007 56.077021) (xy 94.063578 56.128697) (xy 94.000208 56.186466) (xy 93.942439 56.249836)
			(xy 93.890763 56.318265) (xy 93.845622 56.391171) (xy 93.8074 56.467931) (xy 93.776424 56.54789)
			(xy 93.752957 56.630366) (xy 93.737201 56.714656) (xy 93.729289 56.800039) (xy 92.50807 56.800039)
			(xy 92.50807 54.826334) (xy 95.113638 54.826334) (xy 95.113638 54.880866) (xy 95.121398 54.934844)
			(xy 95.136761 54.987168) (xy 95.159413 55.036774) (xy 95.188894 55.082651) (xy 95.224603 55.123866)
			(xy 95.265814 55.15958) (xy 95.311688 55.189066) (xy 95.36129 55.211724) (xy 95.413613 55.227092)
			(xy 95.46759 55.234859) (xy 95.494856 55.235348) (xy 96.358456 55.235348) (xy 96.38573 55.234915)
			(xy 96.439724 55.227158) (xy 96.492064 55.211795) (xy 96.541684 55.189139) (xy 96.587575 55.159652)
			(xy 96.628802 55.123933) (xy 96.664525 55.08271) (xy 96.694018 55.036823) (xy 96.71668 54.987205)
			(xy 96.732049 54.934867) (xy 96.739812 54.880874) (xy 96.739812 54.826326) (xy 96.732049 54.772333)
			(xy 96.71668 54.719995) (xy 96.694018 54.670377) (xy 96.664525 54.62449) (xy 96.628802 54.583267)
			(xy 96.587575 54.547548) (xy 96.541684 54.518061) (xy 96.492064 54.495405) (xy 96.439724 54.480042)
			(xy 96.38573 54.472285) (xy 96.358456 54.471824) (xy 95.494856 54.471824) (xy 95.46759 54.472341)
			(xy 95.413613 54.480108) (xy 95.36129 54.495476) (xy 95.311688 54.518134) (xy 95.265814 54.54762)
			(xy 95.224603 54.583334) (xy 95.188894 54.624549) (xy 95.159413 54.670426) (xy 95.136761 54.720032)
			(xy 95.121399 54.772356) (xy 95.113638 54.826334) (xy 92.50807 54.826334) (xy 92.50807 50.450039)
			(xy 93.729289 50.450039) (xy 93.729289 50.535789) (xy 93.737201 50.621172) (xy 93.752957 50.705462)
			(xy 93.776424 50.787938) (xy 93.8074 50.867897) (xy 93.845622 50.944657) (xy 93.890763 51.017563)
			(xy 93.942439 51.085992) (xy 94.000208 51.149362) (xy 94.063578 51.207131) (xy 94.132007 51.258807)
			(xy 94.204913 51.303948) (xy 94.281673 51.34217) (xy 94.361632 51.373146) (xy 94.444108 51.396613)
			(xy 94.528398 51.412369) (xy 94.613781 51.420281) (xy 94.699531 51.420281) (xy 94.784914 51.412369)
			(xy 94.869204 51.396613) (xy 94.95168 51.373146) (xy 95.031639 51.34217) (xy 95.108399 51.303948)
			(xy 95.181305 51.258807) (xy 95.249734 51.207131) (xy 95.313104 51.149362) (xy 95.370873 51.085992)
			(xy 95.422549 51.017563) (xy 95.46769 50.944657) (xy 95.505912 50.867897) (xy 95.536888 50.787938)
			(xy 95.560355 50.705462) (xy 95.576111 50.621172) (xy 95.584023 50.535789) (xy 95.584518 50.492914)
			(xy 95.584023 50.450039) (xy 96.269289 50.450039) (xy 96.269289 50.535789) (xy 96.277201 50.621172)
			(xy 96.292957 50.705462) (xy 96.316424 50.787938) (xy 96.3474 50.867897) (xy 96.385622 50.944657)
			(xy 96.430763 51.017563) (xy 96.482439 51.085992) (xy 96.540208 51.149362) (xy 96.603578 51.207131)
			(xy 96.672007 51.258807) (xy 96.744913 51.303948) (xy 96.821673 51.34217) (xy 96.901632 51.373146)
			(xy 96.984108 51.396613) (xy 97.068398 51.412369) (xy 97.153781 51.420281) (xy 97.239531 51.420281)
			(xy 97.324914 51.412369) (xy 97.409204 51.396613) (xy 97.49168 51.373146) (xy 97.571639 51.34217)
			(xy 97.648399 51.303948) (xy 97.721305 51.258807) (xy 97.789734 51.207131) (xy 97.853104 51.149362)
			(xy 97.910873 51.085992) (xy 97.962549 51.017563) (xy 98.00769 50.944657) (xy 98.045912 50.867897)
			(xy 98.076888 50.787938) (xy 98.100355 50.705462) (xy 98.116111 50.621172) (xy 98.124023 50.535789)
			(xy 98.124518 50.492914) (xy 98.124023 50.450039) (xy 98.116111 50.364656) (xy 98.100355 50.280366)
			(xy 98.076888 50.19789) (xy 98.045912 50.117931) (xy 98.00769 50.041171) (xy 97.962549 49.968265)
			(xy 97.910873 49.899836) (xy 97.853104 49.836466) (xy 97.789734 49.778697) (xy 97.721305 49.727021)
			(xy 97.648399 49.68188) (xy 97.571639 49.643658) (xy 97.49168 49.612682) (xy 97.409204 49.589215)
			(xy 97.324914 49.573459) (xy 97.239531 49.565547) (xy 97.153781 49.565547) (xy 97.068398 49.573459)
			(xy 96.984108 49.589215) (xy 96.901632 49.612682) (xy 96.821673 49.643658) (xy 96.744913 49.68188)
			(xy 96.672007 49.727021) (xy 96.603578 49.778697) (xy 96.540208 49.836466) (xy 96.482439 49.899836)
			(xy 96.430763 49.968265) (xy 96.385622 50.041171) (xy 96.3474 50.117931) (xy 96.316424 50.19789)
			(xy 96.292957 50.280366) (xy 96.277201 50.364656) (xy 96.269289 50.450039) (xy 95.584023 50.450039)
			(xy 95.576111 50.364656) (xy 95.560355 50.280366) (xy 95.536888 50.19789) (xy 95.505912 50.117931)
			(xy 95.46769 50.041171) (xy 95.422549 49.968265) (xy 95.370873 49.899836) (xy 95.313104 49.836466)
			(xy 95.249734 49.778697) (xy 95.181305 49.727021) (xy 95.108399 49.68188) (xy 95.031639 49.643658)
			(xy 94.95168 49.612682) (xy 94.869204 49.589215) (xy 94.784914 49.573459) (xy 94.699531 49.565547)
			(xy 94.613781 49.565547) (xy 94.528398 49.573459) (xy 94.444108 49.589215) (xy 94.361632 49.612682)
			(xy 94.281673 49.643658) (xy 94.204913 49.68188) (xy 94.132007 49.727021) (xy 94.063578 49.778697)
			(xy 94.000208 49.836466) (xy 93.942439 49.899836) (xy 93.890763 49.968265) (xy 93.845622 50.041171)
			(xy 93.8074 50.117931) (xy 93.776424 50.19789) (xy 93.752957 50.280366) (xy 93.737201 50.364656)
			(xy 93.729289 50.450039) (xy 92.50807 50.450039) (xy 92.50807 44.925539) (xy 93.706937 44.925539)
			(xy 93.706937 45.011289) (xy 93.714849 45.096672) (xy 93.730605 45.180962) (xy 93.754072 45.263438)
			(xy 93.785048 45.343397) (xy 93.82327 45.420157) (xy 93.868411 45.493063) (xy 93.920087 45.561492)
			(xy 93.977856 45.624862) (xy 94.041226 45.682631) (xy 94.109655 45.734307) (xy 94.182561 45.779448)
			(xy 94.259321 45.81767) (xy 94.33928 45.848646) (xy 94.421756 45.872113) (xy 94.506046 45.887869)
			(xy 94.591429 45.895781) (xy 94.677179 45.895781) (xy 94.762562 45.887869) (xy 94.846852 45.872113)
			(xy 94.929328 45.848646) (xy 95.009287 45.81767) (xy 95.086047 45.779448) (xy 95.158953 45.734307)
			(xy 95.227382 45.682631) (xy 95.290752 45.624862) (xy 95.348521 45.561492) (xy 95.400197 45.493063)
			(xy 95.445338 45.420157) (xy 95.48356 45.343397) (xy 95.514536 45.263438) (xy 95.538003 45.180962)
			(xy 95.553759 45.096672) (xy 95.561671 45.011289) (xy 95.562166 44.968414) (xy 95.561671 44.925539)
			(xy 96.246937 44.925539) (xy 96.246937 45.011289) (xy 96.254849 45.096672) (xy 96.270605 45.180962)
			(xy 96.294072 45.263438) (xy 96.325048 45.343397) (xy 96.36327 45.420157) (xy 96.408411 45.493063)
			(xy 96.460087 45.561492) (xy 96.517856 45.624862) (xy 96.581226 45.682631) (xy 96.649655 45.734307)
			(xy 96.722561 45.779448) (xy 96.799321 45.81767) (xy 96.87928 45.848646) (xy 96.961756 45.872113)
			(xy 97.046046 45.887869) (xy 97.131429 45.895781) (xy 97.217179 45.895781) (xy 97.302562 45.887869)
			(xy 97.386852 45.872113) (xy 97.469328 45.848646) (xy 97.549287 45.81767) (xy 97.626047 45.779448)
			(xy 97.698953 45.734307) (xy 97.767382 45.682631) (xy 97.830752 45.624862) (xy 97.888521 45.561492)
			(xy 97.940197 45.493063) (xy 97.985338 45.420157) (xy 98.02356 45.343397) (xy 98.054536 45.263438)
			(xy 98.078003 45.180962) (xy 98.093759 45.096672) (xy 98.101671 45.011289) (xy 98.102166 44.968414)
			(xy 98.101671 44.925539) (xy 98.093759 44.840156) (xy 98.078003 44.755866) (xy 98.054536 44.67339)
			(xy 98.02356 44.593431) (xy 97.985338 44.516671) (xy 97.940197 44.443765) (xy 97.888521 44.375336)
			(xy 97.830752 44.311966) (xy 97.767382 44.254197) (xy 97.698953 44.202521) (xy 97.626047 44.15738)
			(xy 97.549287 44.119158) (xy 97.469328 44.088182) (xy 97.386852 44.064715) (xy 97.302562 44.048959)
			(xy 97.217179 44.041047) (xy 97.131429 44.041047) (xy 97.046046 44.048959) (xy 96.961756 44.064715)
			(xy 96.87928 44.088182) (xy 96.799321 44.119158) (xy 96.722561 44.15738) (xy 96.649655 44.202521)
			(xy 96.581226 44.254197) (xy 96.517856 44.311966) (xy 96.460087 44.375336) (xy 96.408411 44.443765)
			(xy 96.36327 44.516671) (xy 96.325048 44.593431) (xy 96.294072 44.67339) (xy 96.270605 44.755866)
			(xy 96.254849 44.840156) (xy 96.246937 44.925539) (xy 95.561671 44.925539) (xy 95.553759 44.840156)
			(xy 95.538003 44.755866) (xy 95.514536 44.67339) (xy 95.48356 44.593431) (xy 95.445338 44.516671)
			(xy 95.400197 44.443765) (xy 95.348521 44.375336) (xy 95.290752 44.311966) (xy 95.227382 44.254197)
			(xy 95.158953 44.202521) (xy 95.086047 44.15738) (xy 95.009287 44.119158) (xy 94.929328 44.088182)
			(xy 94.846852 44.064715) (xy 94.762562 44.048959) (xy 94.677179 44.041047) (xy 94.591429 44.041047)
			(xy 94.506046 44.048959) (xy 94.421756 44.064715) (xy 94.33928 44.088182) (xy 94.259321 44.119158)
			(xy 94.182561 44.15738) (xy 94.109655 44.202521) (xy 94.041226 44.254197) (xy 93.977856 44.311966)
			(xy 93.920087 44.375336) (xy 93.868411 44.443765) (xy 93.82327 44.516671) (xy 93.785048 44.593431)
			(xy 93.754072 44.67339) (xy 93.730605 44.755866) (xy 93.714849 44.840156) (xy 93.706937 44.925539)
			(xy 92.50807 44.925539) (xy 92.50807 40.580426) (xy 95.09116 40.580426) (xy 95.09116 40.634974) (xy 95.098923 40.688967)
			(xy 95.114291 40.741306) (xy 95.136951 40.790925) (xy 95.166442 40.836814) (xy 95.202164 40.878039)
			(xy 95.243389 40.91376) (xy 95.289279 40.943251) (xy 95.338898 40.965911) (xy 95.391237 40.981278)
			(xy 95.44523 40.989041) (xy 95.472504 40.989504) (xy 96.336104 40.989504) (xy 96.36337 40.988933)
			(xy 96.417347 40.981172) (xy 96.469671 40.965808) (xy 96.519275 40.943154) (xy 96.56515 40.913671)
			(xy 96.606363 40.87796) (xy 96.642074 40.836747) (xy 96.671556 40.790871) (xy 96.69421 40.741267)
			(xy 96.709573 40.688944) (xy 96.717334 40.634966) (xy 96.717334 40.580434) (xy 96.709573 40.526456)
			(xy 96.69421 40.474133) (xy 96.671556 40.424529) (xy 96.642074 40.378653) (xy 96.606363 40.33744)
			(xy 96.56515 40.301729) (xy 96.519275 40.272246) (xy 96.469671 40.249592) (xy 96.417347 40.234228)
			(xy 96.36337 40.226467) (xy 96.336104 40.22598) (xy 95.472504 40.22598) (xy 95.44523 40.226359) (xy 95.391237 40.234122)
			(xy 95.338898 40.249489) (xy 95.289279 40.272149) (xy 95.243389 40.30164) (xy 95.202164 40.337361)
			(xy 95.166442 40.378586) (xy 95.136951 40.424475) (xy 95.114291 40.474094) (xy 95.098923 40.526433)
			(xy 95.09116 40.580426) (xy 92.50807 40.580426) (xy 92.50807 38.575539) (xy 93.706937 38.575539)
			(xy 93.706937 38.661289) (xy 93.714849 38.746672) (xy 93.730605 38.830962) (xy 93.754072 38.913438)
			(xy 93.785048 38.993397) (xy 93.82327 39.070157) (xy 93.868411 39.143063) (xy 93.920087 39.211492)
			(xy 93.977856 39.274862) (xy 94.041226 39.332631) (xy 94.109655 39.384307) (xy 94.182561 39.429448)
			(xy 94.259321 39.46767) (xy 94.33928 39.498646) (xy 94.421756 39.522113) (xy 94.506046 39.537869)
			(xy 94.591429 39.545781) (xy 94.677179 39.545781) (xy 94.762562 39.537869) (xy 94.846852 39.522113)
			(xy 94.929328 39.498646) (xy 95.009287 39.46767) (xy 95.086047 39.429448) (xy 95.158953 39.384307)
			(xy 95.227382 39.332631) (xy 95.290752 39.274862) (xy 95.348521 39.211492) (xy 95.400197 39.143063)
			(xy 95.445338 39.070157) (xy 95.48356 38.993397) (xy 95.514536 38.913438) (xy 95.538003 38.830962)
			(xy 95.553759 38.746672) (xy 95.561671 38.661289) (xy 95.562166 38.618414) (xy 95.561671 38.575539)
			(xy 96.246937 38.575539) (xy 96.246937 38.661289) (xy 96.254849 38.746672) (xy 96.270605 38.830962)
			(xy 96.294072 38.913438) (xy 96.325048 38.993397) (xy 96.36327 39.070157) (xy 96.408411 39.143063)
			(xy 96.460087 39.211492) (xy 96.517856 39.274862) (xy 96.581226 39.332631) (xy 96.649655 39.384307)
			(xy 96.722561 39.429448) (xy 96.799321 39.46767) (xy 96.87928 39.498646) (xy 96.961756 39.522113)
			(xy 97.046046 39.537869) (xy 97.131429 39.545781) (xy 97.217179 39.545781) (xy 97.302562 39.537869)
			(xy 97.386852 39.522113) (xy 97.469328 39.498646) (xy 97.549287 39.46767) (xy 97.626047 39.429448)
			(xy 97.698953 39.384307) (xy 97.767382 39.332631) (xy 97.830752 39.274862) (xy 97.888521 39.211492)
			(xy 97.940197 39.143063) (xy 97.985338 39.070157) (xy 98.02356 38.993397) (xy 98.054536 38.913438)
			(xy 98.078003 38.830962) (xy 98.093759 38.746672) (xy 98.101671 38.661289) (xy 98.102166 38.618414)
			(xy 98.101671 38.575539) (xy 98.093759 38.490156) (xy 98.078003 38.405866) (xy 98.054536 38.32339)
			(xy 98.02356 38.243431) (xy 97.985338 38.166671) (xy 97.940197 38.093765) (xy 97.888521 38.025336)
			(xy 97.830752 37.961966) (xy 97.767382 37.904197) (xy 97.698953 37.852521) (xy 97.626047 37.80738)
			(xy 97.549287 37.769158) (xy 97.469328 37.738182) (xy 97.386852 37.714715) (xy 97.302562 37.698959)
			(xy 97.217179 37.691047) (xy 97.131429 37.691047) (xy 97.046046 37.698959) (xy 96.961756 37.714715)
			(xy 96.87928 37.738182) (xy 96.799321 37.769158) (xy 96.722561 37.80738) (xy 96.649655 37.852521)
			(xy 96.581226 37.904197) (xy 96.517856 37.961966) (xy 96.460087 38.025336) (xy 96.408411 38.093765)
			(xy 96.36327 38.166671) (xy 96.325048 38.243431) (xy 96.294072 38.32339) (xy 96.270605 38.405866)
			(xy 96.254849 38.490156) (xy 96.246937 38.575539) (xy 95.561671 38.575539) (xy 95.553759 38.490156)
			(xy 95.538003 38.405866) (xy 95.514536 38.32339) (xy 95.48356 38.243431) (xy 95.445338 38.166671)
			(xy 95.400197 38.093765) (xy 95.348521 38.025336) (xy 95.290752 37.961966) (xy 95.227382 37.904197)
			(xy 95.158953 37.852521) (xy 95.086047 37.80738) (xy 95.009287 37.769158) (xy 94.929328 37.738182)
			(xy 94.846852 37.714715) (xy 94.762562 37.698959) (xy 94.677179 37.691047) (xy 94.591429 37.691047)
			(xy 94.506046 37.698959) (xy 94.421756 37.714715) (xy 94.33928 37.738182) (xy 94.259321 37.769158)
			(xy 94.182561 37.80738) (xy 94.109655 37.852521) (xy 94.041226 37.904197) (xy 93.977856 37.961966)
			(xy 93.920087 38.025336) (xy 93.868411 38.093765) (xy 93.82327 38.166671) (xy 93.785048 38.243431)
			(xy 93.754072 38.32339) (xy 93.730605 38.405866) (xy 93.714849 38.490156) (xy 93.706937 38.575539)
			(xy 92.50807 38.575539) (xy 92.50807 32.685787) (xy 99.092753 32.685787) (xy 99.092753 32.771537)
			(xy 99.100665 32.85692) (xy 99.116421 32.94121) (xy 99.139888 33.023686) (xy 99.170864 33.103645)
			(xy 99.209086 33.180405) (xy 99.254227 33.253311) (xy 99.305903 33.32174) (xy 99.363672 33.38511)
			(xy 99.427042 33.442879) (xy 99.495471 33.494555) (xy 99.568377 33.539696) (xy 99.645137 33.577918)
			(xy 99.725096 33.608894) (xy 99.807572 33.632361) (xy 99.891862 33.648117) (xy 99.977245 33.656029)
			(xy 100.062995 33.656029) (xy 100.148378 33.648117) (xy 100.232668 33.632361) (xy 100.315144 33.608894)
			(xy 100.395103 33.577918) (xy 100.471863 33.539696) (xy 100.544769 33.494555) (xy 100.613198 33.442879)
			(xy 100.676568 33.38511) (xy 100.734337 33.32174) (xy 100.786013 33.253311) (xy 100.831154 33.180405)
			(xy 100.869376 33.103645) (xy 100.900352 33.023686) (xy 100.923819 32.94121) (xy 100.939575 32.85692)
			(xy 100.947487 32.771537) (xy 100.947982 32.728662) (xy 100.947487 32.685787) (xy 101.632753 32.685787)
			(xy 101.632753 32.771537) (xy 101.640665 32.85692) (xy 101.656421 32.94121) (xy 101.679888 33.023686)
			(xy 101.710864 33.103645) (xy 101.749086 33.180405) (xy 101.794227 33.253311) (xy 101.845903 33.32174)
			(xy 101.903672 33.38511) (xy 101.967042 33.442879) (xy 102.035471 33.494555) (xy 102.108377 33.539696)
			(xy 102.185137 33.577918) (xy 102.265096 33.608894) (xy 102.347572 33.632361) (xy 102.431862 33.648117)
			(xy 102.517245 33.656029) (xy 102.602995 33.656029) (xy 102.688378 33.648117) (xy 102.772668 33.632361)
			(xy 102.855144 33.608894) (xy 102.935103 33.577918) (xy 103.011863 33.539696) (xy 103.084769 33.494555)
			(xy 103.153198 33.442879) (xy 103.216568 33.38511) (xy 103.274337 33.32174) (xy 103.326013 33.253311)
			(xy 103.371154 33.180405) (xy 103.409376 33.103645) (xy 103.440352 33.023686) (xy 103.463819 32.94121)
			(xy 103.479575 32.85692) (xy 103.487487 32.771537) (xy 103.487982 32.728662) (xy 103.487487 32.685787)
			(xy 103.479575 32.600404) (xy 103.463819 32.516114) (xy 103.440352 32.433638) (xy 103.409376 32.353679)
			(xy 103.371154 32.276919) (xy 103.326013 32.204013) (xy 103.274337 32.135584) (xy 103.216568 32.072214)
			(xy 103.153198 32.014445) (xy 103.084769 31.962769) (xy 103.011863 31.917628) (xy 102.935103 31.879406)
			(xy 102.855144 31.84843) (xy 102.772668 31.824963) (xy 102.688378 31.809207) (xy 102.602995 31.801295)
			(xy 102.517245 31.801295) (xy 102.431862 31.809207) (xy 102.347572 31.824963) (xy 102.265096 31.84843)
			(xy 102.185137 31.879406) (xy 102.108377 31.917628) (xy 102.035471 31.962769) (xy 101.967042 32.014445)
			(xy 101.903672 32.072214) (xy 101.845903 32.135584) (xy 101.794227 32.204013) (xy 101.749086 32.276919)
			(xy 101.710864 32.353679) (xy 101.679888 32.433638) (xy 101.656421 32.516114) (xy 101.640665 32.600404)
			(xy 101.632753 32.685787) (xy 100.947487 32.685787) (xy 100.939575 32.600404) (xy 100.923819 32.516114)
			(xy 100.900352 32.433638) (xy 100.869376 32.353679) (xy 100.831154 32.276919) (xy 100.786013 32.204013)
			(xy 100.734337 32.135584) (xy 100.676568 32.072214) (xy 100.613198 32.014445) (xy 100.544769 31.962769)
			(xy 100.471863 31.917628) (xy 100.395103 31.879406) (xy 100.315144 31.84843) (xy 100.232668 31.824963)
			(xy 100.148378 31.809207) (xy 100.062995 31.801295) (xy 99.977245 31.801295) (xy 99.891862 31.809207)
			(xy 99.807572 31.824963) (xy 99.725096 31.84843) (xy 99.645137 31.879406) (xy 99.568377 31.917628)
			(xy 99.495471 31.962769) (xy 99.427042 32.014445) (xy 99.363672 32.072214) (xy 99.305903 32.135584)
			(xy 99.254227 32.204013) (xy 99.209086 32.276919) (xy 99.170864 32.353679) (xy 99.139888 32.433638)
			(xy 99.116421 32.516114) (xy 99.100665 32.600404) (xy 99.092753 32.685787) (xy 92.50807 32.685787)
			(xy 92.50807 30.712026) (xy 100.476968 30.712026) (xy 100.476968 30.766574) (xy 100.484731 30.820568)
			(xy 100.5001 30.872907) (xy 100.522761 30.922526) (xy 100.552253 30.968414) (xy 100.587976 31.009639)
			(xy 100.629202 31.045359) (xy 100.675092 31.074849) (xy 100.724712 31.097507) (xy 100.777052 31.112873)
			(xy 100.831046 31.120634) (xy 100.85832 31.121096) (xy 101.72192 31.121096) (xy 101.749186 31.12054)
			(xy 101.803163 31.112777) (xy 101.855485 31.097411) (xy 101.905088 31.074756) (xy 101.950963 31.045272)
			(xy 101.992174 31.00956) (xy 102.027884 30.968347) (xy 102.057366 30.922471) (xy 102.080018 30.872866)
			(xy 102.095381 30.820543) (xy 102.103142 30.766566) (xy 102.103142 30.712034) (xy 102.095381 30.658057)
			(xy 102.080018 30.605734) (xy 102.057366 30.556129) (xy 102.027884 30.510253) (xy 101.992174 30.46904)
			(xy 101.950963 30.433328) (xy 101.905088 30.403844) (xy 101.855485 30.381189) (xy 101.803163 30.365823)
			(xy 101.749186 30.35806) (xy 101.72192 30.357572) (xy 100.85832 30.357572) (xy 100.831046 30.357966)
			(xy 100.777052 30.365727) (xy 100.724712 30.381093) (xy 100.675092 30.403751) (xy 100.629202 30.433241)
			(xy 100.587976 30.468961) (xy 100.552253 30.510186) (xy 100.522761 30.556074) (xy 100.5001 30.605693)
			(xy 100.484731 30.658032) (xy 100.476968 30.712026) (xy 92.50807 30.712026) (xy 92.50807 26.335787)
			(xy 99.092753 26.335787) (xy 99.092753 26.421537) (xy 99.100665 26.50692) (xy 99.116421 26.59121)
			(xy 99.139888 26.673686) (xy 99.170864 26.753645) (xy 99.209086 26.830405) (xy 99.254227 26.903311)
			(xy 99.305903 26.97174) (xy 99.363672 27.03511) (xy 99.427042 27.092879) (xy 99.495471 27.144555)
			(xy 99.568377 27.189696) (xy 99.645137 27.227918) (xy 99.725096 27.258894) (xy 99.807572 27.282361)
			(xy 99.891862 27.298117) (xy 99.977245 27.306029) (xy 100.062995 27.306029) (xy 100.148378 27.298117)
			(xy 100.232668 27.282361) (xy 100.315144 27.258894) (xy 100.395103 27.227918) (xy 100.471863 27.189696)
			(xy 100.544769 27.144555) (xy 100.613198 27.092879) (xy 100.676568 27.03511) (xy 100.734337 26.97174)
			(xy 100.786013 26.903311) (xy 100.831154 26.830405) (xy 100.869376 26.753645) (xy 100.900352 26.673686)
			(xy 100.923819 26.59121) (xy 100.939575 26.50692) (xy 100.947487 26.421537) (xy 100.947982 26.378662)
			(xy 100.947487 26.335787) (xy 101.632753 26.335787) (xy 101.632753 26.421537) (xy 101.640665 26.50692)
			(xy 101.656421 26.59121) (xy 101.679888 26.673686) (xy 101.710864 26.753645) (xy 101.749086 26.830405)
			(xy 101.794227 26.903311) (xy 101.845903 26.97174) (xy 101.903672 27.03511) (xy 101.967042 27.092879)
			(xy 102.035471 27.144555) (xy 102.108377 27.189696) (xy 102.185137 27.227918) (xy 102.265096 27.258894)
			(xy 102.347572 27.282361) (xy 102.431862 27.298117) (xy 102.517245 27.306029) (xy 102.602995 27.306029)
			(xy 102.688378 27.298117) (xy 102.772668 27.282361) (xy 102.855144 27.258894) (xy 102.935103 27.227918)
			(xy 103.011863 27.189696) (xy 103.084769 27.144555) (xy 103.153198 27.092879) (xy 103.216568 27.03511)
			(xy 103.274337 26.97174) (xy 103.326013 26.903311) (xy 103.371154 26.830405) (xy 103.409376 26.753645)
			(xy 103.440352 26.673686) (xy 103.463819 26.59121) (xy 103.479575 26.50692) (xy 103.487487 26.421537)
			(xy 103.487982 26.378662) (xy 103.487487 26.335787) (xy 103.479575 26.250404) (xy 103.463819 26.166114)
			(xy 103.440352 26.083638) (xy 103.409376 26.003679) (xy 103.371154 25.926919) (xy 103.326013 25.854013)
			(xy 103.274337 25.785584) (xy 103.216568 25.722214) (xy 103.153198 25.664445) (xy 103.084769 25.612769)
			(xy 103.011863 25.567628) (xy 102.935103 25.529406) (xy 102.855144 25.49843) (xy 102.772668 25.474963)
			(xy 102.688378 25.459207) (xy 102.602995 25.451295) (xy 102.517245 25.451295) (xy 102.431862 25.459207)
			(xy 102.347572 25.474963) (xy 102.265096 25.49843) (xy 102.185137 25.529406) (xy 102.108377 25.567628)
			(xy 102.035471 25.612769) (xy 101.967042 25.664445) (xy 101.903672 25.722214) (xy 101.845903 25.785584)
			(xy 101.794227 25.854013) (xy 101.749086 25.926919) (xy 101.710864 26.003679) (xy 101.679888 26.083638)
			(xy 101.656421 26.166114) (xy 101.640665 26.250404) (xy 101.632753 26.335787) (xy 100.947487 26.335787)
			(xy 100.939575 26.250404) (xy 100.923819 26.166114) (xy 100.900352 26.083638) (xy 100.869376 26.003679)
			(xy 100.831154 25.926919) (xy 100.786013 25.854013) (xy 100.734337 25.785584) (xy 100.676568 25.722214)
			(xy 100.613198 25.664445) (xy 100.544769 25.612769) (xy 100.471863 25.567628) (xy 100.395103 25.529406)
			(xy 100.315144 25.49843) (xy 100.232668 25.474963) (xy 100.148378 25.459207) (xy 100.062995 25.451295)
			(xy 99.977245 25.451295) (xy 99.891862 25.459207) (xy 99.807572 25.474963) (xy 99.725096 25.49843)
			(xy 99.645137 25.529406) (xy 99.568377 25.567628) (xy 99.495471 25.612769) (xy 99.427042 25.664445)
			(xy 99.363672 25.722214) (xy 99.305903 25.785584) (xy 99.254227 25.854013) (xy 99.209086 25.926919)
			(xy 99.170864 26.003679) (xy 99.139888 26.083638) (xy 99.116421 26.166114) (xy 99.100665 26.250404)
			(xy 99.092753 26.335787) (xy 92.50807 26.335787) (xy 92.50807 20.841513) (xy 99.085133 20.841513)
			(xy 99.085133 20.927263) (xy 99.093045 21.012646) (xy 99.108801 21.096936) (xy 99.132268 21.179412)
			(xy 99.163244 21.259371) (xy 99.201466 21.336131) (xy 99.246607 21.409037) (xy 99.298283 21.477466)
			(xy 99.356052 21.540836) (xy 99.419422 21.598605) (xy 99.487851 21.650281) (xy 99.560757 21.695422)
			(xy 99.637517 21.733644) (xy 99.717476 21.76462) (xy 99.799952 21.788087) (xy 99.884242 21.803843)
			(xy 99.969625 21.811755) (xy 100.055375 21.811755) (xy 100.140758 21.803843) (xy 100.225048 21.788087)
			(xy 100.307524 21.76462) (xy 100.387483 21.733644) (xy 100.464243 21.695422) (xy 100.537149 21.650281)
			(xy 100.605578 21.598605) (xy 100.668948 21.540836) (xy 100.726717 21.477466) (xy 100.778393 21.409037)
			(xy 100.823534 21.336131) (xy 100.861756 21.259371) (xy 100.892732 21.179412) (xy 100.916199 21.096936)
			(xy 100.931955 21.012646) (xy 100.939867 20.927263) (xy 100.940362 20.884388) (xy 100.939867 20.841513)
			(xy 101.625133 20.841513) (xy 101.625133 20.927263) (xy 101.633045 21.012646) (xy 101.648801 21.096936)
			(xy 101.672268 21.179412) (xy 101.703244 21.259371) (xy 101.741466 21.336131) (xy 101.786607 21.409037)
			(xy 101.838283 21.477466) (xy 101.896052 21.540836) (xy 101.959422 21.598605) (xy 102.027851 21.650281)
			(xy 102.100757 21.695422) (xy 102.177517 21.733644) (xy 102.257476 21.76462) (xy 102.339952 21.788087)
			(xy 102.424242 21.803843) (xy 102.509625 21.811755) (xy 102.595375 21.811755) (xy 102.680758 21.803843)
			(xy 102.765048 21.788087) (xy 102.847524 21.76462) (xy 102.927483 21.733644) (xy 103.004243 21.695422)
			(xy 103.077149 21.650281) (xy 103.145578 21.598605) (xy 103.208948 21.540836) (xy 103.266717 21.477466)
			(xy 103.318393 21.409037) (xy 103.363534 21.336131) (xy 103.401756 21.259371) (xy 103.432732 21.179412)
			(xy 103.456199 21.096936) (xy 103.471955 21.012646) (xy 103.479867 20.927263) (xy 103.480362 20.884388)
			(xy 103.479867 20.841513) (xy 104.165133 20.841513) (xy 104.165133 20.927263) (xy 104.173045 21.012646)
			(xy 104.188801 21.096936) (xy 104.212268 21.179412) (xy 104.243244 21.259371) (xy 104.281466 21.336131)
			(xy 104.326607 21.409037) (xy 104.378283 21.477466) (xy 104.436052 21.540836) (xy 104.499422 21.598605)
			(xy 104.567851 21.650281) (xy 104.640757 21.695422) (xy 104.717517 21.733644) (xy 104.797476 21.76462)
			(xy 104.879952 21.788087) (xy 104.964242 21.803843) (xy 105.049625 21.811755) (xy 105.135375 21.811755)
			(xy 105.220758 21.803843) (xy 105.305048 21.788087) (xy 105.387524 21.76462) (xy 105.467483 21.733644)
			(xy 105.544243 21.695422) (xy 105.617149 21.650281) (xy 105.685578 21.598605) (xy 105.748948 21.540836)
			(xy 105.806717 21.477466) (xy 105.858393 21.409037) (xy 105.903534 21.336131) (xy 105.941756 21.259371)
			(xy 105.972732 21.179412) (xy 105.996199 21.096936) (xy 106.011955 21.012646) (xy 106.019867 20.927263)
			(xy 106.020362 20.884388) (xy 106.019867 20.841513) (xy 106.011955 20.75613) (xy 105.996199 20.67184)
			(xy 105.972732 20.589364) (xy 105.941756 20.509405) (xy 105.903534 20.432645) (xy 105.858393 20.359739)
			(xy 105.806717 20.29131) (xy 105.748948 20.22794) (xy 105.685578 20.170171) (xy 105.617149 20.118495)
			(xy 105.544243 20.073354) (xy 105.467483 20.035132) (xy 105.387524 20.004156) (xy 105.305048 19.980689)
			(xy 105.220758 19.964933) (xy 105.135375 19.957021) (xy 105.049625 19.957021) (xy 104.964242 19.964933)
			(xy 104.879952 19.980689) (xy 104.797476 20.004156) (xy 104.717517 20.035132) (xy 104.640757 20.073354)
			(xy 104.567851 20.118495) (xy 104.499422 20.170171) (xy 104.436052 20.22794) (xy 104.378283 20.29131)
			(xy 104.326607 20.359739) (xy 104.281466 20.432645) (xy 104.243244 20.509405) (xy 104.212268 20.589364)
			(xy 104.188801 20.67184) (xy 104.173045 20.75613) (xy 104.165133 20.841513) (xy 103.479867 20.841513)
			(xy 103.471955 20.75613) (xy 103.456199 20.67184) (xy 103.432732 20.589364) (xy 103.401756 20.509405)
			(xy 103.363534 20.432645) (xy 103.318393 20.359739) (xy 103.266717 20.29131) (xy 103.208948 20.22794)
			(xy 103.145578 20.170171) (xy 103.077149 20.118495) (xy 103.004243 20.073354) (xy 102.927483 20.035132)
			(xy 102.847524 20.004156) (xy 102.765048 19.980689) (xy 102.680758 19.964933) (xy 102.595375 19.957021)
			(xy 102.509625 19.957021) (xy 102.424242 19.964933) (xy 102.339952 19.980689) (xy 102.257476 20.004156)
			(xy 102.177517 20.035132) (xy 102.100757 20.073354) (xy 102.027851 20.118495) (xy 101.959422 20.170171)
			(xy 101.896052 20.22794) (xy 101.838283 20.29131) (xy 101.786607 20.359739) (xy 101.741466 20.432645)
			(xy 101.703244 20.509405) (xy 101.672268 20.589364) (xy 101.648801 20.67184) (xy 101.633045 20.75613)
			(xy 101.625133 20.841513) (xy 100.939867 20.841513) (xy 100.931955 20.75613) (xy 100.916199 20.67184)
			(xy 100.892732 20.589364) (xy 100.861756 20.509405) (xy 100.823534 20.432645) (xy 100.778393 20.359739)
			(xy 100.726717 20.29131) (xy 100.668948 20.22794) (xy 100.605578 20.170171) (xy 100.537149 20.118495)
			(xy 100.464243 20.073354) (xy 100.387483 20.035132) (xy 100.307524 20.004156) (xy 100.225048 19.980689)
			(xy 100.140758 19.964933) (xy 100.055375 19.957021) (xy 99.969625 19.957021) (xy 99.884242 19.964933)
			(xy 99.799952 19.980689) (xy 99.717476 20.004156) (xy 99.637517 20.035132) (xy 99.560757 20.073354)
			(xy 99.487851 20.118495) (xy 99.419422 20.170171) (xy 99.356052 20.22794) (xy 99.298283 20.29131)
			(xy 99.246607 20.359739) (xy 99.201466 20.432645) (xy 99.163244 20.509405) (xy 99.132268 20.589364)
			(xy 99.108801 20.67184) (xy 99.093045 20.75613) (xy 99.085133 20.841513) (xy 92.50807 20.841513)
			(xy 92.50807 14.491513) (xy 99.085133 14.491513) (xy 99.085133 14.577263) (xy 99.093045 14.662646)
			(xy 99.108801 14.746936) (xy 99.132268 14.829412) (xy 99.163244 14.909371) (xy 99.201466 14.986131)
			(xy 99.246607 15.059037) (xy 99.298283 15.127466) (xy 99.356052 15.190836) (xy 99.419422 15.248605)
			(xy 99.487851 15.300281) (xy 99.560757 15.345422) (xy 99.637517 15.383644) (xy 99.717476 15.41462)
			(xy 99.799952 15.438087) (xy 99.884242 15.453843) (xy 99.969625 15.461755) (xy 100.055375 15.461755)
			(xy 100.140758 15.453843) (xy 100.225048 15.438087) (xy 100.307524 15.41462) (xy 100.387483 15.383644)
			(xy 100.464243 15.345422) (xy 100.537149 15.300281) (xy 100.605578 15.248605) (xy 100.668948 15.190836)
			(xy 100.726717 15.127466) (xy 100.778393 15.059037) (xy 100.823534 14.986131) (xy 100.861756 14.909371)
			(xy 100.892732 14.829412) (xy 100.916199 14.746936) (xy 100.931955 14.662646) (xy 100.939867 14.577263)
			(xy 100.940362 14.534388) (xy 100.939867 14.491513) (xy 101.625133 14.491513) (xy 101.625133 14.577263)
			(xy 101.633045 14.662646) (xy 101.648801 14.746936) (xy 101.672268 14.829412) (xy 101.703244 14.909371)
			(xy 101.741466 14.986131) (xy 101.786607 15.059037) (xy 101.838283 15.127466) (xy 101.896052 15.190836)
			(xy 101.959422 15.248605) (xy 102.027851 15.300281) (xy 102.100757 15.345422) (xy 102.177517 15.383644)
			(xy 102.257476 15.41462) (xy 102.339952 15.438087) (xy 102.424242 15.453843) (xy 102.509625 15.461755)
			(xy 102.595375 15.461755) (xy 102.680758 15.453843) (xy 102.765048 15.438087) (xy 102.847524 15.41462)
			(xy 102.927483 15.383644) (xy 103.004243 15.345422) (xy 103.077149 15.300281) (xy 103.145578 15.248605)
			(xy 103.208948 15.190836) (xy 103.266717 15.127466) (xy 103.318393 15.059037) (xy 103.363534 14.986131)
			(xy 103.401756 14.909371) (xy 103.432732 14.829412) (xy 103.456199 14.746936) (xy 103.471955 14.662646)
			(xy 103.479867 14.577263) (xy 103.480362 14.534388) (xy 103.479867 14.491513) (xy 104.165133 14.491513)
			(xy 104.165133 14.577263) (xy 104.173045 14.662646) (xy 104.188801 14.746936) (xy 104.212268 14.829412)
			(xy 104.243244 14.909371) (xy 104.281466 14.986131) (xy 104.326607 15.059037) (xy 104.378283 15.127466)
			(xy 104.436052 15.190836) (xy 104.499422 15.248605) (xy 104.567851 15.300281) (xy 104.640757 15.345422)
			(xy 104.717517 15.383644) (xy 104.797476 15.41462) (xy 104.879952 15.438087) (xy 104.964242 15.453843)
			(xy 105.049625 15.461755) (xy 105.135375 15.461755) (xy 105.220758 15.453843) (xy 105.305048 15.438087)
			(xy 105.387524 15.41462) (xy 105.467483 15.383644) (xy 105.544243 15.345422) (xy 105.617149 15.300281)
			(xy 105.685578 15.248605) (xy 105.748948 15.190836) (xy 105.806717 15.127466) (xy 105.858393 15.059037)
			(xy 105.903534 14.986131) (xy 105.941756 14.909371) (xy 105.972732 14.829412) (xy 105.996199 14.746936)
			(xy 106.011955 14.662646) (xy 106.019867 14.577263) (xy 106.020362 14.534388) (xy 106.019867 14.491513)
			(xy 106.011955 14.40613) (xy 105.996199 14.32184) (xy 105.972732 14.239364) (xy 105.941756 14.159405)
			(xy 105.903534 14.082645) (xy 105.858393 14.009739) (xy 105.806717 13.94131) (xy 105.748948 13.87794)
			(xy 105.685578 13.820171) (xy 105.617149 13.768495) (xy 105.544243 13.723354) (xy 105.467483 13.685132)
			(xy 105.387524 13.654156) (xy 105.305048 13.630689) (xy 105.220758 13.614933) (xy 105.135375 13.607021)
			(xy 105.049625 13.607021) (xy 104.964242 13.614933) (xy 104.879952 13.630689) (xy 104.797476 13.654156)
			(xy 104.717517 13.685132) (xy 104.640757 13.723354) (xy 104.567851 13.768495) (xy 104.499422 13.820171)
			(xy 104.436052 13.87794) (xy 104.378283 13.94131) (xy 104.326607 14.009739) (xy 104.281466 14.082645)
			(xy 104.243244 14.159405) (xy 104.212268 14.239364) (xy 104.188801 14.32184) (xy 104.173045 14.40613)
			(xy 104.165133 14.491513) (xy 103.479867 14.491513) (xy 103.471955 14.40613) (xy 103.456199 14.32184)
			(xy 103.432732 14.239364) (xy 103.401756 14.159405) (xy 103.363534 14.082645) (xy 103.318393 14.009739)
			(xy 103.266717 13.94131) (xy 103.208948 13.87794) (xy 103.145578 13.820171) (xy 103.077149 13.768495)
			(xy 103.004243 13.723354) (xy 102.927483 13.685132) (xy 102.847524 13.654156) (xy 102.765048 13.630689)
			(xy 102.680758 13.614933) (xy 102.595375 13.607021) (xy 102.509625 13.607021) (xy 102.424242 13.614933)
			(xy 102.339952 13.630689) (xy 102.257476 13.654156) (xy 102.177517 13.685132) (xy 102.100757 13.723354)
			(xy 102.027851 13.768495) (xy 101.959422 13.820171) (xy 101.896052 13.87794) (xy 101.838283 13.94131)
			(xy 101.786607 14.009739) (xy 101.741466 14.082645) (xy 101.703244 14.159405) (xy 101.672268 14.239364)
			(xy 101.648801 14.32184) (xy 101.633045 14.40613) (xy 101.625133 14.491513) (xy 100.939867 14.491513)
			(xy 100.931955 14.40613) (xy 100.916199 14.32184) (xy 100.892732 14.239364) (xy 100.861756 14.159405)
			(xy 100.823534 14.082645) (xy 100.778393 14.009739) (xy 100.726717 13.94131) (xy 100.668948 13.87794)
			(xy 100.605578 13.820171) (xy 100.537149 13.768495) (xy 100.464243 13.723354) (xy 100.387483 13.685132)
			(xy 100.307524 13.654156) (xy 100.225048 13.630689) (xy 100.140758 13.614933) (xy 100.055375 13.607021)
			(xy 99.969625 13.607021) (xy 99.884242 13.614933) (xy 99.799952 13.630689) (xy 99.717476 13.654156)
			(xy 99.637517 13.685132) (xy 99.560757 13.723354) (xy 99.487851 13.768495) (xy 99.419422 13.820171)
			(xy 99.356052 13.87794) (xy 99.298283 13.94131) (xy 99.246607 14.009739) (xy 99.201466 14.082645)
			(xy 99.163244 14.159405) (xy 99.132268 14.239364) (xy 99.108801 14.32184) (xy 99.093045 14.40613)
			(xy 99.085133 14.491513) (xy 92.50807 14.491513) (xy 92.50807 -1.181049) (xy 93.729289 -1.181049)
			(xy 93.729289 -1.095299) (xy 93.737201 -1.009916) (xy 93.752957 -0.925626) (xy 93.776424 -0.84315)
			(xy 93.8074 -0.763191) (xy 93.845622 -0.686431) (xy 93.890763 -0.613525) (xy 93.942439 -0.545096)
			(xy 94.000208 -0.481726) (xy 94.063578 -0.423957) (xy 94.132007 -0.372281) (xy 94.204913 -0.32714)
			(xy 94.281673 -0.288918) (xy 94.361632 -0.257942) (xy 94.444108 -0.234475) (xy 94.528398 -0.218719)
			(xy 94.613781 -0.210807) (xy 94.699531 -0.210807) (xy 94.784914 -0.218719) (xy 94.869204 -0.234475)
			(xy 94.95168 -0.257942) (xy 95.031639 -0.288918) (xy 95.108399 -0.32714) (xy 95.181305 -0.372281)
			(xy 95.249734 -0.423957) (xy 95.313104 -0.481726) (xy 95.370873 -0.545096) (xy 95.422549 -0.613525)
			(xy 95.46769 -0.686431) (xy 95.505912 -0.763191) (xy 95.536888 -0.84315) (xy 95.560355 -0.925626)
			(xy 95.576111 -1.009916) (xy 95.584023 -1.095299) (xy 95.584518 -1.138174) (xy 95.584023 -1.181049)
			(xy 96.269289 -1.181049) (xy 96.269289 -1.095299) (xy 96.277201 -1.009916) (xy 96.292957 -0.925626)
			(xy 96.316424 -0.84315) (xy 96.3474 -0.763191) (xy 96.385622 -0.686431) (xy 96.430763 -0.613525)
			(xy 96.482439 -0.545096) (xy 96.540208 -0.481726) (xy 96.603578 -0.423957) (xy 96.672007 -0.372281)
			(xy 96.744913 -0.32714) (xy 96.821673 -0.288918) (xy 96.901632 -0.257942) (xy 96.984108 -0.234475)
			(xy 97.068398 -0.218719) (xy 97.153781 -0.210807) (xy 97.239531 -0.210807) (xy 97.324914 -0.218719)
			(xy 97.409204 -0.234475) (xy 97.49168 -0.257942) (xy 97.571639 -0.288918) (xy 97.648399 -0.32714)
			(xy 97.721305 -0.372281) (xy 97.789734 -0.423957) (xy 97.853104 -0.481726) (xy 97.910873 -0.545096)
			(xy 97.962549 -0.613525) (xy 98.00769 -0.686431) (xy 98.045912 -0.763191) (xy 98.076888 -0.84315)
			(xy 98.100355 -0.925626) (xy 98.116111 -1.009916) (xy 98.124023 -1.095299) (xy 98.124518 -1.138174)
			(xy 98.124023 -1.181049) (xy 98.116111 -1.266432) (xy 98.100355 -1.350722) (xy 98.076888 -1.433198)
			(xy 98.045912 -1.513157) (xy 98.00769 -1.589917) (xy 97.962549 -1.662823) (xy 97.910873 -1.731252)
			(xy 97.853104 -1.794622) (xy 97.789734 -1.852391) (xy 97.721305 -1.904067) (xy 97.648399 -1.949208)
			(xy 97.571639 -1.98743) (xy 97.49168 -2.018406) (xy 97.409204 -2.041873) (xy 97.324914 -2.057629)
			(xy 97.239531 -2.065541) (xy 97.153781 -2.065541) (xy 97.068398 -2.057629) (xy 96.984108 -2.041873)
			(xy 96.901632 -2.018406) (xy 96.821673 -1.98743) (xy 96.744913 -1.949208) (xy 96.672007 -1.904067)
			(xy 96.603578 -1.852391) (xy 96.540208 -1.794622) (xy 96.482439 -1.731252) (xy 96.430763 -1.662823)
			(xy 96.385622 -1.589917) (xy 96.3474 -1.513157) (xy 96.316424 -1.433198) (xy 96.292957 -1.350722)
			(xy 96.277201 -1.266432) (xy 96.269289 -1.181049) (xy 95.584023 -1.181049) (xy 95.576111 -1.266432)
			(xy 95.560355 -1.350722) (xy 95.536888 -1.433198) (xy 95.505912 -1.513157) (xy 95.46769 -1.589917)
			(xy 95.422549 -1.662823) (xy 95.370873 -1.731252) (xy 95.313104 -1.794622) (xy 95.249734 -1.852391)
			(xy 95.181305 -1.904067) (xy 95.108399 -1.949208) (xy 95.031639 -1.98743) (xy 94.95168 -2.018406)
			(xy 94.869204 -2.041873) (xy 94.784914 -2.057629) (xy 94.699531 -2.065541) (xy 94.613781 -2.065541)
			(xy 94.528398 -2.057629) (xy 94.444108 -2.041873) (xy 94.361632 -2.018406) (xy 94.281673 -1.98743)
			(xy 94.204913 -1.949208) (xy 94.132007 -1.904067) (xy 94.063578 -1.852391) (xy 94.000208 -1.794622)
			(xy 93.942439 -1.731252) (xy 93.890763 -1.662823) (xy 93.845622 -1.589917) (xy 93.8074 -1.513157)
			(xy 93.776424 -1.433198) (xy 93.752957 -1.350722) (xy 93.737201 -1.266432) (xy 93.729289 -1.181049)
			(xy 92.50807 -1.181049) (xy 92.50807 -3.154767) (xy 95.113626 -3.154767) (xy 95.113626 -3.100233)
			(xy 95.121387 -3.046253) (xy 95.13675 -2.993928) (xy 95.159403 -2.944321) (xy 95.188884 -2.898442)
			(xy 95.224595 -2.857226) (xy 95.265807 -2.821511) (xy 95.311682 -2.792024) (xy 95.361286 -2.769365)
			(xy 95.41361 -2.753996) (xy 95.467589 -2.746229) (xy 95.494856 -2.74574) (xy 96.358456 -2.74574)
			(xy 96.385729 -2.746196) (xy 96.439721 -2.753954) (xy 96.492059 -2.769316) (xy 96.541678 -2.791971)
			(xy 96.587568 -2.821458) (xy 96.628793 -2.857176) (xy 96.664516 -2.898397) (xy 96.694008 -2.944283)
			(xy 96.716668 -2.993899) (xy 96.732037 -3.046236) (xy 96.7398 -3.100227) (xy 96.7398 -3.154773) (xy 96.732037 -3.208764)
			(xy 96.716668 -3.261101) (xy 96.694008 -3.310717) (xy 96.664516 -3.356603) (xy 96.628793 -3.397824)
			(xy 96.587568 -3.433542) (xy 96.541678 -3.463029) (xy 96.492059 -3.485684) (xy 96.439721 -3.501046)
			(xy 96.385729 -3.508804) (xy 96.358456 -3.509264) (xy 95.494856 -3.509264) (xy 95.467589 -3.508771)
			(xy 95.41361 -3.501004) (xy 95.361286 -3.485635) (xy 95.311682 -3.462976) (xy 95.265807 -3.433489)
			(xy 95.224595 -3.397774) (xy 95.188884 -3.356558) (xy 95.159403 -3.310679) (xy 95.13675 -3.261072)
			(xy 95.121387 -3.208747) (xy 95.113626 -3.154767) (xy 92.50807 -3.154767) (xy 92.50807 -7.531049)
			(xy 93.729289 -7.531049) (xy 93.729289 -7.445299) (xy 93.737201 -7.359916) (xy 93.752957 -7.275626)
			(xy 93.776424 -7.19315) (xy 93.8074 -7.113191) (xy 93.845622 -7.036431) (xy 93.890763 -6.963525)
			(xy 93.942439 -6.895096) (xy 94.000208 -6.831726) (xy 94.063578 -6.773957) (xy 94.132007 -6.722281)
			(xy 94.204913 -6.67714) (xy 94.281673 -6.638918) (xy 94.361632 -6.607942) (xy 94.444108 -6.584475)
			(xy 94.528398 -6.568719) (xy 94.613781 -6.560807) (xy 94.699531 -6.560807) (xy 94.784914 -6.568719)
			(xy 94.869204 -6.584475) (xy 94.95168 -6.607942) (xy 95.031639 -6.638918) (xy 95.108399 -6.67714)
			(xy 95.181305 -6.722281) (xy 95.249734 -6.773957) (xy 95.313104 -6.831726) (xy 95.370873 -6.895096)
			(xy 95.422549 -6.963525) (xy 95.46769 -7.036431) (xy 95.505912 -7.113191) (xy 95.536888 -7.19315)
			(xy 95.560355 -7.275626) (xy 95.576111 -7.359916) (xy 95.584023 -7.445299) (xy 95.584518 -7.488174)
			(xy 95.584023 -7.531049) (xy 96.269289 -7.531049) (xy 96.269289 -7.445299) (xy 96.277201 -7.359916)
			(xy 96.292957 -7.275626) (xy 96.316424 -7.19315) (xy 96.3474 -7.113191) (xy 96.385622 -7.036431)
			(xy 96.430763 -6.963525) (xy 96.482439 -6.895096) (xy 96.540208 -6.831726) (xy 96.603578 -6.773957)
			(xy 96.672007 -6.722281) (xy 96.744913 -6.67714) (xy 96.821673 -6.638918) (xy 96.901632 -6.607942)
			(xy 96.984108 -6.584475) (xy 97.068398 -6.568719) (xy 97.153781 -6.560807) (xy 97.239531 -6.560807)
			(xy 97.324914 -6.568719) (xy 97.409204 -6.584475) (xy 97.49168 -6.607942) (xy 97.571639 -6.638918)
			(xy 97.648399 -6.67714) (xy 97.721305 -6.722281) (xy 97.789734 -6.773957) (xy 97.853104 -6.831726)
			(xy 97.910873 -6.895096) (xy 97.962549 -6.963525) (xy 98.00769 -7.036431) (xy 98.045912 -7.113191)
			(xy 98.076888 -7.19315) (xy 98.100355 -7.275626) (xy 98.116111 -7.359916) (xy 98.124023 -7.445299)
			(xy 98.124518 -7.488174) (xy 98.124023 -7.531049) (xy 98.116111 -7.616432) (xy 98.100355 -7.700722)
			(xy 98.076888 -7.783198) (xy 98.045912 -7.863157) (xy 98.00769 -7.939917) (xy 97.962549 -8.012823)
			(xy 97.910873 -8.081252) (xy 97.853104 -8.144622) (xy 97.789734 -8.202391) (xy 97.721305 -8.254067)
			(xy 97.648399 -8.299208) (xy 97.571639 -8.33743) (xy 97.49168 -8.368406) (xy 97.409204 -8.391873)
			(xy 97.324914 -8.407629) (xy 97.239531 -8.415541) (xy 97.153781 -8.415541) (xy 97.068398 -8.407629)
			(xy 96.984108 -8.391873) (xy 96.901632 -8.368406) (xy 96.821673 -8.33743) (xy 96.744913 -8.299208)
			(xy 96.672007 -8.254067) (xy 96.603578 -8.202391) (xy 96.540208 -8.144622) (xy 96.482439 -8.081252)
			(xy 96.430763 -8.012823) (xy 96.385622 -7.939917) (xy 96.3474 -7.863157) (xy 96.316424 -7.783198)
			(xy 96.292957 -7.700722) (xy 96.277201 -7.616432) (xy 96.269289 -7.531049) (xy 95.584023 -7.531049)
			(xy 95.576111 -7.616432) (xy 95.560355 -7.700722) (xy 95.536888 -7.783198) (xy 95.505912 -7.863157)
			(xy 95.46769 -7.939917) (xy 95.422549 -8.012823) (xy 95.370873 -8.081252) (xy 95.313104 -8.144622)
			(xy 95.249734 -8.202391) (xy 95.181305 -8.254067) (xy 95.108399 -8.299208) (xy 95.031639 -8.33743)
			(xy 94.95168 -8.368406) (xy 94.869204 -8.391873) (xy 94.784914 -8.407629) (xy 94.699531 -8.415541)
			(xy 94.613781 -8.415541) (xy 94.528398 -8.407629) (xy 94.444108 -8.391873) (xy 94.361632 -8.368406)
			(xy 94.281673 -8.33743) (xy 94.204913 -8.299208) (xy 94.132007 -8.254067) (xy 94.063578 -8.202391)
			(xy 94.000208 -8.144622) (xy 93.942439 -8.081252) (xy 93.890763 -8.012823) (xy 93.845622 -7.939917)
			(xy 93.8074 -7.863157) (xy 93.776424 -7.783198) (xy 93.752957 -7.700722) (xy 93.737201 -7.616432)
			(xy 93.729289 -7.531049) (xy 92.50807 -7.531049) (xy 92.50807 -13.055549) (xy 93.714049 -13.055549)
			(xy 93.714049 -12.969799) (xy 93.721961 -12.884416) (xy 93.737717 -12.800126) (xy 93.761184 -12.71765)
			(xy 93.79216 -12.637691) (xy 93.830382 -12.560931) (xy 93.875523 -12.488025) (xy 93.927199 -12.419596)
			(xy 93.984968 -12.356226) (xy 94.048338 -12.298457) (xy 94.116767 -12.246781) (xy 94.189673 -12.20164)
			(xy 94.266433 -12.163418) (xy 94.346392 -12.132442) (xy 94.428868 -12.108975) (xy 94.513158 -12.093219)
			(xy 94.598541 -12.085307) (xy 94.684291 -12.085307) (xy 94.769674 -12.093219) (xy 94.853964 -12.108975)
			(xy 94.93644 -12.132442) (xy 95.016399 -12.163418) (xy 95.093159 -12.20164) (xy 95.166065 -12.246781)
			(xy 95.234494 -12.298457) (xy 95.297864 -12.356226) (xy 95.355633 -12.419596) (xy 95.407309 -12.488025)
			(xy 95.45245 -12.560931) (xy 95.490672 -12.637691) (xy 95.521648 -12.71765) (xy 95.545115 -12.800126)
			(xy 95.560871 -12.884416) (xy 95.568783 -12.969799) (xy 95.569278 -13.012674) (xy 95.568783 -13.055549)
			(xy 96.254049 -13.055549) (xy 96.254049 -12.969799) (xy 96.261961 -12.884416) (xy 96.277717 -12.800126)
			(xy 96.301184 -12.71765) (xy 96.33216 -12.637691) (xy 96.370382 -12.560931) (xy 96.415523 -12.488025)
			(xy 96.467199 -12.419596) (xy 96.524968 -12.356226) (xy 96.588338 -12.298457) (xy 96.656767 -12.246781)
			(xy 96.729673 -12.20164) (xy 96.806433 -12.163418) (xy 96.886392 -12.132442) (xy 96.968868 -12.108975)
			(xy 97.053158 -12.093219) (xy 97.138541 -12.085307) (xy 97.224291 -12.085307) (xy 97.309674 -12.093219)
			(xy 97.393964 -12.108975) (xy 97.47644 -12.132442) (xy 97.556399 -12.163418) (xy 97.633159 -12.20164)
			(xy 97.706065 -12.246781) (xy 97.774494 -12.298457) (xy 97.837864 -12.356226) (xy 97.895633 -12.419596)
			(xy 97.947309 -12.488025) (xy 97.99245 -12.560931) (xy 98.030672 -12.637691) (xy 98.061648 -12.71765)
			(xy 98.085115 -12.800126) (xy 98.100871 -12.884416) (xy 98.108783 -12.969799) (xy 98.109278 -13.012674)
			(xy 98.108783 -13.055549) (xy 98.100871 -13.140932) (xy 98.085115 -13.225222) (xy 98.061648 -13.307698)
			(xy 98.030672 -13.387657) (xy 97.99245 -13.464417) (xy 97.947309 -13.537323) (xy 97.895633 -13.605752)
			(xy 97.837864 -13.669122) (xy 97.774494 -13.726891) (xy 97.706065 -13.778567) (xy 97.633159 -13.823708)
			(xy 97.556399 -13.86193) (xy 97.47644 -13.892906) (xy 97.393964 -13.916373) (xy 97.309674 -13.932129)
			(xy 97.224291 -13.940041) (xy 97.138541 -13.940041) (xy 97.053158 -13.932129) (xy 96.968868 -13.916373)
			(xy 96.886392 -13.892906) (xy 96.806433 -13.86193) (xy 96.729673 -13.823708) (xy 96.656767 -13.778567)
			(xy 96.588338 -13.726891) (xy 96.524968 -13.669122) (xy 96.467199 -13.605752) (xy 96.415523 -13.537323)
			(xy 96.370382 -13.464417) (xy 96.33216 -13.387657) (xy 96.301184 -13.307698) (xy 96.277717 -13.225222)
			(xy 96.261961 -13.140932) (xy 96.254049 -13.055549) (xy 95.568783 -13.055549) (xy 95.560871 -13.140932)
			(xy 95.545115 -13.225222) (xy 95.521648 -13.307698) (xy 95.490672 -13.387657) (xy 95.45245 -13.464417)
			(xy 95.407309 -13.537323) (xy 95.355633 -13.605752) (xy 95.297864 -13.669122) (xy 95.234494 -13.726891)
			(xy 95.166065 -13.778567) (xy 95.093159 -13.823708) (xy 95.016399 -13.86193) (xy 94.93644 -13.892906)
			(xy 94.853964 -13.916373) (xy 94.769674 -13.932129) (xy 94.684291 -13.940041) (xy 94.598541 -13.940041)
			(xy 94.513158 -13.932129) (xy 94.428868 -13.916373) (xy 94.346392 -13.892906) (xy 94.266433 -13.86193)
			(xy 94.189673 -13.823708) (xy 94.116767 -13.778567) (xy 94.048338 -13.726891) (xy 93.984968 -13.669122)
			(xy 93.927199 -13.605752) (xy 93.875523 -13.537323) (xy 93.830382 -13.464417) (xy 93.79216 -13.387657)
			(xy 93.761184 -13.307698) (xy 93.737717 -13.225222) (xy 93.721961 -13.140932) (xy 93.714049 -13.055549)
			(xy 92.50807 -13.055549) (xy 92.50807 -17.400568) (xy 95.098347 -17.400568) (xy 95.098347 -17.346032)
			(xy 95.106109 -17.29205) (xy 95.121474 -17.239722) (xy 95.14413 -17.190114) (xy 95.173616 -17.144235)
			(xy 95.209331 -17.103019) (xy 95.250548 -17.067306) (xy 95.296428 -17.037823) (xy 95.346037 -17.015169)
			(xy 95.398365 -16.999806) (xy 95.452348 -16.992046) (xy 95.479616 -16.991584) (xy 96.343216 -16.991584)
			(xy 96.370488 -16.99198) (xy 96.424476 -16.999744) (xy 96.47681 -17.015113) (xy 96.526424 -17.037773)
			(xy 96.572309 -17.067262) (xy 96.613529 -17.102982) (xy 96.649247 -17.144204) (xy 96.678735 -17.19009)
			(xy 96.701393 -17.239705) (xy 96.716759 -17.292039) (xy 96.724522 -17.346028) (xy 96.724522 -17.400572)
			(xy 96.716759 -17.454561) (xy 96.701393 -17.506895) (xy 96.678735 -17.55651) (xy 96.649247 -17.602396)
			(xy 96.613529 -17.643618) (xy 96.572309 -17.679338) (xy 96.526424 -17.708827) (xy 96.47681 -17.731487)
			(xy 96.424476 -17.746856) (xy 96.370488 -17.75462) (xy 96.343216 -17.755108) (xy 95.479616 -17.755108)
			(xy 95.452348 -17.754554) (xy 95.398365 -17.746794) (xy 95.346037 -17.731431) (xy 95.296428 -17.708777)
			(xy 95.250548 -17.679294) (xy 95.209331 -17.643581) (xy 95.173616 -17.602365) (xy 95.14413 -17.556486)
			(xy 95.121474 -17.506878) (xy 95.106109 -17.45455) (xy 95.098347 -17.400568) (xy 92.50807 -17.400568)
			(xy 92.50807 -19.405549) (xy 93.714049 -19.405549) (xy 93.714049 -19.319799) (xy 93.721961 -19.234416)
			(xy 93.737717 -19.150126) (xy 93.761184 -19.06765) (xy 93.79216 -18.987691) (xy 93.830382 -18.910931)
			(xy 93.875523 -18.838025) (xy 93.927199 -18.769596) (xy 93.984968 -18.706226) (xy 94.048338 -18.648457)
			(xy 94.116767 -18.596781) (xy 94.189673 -18.55164) (xy 94.266433 -18.513418) (xy 94.346392 -18.482442)
			(xy 94.428868 -18.458975) (xy 94.513158 -18.443219) (xy 94.598541 -18.435307) (xy 94.684291 -18.435307)
			(xy 94.769674 -18.443219) (xy 94.853964 -18.458975) (xy 94.93644 -18.482442) (xy 95.016399 -18.513418)
			(xy 95.093159 -18.55164) (xy 95.166065 -18.596781) (xy 95.234494 -18.648457) (xy 95.297864 -18.706226)
			(xy 95.355633 -18.769596) (xy 95.407309 -18.838025) (xy 95.45245 -18.910931) (xy 95.490672 -18.987691)
			(xy 95.521648 -19.06765) (xy 95.545115 -19.150126) (xy 95.560871 -19.234416) (xy 95.568783 -19.319799)
			(xy 95.569278 -19.362674) (xy 95.568783 -19.405549) (xy 96.254049 -19.405549) (xy 96.254049 -19.319799)
			(xy 96.261961 -19.234416) (xy 96.277717 -19.150126) (xy 96.301184 -19.06765) (xy 96.33216 -18.987691)
			(xy 96.370382 -18.910931) (xy 96.415523 -18.838025) (xy 96.467199 -18.769596) (xy 96.524968 -18.706226)
			(xy 96.588338 -18.648457) (xy 96.656767 -18.596781) (xy 96.729673 -18.55164) (xy 96.806433 -18.513418)
			(xy 96.886392 -18.482442) (xy 96.968868 -18.458975) (xy 97.053158 -18.443219) (xy 97.138541 -18.435307)
			(xy 97.224291 -18.435307) (xy 97.309674 -18.443219) (xy 97.393964 -18.458975) (xy 97.47644 -18.482442)
			(xy 97.556399 -18.513418) (xy 97.633159 -18.55164) (xy 97.706065 -18.596781) (xy 97.774494 -18.648457)
			(xy 97.837864 -18.706226) (xy 97.895633 -18.769596) (xy 97.947309 -18.838025) (xy 97.99245 -18.910931)
			(xy 98.030672 -18.987691) (xy 98.061648 -19.06765) (xy 98.085115 -19.150126) (xy 98.100871 -19.234416)
			(xy 98.108783 -19.319799) (xy 98.109278 -19.362674) (xy 98.108783 -19.405549) (xy 98.100871 -19.490932)
			(xy 98.085115 -19.575222) (xy 98.061648 -19.657698) (xy 98.030672 -19.737657) (xy 97.99245 -19.814417)
			(xy 97.947309 -19.887323) (xy 97.895633 -19.955752) (xy 97.837864 -20.019122) (xy 97.774494 -20.076891)
			(xy 97.706065 -20.128567) (xy 97.633159 -20.173708) (xy 97.556399 -20.21193) (xy 97.47644 -20.242906)
			(xy 97.393964 -20.266373) (xy 97.309674 -20.282129) (xy 97.224291 -20.290041) (xy 97.138541 -20.290041)
			(xy 97.053158 -20.282129) (xy 96.968868 -20.266373) (xy 96.886392 -20.242906) (xy 96.806433 -20.21193)
			(xy 96.729673 -20.173708) (xy 96.656767 -20.128567) (xy 96.588338 -20.076891) (xy 96.524968 -20.019122)
			(xy 96.467199 -19.955752) (xy 96.415523 -19.887323) (xy 96.370382 -19.814417) (xy 96.33216 -19.737657)
			(xy 96.301184 -19.657698) (xy 96.277717 -19.575222) (xy 96.261961 -19.490932) (xy 96.254049 -19.405549)
			(xy 95.568783 -19.405549) (xy 95.560871 -19.490932) (xy 95.545115 -19.575222) (xy 95.521648 -19.657698)
			(xy 95.490672 -19.737657) (xy 95.45245 -19.814417) (xy 95.407309 -19.887323) (xy 95.355633 -19.955752)
			(xy 95.297864 -20.019122) (xy 95.234494 -20.076891) (xy 95.166065 -20.128567) (xy 95.093159 -20.173708)
			(xy 95.016399 -20.21193) (xy 94.93644 -20.242906) (xy 94.853964 -20.266373) (xy 94.769674 -20.282129)
			(xy 94.684291 -20.290041) (xy 94.598541 -20.290041) (xy 94.513158 -20.282129) (xy 94.428868 -20.266373)
			(xy 94.346392 -20.242906) (xy 94.266433 -20.21193) (xy 94.189673 -20.173708) (xy 94.116767 -20.128567)
			(xy 94.048338 -20.076891) (xy 93.984968 -20.019122) (xy 93.927199 -19.955752) (xy 93.875523 -19.887323)
			(xy 93.830382 -19.814417) (xy 93.79216 -19.737657) (xy 93.761184 -19.657698) (xy 93.737717 -19.575222)
			(xy 93.721961 -19.490932) (xy 93.714049 -19.405549) (xy 92.50807 -19.405549) (xy 92.50807 -50.979527)
			(xy 99.085133 -50.979527) (xy 99.085133 -50.893777) (xy 99.093045 -50.808394) (xy 99.108801 -50.724104)
			(xy 99.132268 -50.641628) (xy 99.163244 -50.561669) (xy 99.201466 -50.484909) (xy 99.246607 -50.412003)
			(xy 99.298283 -50.343574) (xy 99.356052 -50.280204) (xy 99.419422 -50.222435) (xy 99.487851 -50.170759)
			(xy 99.560757 -50.125618) (xy 99.637517 -50.087396) (xy 99.717476 -50.05642) (xy 99.799952 -50.032953)
			(xy 99.884242 -50.017197) (xy 99.969625 -50.009285) (xy 100.055375 -50.009285) (xy 100.140758 -50.017197)
			(xy 100.225048 -50.032953) (xy 100.307524 -50.05642) (xy 100.387483 -50.087396) (xy 100.464243 -50.125618)
			(xy 100.537149 -50.170759) (xy 100.605578 -50.222435) (xy 100.668948 -50.280204) (xy 100.726717 -50.343574)
			(xy 100.778393 -50.412003) (xy 100.823534 -50.484909) (xy 100.861756 -50.561669) (xy 100.892732 -50.641628)
			(xy 100.916199 -50.724104) (xy 100.931955 -50.808394) (xy 100.939867 -50.893777) (xy 100.940362 -50.936652)
			(xy 100.939867 -50.979527) (xy 101.625133 -50.979527) (xy 101.625133 -50.893777) (xy 101.633045 -50.808394)
			(xy 101.648801 -50.724104) (xy 101.672268 -50.641628) (xy 101.703244 -50.561669) (xy 101.741466 -50.484909)
			(xy 101.786607 -50.412003) (xy 101.838283 -50.343574) (xy 101.896052 -50.280204) (xy 101.959422 -50.222435)
			(xy 102.027851 -50.170759) (xy 102.100757 -50.125618) (xy 102.177517 -50.087396) (xy 102.257476 -50.05642)
			(xy 102.339952 -50.032953) (xy 102.424242 -50.017197) (xy 102.509625 -50.009285) (xy 102.595375 -50.009285)
			(xy 102.680758 -50.017197) (xy 102.765048 -50.032953) (xy 102.847524 -50.05642) (xy 102.927483 -50.087396)
			(xy 103.004243 -50.125618) (xy 103.077149 -50.170759) (xy 103.145578 -50.222435) (xy 103.208948 -50.280204)
			(xy 103.266717 -50.343574) (xy 103.318393 -50.412003) (xy 103.363534 -50.484909) (xy 103.401756 -50.561669)
			(xy 103.432732 -50.641628) (xy 103.456199 -50.724104) (xy 103.471955 -50.808394) (xy 103.479867 -50.893777)
			(xy 103.480362 -50.936652) (xy 103.479867 -50.979527) (xy 104.165133 -50.979527) (xy 104.165133 -50.893777)
			(xy 104.173045 -50.808394) (xy 104.188801 -50.724104) (xy 104.212268 -50.641628) (xy 104.243244 -50.561669)
			(xy 104.281466 -50.484909) (xy 104.326607 -50.412003) (xy 104.378283 -50.343574) (xy 104.436052 -50.280204)
			(xy 104.499422 -50.222435) (xy 104.567851 -50.170759) (xy 104.640757 -50.125618) (xy 104.717517 -50.087396)
			(xy 104.797476 -50.05642) (xy 104.879952 -50.032953) (xy 104.964242 -50.017197) (xy 105.049625 -50.009285)
			(xy 105.135375 -50.009285) (xy 105.220758 -50.017197) (xy 105.305048 -50.032953) (xy 105.387524 -50.05642)
			(xy 105.467483 -50.087396) (xy 105.544243 -50.125618) (xy 105.617149 -50.170759) (xy 105.685578 -50.222435)
			(xy 105.748948 -50.280204) (xy 105.806717 -50.343574) (xy 105.858393 -50.412003) (xy 105.903534 -50.484909)
			(xy 105.941756 -50.561669) (xy 105.972732 -50.641628) (xy 105.996199 -50.724104) (xy 106.011955 -50.808394)
			(xy 106.019867 -50.893777) (xy 106.020362 -50.936652) (xy 106.019867 -50.979527) (xy 106.011955 -51.06491)
			(xy 105.996199 -51.1492) (xy 105.972732 -51.231676) (xy 105.941756 -51.311635) (xy 105.903534 -51.388395)
			(xy 105.858393 -51.461301) (xy 105.806717 -51.52973) (xy 105.748948 -51.5931) (xy 105.685578 -51.650869)
			(xy 105.617149 -51.702545) (xy 105.544243 -51.747686) (xy 105.467483 -51.785908) (xy 105.387524 -51.816884)
			(xy 105.305048 -51.840351) (xy 105.220758 -51.856107) (xy 105.135375 -51.864019) (xy 105.049625 -51.864019)
			(xy 104.964242 -51.856107) (xy 104.879952 -51.840351) (xy 104.797476 -51.816884) (xy 104.717517 -51.785908)
			(xy 104.640757 -51.747686) (xy 104.567851 -51.702545) (xy 104.499422 -51.650869) (xy 104.436052 -51.5931)
			(xy 104.378283 -51.52973) (xy 104.326607 -51.461301) (xy 104.281466 -51.388395) (xy 104.243244 -51.311635)
			(xy 104.212268 -51.231676) (xy 104.188801 -51.1492) (xy 104.173045 -51.06491) (xy 104.165133 -50.979527)
			(xy 103.479867 -50.979527) (xy 103.471955 -51.06491) (xy 103.456199 -51.1492) (xy 103.432732 -51.231676)
			(xy 103.401756 -51.311635) (xy 103.363534 -51.388395) (xy 103.318393 -51.461301) (xy 103.266717 -51.52973)
			(xy 103.208948 -51.5931) (xy 103.145578 -51.650869) (xy 103.077149 -51.702545) (xy 103.004243 -51.747686)
			(xy 102.927483 -51.785908) (xy 102.847524 -51.816884) (xy 102.765048 -51.840351) (xy 102.680758 -51.856107)
			(xy 102.595375 -51.864019) (xy 102.509625 -51.864019) (xy 102.424242 -51.856107) (xy 102.339952 -51.840351)
			(xy 102.257476 -51.816884) (xy 102.177517 -51.785908) (xy 102.100757 -51.747686) (xy 102.027851 -51.702545)
			(xy 101.959422 -51.650869) (xy 101.896052 -51.5931) (xy 101.838283 -51.52973) (xy 101.786607 -51.461301)
			(xy 101.741466 -51.388395) (xy 101.703244 -51.311635) (xy 101.672268 -51.231676) (xy 101.648801 -51.1492)
			(xy 101.633045 -51.06491) (xy 101.625133 -50.979527) (xy 100.939867 -50.979527) (xy 100.931955 -51.06491)
			(xy 100.916199 -51.1492) (xy 100.892732 -51.231676) (xy 100.861756 -51.311635) (xy 100.823534 -51.388395)
			(xy 100.778393 -51.461301) (xy 100.726717 -51.52973) (xy 100.668948 -51.5931) (xy 100.605578 -51.650869)
			(xy 100.537149 -51.702545) (xy 100.464243 -51.747686) (xy 100.387483 -51.785908) (xy 100.307524 -51.816884)
			(xy 100.225048 -51.840351) (xy 100.140758 -51.856107) (xy 100.055375 -51.864019) (xy 99.969625 -51.864019)
			(xy 99.884242 -51.856107) (xy 99.799952 -51.840351) (xy 99.717476 -51.816884) (xy 99.637517 -51.785908)
			(xy 99.560757 -51.747686) (xy 99.487851 -51.702545) (xy 99.419422 -51.650869) (xy 99.356052 -51.5931)
			(xy 99.298283 -51.52973) (xy 99.246607 -51.461301) (xy 99.201466 -51.388395) (xy 99.163244 -51.311635)
			(xy 99.132268 -51.231676) (xy 99.108801 -51.1492) (xy 99.093045 -51.06491) (xy 99.085133 -50.979527)
			(xy 92.50807 -50.979527) (xy 92.50807 -57.329527) (xy 99.085133 -57.329527) (xy 99.085133 -57.243777)
			(xy 99.093045 -57.158394) (xy 99.108801 -57.074104) (xy 99.132268 -56.991628) (xy 99.163244 -56.911669)
			(xy 99.201466 -56.834909) (xy 99.246607 -56.762003) (xy 99.298283 -56.693574) (xy 99.356052 -56.630204)
			(xy 99.419422 -56.572435) (xy 99.487851 -56.520759) (xy 99.560757 -56.475618) (xy 99.637517 -56.437396)
			(xy 99.717476 -56.40642) (xy 99.799952 -56.382953) (xy 99.884242 -56.367197) (xy 99.969625 -56.359285)
			(xy 100.055375 -56.359285) (xy 100.140758 -56.367197) (xy 100.225048 -56.382953) (xy 100.307524 -56.40642)
			(xy 100.387483 -56.437396) (xy 100.464243 -56.475618) (xy 100.537149 -56.520759) (xy 100.605578 -56.572435)
			(xy 100.668948 -56.630204) (xy 100.726717 -56.693574) (xy 100.778393 -56.762003) (xy 100.823534 -56.834909)
			(xy 100.861756 -56.911669) (xy 100.892732 -56.991628) (xy 100.916199 -57.074104) (xy 100.931955 -57.158394)
			(xy 100.939867 -57.243777) (xy 100.940362 -57.286652) (xy 100.939867 -57.329527) (xy 101.625133 -57.329527)
			(xy 101.625133 -57.243777) (xy 101.633045 -57.158394) (xy 101.648801 -57.074104) (xy 101.672268 -56.991628)
			(xy 101.703244 -56.911669) (xy 101.741466 -56.834909) (xy 101.786607 -56.762003) (xy 101.838283 -56.693574)
			(xy 101.896052 -56.630204) (xy 101.959422 -56.572435) (xy 102.027851 -56.520759) (xy 102.100757 -56.475618)
			(xy 102.177517 -56.437396) (xy 102.257476 -56.40642) (xy 102.339952 -56.382953) (xy 102.424242 -56.367197)
			(xy 102.509625 -56.359285) (xy 102.595375 -56.359285) (xy 102.680758 -56.367197) (xy 102.765048 -56.382953)
			(xy 102.847524 -56.40642) (xy 102.927483 -56.437396) (xy 103.004243 -56.475618) (xy 103.077149 -56.520759)
			(xy 103.145578 -56.572435) (xy 103.208948 -56.630204) (xy 103.266717 -56.693574) (xy 103.318393 -56.762003)
			(xy 103.363534 -56.834909) (xy 103.401756 -56.911669) (xy 103.432732 -56.991628) (xy 103.456199 -57.074104)
			(xy 103.471955 -57.158394) (xy 103.479867 -57.243777) (xy 103.480362 -57.286652) (xy 103.479867 -57.329527)
			(xy 104.165133 -57.329527) (xy 104.165133 -57.243777) (xy 104.173045 -57.158394) (xy 104.188801 -57.074104)
			(xy 104.212268 -56.991628) (xy 104.243244 -56.911669) (xy 104.281466 -56.834909) (xy 104.326607 -56.762003)
			(xy 104.378283 -56.693574) (xy 104.436052 -56.630204) (xy 104.499422 -56.572435) (xy 104.567851 -56.520759)
			(xy 104.640757 -56.475618) (xy 104.717517 -56.437396) (xy 104.797476 -56.40642) (xy 104.879952 -56.382953)
			(xy 104.964242 -56.367197) (xy 105.049625 -56.359285) (xy 105.135375 -56.359285) (xy 105.220758 -56.367197)
			(xy 105.305048 -56.382953) (xy 105.387524 -56.40642) (xy 105.467483 -56.437396) (xy 105.544243 -56.475618)
			(xy 105.617149 -56.520759) (xy 105.685578 -56.572435) (xy 105.748948 -56.630204) (xy 105.806717 -56.693574)
			(xy 105.858393 -56.762003) (xy 105.903534 -56.834909) (xy 105.941756 -56.911669) (xy 105.972732 -56.991628)
			(xy 105.996199 -57.074104) (xy 106.011955 -57.158394) (xy 106.019867 -57.243777) (xy 106.020362 -57.286652)
			(xy 106.019867 -57.329527) (xy 106.011955 -57.41491) (xy 105.996199 -57.4992) (xy 105.972732 -57.581676)
			(xy 105.941756 -57.661635) (xy 105.903534 -57.738395) (xy 105.858393 -57.811301) (xy 105.806717 -57.87973)
			(xy 105.748948 -57.9431) (xy 105.685578 -58.000869) (xy 105.617149 -58.052545) (xy 105.544243 -58.097686)
			(xy 105.467483 -58.135908) (xy 105.387524 -58.166884) (xy 105.305048 -58.190351) (xy 105.220758 -58.206107)
			(xy 105.135375 -58.214019) (xy 105.049625 -58.214019) (xy 104.964242 -58.206107) (xy 104.879952 -58.190351)
			(xy 104.797476 -58.166884) (xy 104.717517 -58.135908) (xy 104.640757 -58.097686) (xy 104.567851 -58.052545)
			(xy 104.499422 -58.000869) (xy 104.436052 -57.9431) (xy 104.378283 -57.87973) (xy 104.326607 -57.811301)
			(xy 104.281466 -57.738395) (xy 104.243244 -57.661635) (xy 104.212268 -57.581676) (xy 104.188801 -57.4992)
			(xy 104.173045 -57.41491) (xy 104.165133 -57.329527) (xy 103.479867 -57.329527) (xy 103.471955 -57.41491)
			(xy 103.456199 -57.4992) (xy 103.432732 -57.581676) (xy 103.401756 -57.661635) (xy 103.363534 -57.738395)
			(xy 103.318393 -57.811301) (xy 103.266717 -57.87973) (xy 103.208948 -57.9431) (xy 103.145578 -58.000869)
			(xy 103.077149 -58.052545) (xy 103.004243 -58.097686) (xy 102.927483 -58.135908) (xy 102.847524 -58.166884)
			(xy 102.765048 -58.190351) (xy 102.680758 -58.206107) (xy 102.595375 -58.214019) (xy 102.509625 -58.214019)
			(xy 102.424242 -58.206107) (xy 102.339952 -58.190351) (xy 102.257476 -58.166884) (xy 102.177517 -58.135908)
			(xy 102.100757 -58.097686) (xy 102.027851 -58.052545) (xy 101.959422 -58.000869) (xy 101.896052 -57.9431)
			(xy 101.838283 -57.87973) (xy 101.786607 -57.811301) (xy 101.741466 -57.738395) (xy 101.703244 -57.661635)
			(xy 101.672268 -57.581676) (xy 101.648801 -57.4992) (xy 101.633045 -57.41491) (xy 101.625133 -57.329527)
			(xy 100.939867 -57.329527) (xy 100.931955 -57.41491) (xy 100.916199 -57.4992) (xy 100.892732 -57.581676)
			(xy 100.861756 -57.661635) (xy 100.823534 -57.738395) (xy 100.778393 -57.811301) (xy 100.726717 -57.87973)
			(xy 100.668948 -57.9431) (xy 100.605578 -58.000869) (xy 100.537149 -58.052545) (xy 100.464243 -58.097686)
			(xy 100.387483 -58.135908) (xy 100.307524 -58.166884) (xy 100.225048 -58.190351) (xy 100.140758 -58.206107)
			(xy 100.055375 -58.214019) (xy 99.969625 -58.214019) (xy 99.884242 -58.206107) (xy 99.799952 -58.190351)
			(xy 99.717476 -58.166884) (xy 99.637517 -58.135908) (xy 99.560757 -58.097686) (xy 99.487851 -58.052545)
			(xy 99.419422 -58.000869) (xy 99.356052 -57.9431) (xy 99.298283 -57.87973) (xy 99.246607 -57.811301)
			(xy 99.201466 -57.738395) (xy 99.163244 -57.661635) (xy 99.132268 -57.581676) (xy 99.108801 -57.4992)
			(xy 99.093045 -57.41491) (xy 99.085133 -57.329527) (xy 92.50807 -57.329527) (xy 92.50807 -62.793575)
			(xy 99.085133 -62.793575) (xy 99.085133 -62.707825) (xy 99.093045 -62.622442) (xy 99.108801 -62.538152)
			(xy 99.132268 -62.455676) (xy 99.163244 -62.375717) (xy 99.201466 -62.298957) (xy 99.246607 -62.226051)
			(xy 99.298283 -62.157622) (xy 99.356052 -62.094252) (xy 99.419422 -62.036483) (xy 99.487851 -61.984807)
			(xy 99.560757 -61.939666) (xy 99.637517 -61.901444) (xy 99.717476 -61.870468) (xy 99.799952 -61.847001)
			(xy 99.884242 -61.831245) (xy 99.969625 -61.823333) (xy 100.055375 -61.823333) (xy 100.140758 -61.831245)
			(xy 100.225048 -61.847001) (xy 100.307524 -61.870468) (xy 100.387483 -61.901444) (xy 100.464243 -61.939666)
			(xy 100.537149 -61.984807) (xy 100.605578 -62.036483) (xy 100.668948 -62.094252) (xy 100.726717 -62.157622)
			(xy 100.778393 -62.226051) (xy 100.823534 -62.298957) (xy 100.861756 -62.375717) (xy 100.892732 -62.455676)
			(xy 100.916199 -62.538152) (xy 100.931955 -62.622442) (xy 100.939867 -62.707825) (xy 100.940362 -62.7507)
			(xy 100.939867 -62.793575) (xy 101.625133 -62.793575) (xy 101.625133 -62.707825) (xy 101.633045 -62.622442)
			(xy 101.648801 -62.538152) (xy 101.672268 -62.455676) (xy 101.703244 -62.375717) (xy 101.741466 -62.298957)
			(xy 101.786607 -62.226051) (xy 101.838283 -62.157622) (xy 101.896052 -62.094252) (xy 101.959422 -62.036483)
			(xy 102.027851 -61.984807) (xy 102.100757 -61.939666) (xy 102.177517 -61.901444) (xy 102.257476 -61.870468)
			(xy 102.339952 -61.847001) (xy 102.424242 -61.831245) (xy 102.509625 -61.823333) (xy 102.595375 -61.823333)
			(xy 102.680758 -61.831245) (xy 102.765048 -61.847001) (xy 102.847524 -61.870468) (xy 102.927483 -61.901444)
			(xy 103.004243 -61.939666) (xy 103.077149 -61.984807) (xy 103.145578 -62.036483) (xy 103.208948 -62.094252)
			(xy 103.266717 -62.157622) (xy 103.318393 -62.226051) (xy 103.363534 -62.298957) (xy 103.401756 -62.375717)
			(xy 103.432732 -62.455676) (xy 103.456199 -62.538152) (xy 103.471955 -62.622442) (xy 103.479867 -62.707825)
			(xy 103.480362 -62.7507) (xy 103.479867 -62.793575) (xy 104.165133 -62.793575) (xy 104.165133 -62.707825)
			(xy 104.173045 -62.622442) (xy 104.188801 -62.538152) (xy 104.212268 -62.455676) (xy 104.243244 -62.375717)
			(xy 104.281466 -62.298957) (xy 104.326607 -62.226051) (xy 104.378283 -62.157622) (xy 104.436052 -62.094252)
			(xy 104.499422 -62.036483) (xy 104.567851 -61.984807) (xy 104.640757 -61.939666) (xy 104.717517 -61.901444)
			(xy 104.797476 -61.870468) (xy 104.879952 -61.847001) (xy 104.964242 -61.831245) (xy 105.049625 -61.823333)
			(xy 105.135375 -61.823333) (xy 105.220758 -61.831245) (xy 105.305048 -61.847001) (xy 105.387524 -61.870468)
			(xy 105.467483 -61.901444) (xy 105.544243 -61.939666) (xy 105.617149 -61.984807) (xy 105.685578 -62.036483)
			(xy 105.748948 -62.094252) (xy 105.806717 -62.157622) (xy 105.858393 -62.226051) (xy 105.903534 -62.298957)
			(xy 105.941756 -62.375717) (xy 105.972732 -62.455676) (xy 105.996199 -62.538152) (xy 106.011955 -62.622442)
			(xy 106.019867 -62.707825) (xy 106.020362 -62.7507) (xy 106.019867 -62.793575) (xy 106.011955 -62.878958)
			(xy 105.996199 -62.963248) (xy 105.972732 -63.045724) (xy 105.941756 -63.125683) (xy 105.903534 -63.202443)
			(xy 105.858393 -63.275349) (xy 105.806717 -63.343778) (xy 105.748948 -63.407148) (xy 105.685578 -63.464917)
			(xy 105.617149 -63.516593) (xy 105.544243 -63.561734) (xy 105.467483 -63.599956) (xy 105.387524 -63.630932)
			(xy 105.305048 -63.654399) (xy 105.220758 -63.670155) (xy 105.135375 -63.678067) (xy 105.049625 -63.678067)
			(xy 104.964242 -63.670155) (xy 104.879952 -63.654399) (xy 104.797476 -63.630932) (xy 104.717517 -63.599956)
			(xy 104.640757 -63.561734) (xy 104.567851 -63.516593) (xy 104.499422 -63.464917) (xy 104.436052 -63.407148)
			(xy 104.378283 -63.343778) (xy 104.326607 -63.275349) (xy 104.281466 -63.202443) (xy 104.243244 -63.125683)
			(xy 104.212268 -63.045724) (xy 104.188801 -62.963248) (xy 104.173045 -62.878958) (xy 104.165133 -62.793575)
			(xy 103.479867 -62.793575) (xy 103.471955 -62.878958) (xy 103.456199 -62.963248) (xy 103.432732 -63.045724)
			(xy 103.401756 -63.125683) (xy 103.363534 -63.202443) (xy 103.318393 -63.275349) (xy 103.266717 -63.343778)
			(xy 103.208948 -63.407148) (xy 103.145578 -63.464917) (xy 103.077149 -63.516593) (xy 103.004243 -63.561734)
			(xy 102.927483 -63.599956) (xy 102.847524 -63.630932) (xy 102.765048 -63.654399) (xy 102.680758 -63.670155)
			(xy 102.595375 -63.678067) (xy 102.509625 -63.678067) (xy 102.424242 -63.670155) (xy 102.339952 -63.654399)
			(xy 102.257476 -63.630932) (xy 102.177517 -63.599956) (xy 102.100757 -63.561734) (xy 102.027851 -63.516593)
			(xy 101.959422 -63.464917) (xy 101.896052 -63.407148) (xy 101.838283 -63.343778) (xy 101.786607 -63.275349)
			(xy 101.741466 -63.202443) (xy 101.703244 -63.125683) (xy 101.672268 -63.045724) (xy 101.648801 -62.963248)
			(xy 101.633045 -62.878958) (xy 101.625133 -62.793575) (xy 100.939867 -62.793575) (xy 100.931955 -62.878958)
			(xy 100.916199 -62.963248) (xy 100.892732 -63.045724) (xy 100.861756 -63.125683) (xy 100.823534 -63.202443)
			(xy 100.778393 -63.275349) (xy 100.726717 -63.343778) (xy 100.668948 -63.407148) (xy 100.605578 -63.464917)
			(xy 100.537149 -63.516593) (xy 100.464243 -63.561734) (xy 100.387483 -63.599956) (xy 100.307524 -63.630932)
			(xy 100.225048 -63.654399) (xy 100.140758 -63.670155) (xy 100.055375 -63.678067) (xy 99.969625 -63.678067)
			(xy 99.884242 -63.670155) (xy 99.799952 -63.654399) (xy 99.717476 -63.630932) (xy 99.637517 -63.599956)
			(xy 99.560757 -63.561734) (xy 99.487851 -63.516593) (xy 99.419422 -63.464917) (xy 99.356052 -63.407148)
			(xy 99.298283 -63.343778) (xy 99.246607 -63.275349) (xy 99.201466 -63.202443) (xy 99.163244 -63.125683)
			(xy 99.132268 -63.045724) (xy 99.108801 -62.963248) (xy 99.093045 -62.878958) (xy 99.085133 -62.793575)
			(xy 92.50807 -62.793575) (xy 92.50807 -69.143575) (xy 99.085133 -69.143575) (xy 99.085133 -69.057825)
			(xy 99.093045 -68.972442) (xy 99.108801 -68.888152) (xy 99.132268 -68.805676) (xy 99.163244 -68.725717)
			(xy 99.201466 -68.648957) (xy 99.246607 -68.576051) (xy 99.298283 -68.507622) (xy 99.356052 -68.444252)
			(xy 99.419422 -68.386483) (xy 99.487851 -68.334807) (xy 99.560757 -68.289666) (xy 99.637517 -68.251444)
			(xy 99.717476 -68.220468) (xy 99.799952 -68.197001) (xy 99.884242 -68.181245) (xy 99.969625 -68.173333)
			(xy 100.055375 -68.173333) (xy 100.140758 -68.181245) (xy 100.225048 -68.197001) (xy 100.307524 -68.220468)
			(xy 100.387483 -68.251444) (xy 100.464243 -68.289666) (xy 100.537149 -68.334807) (xy 100.605578 -68.386483)
			(xy 100.668948 -68.444252) (xy 100.726717 -68.507622) (xy 100.778393 -68.576051) (xy 100.823534 -68.648957)
			(xy 100.861756 -68.725717) (xy 100.892732 -68.805676) (xy 100.916199 -68.888152) (xy 100.931955 -68.972442)
			(xy 100.939867 -69.057825) (xy 100.940362 -69.1007) (xy 100.939867 -69.143575) (xy 101.625133 -69.143575)
			(xy 101.625133 -69.057825) (xy 101.633045 -68.972442) (xy 101.648801 -68.888152) (xy 101.672268 -68.805676)
			(xy 101.703244 -68.725717) (xy 101.741466 -68.648957) (xy 101.786607 -68.576051) (xy 101.838283 -68.507622)
			(xy 101.896052 -68.444252) (xy 101.959422 -68.386483) (xy 102.027851 -68.334807) (xy 102.100757 -68.289666)
			(xy 102.177517 -68.251444) (xy 102.257476 -68.220468) (xy 102.339952 -68.197001) (xy 102.424242 -68.181245)
			(xy 102.509625 -68.173333) (xy 102.595375 -68.173333) (xy 102.680758 -68.181245) (xy 102.765048 -68.197001)
			(xy 102.847524 -68.220468) (xy 102.927483 -68.251444) (xy 103.004243 -68.289666) (xy 103.077149 -68.334807)
			(xy 103.145578 -68.386483) (xy 103.208948 -68.444252) (xy 103.266717 -68.507622) (xy 103.318393 -68.576051)
			(xy 103.363534 -68.648957) (xy 103.401756 -68.725717) (xy 103.432732 -68.805676) (xy 103.456199 -68.888152)
			(xy 103.471955 -68.972442) (xy 103.479867 -69.057825) (xy 103.480362 -69.1007) (xy 103.479867 -69.143575)
			(xy 104.165133 -69.143575) (xy 104.165133 -69.057825) (xy 104.173045 -68.972442) (xy 104.188801 -68.888152)
			(xy 104.212268 -68.805676) (xy 104.243244 -68.725717) (xy 104.281466 -68.648957) (xy 104.326607 -68.576051)
			(xy 104.378283 -68.507622) (xy 104.436052 -68.444252) (xy 104.499422 -68.386483) (xy 104.567851 -68.334807)
			(xy 104.640757 -68.289666) (xy 104.717517 -68.251444) (xy 104.797476 -68.220468) (xy 104.879952 -68.197001)
			(xy 104.964242 -68.181245) (xy 105.049625 -68.173333) (xy 105.135375 -68.173333) (xy 105.220758 -68.181245)
			(xy 105.305048 -68.197001) (xy 105.387524 -68.220468) (xy 105.467483 -68.251444) (xy 105.544243 -68.289666)
			(xy 105.617149 -68.334807) (xy 105.685578 -68.386483) (xy 105.748948 -68.444252) (xy 105.806717 -68.507622)
			(xy 105.858393 -68.576051) (xy 105.903534 -68.648957) (xy 105.941756 -68.725717) (xy 105.972732 -68.805676)
			(xy 105.996199 -68.888152) (xy 106.011955 -68.972442) (xy 106.019867 -69.057825) (xy 106.020362 -69.1007)
			(xy 106.019867 -69.143575) (xy 106.011955 -69.228958) (xy 105.996199 -69.313248) (xy 105.972732 -69.395724)
			(xy 105.941756 -69.475683) (xy 105.903534 -69.552443) (xy 105.858393 -69.625349) (xy 105.806717 -69.693778)
			(xy 105.748948 -69.757148) (xy 105.685578 -69.814917) (xy 105.617149 -69.866593) (xy 105.544243 -69.911734)
			(xy 105.467483 -69.949956) (xy 105.387524 -69.980932) (xy 105.305048 -70.004399) (xy 105.220758 -70.020155)
			(xy 105.135375 -70.028067) (xy 105.049625 -70.028067) (xy 104.964242 -70.020155) (xy 104.879952 -70.004399)
			(xy 104.797476 -69.980932) (xy 104.717517 -69.949956) (xy 104.640757 -69.911734) (xy 104.567851 -69.866593)
			(xy 104.499422 -69.814917) (xy 104.436052 -69.757148) (xy 104.378283 -69.693778) (xy 104.326607 -69.625349)
			(xy 104.281466 -69.552443) (xy 104.243244 -69.475683) (xy 104.212268 -69.395724) (xy 104.188801 -69.313248)
			(xy 104.173045 -69.228958) (xy 104.165133 -69.143575) (xy 103.479867 -69.143575) (xy 103.471955 -69.228958)
			(xy 103.456199 -69.313248) (xy 103.432732 -69.395724) (xy 103.401756 -69.475683) (xy 103.363534 -69.552443)
			(xy 103.318393 -69.625349) (xy 103.266717 -69.693778) (xy 103.208948 -69.757148) (xy 103.145578 -69.814917)
			(xy 103.077149 -69.866593) (xy 103.004243 -69.911734) (xy 102.927483 -69.949956) (xy 102.847524 -69.980932)
			(xy 102.765048 -70.004399) (xy 102.680758 -70.020155) (xy 102.595375 -70.028067) (xy 102.509625 -70.028067)
			(xy 102.424242 -70.020155) (xy 102.339952 -70.004399) (xy 102.257476 -69.980932) (xy 102.177517 -69.949956)
			(xy 102.100757 -69.911734) (xy 102.027851 -69.866593) (xy 101.959422 -69.814917) (xy 101.896052 -69.757148)
			(xy 101.838283 -69.693778) (xy 101.786607 -69.625349) (xy 101.741466 -69.552443) (xy 101.703244 -69.475683)
			(xy 101.672268 -69.395724) (xy 101.648801 -69.313248) (xy 101.633045 -69.228958) (xy 101.625133 -69.143575)
			(xy 100.939867 -69.143575) (xy 100.931955 -69.228958) (xy 100.916199 -69.313248) (xy 100.892732 -69.395724)
			(xy 100.861756 -69.475683) (xy 100.823534 -69.552443) (xy 100.778393 -69.625349) (xy 100.726717 -69.693778)
			(xy 100.668948 -69.757148) (xy 100.605578 -69.814917) (xy 100.537149 -69.866593) (xy 100.464243 -69.911734)
			(xy 100.387483 -69.949956) (xy 100.307524 -69.980932) (xy 100.225048 -70.004399) (xy 100.140758 -70.020155)
			(xy 100.055375 -70.028067) (xy 99.969625 -70.028067) (xy 99.884242 -70.020155) (xy 99.799952 -70.004399)
			(xy 99.717476 -69.980932) (xy 99.637517 -69.949956) (xy 99.560757 -69.911734) (xy 99.487851 -69.866593)
			(xy 99.419422 -69.814917) (xy 99.356052 -69.757148) (xy 99.298283 -69.693778) (xy 99.246607 -69.625349)
			(xy 99.201466 -69.552443) (xy 99.163244 -69.475683) (xy 99.132268 -69.395724) (xy 99.108801 -69.313248)
			(xy 99.093045 -69.228958) (xy 99.085133 -69.143575) (xy 92.50807 -69.143575) (xy 92.50807 -94.976137)
			(xy 93.729289 -94.976137) (xy 93.729289 -94.890387) (xy 93.737201 -94.805004) (xy 93.752957 -94.720714)
			(xy 93.776424 -94.638238) (xy 93.8074 -94.558279) (xy 93.845622 -94.481519) (xy 93.890763 -94.408613)
			(xy 93.942439 -94.340184) (xy 94.000208 -94.276814) (xy 94.063578 -94.219045) (xy 94.132007 -94.167369)
			(xy 94.204913 -94.122228) (xy 94.281673 -94.084006) (xy 94.361632 -94.05303) (xy 94.444108 -94.029563)
			(xy 94.528398 -94.013807) (xy 94.613781 -94.005895) (xy 94.699531 -94.005895) (xy 94.784914 -94.013807)
			(xy 94.869204 -94.029563) (xy 94.95168 -94.05303) (xy 95.031639 -94.084006) (xy 95.108399 -94.122228)
			(xy 95.181305 -94.167369) (xy 95.249734 -94.219045) (xy 95.313104 -94.276814) (xy 95.370873 -94.340184)
			(xy 95.422549 -94.408613) (xy 95.46769 -94.481519) (xy 95.505912 -94.558279) (xy 95.536888 -94.638238)
			(xy 95.560355 -94.720714) (xy 95.576111 -94.805004) (xy 95.584023 -94.890387) (xy 95.584518 -94.933262)
			(xy 95.584023 -94.976137) (xy 96.269289 -94.976137) (xy 96.269289 -94.890387) (xy 96.277201 -94.805004)
			(xy 96.292957 -94.720714) (xy 96.316424 -94.638238) (xy 96.3474 -94.558279) (xy 96.385622 -94.481519)
			(xy 96.430763 -94.408613) (xy 96.482439 -94.340184) (xy 96.540208 -94.276814) (xy 96.603578 -94.219045)
			(xy 96.672007 -94.167369) (xy 96.744913 -94.122228) (xy 96.821673 -94.084006) (xy 96.901632 -94.05303)
			(xy 96.984108 -94.029563) (xy 97.068398 -94.013807) (xy 97.153781 -94.005895) (xy 97.239531 -94.005895)
			(xy 97.324914 -94.013807) (xy 97.409204 -94.029563) (xy 97.49168 -94.05303) (xy 97.571639 -94.084006)
			(xy 97.648399 -94.122228) (xy 97.721305 -94.167369) (xy 97.789734 -94.219045) (xy 97.853104 -94.276814)
			(xy 97.910873 -94.340184) (xy 97.962549 -94.408613) (xy 98.00769 -94.481519) (xy 98.045912 -94.558279)
			(xy 98.076888 -94.638238) (xy 98.100355 -94.720714) (xy 98.116111 -94.805004) (xy 98.124023 -94.890387)
			(xy 98.124518 -94.933262) (xy 98.124023 -94.976137) (xy 98.116111 -95.06152) (xy 98.100355 -95.14581)
			(xy 98.076888 -95.228286) (xy 98.045912 -95.308245) (xy 98.00769 -95.385005) (xy 97.962549 -95.457911)
			(xy 97.910873 -95.52634) (xy 97.853104 -95.58971) (xy 97.789734 -95.647479) (xy 97.721305 -95.699155)
			(xy 97.648399 -95.744296) (xy 97.571639 -95.782518) (xy 97.49168 -95.813494) (xy 97.409204 -95.836961)
			(xy 97.324914 -95.852717) (xy 97.239531 -95.860629) (xy 97.153781 -95.860629) (xy 97.068398 -95.852717)
			(xy 96.984108 -95.836961) (xy 96.901632 -95.813494) (xy 96.821673 -95.782518) (xy 96.744913 -95.744296)
			(xy 96.672007 -95.699155) (xy 96.603578 -95.647479) (xy 96.540208 -95.58971) (xy 96.482439 -95.52634)
			(xy 96.430763 -95.457911) (xy 96.385622 -95.385005) (xy 96.3474 -95.308245) (xy 96.316424 -95.228286)
			(xy 96.292957 -95.14581) (xy 96.277201 -95.06152) (xy 96.269289 -94.976137) (xy 95.584023 -94.976137)
			(xy 95.576111 -95.06152) (xy 95.560355 -95.14581) (xy 95.536888 -95.228286) (xy 95.505912 -95.308245)
			(xy 95.46769 -95.385005) (xy 95.422549 -95.457911) (xy 95.370873 -95.52634) (xy 95.313104 -95.58971)
			(xy 95.249734 -95.647479) (xy 95.181305 -95.699155) (xy 95.108399 -95.744296) (xy 95.031639 -95.782518)
			(xy 94.95168 -95.813494) (xy 94.869204 -95.836961) (xy 94.784914 -95.852717) (xy 94.699531 -95.860629)
			(xy 94.613781 -95.860629) (xy 94.528398 -95.852717) (xy 94.444108 -95.836961) (xy 94.361632 -95.813494)
			(xy 94.281673 -95.782518) (xy 94.204913 -95.744296) (xy 94.132007 -95.699155) (xy 94.063578 -95.647479)
			(xy 94.000208 -95.58971) (xy 93.942439 -95.52634) (xy 93.890763 -95.457911) (xy 93.845622 -95.385005)
			(xy 93.8074 -95.308245) (xy 93.776424 -95.228286) (xy 93.752957 -95.14581) (xy 93.737201 -95.06152)
			(xy 93.729289 -94.976137) (xy 92.50807 -94.976137) (xy 92.50807 -96.949868) (xy 95.113614 -96.949868)
			(xy 95.113614 -96.895332) (xy 95.121375 -96.841351) (xy 95.136739 -96.789023) (xy 95.159392 -96.739415)
			(xy 95.188875 -96.693535) (xy 95.224586 -96.652317) (xy 95.2658 -96.616601) (xy 95.311676 -96.587113)
			(xy 95.361282 -96.564454) (xy 95.413608 -96.549084) (xy 95.467588 -96.541317) (xy 95.494856 -96.540828)
			(xy 96.358456 -96.540828) (xy 96.385728 -96.541308) (xy 96.439719 -96.549065) (xy 96.492055 -96.564427)
			(xy 96.541673 -96.587082) (xy 96.587561 -96.616568) (xy 96.628785 -96.652284) (xy 96.664506 -96.693504)
			(xy 96.693997 -96.739389) (xy 96.716657 -96.789004) (xy 96.732025 -96.841338) (xy 96.739788 -96.895328)
			(xy 96.739788 -96.949872) (xy 96.732025 -97.003862) (xy 96.716657 -97.056196) (xy 96.693997 -97.105811)
			(xy 96.664506 -97.151696) (xy 96.628785 -97.192916) (xy 96.587561 -97.228632) (xy 96.541673 -97.258118)
			(xy 96.492055 -97.280773) (xy 96.439719 -97.296135) (xy 96.385728 -97.303892) (xy 96.358456 -97.304352)
			(xy 95.494856 -97.304352) (xy 95.467588 -97.303883) (xy 95.413608 -97.296116) (xy 95.361282 -97.280746)
			(xy 95.311676 -97.258087) (xy 95.2658 -97.228599) (xy 95.224586 -97.192883) (xy 95.188875 -97.151665)
			(xy 95.159392 -97.105785) (xy 95.136739 -97.056177) (xy 95.121375 -97.003849) (xy 95.113614 -96.949868)
			(xy 92.50807 -96.949868) (xy 92.50807 -101.326137) (xy 93.729289 -101.326137) (xy 93.729289 -101.240387)
			(xy 93.737201 -101.155004) (xy 93.752957 -101.070714) (xy 93.776424 -100.988238) (xy 93.8074 -100.908279)
			(xy 93.845622 -100.831519) (xy 93.890763 -100.758613) (xy 93.942439 -100.690184) (xy 94.000208 -100.626814)
			(xy 94.063578 -100.569045) (xy 94.132007 -100.517369) (xy 94.204913 -100.472228) (xy 94.281673 -100.434006)
			(xy 94.361632 -100.40303) (xy 94.444108 -100.379563) (xy 94.528398 -100.363807) (xy 94.613781 -100.355895)
			(xy 94.699531 -100.355895) (xy 94.784914 -100.363807) (xy 94.869204 -100.379563) (xy 94.95168 -100.40303)
			(xy 95.031639 -100.434006) (xy 95.108399 -100.472228) (xy 95.181305 -100.517369) (xy 95.249734 -100.569045)
			(xy 95.313104 -100.626814) (xy 95.370873 -100.690184) (xy 95.422549 -100.758613) (xy 95.46769 -100.831519)
			(xy 95.505912 -100.908279) (xy 95.536888 -100.988238) (xy 95.560355 -101.070714) (xy 95.576111 -101.155004)
			(xy 95.584023 -101.240387) (xy 95.584518 -101.283262) (xy 95.584023 -101.326137) (xy 96.269289 -101.326137)
			(xy 96.269289 -101.240387) (xy 96.277201 -101.155004) (xy 96.292957 -101.070714) (xy 96.316424 -100.988238)
			(xy 96.3474 -100.908279) (xy 96.385622 -100.831519) (xy 96.430763 -100.758613) (xy 96.482439 -100.690184)
			(xy 96.540208 -100.626814) (xy 96.603578 -100.569045) (xy 96.672007 -100.517369) (xy 96.744913 -100.472228)
			(xy 96.821673 -100.434006) (xy 96.901632 -100.40303) (xy 96.984108 -100.379563) (xy 97.068398 -100.363807)
			(xy 97.153781 -100.355895) (xy 97.239531 -100.355895) (xy 97.324914 -100.363807) (xy 97.409204 -100.379563)
			(xy 97.49168 -100.40303) (xy 97.571639 -100.434006) (xy 97.648399 -100.472228) (xy 97.721305 -100.517369)
			(xy 97.789734 -100.569045) (xy 97.853104 -100.626814) (xy 97.910873 -100.690184) (xy 97.962549 -100.758613)
			(xy 98.00769 -100.831519) (xy 98.045912 -100.908279) (xy 98.076888 -100.988238) (xy 98.100355 -101.070714)
			(xy 98.116111 -101.155004) (xy 98.124023 -101.240387) (xy 98.124518 -101.283262) (xy 98.124023 -101.326137)
			(xy 98.122681 -101.340615) (xy 99.085133 -101.340615) (xy 99.085133 -101.254865) (xy 99.093045 -101.169482)
			(xy 99.108801 -101.085192) (xy 99.132268 -101.002716) (xy 99.163244 -100.922757) (xy 99.201466 -100.845997)
			(xy 99.246607 -100.773091) (xy 99.298283 -100.704662) (xy 99.356052 -100.641292) (xy 99.419422 -100.583523)
			(xy 99.487851 -100.531847) (xy 99.560757 -100.486706) (xy 99.637517 -100.448484) (xy 99.717476 -100.417508)
			(xy 99.799952 -100.394041) (xy 99.884242 -100.378285) (xy 99.969625 -100.370373) (xy 100.055375 -100.370373)
			(xy 100.140758 -100.378285) (xy 100.225048 -100.394041) (xy 100.307524 -100.417508) (xy 100.387483 -100.448484)
			(xy 100.464243 -100.486706) (xy 100.537149 -100.531847) (xy 100.605578 -100.583523) (xy 100.668948 -100.641292)
			(xy 100.726717 -100.704662) (xy 100.778393 -100.773091) (xy 100.823534 -100.845997) (xy 100.861756 -100.922757)
			(xy 100.892732 -101.002716) (xy 100.916199 -101.085192) (xy 100.931955 -101.169482) (xy 100.939867 -101.254865)
			(xy 100.940362 -101.29774) (xy 100.939867 -101.340615) (xy 101.625133 -101.340615) (xy 101.625133 -101.254865)
			(xy 101.633045 -101.169482) (xy 101.648801 -101.085192) (xy 101.672268 -101.002716) (xy 101.703244 -100.922757)
			(xy 101.741466 -100.845997) (xy 101.786607 -100.773091) (xy 101.838283 -100.704662) (xy 101.896052 -100.641292)
			(xy 101.959422 -100.583523) (xy 102.027851 -100.531847) (xy 102.100757 -100.486706) (xy 102.177517 -100.448484)
			(xy 102.257476 -100.417508) (xy 102.339952 -100.394041) (xy 102.424242 -100.378285) (xy 102.509625 -100.370373)
			(xy 102.595375 -100.370373) (xy 102.680758 -100.378285) (xy 102.765048 -100.394041) (xy 102.847524 -100.417508)
			(xy 102.927483 -100.448484) (xy 103.004243 -100.486706) (xy 103.077149 -100.531847) (xy 103.145578 -100.583523)
			(xy 103.208948 -100.641292) (xy 103.266717 -100.704662) (xy 103.318393 -100.773091) (xy 103.363534 -100.845997)
			(xy 103.401756 -100.922757) (xy 103.432732 -101.002716) (xy 103.456199 -101.085192) (xy 103.471955 -101.169482)
			(xy 103.479867 -101.254865) (xy 103.480362 -101.29774) (xy 103.479867 -101.340615) (xy 104.165133 -101.340615)
			(xy 104.165133 -101.254865) (xy 104.173045 -101.169482) (xy 104.188801 -101.085192) (xy 104.212268 -101.002716)
			(xy 104.243244 -100.922757) (xy 104.281466 -100.845997) (xy 104.326607 -100.773091) (xy 104.378283 -100.704662)
			(xy 104.436052 -100.641292) (xy 104.499422 -100.583523) (xy 104.567851 -100.531847) (xy 104.640757 -100.486706)
			(xy 104.717517 -100.448484) (xy 104.797476 -100.417508) (xy 104.879952 -100.394041) (xy 104.964242 -100.378285)
			(xy 105.049625 -100.370373) (xy 105.135375 -100.370373) (xy 105.220758 -100.378285) (xy 105.305048 -100.394041)
			(xy 105.387524 -100.417508) (xy 105.467483 -100.448484) (xy 105.544243 -100.486706) (xy 105.617149 -100.531847)
			(xy 105.685578 -100.583523) (xy 105.748948 -100.641292) (xy 105.806717 -100.704662) (xy 105.858393 -100.773091)
			(xy 105.903534 -100.845997) (xy 105.941756 -100.922757) (xy 105.972732 -101.002716) (xy 105.996199 -101.085192)
			(xy 106.011955 -101.169482) (xy 106.019867 -101.254865) (xy 106.020362 -101.29774) (xy 106.019867 -101.340615)
			(xy 106.011955 -101.425998) (xy 105.996199 -101.510288) (xy 105.972732 -101.592764) (xy 105.941756 -101.672723)
			(xy 105.903534 -101.749483) (xy 105.858393 -101.822389) (xy 105.806717 -101.890818) (xy 105.748948 -101.954188)
			(xy 105.685578 -102.011957) (xy 105.617149 -102.063633) (xy 105.544243 -102.108774) (xy 105.467483 -102.146996)
			(xy 105.387524 -102.177972) (xy 105.305048 -102.201439) (xy 105.220758 -102.217195) (xy 105.135375 -102.225107)
			(xy 105.049625 -102.225107) (xy 104.964242 -102.217195) (xy 104.879952 -102.201439) (xy 104.797476 -102.177972)
			(xy 104.717517 -102.146996) (xy 104.640757 -102.108774) (xy 104.567851 -102.063633) (xy 104.499422 -102.011957)
			(xy 104.436052 -101.954188) (xy 104.378283 -101.890818) (xy 104.326607 -101.822389) (xy 104.281466 -101.749483)
			(xy 104.243244 -101.672723) (xy 104.212268 -101.592764) (xy 104.188801 -101.510288) (xy 104.173045 -101.425998)
			(xy 104.165133 -101.340615) (xy 103.479867 -101.340615) (xy 103.471955 -101.425998) (xy 103.456199 -101.510288)
			(xy 103.432732 -101.592764) (xy 103.401756 -101.672723) (xy 103.363534 -101.749483) (xy 103.318393 -101.822389)
			(xy 103.266717 -101.890818) (xy 103.208948 -101.954188) (xy 103.145578 -102.011957) (xy 103.077149 -102.063633)
			(xy 103.004243 -102.108774) (xy 102.927483 -102.146996) (xy 102.847524 -102.177972) (xy 102.765048 -102.201439)
			(xy 102.680758 -102.217195) (xy 102.595375 -102.225107) (xy 102.509625 -102.225107) (xy 102.424242 -102.217195)
			(xy 102.339952 -102.201439) (xy 102.257476 -102.177972) (xy 102.177517 -102.146996) (xy 102.100757 -102.108774)
			(xy 102.027851 -102.063633) (xy 101.959422 -102.011957) (xy 101.896052 -101.954188) (xy 101.838283 -101.890818)
			(xy 101.786607 -101.822389) (xy 101.741466 -101.749483) (xy 101.703244 -101.672723) (xy 101.672268 -101.592764)
			(xy 101.648801 -101.510288) (xy 101.633045 -101.425998) (xy 101.625133 -101.340615) (xy 100.939867 -101.340615)
			(xy 100.931955 -101.425998) (xy 100.916199 -101.510288) (xy 100.892732 -101.592764) (xy 100.861756 -101.672723)
			(xy 100.823534 -101.749483) (xy 100.778393 -101.822389) (xy 100.726717 -101.890818) (xy 100.668948 -101.954188)
			(xy 100.605578 -102.011957) (xy 100.537149 -102.063633) (xy 100.464243 -102.108774) (xy 100.387483 -102.146996)
			(xy 100.307524 -102.177972) (xy 100.225048 -102.201439) (xy 100.140758 -102.217195) (xy 100.055375 -102.225107)
			(xy 99.969625 -102.225107) (xy 99.884242 -102.217195) (xy 99.799952 -102.201439) (xy 99.717476 -102.177972)
			(xy 99.637517 -102.146996) (xy 99.560757 -102.108774) (xy 99.487851 -102.063633) (xy 99.419422 -102.011957)
			(xy 99.356052 -101.954188) (xy 99.298283 -101.890818) (xy 99.246607 -101.822389) (xy 99.201466 -101.749483)
			(xy 99.163244 -101.672723) (xy 99.132268 -101.592764) (xy 99.108801 -101.510288) (xy 99.093045 -101.425998)
			(xy 99.085133 -101.340615) (xy 98.122681 -101.340615) (xy 98.116111 -101.41152) (xy 98.100355 -101.49581)
			(xy 98.076888 -101.578286) (xy 98.045912 -101.658245) (xy 98.00769 -101.735005) (xy 97.962549 -101.807911)
			(xy 97.910873 -101.87634) (xy 97.853104 -101.93971) (xy 97.789734 -101.997479) (xy 97.721305 -102.049155)
			(xy 97.648399 -102.094296) (xy 97.571639 -102.132518) (xy 97.49168 -102.163494) (xy 97.409204 -102.186961)
			(xy 97.324914 -102.202717) (xy 97.239531 -102.210629) (xy 97.153781 -102.210629) (xy 97.068398 -102.202717)
			(xy 96.984108 -102.186961) (xy 96.901632 -102.163494) (xy 96.821673 -102.132518) (xy 96.744913 -102.094296)
			(xy 96.672007 -102.049155) (xy 96.603578 -101.997479) (xy 96.540208 -101.93971) (xy 96.482439 -101.87634)
			(xy 96.430763 -101.807911) (xy 96.385622 -101.735005) (xy 96.3474 -101.658245) (xy 96.316424 -101.578286)
			(xy 96.292957 -101.49581) (xy 96.277201 -101.41152) (xy 96.269289 -101.326137) (xy 95.584023 -101.326137)
			(xy 95.576111 -101.41152) (xy 95.560355 -101.49581) (xy 95.536888 -101.578286) (xy 95.505912 -101.658245)
			(xy 95.46769 -101.735005) (xy 95.422549 -101.807911) (xy 95.370873 -101.87634) (xy 95.313104 -101.93971)
			(xy 95.249734 -101.997479) (xy 95.181305 -102.049155) (xy 95.108399 -102.094296) (xy 95.031639 -102.132518)
			(xy 94.95168 -102.163494) (xy 94.869204 -102.186961) (xy 94.784914 -102.202717) (xy 94.699531 -102.210629)
			(xy 94.613781 -102.210629) (xy 94.528398 -102.202717) (xy 94.444108 -102.186961) (xy 94.361632 -102.163494)
			(xy 94.281673 -102.132518) (xy 94.204913 -102.094296) (xy 94.132007 -102.049155) (xy 94.063578 -101.997479)
			(xy 94.000208 -101.93971) (xy 93.942439 -101.87634) (xy 93.890763 -101.807911) (xy 93.845622 -101.735005)
			(xy 93.8074 -101.658245) (xy 93.776424 -101.578286) (xy 93.752957 -101.49581) (xy 93.737201 -101.41152)
			(xy 93.729289 -101.326137) (xy 92.50807 -101.326137) (xy 92.50807 -107.690615) (xy 99.085133 -107.690615)
			(xy 99.085133 -107.604865) (xy 99.093045 -107.519482) (xy 99.108801 -107.435192) (xy 99.132268 -107.352716)
			(xy 99.163244 -107.272757) (xy 99.201466 -107.195997) (xy 99.246607 -107.123091) (xy 99.298283 -107.054662)
			(xy 99.356052 -106.991292) (xy 99.419422 -106.933523) (xy 99.487851 -106.881847) (xy 99.560757 -106.836706)
			(xy 99.637517 -106.798484) (xy 99.717476 -106.767508) (xy 99.799952 -106.744041) (xy 99.884242 -106.728285)
			(xy 99.969625 -106.720373) (xy 100.055375 -106.720373) (xy 100.140758 -106.728285) (xy 100.225048 -106.744041)
			(xy 100.307524 -106.767508) (xy 100.387483 -106.798484) (xy 100.464243 -106.836706) (xy 100.537149 -106.881847)
			(xy 100.605578 -106.933523) (xy 100.668948 -106.991292) (xy 100.726717 -107.054662) (xy 100.778393 -107.123091)
			(xy 100.823534 -107.195997) (xy 100.861756 -107.272757) (xy 100.892732 -107.352716) (xy 100.916199 -107.435192)
			(xy 100.931955 -107.519482) (xy 100.939867 -107.604865) (xy 100.940362 -107.64774) (xy 100.939867 -107.690615)
			(xy 101.625133 -107.690615) (xy 101.625133 -107.604865) (xy 101.633045 -107.519482) (xy 101.648801 -107.435192)
			(xy 101.672268 -107.352716) (xy 101.703244 -107.272757) (xy 101.741466 -107.195997) (xy 101.786607 -107.123091)
			(xy 101.838283 -107.054662) (xy 101.896052 -106.991292) (xy 101.959422 -106.933523) (xy 102.027851 -106.881847)
			(xy 102.100757 -106.836706) (xy 102.177517 -106.798484) (xy 102.257476 -106.767508) (xy 102.339952 -106.744041)
			(xy 102.424242 -106.728285) (xy 102.509625 -106.720373) (xy 102.595375 -106.720373) (xy 102.680758 -106.728285)
			(xy 102.765048 -106.744041) (xy 102.847524 -106.767508) (xy 102.927483 -106.798484) (xy 103.004243 -106.836706)
			(xy 103.077149 -106.881847) (xy 103.145578 -106.933523) (xy 103.208948 -106.991292) (xy 103.266717 -107.054662)
			(xy 103.318393 -107.123091) (xy 103.363534 -107.195997) (xy 103.401756 -107.272757) (xy 103.432732 -107.352716)
			(xy 103.456199 -107.435192) (xy 103.471955 -107.519482) (xy 103.479867 -107.604865) (xy 103.480362 -107.64774)
			(xy 103.479867 -107.690615) (xy 104.165133 -107.690615) (xy 104.165133 -107.604865) (xy 104.173045 -107.519482)
			(xy 104.188801 -107.435192) (xy 104.212268 -107.352716) (xy 104.243244 -107.272757) (xy 104.281466 -107.195997)
			(xy 104.326607 -107.123091) (xy 104.378283 -107.054662) (xy 104.436052 -106.991292) (xy 104.499422 -106.933523)
			(xy 104.567851 -106.881847) (xy 104.640757 -106.836706) (xy 104.717517 -106.798484) (xy 104.797476 -106.767508)
			(xy 104.879952 -106.744041) (xy 104.964242 -106.728285) (xy 105.049625 -106.720373) (xy 105.135375 -106.720373)
			(xy 105.220758 -106.728285) (xy 105.305048 -106.744041) (xy 105.387524 -106.767508) (xy 105.467483 -106.798484)
			(xy 105.544243 -106.836706) (xy 105.617149 -106.881847) (xy 105.685578 -106.933523) (xy 105.748948 -106.991292)
			(xy 105.806717 -107.054662) (xy 105.858393 -107.123091) (xy 105.903534 -107.195997) (xy 105.941756 -107.272757)
			(xy 105.972732 -107.352716) (xy 105.996199 -107.435192) (xy 106.011955 -107.519482) (xy 106.019867 -107.604865)
			(xy 106.020362 -107.64774) (xy 106.019867 -107.690615) (xy 106.011955 -107.775998) (xy 105.996199 -107.860288)
			(xy 105.972732 -107.942764) (xy 105.941756 -108.022723) (xy 105.903534 -108.099483) (xy 105.858393 -108.172389)
			(xy 105.806717 -108.240818) (xy 105.748948 -108.304188) (xy 105.685578 -108.361957) (xy 105.617149 -108.413633)
			(xy 105.544243 -108.458774) (xy 105.467483 -108.496996) (xy 105.387524 -108.527972) (xy 105.305048 -108.551439)
			(xy 105.220758 -108.567195) (xy 105.135375 -108.575107) (xy 105.049625 -108.575107) (xy 104.964242 -108.567195)
			(xy 104.879952 -108.551439) (xy 104.797476 -108.527972) (xy 104.717517 -108.496996) (xy 104.640757 -108.458774)
			(xy 104.567851 -108.413633) (xy 104.499422 -108.361957) (xy 104.436052 -108.304188) (xy 104.378283 -108.240818)
			(xy 104.326607 -108.172389) (xy 104.281466 -108.099483) (xy 104.243244 -108.022723) (xy 104.212268 -107.942764)
			(xy 104.188801 -107.860288) (xy 104.173045 -107.775998) (xy 104.165133 -107.690615) (xy 103.479867 -107.690615)
			(xy 103.471955 -107.775998) (xy 103.456199 -107.860288) (xy 103.432732 -107.942764) (xy 103.401756 -108.022723)
			(xy 103.363534 -108.099483) (xy 103.318393 -108.172389) (xy 103.266717 -108.240818) (xy 103.208948 -108.304188)
			(xy 103.145578 -108.361957) (xy 103.077149 -108.413633) (xy 103.004243 -108.458774) (xy 102.927483 -108.496996)
			(xy 102.847524 -108.527972) (xy 102.765048 -108.551439) (xy 102.680758 -108.567195) (xy 102.595375 -108.575107)
			(xy 102.509625 -108.575107) (xy 102.424242 -108.567195) (xy 102.339952 -108.551439) (xy 102.257476 -108.527972)
			(xy 102.177517 -108.496996) (xy 102.100757 -108.458774) (xy 102.027851 -108.413633) (xy 101.959422 -108.361957)
			(xy 101.896052 -108.304188) (xy 101.838283 -108.240818) (xy 101.786607 -108.172389) (xy 101.741466 -108.099483)
			(xy 101.703244 -108.022723) (xy 101.672268 -107.942764) (xy 101.648801 -107.860288) (xy 101.633045 -107.775998)
			(xy 101.625133 -107.690615) (xy 100.939867 -107.690615) (xy 100.931955 -107.775998) (xy 100.916199 -107.860288)
			(xy 100.892732 -107.942764) (xy 100.861756 -108.022723) (xy 100.823534 -108.099483) (xy 100.778393 -108.172389)
			(xy 100.726717 -108.240818) (xy 100.668948 -108.304188) (xy 100.605578 -108.361957) (xy 100.537149 -108.413633)
			(xy 100.464243 -108.458774) (xy 100.387483 -108.496996) (xy 100.307524 -108.527972) (xy 100.225048 -108.551439)
			(xy 100.140758 -108.567195) (xy 100.055375 -108.575107) (xy 99.969625 -108.575107) (xy 99.884242 -108.567195)
			(xy 99.799952 -108.551439) (xy 99.717476 -108.527972) (xy 99.637517 -108.496996) (xy 99.560757 -108.458774)
			(xy 99.487851 -108.413633) (xy 99.419422 -108.361957) (xy 99.356052 -108.304188) (xy 99.298283 -108.240818)
			(xy 99.246607 -108.172389) (xy 99.201466 -108.099483) (xy 99.163244 -108.022723) (xy 99.132268 -107.942764)
			(xy 99.108801 -107.860288) (xy 99.093045 -107.775998) (xy 99.085133 -107.690615) (xy 92.50807 -107.690615)
			(xy 92.50807 -115.464644) (xy 115.904253 -115.464644) (xy 115.904253 -115.335504) (xy 115.912203 -115.206609)
			(xy 115.928073 -115.078449) (xy 115.951802 -114.951508) (xy 115.983301 -114.826269) (xy 116.02245 -114.703206)
			(xy 116.069101 -114.582787) (xy 116.123076 -114.465468) (xy 116.184171 -114.351694) (xy 116.252154 -114.241897)
			(xy 116.326768 -114.136494) (xy 116.407729 -114.035884) (xy 116.494729 -113.940449) (xy 116.58744 -113.85055)
			(xy 116.68551 -113.766529) (xy 116.788565 -113.688705) (xy 116.896216 -113.617373) (xy 117.008055 -113.552803)
			(xy 117.123656 -113.495241) (xy 117.242581 -113.444904) (xy 117.36438 -113.401984) (xy 117.48859 -113.366643)
			(xy 117.614739 -113.339016) (xy 117.742351 -113.319207) (xy 117.87094 -113.307291) (xy 118.000018 -113.303315)
			(xy 118.129096 -113.307291) (xy 118.257685 -113.319207) (xy 118.385297 -113.339016) (xy 118.511446 -113.366643)
			(xy 118.635656 -113.401984) (xy 118.757455 -113.444904) (xy 118.87638 -113.495241) (xy 118.991981 -113.552803)
			(xy 119.10382 -113.617373) (xy 119.211471 -113.688705) (xy 119.314526 -113.766529) (xy 119.412596 -113.85055)
			(xy 119.505307 -113.940449) (xy 119.592307 -114.035884) (xy 119.673268 -114.136494) (xy 119.747882 -114.241897)
			(xy 119.815865 -114.351694) (xy 119.87696 -114.465468) (xy 119.930935 -114.582787) (xy 119.977586 -114.703206)
			(xy 120.016735 -114.826269) (xy 120.048234 -114.951508) (xy 120.071963 -115.078449) (xy 120.087833 -115.206609)
			(xy 120.095783 -115.335504) (xy 120.09628 -115.400074) (xy 120.095783 -115.464644) (xy 120.087833 -115.593539)
			(xy 120.071963 -115.721699) (xy 120.048234 -115.84864) (xy 120.016735 -115.973879) (xy 119.977586 -116.096942)
			(xy 119.930935 -116.217361) (xy 119.87696 -116.33468) (xy 119.815865 -116.448454) (xy 119.747882 -116.558251)
			(xy 119.673268 -116.663654) (xy 119.592307 -116.764264) (xy 119.505307 -116.859699) (xy 119.412596 -116.949598)
			(xy 119.314526 -117.033619) (xy 119.211471 -117.111443) (xy 119.10382 -117.182775) (xy 118.991981 -117.247345)
			(xy 118.87638 -117.304907) (xy 118.757455 -117.355244) (xy 118.635656 -117.398164) (xy 118.511446 -117.433505)
			(xy 118.385297 -117.461132) (xy 118.257685 -117.480941) (xy 118.129096 -117.492857) (xy 118.000018 -117.496834)
			(xy 117.87094 -117.492857) (xy 117.742351 -117.480941) (xy 117.614739 -117.461132) (xy 117.48859 -117.433505)
			(xy 117.36438 -117.398164) (xy 117.242581 -117.355244) (xy 117.123656 -117.304907) (xy 117.008055 -117.247345)
			(xy 116.896216 -117.182775) (xy 116.788565 -117.111443) (xy 116.68551 -117.033619) (xy 116.58744 -116.949598)
			(xy 116.494729 -116.859699) (xy 116.407729 -116.764264) (xy 116.326768 -116.663654) (xy 116.252154 -116.558251)
			(xy 116.184171 -116.448454) (xy 116.123076 -116.33468) (xy 116.069101 -116.217361) (xy 116.02245 -116.096942)
			(xy 115.983301 -115.973879) (xy 115.951802 -115.84864) (xy 115.928073 -115.721699) (xy 115.912203 -115.593539)
			(xy 115.904253 -115.464644) (xy 92.50807 -115.464644) (xy 92.50807 -118.400068) (xy 92.508591 -118.455876)
			(xy 92.516929 -118.567181) (xy 92.533562 -118.677551) (xy 92.558397 -118.78637) (xy 92.591294 -118.893028)
			(xy 92.63207 -118.99693) (xy 92.680497 -119.097494) (xy 92.736303 -119.194158) (xy 92.799176 -119.286381)
			(xy 92.868766 -119.373648) (xy 92.944683 -119.45547) (xy 93.026502 -119.531391) (xy 93.113766 -119.600984)
			(xy 93.205986 -119.663862) (xy 93.302648 -119.719673) (xy 93.40321 -119.768103) (xy 93.50711 -119.808884)
			(xy 93.613767 -119.841786) (xy 93.722584 -119.866625) (xy 93.832954 -119.883263) (xy 93.944258 -119.891607)
			(xy 94.000066 -119.892064)
		)
		(stroke
			(width 0)
			(type solid)
		)
		(fill yes)
		(layer "In5.Cu")
		(net "GND_P1")
	)
	(gr_arc
		(start 0.249936 -85.000084)
		(mid 0.073205 -85.073289)
		(end 0 -85.25002)
		(stroke
			(width 2.032)
			(type default)
		)
		(layer "In5.Cu")
	)
	(gr_line
		(start 0.249936 -85.000084)
		(end 2.249932 -85.000084)
		(stroke
			(width 2.032)
			(type default)
		)
		(layer "In5.Cu")
	)
	(gr_arc
		(start 1.999996 0)
		(mid 0.585785 -0.585785)
		(end 0 -1.999996)
		(stroke
			(width 2.032)
			(type default)
		)
		(layer "In5.Cu")
	)
	(gr_line
		(start 1.999996 0)
		(end 33.99028 0)
		(stroke
			(width 2.032)
			(type default)
		)
		(layer "In5.Cu")
	)
	(gr_arc
		(start 2.249932 -85.000084)
		(mid 2.603574 -84.8536)
		(end 2.750058 -84.499958)
		(stroke
			(width 2.032)
			(type default)
		)
		(layer "In5.Cu")
	)
	(gr_line
		(start 2.249932 -81.499964)
		(end 0.249936 -81.499964)
		(stroke
			(width 2.032)
			(type default)
		)
		(layer "In5.Cu")
	)
	(gr_line
		(start 2.750058 -84.499958)
		(end 2.750058 -82.00009)
		(stroke
			(width 2.032)
			(type default)
		)
		(layer "In5.Cu")
	)
	(gr_arc
		(start 2.750058 -82.00009)
		(mid 2.603574 -81.646448)
		(end 2.249932 -81.499964)
		(stroke
			(width 2.032)
			(type default)
		)
		(layer "In5.Cu")
	)
	(gr_line
		(start 4.500118 -114.3)
		(end 1.999996 -114.3)
		(stroke
			(width 2.032)
			(type default)
		)
		(layer "In5.Cu")
	)
	(gr_line
		(start 4.99999 -119.132096)
		(end 4.99999 -114.800126)
		(stroke
			(width 2.032)
			(type default)
		)
		(layer "In5.Cu")
	)
	(gr_arc
		(start 4.99999 -114.800126)
		(mid 4.853581 -114.446663)
		(end 4.500118 -114.3)
		(stroke
			(width 2.032)
			(type default)
		)
		(layer "In5.Cu")
	)
	(gr_line
		(start 5.475986 -34.977578)
		(end 5.475986 -24.777446)
		(stroke
			(width 0.508)
			(type default)
		)
		(layer "In5.Cu")
	)
	(gr_line
		(start 5.475986 -24.777446)
		(end 6.753606 -23.499826)
		(stroke
			(width 0.508)
			(type default)
		)
		(layer "In5.Cu")
	)
	(gr_line
		(start 5.732018 -120.400064)
		(end 4.99999 -119.132096)
		(stroke
			(width 2.032)
			(type default)
		)
		(layer "In5.Cu")
	)
	(gr_line
		(start 6.496304 -35.997896)
		(end 5.475986 -34.977578)
		(stroke
			(width 0.508)
			(type default)
		)
		(layer "In5.Cu")
	)
	(gr_line
		(start 6.753606 -23.499826)
		(end 10.309606 -23.499826)
		(stroke
			(width 0.508)
			(type default)
		)
		(layer "In5.Cu")
	)
	(gr_line
		(start 10.014966 -120.400064)
		(end 5.732018 -120.400064)
		(stroke
			(width 2.032)
			(type default)
		)
		(layer "In5.Cu")
	)
	(gr_line
		(start 10.309606 -23.499826)
		(end 12.187174 -23.499826)
		(stroke
			(width 0.508)
			(type default)
		)
		(layer "In5.Cu")
	)
	(gr_line
		(start 10.765028 -119.650002)
		(end 10.014966 -120.400064)
		(stroke
			(width 2.032)
			(type default)
		)
		(layer "In5.Cu")
	)
	(gr_line
		(start 10.765028 -114.800126)
		(end 10.765028 -119.650002)
		(stroke
			(width 2.032)
			(type default)
		)
		(layer "In5.Cu")
	)
	(gr_arc
		(start 11.2649 -114.3)
		(mid 10.911422 -114.446573)
		(end 10.765028 -114.800126)
		(stroke
			(width 2.032)
			(type default)
		)
		(layer "In5.Cu")
	)
	(gr_line
		(start 11.4554 -77.9018)
		(end 11.4554 -72.6186)
		(stroke
			(width 0.635)
			(type default)
		)
		(layer "In5.Cu")
	)
	(gr_line
		(start 11.4554 -72.6186)
		(end 12.073382 -72.000618)
		(stroke
			(width 0.635)
			(type default)
		)
		(layer "In5.Cu")
	)
	(gr_line
		(start 12.073382 -102.771956)
		(end 12.073382 -78.519782)
		(stroke
			(width 0.635)
			(type default)
		)
		(layer "In5.Cu")
	)
	(gr_line
		(start 12.073382 -78.519782)
		(end 11.4554 -77.9018)
		(stroke
			(width 0.635)
			(type default)
		)
		(layer "In5.Cu")
	)
	(gr_line
		(start 12.073382 -72.000618)
		(end 12.073382 -62.99073)
		(stroke
			(width 0.635)
			(type default)
		)
		(layer "In5.Cu")
	)
	(gr_line
		(start 12.073382 -62.99073)
		(end 16.511778 -58.552334)
		(stroke
			(width 0.635)
			(type default)
		)
		(layer "In5.Cu")
	)
	(gr_line
		(start 12.187174 -23.499826)
		(end 15.113 -20.574)
		(stroke
			(width 0.508)
			(type default)
		)
		(layer "In5.Cu")
	)
	(gr_line
		(start 12.765024 -114.3)
		(end 11.2649 -114.3)
		(stroke
			(width 2.032)
			(type default)
		)
		(layer "In5.Cu")
	)
	(gr_line
		(start 13.264896 -119.650002)
		(end 13.264896 -114.800126)
		(stroke
			(width 2.032)
			(type default)
		)
		(layer "In5.Cu")
	)
	(gr_arc
		(start 13.264896 -114.800126)
		(mid 13.118487 -114.446663)
		(end 12.765024 -114.3)
		(stroke
			(width 2.032)
			(type default)
		)
		(layer "In5.Cu")
	)
	(gr_line
		(start 14.014958 -120.400064)
		(end 13.264896 -119.650002)
		(stroke
			(width 2.032)
			(type default)
		)
		(layer "In5.Cu")
	)
	(gr_line
		(start 14.089888 -104.788462)
		(end 12.073382 -102.771956)
		(stroke
			(width 0.635)
			(type default)
		)
		(layer "In5.Cu")
	)
	(gr_line
		(start 15.113 -20.574)
		(end 15.113 -16.383)
		(stroke
			(width 0.508)
			(type default)
		)
		(layer "In5.Cu")
	)
	(gr_line
		(start 15.113 -16.383)
		(end 15.113 -13.589)
		(stroke
			(width 0.508)
			(type default)
		)
		(layer "In5.Cu")
	)
	(gr_line
		(start 15.113 -13.589)
		(end 16.7894 -11.9126)
		(stroke
			(width 0.508)
			(type default)
		)
		(layer "In5.Cu")
	)
	(gr_line
		(start 15.906496 -52.419758)
		(end 0.373126 -52.419758)
		(stroke
			(width 0.635)
			(type default)
		)
		(layer "In5.Cu")
	)
	(gr_line
		(start 16.04264 -52.556156)
		(end 16.506698 -53.020214)
		(stroke
			(width 0.508)
			(type default)
		)
		(layer "In5.Cu")
	)
	(gr_line
		(start 16.511778 -58.552334)
		(end 16.511778 -53.02504)
		(stroke
			(width 0.635)
			(type default)
		)
		(layer "In5.Cu")
	)
	(gr_line
		(start 16.511778 -53.02504)
		(end 15.906496 -52.419758)
		(stroke
			(width 0.635)
			(type default)
		)
		(layer "In5.Cu")
	)
	(gr_line
		(start 16.7894 -11.9126)
		(end 25.2476 -11.9126)
		(stroke
			(width 0.508)
			(type default)
		)
		(layer "In5.Cu")
	)
	(gr_line
		(start 25.168352 -35.997896)
		(end 6.496304 -35.997896)
		(stroke
			(width 0.508)
			(type default)
		)
		(layer "In5.Cu")
	)
	(gr_line
		(start 25.168352 -35.997896)
		(end 25.863296 -35.997896)
		(stroke
			(width 0.508)
			(type default)
		)
		(layer "In5.Cu")
	)
	(gr_line
		(start 25.2476 -11.9126)
		(end 27.6606 -14.3256)
		(stroke
			(width 0.508)
			(type default)
		)
		(layer "In5.Cu")
	)
	(gr_line
		(start 25.3492 -86.106)
		(end 25.3492 -64.0842)
		(stroke
			(width 0.508)
			(type default)
		)
		(layer "In5.Cu")
	)
	(gr_line
		(start 25.3492 -64.0842)
		(end 27.1272 -62.3062)
		(stroke
			(width 0.508)
			(type default)
		)
		(layer "In5.Cu")
	)
	(gr_line
		(start 25.863296 -35.997896)
		(end 27.9146 -38.0492)
		(stroke
			(width 0.508)
			(type default)
		)
		(layer "In5.Cu")
	)
	(gr_line
		(start 27.1272 -62.3062)
		(end 31.4706 -62.3062)
		(stroke
			(width 0.508)
			(type default)
		)
		(layer "In5.Cu")
	)
	(gr_line
		(start 27.6606 -15.621)
		(end 35.53714 -23.49754)
		(stroke
			(width 0.508)
			(type default)
		)
		(layer "In5.Cu")
	)
	(gr_line
		(start 27.6606 -14.3256)
		(end 27.6606 -15.621)
		(stroke
			(width 0.508)
			(type default)
		)
		(layer "In5.Cu")
	)
	(gr_line
		(start 27.9146 -40.51427)
		(end 32.206946 -44.806616)
		(stroke
			(width 0.508)
			(type default)
		)
		(layer "In5.Cu")
	)
	(gr_line
		(start 27.9146 -38.0492)
		(end 27.9146 -40.51427)
		(stroke
			(width 0.508)
			(type default)
		)
		(layer "In5.Cu")
	)
	(gr_line
		(start 28.6004 -89.3572)
		(end 25.3492 -86.106)
		(stroke
			(width 0.508)
			(type default)
		)
		(layer "In5.Cu")
	)
	(gr_line
		(start 29.1338 -83.9216)
		(end 31.623 -86.4108)
		(stroke
			(width 0.508)
			(type default)
		)
		(layer "In5.Cu")
	)
	(gr_line
		(start 29.1338 -67.1576)
		(end 29.1338 -83.9216)
		(stroke
			(width 0.508)
			(type default)
		)
		(layer "In5.Cu")
	)
	(gr_line
		(start 29.9212 -66.3702)
		(end 29.1338 -67.1576)
		(stroke
			(width 0.508)
			(type default)
		)
		(layer "In5.Cu")
	)
	(gr_line
		(start 30.87497 -120.400064)
		(end 14.014958 -120.400064)
		(stroke
			(width 2.032)
			(type default)
		)
		(layer "In5.Cu")
	)
	(gr_line
		(start 31.4706 -62.3062)
		(end 32.206946 -61.569854)
		(stroke
			(width 0.508)
			(type default)
		)
		(layer "In5.Cu")
	)
	(gr_line
		(start 31.623 -86.4108)
		(end 38.2524 -86.4108)
		(stroke
			(width 0.508)
			(type default)
		)
		(layer "In5.Cu")
	)
	(gr_line
		(start 31.625032 -119.650002)
		(end 30.87497 -120.400064)
		(stroke
			(width 2.032)
			(type default)
		)
		(layer "In5.Cu")
	)
	(gr_line
		(start 31.625032 -114.77498)
		(end 31.625032 -119.650002)
		(stroke
			(width 2.032)
			(type default)
		)
		(layer "In5.Cu")
	)
	(gr_line
		(start 31.969456 -104.788462)
		(end 14.089888 -104.788462)
		(stroke
			(width 0.635)
			(type default)
		)
		(layer "In5.Cu")
	)
	(gr_line
		(start 32.206946 -61.569854)
		(end 32.206946 -44.806616)
		(stroke
			(width 0.508)
			(type default)
		)
		(layer "In5.Cu")
	)
	(gr_line
		(start 33.99028 0)
		(end 88.000078 0)
		(stroke
			(width 2.032)
			(type default)
		)
		(layer "In5.Cu")
	)
	(gr_line
		(start 34.37509 -119.650002)
		(end 34.37509 -114.77498)
		(stroke
			(width 2.032)
			(type default)
		)
		(layer "In5.Cu")
	)
	(gr_arc
		(start 34.37509 -114.77498)
		(mid 32.999934 -113.399824)
		(end 31.625032 -114.77498)
		(stroke
			(width 2.032)
			(type default)
		)
		(layer "In5.Cu")
	)
	(gr_line
		(start 34.9758 -66.3702)
		(end 29.9212 -66.3702)
		(stroke
			(width 0.508)
			(type default)
		)
		(layer "In5.Cu")
	)
	(gr_line
		(start 35.124898 -120.400064)
		(end 34.37509 -119.650002)
		(stroke
			(width 2.032)
			(type default)
		)
		(layer "In5.Cu")
	)
	(gr_line
		(start 35.53714 -23.49754)
		(end 38.243256 -23.49754)
		(stroke
			(width 0.508)
			(type default)
		)
		(layer "In5.Cu")
	)
	(gr_line
		(start 37.554154 -63.791846)
		(end 34.9758 -66.3702)
		(stroke
			(width 0.508)
			(type default)
		)
		(layer "In5.Cu")
	)
	(gr_line
		(start 37.554154 -63.304166)
		(end 37.554154 -63.791846)
		(stroke
			(width 0.508)
			(type default)
		)
		(layer "In5.Cu")
	)
	(gr_line
		(start 37.554154 -33.65754)
		(end 37.554154 -63.304166)
		(stroke
			(width 0.508)
			(type default)
		)
		(layer "In5.Cu")
	)
	(gr_line
		(start 37.560504 -56.09209)
		(end 37.527484 -56.12511)
		(stroke
			(width 0.508)
			(type default)
		)
		(layer "In5.Cu")
	)
	(gr_line
		(start 37.98316 -33.228534)
		(end 37.554154 -33.65754)
		(stroke
			(width 0.508)
			(type default)
		)
		(layer "In5.Cu")
	)
	(gr_line
		(start 38.243256 -23.49754)
		(end 46.283118 -23.499826)
		(stroke
			(width 0.508)
			(type default)
		)
		(layer "In5.Cu")
	)
	(gr_line
		(start 38.2524 -86.4108)
		(end 39.0906 -85.5726)
		(stroke
			(width 0.508)
			(type default)
		)
		(layer "In5.Cu")
	)
	(gr_line
		(start 39.0906 -85.5726)
		(end 39.0906 -74.549254)
		(stroke
			(width 0.508)
			(type default)
		)
		(layer "In5.Cu")
	)
	(gr_line
		(start 39.0906 -74.549254)
		(end 39.741094 -73.89876)
		(stroke
			(width 0.508)
			(type default)
		)
		(layer "In5.Cu")
	)
	(gr_line
		(start 39.523162 -33.217358)
		(end 39.901368 -33.595564)
		(stroke
			(width 0.508)
			(type default)
		)
		(layer "In5.Cu")
	)
	(gr_line
		(start 39.741094 -73.89876)
		(end 51.938174 -73.89876)
		(stroke
			(width 0.508)
			(type default)
		)
		(layer "In5.Cu")
	)
	(gr_line
		(start 39.811452 -33.228534)
		(end 37.98316 -33.228534)
		(stroke
			(width 0.508)
			(type default)
		)
		(layer "In5.Cu")
	)
	(gr_line
		(start 39.897558 -32.842962)
		(end 39.523162 -33.217358)
		(stroke
			(width 0.508)
			(type default)
		)
		(layer "In5.Cu")
	)
	(gr_line
		(start 39.91483 -34.593276)
		(end 42.681144 -37.35959)
		(stroke
			(width 0.508)
			(type default)
		)
		(layer "In5.Cu")
	)
	(gr_line
		(start 39.91483 -30.628844)
		(end 39.91483 -34.593276)
		(stroke
			(width 0.508)
			(type default)
		)
		(layer "In5.Cu")
	)
	(gr_line
		(start 41.185338 -29.358336)
		(end 39.91483 -30.628844)
		(stroke
			(width 0.508)
			(type default)
		)
		(layer "In5.Cu")
	)
	(gr_line
		(start 42.421302 -89.3572)
		(end 28.6004 -89.3572)
		(stroke
			(width 0.508)
			(type default)
		)
		(layer "In5.Cu")
	)
	(gr_line
		(start 42.681144 -37.35959)
		(end 68.887086 -37.35959)
		(stroke
			(width 0.508)
			(type default)
		)
		(layer "In5.Cu")
	)
	(gr_line
		(start 43.584876 -120.400064)
		(end 35.124898 -120.400064)
		(stroke
			(width 2.032)
			(type default)
		)
		(layer "In5.Cu")
	)
	(gr_line
		(start 44.334938 -119.650002)
		(end 43.584876 -120.400064)
		(stroke
			(width 2.032)
			(type default)
		)
		(layer "In5.Cu")
	)
	(gr_line
		(start 44.334938 -114.324892)
		(end 44.334938 -119.650002)
		(stroke
			(width 2.032)
			(type default)
		)
		(layer "In5.Cu")
	)
	(gr_line
		(start 46.185074 -119.650002)
		(end 46.185074 -114.324892)
		(stroke
			(width 2.032)
			(type default)
		)
		(layer "In5.Cu")
	)
	(gr_arc
		(start 46.185074 -114.324892)
		(mid 45.260006 -113.399824)
		(end 44.334938 -114.324892)
		(stroke
			(width 2.032)
			(type default)
		)
		(layer "In5.Cu")
	)
	(gr_line
		(start 46.283118 -23.499826)
		(end 49.889664 -19.89328)
		(stroke
			(width 0.508)
			(type default)
		)
		(layer "In5.Cu")
	)
	(gr_line
		(start 46.4312 -85.347302)
		(end 42.421302 -89.3572)
		(stroke
			(width 0.508)
			(type default)
		)
		(layer "In5.Cu")
	)
	(gr_line
		(start 46.4312 -79.0194)
		(end 46.4312 -85.347302)
		(stroke
			(width 0.508)
			(type default)
		)
		(layer "In5.Cu")
	)
	(gr_line
		(start 46.934882 -120.400064)
		(end 46.185074 -119.650002)
		(stroke
			(width 2.032)
			(type default)
		)
		(layer "In5.Cu")
	)
	(gr_line
		(start 46.99 -78.4606)
		(end 46.4312 -79.0194)
		(stroke
			(width 0.508)
			(type default)
		)
		(layer "In5.Cu")
	)
	(gr_line
		(start 49.889664 -19.89328)
		(end 56.833008 -19.89328)
		(stroke
			(width 0.508)
			(type default)
		)
		(layer "In5.Cu")
	)
	(gr_line
		(start 53.825902 -73.472548)
		(end 53.45049 -73.84796)
		(stroke
			(width 0.508)
			(type default)
		)
		(layer "In5.Cu")
	)
	(gr_line
		(start 53.85181 -73.509124)
		(end 53.462174 -73.89876)
		(stroke
			(width 0.508)
			(type default)
		)
		(layer "In5.Cu")
	)
	(gr_line
		(start 53.85181 -73.509124)
		(end 53.85181 -70.87997)
		(stroke
			(width 0.508)
			(type default)
		)
		(layer "In5.Cu")
	)
	(gr_line
		(start 53.85181 -70.87997)
		(end 54.728618 -70.003162)
		(stroke
			(width 0.508)
			(type default)
		)
		(layer "In5.Cu")
	)
	(gr_line
		(start 54.20487 -73.851516)
		(end 53.825902 -73.472548)
		(stroke
			(width 0.508)
			(type default)
		)
		(layer "In5.Cu")
	)
	(gr_line
		(start 56.3372 -70.003162)
		(end 54.728618 -70.003162)
		(stroke
			(width 0.508)
			(type default)
		)
		(layer "In5.Cu")
	)
	(gr_line
		(start 56.833008 -19.89328)
		(end 60.439554 -23.499826)
		(stroke
			(width 0.508)
			(type default)
		)
		(layer "In5.Cu")
	)
	(gr_line
		(start 56.895238 -70.5612)
		(end 56.3372 -70.003162)
		(stroke
			(width 0.508)
			(type default)
		)
		(layer "In5.Cu")
	)
	(gr_line
		(start 57.0738 -78.4606)
		(end 46.99 -78.4606)
		(stroke
			(width 0.508)
			(type default)
		)
		(layer "In5.Cu")
	)
	(gr_line
		(start 57.867296 -73.947782)
		(end 58.23204 -74.312526)
		(stroke
			(width 0.508)
			(type default)
		)
		(layer "In5.Cu")
	)
	(gr_line
		(start 58.219594 -73.956418)
		(end 58.227722 -73.964546)
		(stroke
			(width 0.508)
			(type default)
		)
		(layer "In5.Cu")
	)
	(gr_line
		(start 58.227722 -77.306678)
		(end 57.0738 -78.4606)
		(stroke
			(width 0.508)
			(type default)
		)
		(layer "In5.Cu")
	)
	(gr_line
		(start 58.227722 -75.694286)
		(end 58.227722 -77.306678)
		(stroke
			(width 0.508)
			(type default)
		)
		(layer "In5.Cu")
	)
	(gr_line
		(start 58.227722 -73.964546)
		(end 58.227722 -75.694286)
		(stroke
			(width 0.508)
			(type default)
		)
		(layer "In5.Cu")
	)
	(gr_line
		(start 58.23204 -74.312526)
		(end 58.629804 -73.914762)
		(stroke
			(width 0.508)
			(type default)
		)
		(layer "In5.Cu")
	)
	(gr_line
		(start 58.5978 -70.5612)
		(end 56.895238 -70.5612)
		(stroke
			(width 0.508)
			(type default)
		)
		(layer "In5.Cu")
	)
	(gr_line
		(start 59.155838 -70.003162)
		(end 58.5978 -70.5612)
		(stroke
			(width 0.508)
			(type default)
		)
		(layer "In5.Cu")
	)
	(gr_line
		(start 60.439554 -23.499826)
		(end 89.479882 -23.499826)
		(stroke
			(width 0.508)
			(type default)
		)
		(layer "In5.Cu")
	)
	(gr_line
		(start 63.784988 -120.400064)
		(end 46.934882 -120.400064)
		(stroke
			(width 2.032)
			(type default)
		)
		(layer "In5.Cu")
	)
	(gr_line
		(start 64.160654 -104.788462)
		(end 31.969456 -104.788462)
		(stroke
			(width 0.635)
			(type default)
		)
		(layer "In5.Cu")
	)
	(gr_line
		(start 64.53505 -119.650002)
		(end 63.784988 -120.400064)
		(stroke
			(width 2.032)
			(type default)
		)
		(layer "In5.Cu")
	)
	(gr_line
		(start 64.53505 -114.525044)
		(end 64.53505 -119.650002)
		(stroke
			(width 2.032)
			(type default)
		)
		(layer "In5.Cu")
	)
	(gr_line
		(start 65.65138 -103.297736)
		(end 64.160654 -104.788462)
		(stroke
			(width 0.635)
			(type default)
		)
		(layer "In5.Cu")
	)
	(gr_line
		(start 66.784982 -119.650002)
		(end 66.784982 -114.525044)
		(stroke
			(width 2.032)
			(type default)
		)
		(layer "In5.Cu")
	)
	(gr_arc
		(start 66.784982 -114.525044)
		(mid 65.660016 -113.400078)
		(end 64.53505 -114.525044)
		(stroke
			(width 2.032)
			(type default)
		)
		(layer "In5.Cu")
	)
	(gr_line
		(start 67.535044 -120.400064)
		(end 66.784982 -119.650002)
		(stroke
			(width 2.032)
			(type default)
		)
		(layer "In5.Cu")
	)
	(gr_line
		(start 68.382134 -70.003162)
		(end 59.155838 -70.003162)
		(stroke
			(width 0.508)
			(type default)
		)
		(layer "In5.Cu")
	)
	(gr_line
		(start 68.887086 -37.35959)
		(end 69.60108 -38.073584)
		(stroke
			(width 0.508)
			(type default)
		)
		(layer "In5.Cu")
	)
	(gr_line
		(start 69.60108 -68.784216)
		(end 68.382134 -70.003162)
		(stroke
			(width 0.508)
			(type default)
		)
		(layer "In5.Cu")
	)
	(gr_line
		(start 69.60108 -38.754558)
		(end 69.60108 -68.784216)
		(stroke
			(width 0.508)
			(type default)
		)
		(layer "In5.Cu")
	)
	(gr_line
		(start 69.60108 -38.073584)
		(end 69.60108 -38.754558)
		(stroke
			(width 0.508)
			(type default)
		)
		(layer "In5.Cu")
	)
	(gr_line
		(start 75.82916 -73.89876)
		(end 51.938174 -73.89876)
		(stroke
			(width 0.508)
			(type default)
		)
		(layer "In5.Cu")
	)
	(gr_line
		(start 75.82916 -73.89876)
		(end 89.96299 -73.89876)
		(stroke
			(width 0.508)
			(type default)
		)
		(layer "In5.Cu")
	)
	(gr_line
		(start 75.989942 -120.400064)
		(end 67.535044 -120.400064)
		(stroke
			(width 2.032)
			(type default)
		)
		(layer "In5.Cu")
	)
	(gr_line
		(start 76.740004 -119.650002)
		(end 75.989942 -120.400064)
		(stroke
			(width 2.032)
			(type default)
		)
		(layer "In5.Cu")
	)
	(gr_line
		(start 76.740004 -114.800126)
		(end 76.740004 -119.650002)
		(stroke
			(width 2.032)
			(type default)
		)
		(layer "In5.Cu")
	)
	(gr_arc
		(start 77.239876 -114.3)
		(mid 76.886398 -114.446573)
		(end 76.740004 -114.800126)
		(stroke
			(width 2.032)
			(type default)
		)
		(layer "In5.Cu")
	)
	(gr_line
		(start 78.74 -114.3)
		(end 77.239876 -114.3)
		(stroke
			(width 2.032)
			(type default)
		)
		(layer "In5.Cu")
	)
	(gr_line
		(start 79.240126 -119.650002)
		(end 79.240126 -114.800126)
		(stroke
			(width 2.032)
			(type default)
		)
		(layer "In5.Cu")
	)
	(gr_arc
		(start 79.240126 -114.800126)
		(mid 79.093642 -114.446484)
		(end 78.74 -114.3)
		(stroke
			(width 2.032)
			(type default)
		)
		(layer "In5.Cu")
	)
	(gr_line
		(start 79.563468 -103.297736)
		(end 65.65138 -103.297736)
		(stroke
			(width 0.635)
			(type default)
		)
		(layer "In5.Cu")
	)
	(gr_line
		(start 79.989934 -120.400064)
		(end 79.240126 -119.650002)
		(stroke
			(width 2.032)
			(type default)
		)
		(layer "In5.Cu")
	)
	(gr_line
		(start 81.82356 -101.037644)
		(end 79.563468 -103.297736)
		(stroke
			(width 0.635)
			(type default)
		)
		(layer "In5.Cu")
	)
	(gr_line
		(start 81.82356 -100.271072)
		(end 81.82356 -101.037644)
		(stroke
			(width 0.635)
			(type default)
		)
		(layer "In5.Cu")
	)
	(gr_line
		(start 81.82356 -79.50835)
		(end 81.82356 -100.271072)
		(stroke
			(width 0.635)
			(type default)
		)
		(layer "In5.Cu")
	)
	(gr_line
		(start 82.145378 -29.358336)
		(end 41.185338 -29.358336)
		(stroke
			(width 0.508)
			(type default)
		)
		(layer "In5.Cu")
	)
	(gr_line
		(start 82.54238 -33.00095)
		(end 82.574638 -32.968692)
		(stroke
			(width 0.508)
			(type default)
		)
		(layer "In5.Cu")
	)
	(gr_line
		(start 82.574638 -32.968692)
		(end 82.574638 -29.787596)
		(stroke
			(width 0.508)
			(type default)
		)
		(layer "In5.Cu")
	)
	(gr_line
		(start 82.574638 -29.787596)
		(end 82.145378 -29.358336)
		(stroke
			(width 0.508)
			(type default)
		)
		(layer "In5.Cu")
	)
	(gr_line
		(start 82.821526 -78.510384)
		(end 81.82356 -79.50835)
		(stroke
			(width 0.635)
			(type default)
		)
		(layer "In5.Cu")
	)
	(gr_line
		(start 83.440778 -33.899348)
		(end 82.54238 -33.00095)
		(stroke
			(width 0.508)
			(type default)
		)
		(layer "In5.Cu")
	)
	(gr_line
		(start 84.268056 -120.400064)
		(end 79.989934 -120.400064)
		(stroke
			(width 2.032)
			(type default)
		)
		(layer "In5.Cu")
	)
	(gr_line
		(start 85.000084 -119.132096)
		(end 84.268056 -120.400064)
		(stroke
			(width 2.032)
			(type default)
		)
		(layer "In5.Cu")
	)
	(gr_line
		(start 85.000084 -114.800126)
		(end 85.000084 -119.132096)
		(stroke
			(width 2.032)
			(type default)
		)
		(layer "In5.Cu")
	)
	(gr_arc
		(start 85.499956 -114.3)
		(mid 85.146478 -114.446573)
		(end 85.000084 -114.800126)
		(stroke
			(width 2.032)
			(type default)
		)
		(layer "In5.Cu")
	)
	(gr_arc
		(start 87.250016 -84.499958)
		(mid 87.39632 -84.853675)
		(end 87.749888 -85.000084)
		(stroke
			(width 2.032)
			(type default)
		)
		(layer "In5.Cu")
	)
	(gr_line
		(start 87.250016 -82.00009)
		(end 87.250016 -84.499958)
		(stroke
			(width 2.032)
			(type default)
		)
		(layer "In5.Cu")
	)
	(gr_line
		(start 87.749888 -85.000084)
		(end 89.749884 -85.000084)
		(stroke
			(width 2.032)
			(type default)
		)
		(layer "In5.Cu")
	)
	(gr_arc
		(start 87.749888 -81.499964)
		(mid 87.39641 -81.646537)
		(end 87.250016 -82.00009)
		(stroke
			(width 2.032)
			(type default)
		)
		(layer "In5.Cu")
	)
	(gr_line
		(start 88.000078 -114.3)
		(end 85.499956 -114.3)
		(stroke
			(width 2.032)
			(type default)
		)
		(layer "In5.Cu")
	)
	(gr_arc
		(start 88.000078 -114.3)
		(mid 89.414304 -113.714223)
		(end 90.000074 -112.300004)
		(stroke
			(width 2.032)
			(type default)
		)
		(layer "In5.Cu")
	)
	(gr_line
		(start 88.67267 -73.89876)
		(end 89.176606 -74.402696)
		(stroke
			(width 0.508)
			(type default)
		)
		(layer "In5.Cu")
	)
	(gr_line
		(start 88.673686 -33.883092)
		(end 89.177622 -34.387028)
		(stroke
			(width 0.508)
			(type default)
		)
		(layer "In5.Cu")
	)
	(gr_line
		(start 88.673686 -33.878012)
		(end 88.673686 -33.883092)
		(stroke
			(width 0.508)
			(type default)
		)
		(layer "In5.Cu")
	)
	(gr_line
		(start 88.713564 -78.553056)
		(end 89.2175 -79.056992)
		(stroke
			(width 0.508)
			(type default)
		)
		(layer "In5.Cu")
	)
	(gr_line
		(start 88.713564 -78.547976)
		(end 88.713564 -78.553056)
		(stroke
			(width 0.508)
			(type default)
		)
		(layer "In5.Cu")
	)
	(gr_line
		(start 88.83269 -23.482808)
		(end 89.336626 -23.986744)
		(stroke
			(width 0.508)
			(type default)
		)
		(layer "In5.Cu")
	)
	(gr_line
		(start 88.83269 -23.477728)
		(end 88.83269 -23.482808)
		(stroke
			(width 0.508)
			(type default)
		)
		(layer "In5.Cu")
	)
	(gr_line
		(start 89.131902 -73.434448)
		(end 88.67267 -73.89368)
		(stroke
			(width 0.508)
			(type default)
		)
		(layer "In5.Cu")
	)
	(gr_line
		(start 89.132918 -33.41878)
		(end 88.673686 -33.878012)
		(stroke
			(width 0.508)
			(type default)
		)
		(layer "In5.Cu")
	)
	(gr_line
		(start 89.172796 -78.088744)
		(end 88.713564 -78.547976)
		(stroke
			(width 0.508)
			(type default)
		)
		(layer "In5.Cu")
	)
	(gr_line
		(start 89.291922 -23.018496)
		(end 88.83269 -23.477728)
		(stroke
			(width 0.508)
			(type default)
		)
		(layer "In5.Cu")
	)
	(gr_line
		(start 89.388696 -33.899348)
		(end 83.440778 -33.899348)
		(stroke
			(width 0.508)
			(type default)
		)
		(layer "In5.Cu")
	)
	(gr_line
		(start 89.423494 -24.696166)
		(end 89.424002 -24.696674)
		(stroke
			(width 0.508)
			(type default)
		)
		(layer "In5.Cu")
	)
	(gr_line
		(start 89.448386 -78.510384)
		(end 82.821526 -78.510384)
		(stroke
			(width 0.635)
			(type default)
		)
		(layer "In5.Cu")
	)
	(gr_line
		(start 89.479882 -23.499826)
		(end 89.485724 -23.505668)
		(stroke
			(width 0.508)
			(type default)
		)
		(layer "In5.Cu")
	)
	(gr_line
		(start 89.749884 -81.499964)
		(end 87.749888 -81.499964)
		(stroke
			(width 2.032)
			(type default)
		)
		(layer "In5.Cu")
	)
	(gr_arc
		(start 89.749884 -81.499964)
		(mid 89.926765 -81.426838)
		(end 90.000074 -81.250028)
		(stroke
			(width 2.032)
			(type default)
		)
		(layer "In5.Cu")
	)
	(gr_line
		(start 89.96299 -73.89876)
		(end 90.000074 -73.935844)
		(stroke
			(width 0.508)
			(type default)
		)
		(layer "In5.Cu")
	)
	(gr_arc
		(start 90.000074 -85.25002)
		(mid 89.926848 -85.073114)
		(end 89.749884 -85.000084)
		(stroke
			(width 2.032)
			(type default)
		)
		(layer "In5.Cu")
	)
	(gr_line
		(start 90.000074 -85.25002)
		(end 90.000074 -112.300004)
		(stroke
			(width 2.032)
			(type default)
		)
		(layer "In5.Cu")
	)
	(gr_arc
		(start 90.000074 -1.999996)
		(mid 89.414286 -0.585796)
		(end 88.000078 0)
		(stroke
			(width 2.032)
			(type default)
		)
		(layer "In5.Cu")
	)
	(gr_line
		(start 90.000074 -1.999996)
		(end 90.000074 -81.250028)
		(stroke
			(width 2.032)
			(type default)
		)
		(layer "In5.Cu")
	)
	(gr_line
		(start 0 -112.300004)
		(end 0 -85.25002)
		(stroke
			(width 2.032)
			(type default)
		)
		(layer "In6.Cu")
	)
	(gr_arc
		(start 0 -112.300004)
		(mid 0.585785 -113.714215)
		(end 1.999996 -114.3)
		(stroke
			(width 2.032)
			(type default)
		)
		(layer "In6.Cu")
	)
	(gr_line
		(start 0 -81.250028)
		(end 0 -1.999996)
		(stroke
			(width 2.032)
			(type default)
		)
		(layer "In6.Cu")
	)
	(gr_arc
		(start 0 -81.250028)
		(mid 0.073204 -81.426762)
		(end 0.249936 -81.499964)
		(stroke
			(width 2.032)
			(type default)
		)
		(layer "In6.Cu")
	)
	(gr_poly
		(pts
			(xy 31.877 -37.690044)
			(arc
				(start 31.877 -28.56611)
				(mid 31.796694 -28.443502)
				(end 31.768542 -28.299664)
			)
			(arc
				(start 31.768542 -28.299664)
				(mid 31.797377 -28.154165)
				(end 31.87954 -28.030678)
			)
			(arc
				(start 31.87954 -28.030678)
				(mid 31.903861 -27.953216)
				(end 31.951422 -27.887422)
			)
			(xy 33.2994 -26.539444) (xy 33.2994 -21.011642)
			(arc
				(start 33.265618 -20.99945)
				(mid 33.011937 -20.64004)
				(end 33.265618 -20.28063)
			)
			(xy 33.2994 -20.268438) (xy 33.2994 -19.764756) (xy 32.762444 -19.2278) (xy 30.479238 -19.2278)
			(arc
				(start 30.46984 -19.266662)
				(mid 30.099 -19.558525)
				(end 29.72816 -19.266662)
			)
			(xy 29.718762 -19.2278) (xy 25.272238 -19.2278)
			(arc
				(start 25.26284 -19.266662)
				(mid 25.236954 -19.339883)
				(end 25.1968 -19.406362)
			)
			(xy 25.1968 -29.968444) (xy 27.539188 -32.310832)
			(arc
				(start 27.571446 -32.295084)
				(mid 27.652009 -32.266992)
				(end 27.7368 -32.257492)
			)
			(arc
				(start 27.7368 -32.257492)
				(mid 28.006567 -32.369233)
				(end 28.118308 -32.639)
			)
			(arc
				(start 28.118308 -32.639)
				(mid 28.078935 -32.807796)
				(end 27.968956 -32.941768)
			)
			(xy 27.968956 -34.193226)
			(arc
				(start 28.000452 -34.20618)
				(mid 28.237738 -34.55924)
				(end 28.000452 -34.9123)
			)
			(xy 27.968956 -34.925254) (xy 27.968956 -36.2712) (xy 29.670756 -37.973) (xy 31.594044 -37.973)
		)
		(stroke
			(width 0)
			(type solid)
		)
		(fill yes)
		(layer "In6.Cu")
		(net "CRT_VCC5")
	)
	(gr_poly
		(pts
			(arc
				(start 12.864084 -58.3565)
				(mid 13.208 -58.140108)
				(end 13.551916 -58.3565)
			)
			(xy 15.1765 -58.3565) (xy 15.1765 -51.156362)
			(arc
				(start 15.136114 -51.14798)
				(mid 14.83306 -50.7746)
				(end 15.136114 -50.40122)
			)
			(xy 15.1765 -50.392838)
			(arc
				(start 15.1765 -43.702224)
				(mid 15.200653 -43.580708)
				(end 15.269464 -43.477688)
			)
			(arc
				(start 17.214088 -41.533064)
				(mid 17.31712 -41.464283)
				(end 17.438624 -41.4401)
			)
			(xy 21.534628 -41.4401) (xy 22.8473 -40.127428) (xy 22.8473 -38.002972) (xy 17.048734 -32.204406)
			(xy 17.025112 -32.206438)
			(arc
				(start 16.9926 -32.207708)
				(mid 16.722833 -32.095967)
				(end 16.611092 -31.8262)
			)
			(xy 16.612362 -31.793688) (xy 16.614394 -31.770066)
			(arc
				(start 15.691866 -30.847538)
				(mid 15.611408 -30.818126)
				(end 15.53718 -30.860746)
			)
			(arc
				(start 15.53718 -30.860746)
				(mid 15.401144 -30.978944)
				(end 15.22603 -31.021528)
			)
			(arc
				(start 15.22603 -31.021528)
				(mid 15.001235 -30.948266)
				(end 14.86281 -30.756606)
			)
			(xy 14.85138 -30.7213) (xy 13.923772 -30.7213) (xy 9.2329 -35.412172)
			(arc
				(start 9.2329 -55.028084)
				(mid 9.449292 -55.372)
				(end 9.2329 -55.715916)
			)
			(xy 9.2329 -57.551828) (xy 10.037572 -58.3565)
		)
		(stroke
			(width 0)
			(type solid)
		)
		(fill yes)
		(layer "In6.Cu")
		(net "P12V_AUX")
	)
	(gr_poly
		(pts
			(xy -3.999992 -119.892064) (xy -3.944185 -119.891542) (xy -3.832883 -119.883201) (xy -3.722516 -119.866566)
			(xy -3.6137 -119.841729) (xy -3.507045 -119.80883) (xy -3.403146 -119.768053) (xy -3.302586 -119.719626)
			(xy -3.205925 -119.663818) (xy -3.113705 -119.600944) (xy -3.026442 -119.531354) (xy -2.944623 -119.455437)
			(xy -2.868706 -119.373618) (xy -2.799116 -119.286355) (xy -2.736242 -119.194135) (xy -2.680434 -119.097474)
			(xy -2.632007 -118.996914) (xy -2.59123 -118.893015) (xy -2.558331 -118.78636) (xy -2.533494 -118.677544)
			(xy -2.516859 -118.567177) (xy -2.508518 -118.455875) (xy -2.507996 -118.400068) (xy -2.507996 -6.59003)
			(xy -2.508518 -6.534223) (xy -2.516859 -6.422921) (xy -2.533494 -6.312554) (xy -2.558331 -6.203738)
			(xy -2.59123 -6.097083) (xy -2.632007 -5.993184) (xy -2.680434 -5.892624) (xy -2.736242 -5.795963)
			(xy -2.799116 -5.703743) (xy -2.868706 -5.61648) (xy -2.944623 -5.534661) (xy -3.026442 -5.458744)
			(xy -3.113705 -5.389154) (xy -3.205925 -5.32628) (xy -3.302586 -5.270472) (xy -3.403146 -5.222045)
			(xy -3.507045 -5.181268) (xy -3.6137 -5.148369) (xy -3.722516 -5.123532) (xy -3.832883 -5.106897)
			(xy -3.944185 -5.098556) (xy -3.999992 -5.098034) (xy -17.78 -5.098034) (xy -17.835807 -5.098556)
			(xy -17.947109 -5.106897) (xy -18.057476 -5.123532) (xy -18.166292 -5.148369) (xy -18.272947 -5.181268)
			(xy -18.376846 -5.222045) (xy -18.477406 -5.270472) (xy -18.574067 -5.32628) (xy -18.666287 -5.389154)
			(xy -18.75355 -5.458744) (xy -18.835369 -5.534661) (xy -18.911286 -5.61648) (xy -18.980876 -5.703743)
			(xy -19.04375 -5.795963) (xy -19.099558 -5.892624) (xy -19.147985 -5.993184) (xy -19.188762 -6.097083)
			(xy -19.221661 -6.203738) (xy -19.246498 -6.312554) (xy -19.263133 -6.422921) (xy -19.271474 -6.534223)
			(xy -19.271996 -6.59003) (xy -19.271996 -115.464644) (xy -16.875771 -115.464644) (xy -16.875771 -115.335504)
			(xy -16.867821 -115.206609) (xy -16.851951 -115.078449) (xy -16.828222 -114.951508) (xy -16.796723 -114.826269)
			(xy -16.757574 -114.703206) (xy -16.710923 -114.582787) (xy -16.656948 -114.465468) (xy -16.595853 -114.351694)
			(xy -16.52787 -114.241897) (xy -16.453256 -114.136494) (xy -16.372295 -114.035884) (xy -16.285295 -113.940449)
			(xy -16.192584 -113.85055) (xy -16.094514 -113.766529) (xy -15.991459 -113.688705) (xy -15.883808 -113.617373)
			(xy -15.771969 -113.552803) (xy -15.656368 -113.495241) (xy -15.537443 -113.444904) (xy -15.415644 -113.401984)
			(xy -15.291434 -113.366643) (xy -15.165285 -113.339016) (xy -15.037673 -113.319207) (xy -14.909084 -113.307291)
			(xy -14.780006 -113.303315) (xy -14.650928 -113.307291) (xy -14.522339 -113.319207) (xy -14.394727 -113.339016)
			(xy -14.268578 -113.366643) (xy -14.144368 -113.401984) (xy -14.022569 -113.444904) (xy -13.903644 -113.495241)
			(xy -13.788043 -113.552803) (xy -13.676204 -113.617373) (xy -13.568553 -113.688705) (xy -13.465498 -113.766529)
			(xy -13.367428 -113.85055) (xy -13.274717 -113.940449) (xy -13.187717 -114.035884) (xy -13.106756 -114.136494)
			(xy -13.032142 -114.241897) (xy -12.964159 -114.351694) (xy -12.903064 -114.465468) (xy -12.849089 -114.582787)
			(xy -12.802438 -114.703206) (xy -12.763289 -114.826269) (xy -12.73179 -114.951508) (xy -12.708061 -115.078449)
			(xy -12.692191 -115.206609) (xy -12.684241 -115.335504) (xy -12.683744 -115.400074) (xy -12.684241 -115.464644)
			(xy -12.692191 -115.593539) (xy -12.708061 -115.721699) (xy -12.73179 -115.84864) (xy -12.763289 -115.973879)
			(xy -12.802438 -116.096942) (xy -12.849089 -116.217361) (xy -12.903064 -116.33468) (xy -12.964159 -116.448454)
			(xy -13.032142 -116.558251) (xy -13.106756 -116.663654) (xy -13.187717 -116.764264) (xy -13.274717 -116.859699)
			(xy -13.367428 -116.949598) (xy -13.465498 -117.033619) (xy -13.568553 -117.111443) (xy -13.676204 -117.182775)
			(xy -13.788043 -117.247345) (xy -13.903644 -117.304907) (xy -14.022569 -117.355244) (xy -14.144368 -117.398164)
			(xy -14.268578 -117.433505) (xy -14.394727 -117.461132) (xy -14.522339 -117.480941) (xy -14.650928 -117.492857)
			(xy -14.780006 -117.496834) (xy -14.909084 -117.492857) (xy -15.037673 -117.480941) (xy -15.165285 -117.461132)
			(xy -15.291434 -117.433505) (xy -15.415644 -117.398164) (xy -15.537443 -117.355244) (xy -15.656368 -117.304907)
			(xy -15.771969 -117.247345) (xy -15.883808 -117.182775) (xy -15.991459 -117.111443) (xy -16.094514 -117.033619)
			(xy -16.192584 -116.949598) (xy -16.285295 -116.859699) (xy -16.372295 -116.764264) (xy -16.453256 -116.663654)
			(xy -16.52787 -116.558251) (xy -16.595853 -116.448454) (xy -16.656948 -116.33468) (xy -16.710923 -116.217361)
			(xy -16.757574 -116.096942) (xy -16.796723 -115.973879) (xy -16.828222 -115.84864) (xy -16.851951 -115.721699)
			(xy -16.867821 -115.593539) (xy -16.875771 -115.464644) (xy -19.271996 -115.464644) (xy -19.271996 -118.400068)
			(xy -19.271474 -118.455875) (xy -19.263133 -118.567177) (xy -19.246498 -118.677544) (xy -19.221661 -118.78636)
			(xy -19.188762 -118.893015) (xy -19.147985 -118.996914) (xy -19.099558 -119.097474) (xy -19.04375 -119.194135)
			(xy -18.980876 -119.286355) (xy -18.911286 -119.373618) (xy -18.835369 -119.455437) (xy -18.75355 -119.531354)
			(xy -18.666287 -119.600944) (xy -18.574067 -119.663818) (xy -18.477406 -119.719626) (xy -18.376846 -119.768053)
			(xy -18.272947 -119.80883) (xy -18.166292 -119.841729) (xy -18.057476 -119.866566) (xy -17.947109 -119.883201)
			(xy -17.835807 -119.891542) (xy -17.78 -119.892064)
		)
		(stroke
			(width 0)
			(type solid)
		)
		(fill yes)
		(layer "In6.Cu")
		(net "T_GND")
	)
	(gr_poly
		(pts
			(arc
				(start 60.653422 -79.322422)
				(mid 60.735799 -79.267316)
				(end 60.833 -79.248)
			)
			(xy 65.123568 -79.248)
			(arc
				(start 65.131188 -79.20609)
				(mid 65.5066 -78.891792)
				(end 65.882012 -79.20609)
			)
			(xy 65.889632 -79.248)
			(arc
				(start 68.961 -79.248)
				(mid 69.058187 -79.26735)
				(end 69.140578 -79.322422)
			)
			(arc
				(start 70.022212 -80.204056)
				(mid 70.13855 -80.135083)
				(end 70.27164 -80.111092)
			)
			(arc
				(start 70.27164 -80.111092)
				(mid 70.442369 -80.151456)
				(end 70.576948 -80.264)
			)
			(xy 77.745844 -80.264) (xy 78.232 -79.777844) (xy 78.232 -78.210156) (xy 77.491844 -77.47)
			(arc
				(start 72.136 -77.47)
				(mid 72.038813 -77.45065)
				(end 71.956422 -77.395578)
			)
			(xy 71.776844 -77.216) (xy 64.240156 -77.216)
			(arc
				(start 63.806578 -77.649578)
				(mid 63.724201 -77.704684)
				(end 63.627 -77.724)
			)
			(arc
				(start 63.480442 -77.724)
				(mid 63.2206 -77.826084)
				(end 62.960758 -77.724)
			)
			(arc
				(start 62.743334 -77.724)
				(mid 62.4586 -77.851477)
				(end 62.173866 -77.724)
			)
			(xy 58.476388 -77.724)
			(arc
				(start 58.462926 -77.753972)
				(mid 58.1152 -77.978515)
				(end 57.767474 -77.753972)
			)
			(xy 57.754012 -77.724) (xy 57.636156 -77.724)
			(arc
				(start 56.821578 -78.538578)
				(mid 56.739201 -78.593684)
				(end 56.642 -78.613)
			)
			(arc
				(start 54.594506 -78.613)
				(mid 54.25694 -78.816728)
				(end 53.919374 -78.613)
			)
			(arc
				(start 53.721 -78.613)
				(mid 53.623813 -78.59365)
				(end 53.541422 -78.538578)
			)
			(xy 51.858164 -76.85532)
			(arc
				(start 51.846226 -76.851764)
				(mid 51.651381 -76.713786)
				(end 51.576732 -76.48702)
			)
			(arc
				(start 51.576732 -76.48702)
				(mid 51.60591 -76.340691)
				(end 51.689 -76.216764)
			)
			(xy 51.689 -74.146156) (xy 50.059844 -72.517)
			(arc
				(start 43.561 -72.517)
				(mid 43.463813 -72.49765)
				(end 43.381422 -72.442578)
			)
			(arc
				(start 42.060622 -71.121778)
				(mid 42.005516 -71.039401)
				(end 41.9862 -70.9422)
			)
			(arc
				(start 41.9862 -65.24879)
				(mid 41.958655 -65.178976)
				(end 41.890696 -65.14719)
			)
			(arc
				(start 41.890696 -65.14719)
				(mid 41.635722 -65.028032)
				(end 41.531794 -64.766444)
			)
			(arc
				(start 41.531794 -64.766444)
				(mid 41.549944 -64.650171)
				(end 41.60266 -64.544956)
			)
			(arc
				(start 41.60266 -64.544956)
				(mid 41.585577 -64.493605)
				(end 41.5798 -64.4398)
			)
			(xy 41.5798 -64.438022) (xy 41.589198 -62.984126) (xy 40.385492 -61.780166) (xy 31.577788 -61.780166)
			(arc
				(start 31.565088 -61.81217)
				(mid 31.210504 -62.052779)
				(end 30.85592 -61.81217)
			)
			(xy 30.84322 -61.780166)
			(arc
				(start 30.209236 -61.780166)
				(mid 29.93136 -61.90028)
				(end 29.653484 -61.780166)
			)
			(arc
				(start 18.346166 -61.780166)
				(mid 18.248979 -61.760816)
				(end 18.166588 -61.705744)
			)
			(arc
				(start 18.154396 -61.693552)
				(mid 18.082922 -61.7152)
				(end 18.0086 -61.722508)
			)
			(arc
				(start 18.0086 -61.722508)
				(mid 17.738833 -61.610767)
				(end 17.627092 -61.341)
			)
			(arc
				(start 17.627092 -61.341)
				(mid 17.631804 -61.281732)
				(end 17.645634 -61.223906)
			)
			(xy 17.655032 -61.194188) (xy 15.452344 -58.9915) (xy 10.16 -58.9915) (xy 10.16 -61.235844) (xy 12.805156 -63.881)
			(xy 23.05177 -63.881)
			(arc
				(start 23.060152 -63.877952)
				(mid 23.1902 -63.855087)
				(end 23.320248 -63.877952)
			)
			(xy 23.32863 -63.881) (xy 29.868622 -63.881)
			(arc
				(start 29.87421 -63.83655)
				(mid 30.000237 -63.59789)
				(end 30.25267 -63.502286)
			)
			(arc
				(start 30.25267 -63.502286)
				(mid 30.505177 -63.597807)
				(end 30.63113 -63.83655)
			)
			(xy 30.636718 -63.881)
			(arc
				(start 31.369 -63.881)
				(mid 31.466187 -63.90035)
				(end 31.548578 -63.955422)
			)
			(xy 37.90442 -70.311264)
			(arc
				(start 37.939472 -70.286118)
				(mid 38.044684 -70.233393)
				(end 38.16096 -70.215252)
			)
			(arc
				(start 38.16096 -70.215252)
				(mid 38.430727 -70.326993)
				(end 38.542468 -70.59676)
			)
			(arc
				(start 38.542468 -70.59676)
				(mid 38.524318 -70.713033)
				(end 38.471602 -70.818248)
			)
			(xy 38.446456 -70.8533) (xy 41.29913 -73.705974)
			(arc
				(start 41.30929 -73.710038)
				(mid 41.443085 -73.796715)
				(end 41.529762 -73.93051)
			)
			(xy 41.533826 -73.94067) (xy 42.015156 -74.422)
			(arc
				(start 45.756576 -74.422)
				(mid 46.023276 -74.31329)
				(end 46.289976 -74.422)
			)
			(arc
				(start 48.641 -74.422)
				(mid 48.738187 -74.44135)
				(end 48.820578 -74.496422)
			)
			(arc
				(start 49.963578 -75.639422)
				(mid 50.018684 -75.721799)
				(end 50.038 -75.819)
			)
			(xy 50.038 -77.872844) (xy 53.064156 -80.899) (xy 59.076844 -80.899)
		)
		(stroke
			(width 0)
			(type solid)
		)
		(fill yes)
		(layer "In6.Cu")
		(net "P3V3_LDO")
	)
	(gr_poly
		(pts
			(xy 56.484266 -73.65238) (xy 56.49911 -73.628326) (xy 56.534774 -73.584477) (xy 56.576515 -73.546366)
			(xy 56.623418 -73.514827) (xy 56.67446 -73.490548) (xy 56.728524 -73.474062) (xy 56.784427 -73.465727)
			(xy 56.840949 -73.465727) (xy 56.896852 -73.474062) (xy 56.950916 -73.490548) (xy 57.001958 -73.514827)
			(xy 57.048861 -73.546366) (xy 57.090602 -73.584477) (xy 57.126266 -73.628326) (xy 57.14111 -73.65238)
			(xy 64.7192 -73.65238) (xy 65.36563 -73.00595) (xy 65.36563 -72.708008) (xy 65.340231 -72.695094)
			(xy 65.293241 -72.662874) (xy 65.251561 -72.624027) (xy 65.216118 -72.579416) (xy 65.1877 -72.530032)
			(xy 65.166939 -72.476973) (xy 65.154294 -72.421418) (xy 65.150048 -72.3646) (xy 65.154294 -72.307782)
			(xy 65.166939 -72.252227) (xy 65.1877 -72.199168) (xy 65.216118 -72.149784) (xy 65.251561 -72.105173)
			(xy 65.293241 -72.066326) (xy 65.340231 -72.034106) (xy 65.36563 -72.021192) (xy 65.36563 -68.71335)
			(xy 65.366206 -68.688392) (xy 65.375954 -68.639436) (xy 65.395066 -68.593323) (xy 65.422808 -68.551824)
			(xy 65.440052 -68.533772) (xy 65.910968 -68.062856) (xy 65.92901 -68.045598) (xy 65.970504 -68.017845)
			(xy 66.016622 -67.998736) (xy 66.065586 -67.989008) (xy 66.090546 -67.988434) (xy 67.438524 -67.988434)
			(xy 67.458298 -67.968164) (xy 67.502765 -67.933105) (xy 67.551926 -67.905005) (xy 67.604701 -67.88448)
			(xy 67.65993 -67.871982) (xy 67.7164 -67.867785) (xy 67.77287 -67.871982) (xy 67.828099 -67.88448)
			(xy 67.880874 -67.905005) (xy 67.930035 -67.933105) (xy 67.974502 -67.968164) (xy 67.994276 -67.988434)
			(xy 88.589358 -67.988434) (xy 88.984074 -67.593718) (xy 88.984074 -66.524886) (xy 88.964392 -66.506703)
			(xy 88.929811 -66.465774) (xy 88.901293 -66.42041) (xy 88.879401 -66.371504) (xy 88.864564 -66.320016)
			(xy 88.857074 -66.266959) (xy 88.857078 -66.213377) (xy 88.864577 -66.160321) (xy 88.879423 -66.108836)
			(xy 88.901323 -66.059933) (xy 88.929848 -66.014574) (xy 88.964437 -65.973651) (xy 88.984074 -65.955418)
			(xy 88.984074 -61.444886) (xy 88.964392 -61.426703) (xy 88.929811 -61.385774) (xy 88.901293 -61.34041)
			(xy 88.879401 -61.291504) (xy 88.864564 -61.240016) (xy 88.857074 -61.186959) (xy 88.857078 -61.133377)
			(xy 88.864577 -61.080321) (xy 88.879423 -61.028836) (xy 88.901323 -60.979933) (xy 88.929848 -60.934574)
			(xy 88.964437 -60.893651) (xy 88.984074 -60.875418) (xy 88.984074 -56.364886) (xy 88.964392 -56.346703)
			(xy 88.929811 -56.305774) (xy 88.901293 -56.26041) (xy 88.879401 -56.211504) (xy 88.864564 -56.160016)
			(xy 88.857074 -56.106959) (xy 88.857078 -56.053377) (xy 88.864577 -56.000321) (xy 88.879423 -55.948836)
			(xy 88.901323 -55.899933) (xy 88.929848 -55.854574) (xy 88.964437 -55.813651) (xy 88.984074 -55.795418)
			(xy 88.984074 -51.284886) (xy 88.964392 -51.266703) (xy 88.929811 -51.225774) (xy 88.901293 -51.18041)
			(xy 88.879401 -51.131504) (xy 88.864564 -51.080016) (xy 88.857074 -51.026959) (xy 88.857078 -50.973377)
			(xy 88.864577 -50.920321) (xy 88.879423 -50.868836) (xy 88.901323 -50.819933) (xy 88.929848 -50.774574)
			(xy 88.964437 -50.733651) (xy 88.984074 -50.715418) (xy 88.984074 -46.204886) (xy 88.964392 -46.186703)
			(xy 88.929811 -46.145774) (xy 88.901293 -46.10041) (xy 88.879401 -46.051504) (xy 88.864564 -46.000016)
			(xy 88.857074 -45.946959) (xy 88.857078 -45.893377) (xy 88.864577 -45.840321) (xy 88.879423 -45.788836)
			(xy 88.901323 -45.739933) (xy 88.929848 -45.694574) (xy 88.964437 -45.653651) (xy 88.984074 -45.635418)
			(xy 88.984074 -41.124886) (xy 88.964392 -41.106703) (xy 88.929811 -41.065774) (xy 88.901293 -41.02041)
			(xy 88.879401 -40.971504) (xy 88.864564 -40.920016) (xy 88.857074 -40.866959) (xy 88.857078 -40.813377)
			(xy 88.864577 -40.760321) (xy 88.879423 -40.708836) (xy 88.901323 -40.659933) (xy 88.929848 -40.614574)
			(xy 88.964437 -40.573651) (xy 88.984074 -40.555418) (xy 88.984074 -36.044886) (xy 88.964448 -36.026789)
			(xy 88.929946 -35.986052) (xy 88.901465 -35.9409) (xy 88.87956 -35.892216) (xy 88.864661 -35.840953)
			(xy 88.857058 -35.788113) (xy 88.856566 -35.761422) (xy 88.856566 -35.740594) (xy 88.58631 -35.470338)
			(xy 84.398104 -35.470338) (xy 84.389722 -35.473386) (xy 84.358844 -35.483615) (xy 84.294736 -35.4946)
			(xy 84.262214 -35.49523) (xy 84.229693 -35.494592) (xy 84.165587 -35.483604) (xy 84.134706 -35.473386)
			(xy 84.126324 -35.470338) (xy 75.705462 -35.470338) (xy 75.680507 -35.469723) (xy 75.631555 -35.45998)
			(xy 75.585445 -35.440877) (xy 75.543946 -35.413146) (xy 75.525884 -35.395916) (xy 72.772524 -32.642556)
			(xy 62.692534 -32.642556) (xy 62.679123 -32.666409) (xy 62.646515 -32.710354) (xy 62.60796 -32.749186)
			(xy 62.564249 -32.782107) (xy 62.516281 -32.808441) (xy 62.46504 -32.827648) (xy 62.411581 -32.839332)
			(xy 62.357 -32.843253) (xy 62.302419 -32.839332) (xy 62.24896 -32.827648) (xy 62.197719 -32.808441)
			(xy 62.149751 -32.782107) (xy 62.10604 -32.749186) (xy 62.067485 -32.710354) (xy 62.034877 -32.666409)
			(xy 62.021466 -32.642556) (xy 59.829446 -32.642556) (xy 59.804488 -32.641979) (xy 59.755533 -32.63223)
			(xy 59.709421 -32.613117) (xy 59.667924 -32.585374) (xy 59.649868 -32.568134) (xy 57.666128 -30.584394)
			(xy 37.83584 -30.584394) (xy 36.022788 -32.397446) (xy 36.02355 -41.022016) (xy 36.02355 -41.02227)
			(xy 36.02355 -41.025572) (xy 36.02355 -41.277794) (xy 36.806378 -42.060622) (xy 36.823643 -42.078661)
			(xy 36.851411 -42.120152) (xy 36.870533 -42.16627) (xy 36.880273 -42.215237) (xy 36.8808 -42.2402)
			(xy 36.8808 -42.733214) (xy 36.905024 -42.746527) (xy 36.949701 -42.779072) (xy 36.989214 -42.817722)
			(xy 37.022737 -42.861671) (xy 37.049567 -42.909996) (xy 37.069144 -42.961687) (xy 37.081057 -43.015662)
			(xy 37.085056 -43.070791) (xy 37.081059 -43.12592) (xy 37.069149 -43.179895) (xy 37.049575 -43.231587)
			(xy 37.022747 -43.279914) (xy 36.989227 -43.323864) (xy 36.949715 -43.362516) (xy 36.90504 -43.395063)
			(xy 36.8808 -43.408346) (xy 36.8808 -43.96232) (xy 36.880187 -43.987276) (xy 36.870446 -44.036228)
			(xy 36.851342 -44.082339) (xy 36.82361 -44.123837) (xy 36.806378 -44.141898) (xy 36.023804 -44.924472)
			(xy 36.023805 -44.932168) (xy 66.731138 -44.932168) (xy 66.731138 -44.877632) (xy 66.738899 -44.823652)
			(xy 66.754264 -44.771325) (xy 66.776918 -44.721717) (xy 66.806402 -44.675839) (xy 66.842114 -44.634623)
			(xy 66.883329 -44.598909) (xy 66.929207 -44.569424) (xy 66.978814 -44.546768) (xy 67.03114 -44.531402)
			(xy 67.08512 -44.523639) (xy 67.112388 -44.523152) (xy 68.001388 -44.523152) (xy 68.028661 -44.523587)
			(xy 68.082651 -44.531348) (xy 68.134987 -44.546714) (xy 68.184603 -44.569371) (xy 68.23049 -44.59886)
			(xy 68.271713 -44.634578) (xy 68.307433 -44.6758) (xy 68.336923 -44.721686) (xy 68.359582 -44.771302)
			(xy 68.37495 -44.823638) (xy 68.382712 -44.877627) (xy 68.382712 -44.932173) (xy 68.37495 -44.986162)
			(xy 68.359582 -45.038498) (xy 68.336923 -45.088114) (xy 68.307433 -45.134) (xy 68.271713 -45.175222)
			(xy 68.23049 -45.21094) (xy 68.184603 -45.240429) (xy 68.134987 -45.263086) (xy 68.082651 -45.278452)
			(xy 68.028661 -45.286213) (xy 68.001388 -45.286676) (xy 67.112388 -45.286676) (xy 67.08512 -45.286161)
			(xy 67.03114 -45.278398) (xy 66.978814 -45.263032) (xy 66.929207 -45.240376) (xy 66.883329 -45.210891)
			(xy 66.842114 -45.175177) (xy 66.806402 -45.133961) (xy 66.776918 -45.088083) (xy 66.754264 -45.038475)
			(xy 66.738899 -44.986148) (xy 66.731138 -44.932168) (xy 36.023805 -44.932168) (xy 36.024058 -48.616616)
			(xy 36.039298 -48.631348) (xy 36.060324 -48.652979) (xy 36.095968 -48.701643) (xy 36.123513 -48.755308)
			(xy 36.142274 -48.812638) (xy 36.151784 -48.872205) (xy 36.152328 -48.902366) (xy 36.152328 -48.90262)
			(xy 36.151762 -48.932782) (xy 36.142277 -48.992355) (xy 36.123531 -49.049692) (xy 36.095991 -49.103362)
			(xy 36.060345 -49.152027) (xy 36.039298 -49.173638) (xy 36.024058 -49.188624) (xy 36.024312 -50.351436)
			(xy 36.041584 -50.366676) (xy 36.061525 -50.384868) (xy 36.09659 -50.425904) (xy 36.12552 -50.471472)
			(xy 36.147738 -50.520664) (xy 36.162801 -50.572496) (xy 36.170406 -50.625934) (xy 36.170403 -50.679911)
			(xy 36.162791 -50.733348) (xy 36.147723 -50.785178) (xy 36.125499 -50.834367) (xy 36.096563 -50.879932)
			(xy 36.061493 -50.920964) (xy 36.041584 -50.939192) (xy 36.024312 -50.954432) (xy 36.024566 -53.726842)
			(xy 36.550854 -54.229) (xy 38.100254 -54.229) (xy 38.11571 -54.228462) (xy 38.145206 -54.219219)
			(xy 38.170581 -54.201567) (xy 38.189506 -54.177126) (xy 38.200243 -54.14814) (xy 38.2016 -54.132734)
			(xy 38.203662 -54.103826) (xy 38.215427 -54.047081) (xy 38.235639 -53.992767) (xy 38.263832 -53.942135)
			(xy 38.299359 -53.896349) (xy 38.341401 -53.856463) (xy 38.388992 -53.823394) (xy 38.441037 -53.797902)
			(xy 38.496338 -53.780575) (xy 38.553624 -53.771811) (xy 38.5826 -53.771292) (xy 38.607542 -53.771698)
			(xy 38.657001 -53.7782) (xy 38.705191 -53.791092) (xy 38.728396 -53.800248) (xy 38.759638 -53.813202)
			(xy 38.857682 -53.715158) (xy 38.857682 -51.369468) (xy 38.858296 -51.344512) (xy 38.868039 -51.295561)
			(xy 38.887143 -51.249451) (xy 38.914874 -51.207953) (xy 38.932104 -51.18989) (xy 39.232078 -50.889916)
			(xy 39.250118 -50.872656) (xy 39.291612 -50.844898) (xy 39.33773 -50.825786) (xy 39.386695 -50.816058)
			(xy 39.411656 -50.815494) (xy 41.78173 -50.815494) (xy 41.803606 -50.800086) (xy 41.850808 -50.774887)
			(xy 41.901067 -50.756526) (xy 41.953398 -50.745364) (xy 42.006774 -50.741618) (xy 42.06015 -50.745364)
			(xy 42.112481 -50.756526) (xy 42.16274 -50.774887) (xy 42.209942 -50.800086) (xy 42.231818 -50.815494)
			(xy 43.217084 -50.815494) (xy 43.242037 -50.816113) (xy 43.290983 -50.825865) (xy 43.337086 -50.844976)
			(xy 43.378575 -50.872713) (xy 43.396662 -50.889916) (xy 43.87088 -51.364134) (xy 43.888144 -51.382173)
			(xy 43.915909 -51.423665) (xy 43.935029 -51.469783) (xy 43.944766 -51.518749) (xy 43.945302 -51.543712)
			(xy 43.945302 -52.507134) (xy 43.99534 -52.557172) (xy 44.003722 -52.560982) (xy 44.028425 -52.572742)
			(xy 44.074473 -52.602285) (xy 44.115828 -52.638104) (xy 44.151642 -52.679463) (xy 44.18118 -52.725515)
			(xy 44.192952 -52.750212) (xy 44.196762 -52.758594) (xy 44.316142 -52.877974) (xy 53.94706 -52.877974)
			(xy 54.525418 -52.299616) (xy 54.525418 -46.938946) (xy 54.526035 -46.913992) (xy 54.535782 -46.865044)
			(xy 54.554891 -46.818938) (xy 54.582627 -46.777446) (xy 54.59984 -46.759368) (xy 54.95671 -46.402498)
			(xy 54.974749 -46.385233) (xy 55.016241 -46.357466) (xy 55.062359 -46.338343) (xy 55.111325 -46.328603)
			(xy 55.136288 -46.328076) (xy 60.382404 -46.328076) (xy 60.407361 -46.328688) (xy 60.456315 -46.338425)
			(xy 60.502429 -46.357525) (xy 60.543932 -46.385254) (xy 60.561982 -46.402498) (xy 60.926726 -46.767242)
			(xy 60.943987 -46.785283) (xy 60.971746 -46.826776) (xy 60.990861 -46.872894) (xy 61.000595 -46.921858)
			(xy 61.001148 -46.94682) (xy 61.001148 -52.67175) (xy 66.314303 -52.67175) (xy 66.314303 -52.61725)
			(xy 66.32206 -52.563304) (xy 66.337415 -52.511011) (xy 66.360056 -52.461436) (xy 66.389522 -52.415587)
			(xy 66.425214 -52.374399) (xy 66.466403 -52.33871) (xy 66.512253 -52.309246) (xy 66.56183 -52.286608)
			(xy 66.614123 -52.271256) (xy 66.66807 -52.263502) (xy 66.69532 -52.26304) (xy 67.58432 -52.26304)
			(xy 67.611574 -52.263431) (xy 67.665526 -52.271191) (xy 67.717825 -52.28655) (xy 67.767406 -52.309195)
			(xy 67.81326 -52.338666) (xy 67.854453 -52.374362) (xy 67.890146 -52.415556) (xy 67.919615 -52.461412)
			(xy 67.942257 -52.510994) (xy 67.957613 -52.563293) (xy 67.96537 -52.617246) (xy 67.96537 -52.671754)
			(xy 67.957613 -52.725707) (xy 67.942257 -52.778006) (xy 67.919615 -52.827588) (xy 67.890146 -52.873444)
			(xy 67.854453 -52.914638) (xy 67.81326 -52.950334) (xy 67.767406 -52.979805) (xy 67.717825 -53.00245)
			(xy 67.665526 -53.017809) (xy 67.611574 -53.025569) (xy 67.58432 -53.026056) (xy 66.69532 -53.026056)
			(xy 66.66807 -53.025498) (xy 66.614123 -53.017744) (xy 66.56183 -53.002392) (xy 66.512253 -52.979754)
			(xy 66.466403 -52.95029) (xy 66.425214 -52.914601) (xy 66.389522 -52.873413) (xy 66.360056 -52.827564)
			(xy 66.337415 -52.777989) (xy 66.32206 -52.725696) (xy 66.314303 -52.67175) (xy 61.001148 -52.67175)
			(xy 61.001148 -54.037992) (xy 61.420756 -54.4576) (xy 66.010282 -54.4576) (xy 66.02095 -54.421278)
			(xy 66.028614 -54.397091) (xy 66.049839 -54.351008) (xy 66.07739 -54.308404) (xy 66.110711 -54.270144)
			(xy 66.149125 -54.237001) (xy 66.191856 -54.209647) (xy 66.238037 -54.188636) (xy 66.286733 -54.174394)
			(xy 66.336958 -54.167209) (xy 66.362326 -54.16677) (xy 66.387827 -54.167208) (xy 66.438306 -54.174485)
			(xy 66.487232 -54.188887) (xy 66.533603 -54.210119) (xy 66.576473 -54.237747) (xy 66.596006 -54.254146)
			(xy 66.603751 -54.260239) (xy 66.622395 -54.266567) (xy 66.64205 -54.265428) (xy 66.659837 -54.256987)
			(xy 66.666872 -54.250082) (xy 66.685031 -54.230753) (xy 66.725766 -54.196793) (xy 66.770809 -54.168798)
			(xy 66.819293 -54.147306) (xy 66.870285 -54.132731) (xy 66.922803 -54.125352) (xy 66.94932 -54.12486)
			(xy 67.83832 -54.12486) (xy 67.863939 -54.125289) (xy 67.914713 -54.132174) (xy 67.96411 -54.145791)
			(xy 68.01124 -54.165894) (xy 68.055257 -54.192123) (xy 68.095368 -54.224006) (xy 68.113402 -54.242208)
			(xy 68.120602 -54.24899) (xy 68.138684 -54.256961) (xy 68.158437 -54.257525) (xy 68.176944 -54.250597)
			(xy 68.184522 -54.24424) (xy 68.20434 -54.22671) (xy 68.248188 -54.1971) (xy 68.295935 -54.174307)
			(xy 68.346531 -54.158832) (xy 68.398859 -54.151017) (xy 68.425314 -54.150514) (xy 68.451496 -54.150979)
			(xy 68.503294 -54.158652) (xy 68.553409 -54.173829) (xy 68.60076 -54.196185) (xy 68.644325 -54.225236)
			(xy 68.683165 -54.260355) (xy 68.716441 -54.300786) (xy 68.743436 -54.345655) (xy 68.763566 -54.393994)
			(xy 68.7705 -54.419246) (xy 68.780152 -54.4576) (xy 74.570844 -54.4576) (xy 74.852022 -54.176422)
			(xy 74.870061 -54.159157) (xy 74.911552 -54.131389) (xy 74.95767 -54.112267) (xy 75.006637 -54.102527)
			(xy 75.0316 -54.102) (xy 78.1558 -54.102) (xy 78.177473 -54.088524) (xy 78.22386 -54.067245) (xy 78.272811 -54.052813)
			(xy 78.323323 -54.045526) (xy 78.34884 -54.045104) (xy 78.372671 -54.045488) (xy 78.419908 -54.051849)
			(xy 78.465874 -54.064453) (xy 78.509749 -54.083074) (xy 78.53045 -54.094888) (xy 78.542388 -54.102)
			(xy 78.73111 -54.102) (xy 78.745128 -54.080226) (xy 78.778459 -54.040595) (xy 78.817173 -54.006203)
			(xy 78.860455 -53.977773) (xy 78.907395 -53.955904) (xy 78.957004 -53.941055) (xy 79.00824 -53.933539)
			(xy 79.034132 -53.93309) (xy 79.062114 -53.933641) (xy 79.117387 -53.9424) (xy 79.17061 -53.959698)
			(xy 79.220472 -53.985107) (xy 79.265745 -54.018004) (xy 79.305315 -54.057578) (xy 79.338208 -54.102854)
			(xy 79.363614 -54.152718) (xy 79.380907 -54.205942) (xy 79.389661 -54.261216) (xy 79.39024 -54.289198)
			(xy 79.389224 -54.316122) (xy 79.387446 -54.33949) (xy 79.833978 -54.786022) (xy 79.851243 -54.804061)
			(xy 79.879011 -54.845552) (xy 79.898133 -54.89167) (xy 79.907873 -54.940637) (xy 79.9084 -54.9656)
			(xy 79.9084 -56.5912) (xy 79.907788 -56.616157) (xy 79.898051 -56.665111) (xy 79.87895 -56.711224)
			(xy 79.85122 -56.752726) (xy 79.833978 -56.770778) (xy 79.325978 -57.278778) (xy 79.307939 -57.296043)
			(xy 79.266448 -57.323811) (xy 79.22033 -57.342933) (xy 79.171363 -57.352673) (xy 79.1464 -57.3532)
			(xy 70.107556 -57.3532) (xy 69.2404 -58.220356) (xy 69.2404 -63.378334) (xy 69.276214 -63.389256)
			(xy 69.301882 -63.397624) (xy 69.350744 -63.420583) (xy 69.39588 -63.450202) (xy 69.436388 -63.485889)
			(xy 69.47146 -63.526932) (xy 69.500395 -63.572511) (xy 69.522613 -63.621713) (xy 69.537672 -63.673557)
			(xy 69.54527 -63.727007) (xy 69.545708 -63.754) (xy 69.545169 -63.782886) (xy 69.536448 -63.839997)
			(xy 69.519219 -63.895141) (xy 69.493878 -63.94706) (xy 69.461001 -63.994566) (xy 69.421341 -64.036576)
			(xy 69.375803 -64.072128) (xy 69.325428 -64.100413) (xy 69.271365 -64.120782) (xy 69.21485 -64.132772)
			(xy 69.186044 -64.135) (xy 69.16674 -64.136016) (xy 68.26504 -65.037716) (xy 68.246999 -65.054976)
			(xy 68.205506 -65.082734) (xy 68.159388 -65.101846) (xy 68.110423 -65.111577) (xy 68.085462 -65.112138)
			(xy 65.724786 -65.112138) (xy 65.720214 -65.1129) (xy 65.703466 -65.115728) (xy 65.669634 -65.118777)
			(xy 65.65265 -65.118996) (xy 65.635665 -65.1188) (xy 65.601832 -65.115748) (xy 65.585086 -65.1129)
			(xy 65.580514 -65.112138) (xy 64.40043 -65.112138) (xy 64.393572 -65.11417) (xy 64.368186 -65.120844)
			(xy 64.316185 -65.127984) (xy 64.28994 -65.128394) (xy 64.263695 -65.12799) (xy 64.211693 -65.120847)
			(xy 64.186308 -65.11417) (xy 64.17945 -65.112138) (xy 61.916818 -65.112138) (xy 61.897123 -65.131683)
			(xy 61.853091 -65.165445) (xy 61.804633 -65.192473) (xy 61.752771 -65.212197) (xy 61.698599 -65.2242)
			(xy 61.64326 -65.22823) (xy 61.587921 -65.2242) (xy 61.533749 -65.212197) (xy 61.481887 -65.192473)
			(xy 61.433429 -65.165445) (xy 61.389397 -65.131683) (xy 61.369702 -65.112138) (xy 58.764424 -65.112138)
			(xy 58.752434 -65.136169) (xy 58.722714 -65.180902) (xy 58.687018 -65.221028) (xy 58.64605 -65.255754)
			(xy 58.60062 -65.284395) (xy 58.551623 -65.306386) (xy 58.500028 -65.321292) (xy 58.446853 -65.32882)
			(xy 58.393147 -65.32882) (xy 58.339972 -65.321292) (xy 58.288377 -65.306386) (xy 58.23938 -65.284395)
			(xy 58.19395 -65.255754) (xy 58.152982 -65.221028) (xy 58.117286 -65.180902) (xy 58.087566 -65.136169)
			(xy 58.075576 -65.112138) (xy 55.715154 -65.112138) (xy 55.709566 -65.117726) (xy 55.343298 -65.483994)
			(xy 55.343298 -66.685668) (xy 55.376572 -66.69786) (xy 55.402097 -66.707739) (xy 55.450248 -66.73376)
			(xy 55.494186 -66.766394) (xy 55.53301 -66.804972) (xy 55.565924 -66.848701) (xy 55.592252 -66.896685)
			(xy 55.611453 -66.947938) (xy 55.623134 -67.001409) (xy 55.627054 -67.056) (xy 55.623134 -67.110591)
			(xy 55.611453 -67.164062) (xy 55.592252 -67.215315) (xy 55.565924 -67.263299) (xy 55.53301 -67.307028)
			(xy 55.494186 -67.345606) (xy 55.450248 -67.37824) (xy 55.402097 -67.404261) (xy 55.376572 -67.41414)
			(xy 55.343298 -67.426332) (xy 55.343298 -73.32091) (xy 55.674768 -73.65238)
		)
		(stroke
			(width 0)
			(type solid)
		)
		(fill yes)
		(layer "In6.Cu")
		(net "P1V2_AUX")
	)
	(gr_poly
		(pts
			(xy 54.8513 -64.595248) (xy 54.875258 -64.57943) (xy 54.926918 -64.554387) (xy 54.981741 -64.537352)
			(xy 55.038496 -64.528707) (xy 55.0672 -64.528192) (xy 55.095907 -64.528707) (xy 55.152671 -64.537313)
			(xy 55.207499 -64.554345) (xy 55.259148 -64.579416) (xy 55.2831 -64.595248) (xy 55.296054 -64.604138)
			(xy 55.372 -64.604138) (xy 55.379967 -64.60319) (xy 55.395981 -64.602172) (xy 55.404004 -64.602106)
			(xy 55.412027 -64.602166) (xy 55.428042 -64.603179) (xy 55.436008 -64.604138) (xy 56.479948 -64.604138)
			(xy 56.492902 -64.572896) (xy 56.504132 -64.547154) (xy 56.533043 -64.499007) (xy 56.5687 -64.455619)
			(xy 56.610334 -64.417928) (xy 56.657044 -64.386748) (xy 56.70782 -64.362754) (xy 56.761566 -64.346463)
			(xy 56.81712 -64.338229) (xy 56.87328 -64.338229) (xy 56.928834 -64.346463) (xy 56.98258 -64.362754)
			(xy 57.033356 -64.386748) (xy 57.080066 -64.417928) (xy 57.1217 -64.455619) (xy 57.157357 -64.499007)
			(xy 57.186268 -64.547154) (xy 57.197498 -64.572896) (xy 57.210452 -64.604138) (xy 58.242708 -64.604138)
			(xy 58.264044 -64.599566) (xy 58.288636 -64.589041) (xy 58.340033 -64.574217) (xy 58.393 -64.566742)
			(xy 58.419746 -64.566292) (xy 58.420254 -64.566292) (xy 58.44704 -64.566751) (xy 58.500084 -64.574243)
			(xy 58.551566 -64.58906) (xy 58.57621 -64.599566) (xy 58.586116 -64.604138) (xy 61.348366 -64.604138)
			(xy 61.366583 -64.582733) (xy 61.408231 -64.544992) (xy 61.454966 -64.513769) (xy 61.505775 -64.489741)
			(xy 61.559561 -64.473427) (xy 61.615158 -64.465181) (xy 61.671362 -64.465181) (xy 61.726959 -64.473427)
			(xy 61.780745 -64.489741) (xy 61.831554 -64.513769) (xy 61.878289 -64.544992) (xy 61.919937 -64.582733)
			(xy 61.938154 -64.604138) (xy 63.934848 -64.604138) (xy 63.948818 -64.576198) (xy 63.96187 -64.55124)
			(xy 63.994205 -64.505126) (xy 64.03297 -64.464267) (xy 64.077321 -64.429553) (xy 64.126294 -64.401738)
			(xy 64.178825 -64.381427) (xy 64.233772 -64.36906) (xy 64.28994 -64.364908) (xy 64.346108 -64.36906)
			(xy 64.401055 -64.381427) (xy 64.453586 -64.401738) (xy 64.502559 -64.429553) (xy 64.54691 -64.464267)
			(xy 64.585675 -64.505126) (xy 64.61801 -64.55124) (xy 64.631062 -64.576198) (xy 64.645032 -64.604138)
			(xy 65.293748 -64.604138) (xy 65.307464 -64.574928) (xy 65.319378 -64.550723) (xy 65.34901 -64.505639)
			(xy 65.384697 -64.465179) (xy 65.425727 -64.430149) (xy 65.471283 -64.401249) (xy 65.520455 -64.379053)
			(xy 65.572264 -64.364006) (xy 65.625675 -64.356406) (xy 65.679625 -64.356406) (xy 65.733036 -64.364006)
			(xy 65.784845 -64.379053) (xy 65.834017 -64.401249) (xy 65.879573 -64.430149) (xy 65.920603 -64.465179)
			(xy 65.95629 -64.505639) (xy 65.985922 -64.550723) (xy 65.997836 -64.574928) (xy 66.011552 -64.604138)
			(xy 67.980306 -64.604138) (xy 68.7324 -63.852044) (xy 68.7324 -58.1152) (xy 68.733012 -58.090243)
			(xy 68.742749 -58.041289) (xy 68.76185 -57.995176) (xy 68.78958 -57.953674) (xy 68.806822 -57.935622)
			(xy 69.822822 -56.919622) (xy 69.840861 -56.902357) (xy 69.882352 -56.874589) (xy 69.92847 -56.855467)
			(xy 69.977437 -56.845727) (xy 70.0024 -56.8452) (xy 79.041244 -56.8452) (xy 79.4004 -56.486044) (xy 79.4004 -55.070756)
			(xy 78.969362 -54.639718) (xy 78.955138 -54.636416) (xy 78.938249 -54.632306) (xy 78.905297 -54.621237)
			(xy 78.889352 -54.614318) (xy 78.879446 -54.61) (xy 78.637384 -54.61) (xy 78.621833 -54.630699) (xy 78.585731 -54.667806)
			(xy 78.544636 -54.699295) (xy 78.499416 -54.724502) (xy 78.451022 -54.742897) (xy 78.400475 -54.754091)
			(xy 78.34884 -54.757849) (xy 78.297205 -54.754091) (xy 78.246658 -54.742897) (xy 78.198264 -54.724502)
			(xy 78.153044 -54.699295) (xy 78.111949 -54.667806) (xy 78.075847 -54.630699) (xy 78.060296 -54.61)
			(xy 75.136756 -54.61) (xy 74.855578 -54.891178) (xy 74.837539 -54.908443) (xy 74.796048 -54.936211)
			(xy 74.74993 -54.955333) (xy 74.700963 -54.965073) (xy 74.676 -54.9656) (xy 61.3156 -54.9656) (xy 61.290643 -54.964988)
			(xy 61.241689 -54.955251) (xy 61.195576 -54.93615) (xy 61.154074 -54.90842) (xy 61.136022 -54.891178)
			(xy 60.56757 -54.322726) (xy 60.550312 -54.304685) (xy 60.522558 -54.26319) (xy 60.503449 -54.217072)
			(xy 60.493722 -54.168109) (xy 60.493148 -54.143148) (xy 60.493148 -47.051976) (xy 60.277248 -46.836076)
			(xy 55.241444 -46.836076) (xy 55.033418 -47.044102) (xy 55.033418 -52.404772) (xy 55.0328 -52.429726)
			(xy 55.023051 -52.478673) (xy 55.003942 -52.524778) (xy 54.976207 -52.56627) (xy 54.958996 -52.58435)
			(xy 54.370478 -53.172868) (xy 54.38902 -53.206396) (xy 54.402019 -53.231046) (xy 54.420466 -53.283625)
			(xy 54.42983 -53.338555) (xy 54.430422 -53.366416) (xy 54.429911 -53.392403) (xy 54.421779 -53.443736)
			(xy 54.405717 -53.493165) (xy 54.38212 -53.539474) (xy 54.35157 -53.581521) (xy 54.314819 -53.618272)
			(xy 54.272772 -53.648821) (xy 54.226464 -53.672417) (xy 54.177034 -53.688479) (xy 54.125701 -53.696611)
			(xy 54.099714 -53.697124) (xy 54.074245 -53.696649) (xy 54.023909 -53.68883) (xy 53.975366 -53.67339)
			(xy 53.929763 -53.650694) (xy 53.888176 -53.621278) (xy 53.851588 -53.585837) (xy 53.820863 -53.545207)
			(xy 53.796727 -53.500349) (xy 53.779749 -53.452322) (xy 53.774594 -53.427376) (xy 53.76672 -53.385974)
			(xy 53.632862 -53.385974) (xy 53.624988 -53.427376) (xy 53.619832 -53.452328) (xy 53.602875 -53.500372)
			(xy 53.578753 -53.545249) (xy 53.548034 -53.585896) (xy 53.511446 -53.621352) (xy 53.469855 -53.650779)
			(xy 53.424243 -53.673481) (xy 53.375689 -53.68892) (xy 53.325343 -53.696732) (xy 53.274393 -53.696732)
			(xy 53.224047 -53.68892) (xy 53.175493 -53.673481) (xy 53.129881 -53.650779) (xy 53.08829 -53.621352)
			(xy 53.051702 -53.585896) (xy 53.020983 -53.545249) (xy 52.996861 -53.500372) (xy 52.979904 -53.452328)
			(xy 52.974748 -53.427376) (xy 52.966874 -53.385974) (xy 52.032662 -53.385974) (xy 52.024788 -53.427376)
			(xy 52.019632 -53.452328) (xy 52.002675 -53.500372) (xy 51.978553 -53.545249) (xy 51.947834 -53.585896)
			(xy 51.911246 -53.621352) (xy 51.869655 -53.650779) (xy 51.824043 -53.673481) (xy 51.775489 -53.68892)
			(xy 51.725143 -53.696732) (xy 51.674193 -53.696732) (xy 51.623847 -53.68892) (xy 51.575293 -53.673481)
			(xy 51.529681 -53.650779) (xy 51.48809 -53.621352) (xy 51.451502 -53.585896) (xy 51.420783 -53.545249)
			(xy 51.396661 -53.500372) (xy 51.379704 -53.452328) (xy 51.374548 -53.427376) (xy 51.366674 -53.385974)
			(xy 51.232816 -53.385974) (xy 51.224942 -53.427376) (xy 51.219786 -53.452328) (xy 51.202829 -53.500372)
			(xy 51.178707 -53.545249) (xy 51.147988 -53.585896) (xy 51.1114 -53.621352) (xy 51.069809 -53.650779)
			(xy 51.024197 -53.673481) (xy 50.975643 -53.68892) (xy 50.925297 -53.696732) (xy 50.874347 -53.696732)
			(xy 50.824001 -53.68892) (xy 50.775447 -53.673481) (xy 50.729835 -53.650779) (xy 50.688244 -53.621352)
			(xy 50.651656 -53.585896) (xy 50.620937 -53.545249) (xy 50.596815 -53.500372) (xy 50.579858 -53.452328)
			(xy 50.574702 -53.427376) (xy 50.566828 -53.385974) (xy 48.83277 -53.385974) (xy 48.824896 -53.427376)
			(xy 48.81974 -53.452328) (xy 48.802783 -53.500372) (xy 48.778661 -53.545249) (xy 48.747942 -53.585896)
			(xy 48.711354 -53.621352) (xy 48.669763 -53.650779) (xy 48.624151 -53.673481) (xy 48.575597 -53.68892)
			(xy 48.525251 -53.696732) (xy 48.474301 -53.696732) (xy 48.423955 -53.68892) (xy 48.375401 -53.673481)
			(xy 48.329789 -53.650779) (xy 48.288198 -53.621352) (xy 48.25161 -53.585896) (xy 48.220891 -53.545249)
			(xy 48.196769 -53.500372) (xy 48.179812 -53.452328) (xy 48.174656 -53.427376) (xy 48.166782 -53.385974)
			(xy 48.03267 -53.385974) (xy 48.024796 -53.427376) (xy 48.01964 -53.452328) (xy 48.002683 -53.500372)
			(xy 47.978561 -53.545249) (xy 47.947842 -53.585896) (xy 47.911254 -53.621352) (xy 47.869663 -53.650779)
			(xy 47.824051 -53.673481) (xy 47.775497 -53.68892) (xy 47.725151 -53.696732) (xy 47.674201 -53.696732)
			(xy 47.623855 -53.68892) (xy 47.575301 -53.673481) (xy 47.529689 -53.650779) (xy 47.488098 -53.621352)
			(xy 47.45151 -53.585896) (xy 47.420791 -53.545249) (xy 47.396669 -53.500372) (xy 47.379712 -53.452328)
			(xy 47.374556 -53.427376) (xy 47.366682 -53.385974) (xy 47.232824 -53.385974) (xy 47.22495 -53.427376)
			(xy 47.219794 -53.452328) (xy 47.202837 -53.500372) (xy 47.178715 -53.545249) (xy 47.147996 -53.585896)
			(xy 47.111408 -53.621352) (xy 47.069817 -53.650779) (xy 47.024205 -53.673481) (xy 46.975651 -53.68892)
			(xy 46.925305 -53.696732) (xy 46.874355 -53.696732) (xy 46.824009 -53.68892) (xy 46.775455 -53.673481)
			(xy 46.729843 -53.650779) (xy 46.688252 -53.621352) (xy 46.651664 -53.585896) (xy 46.620945 -53.545249)
			(xy 46.596823 -53.500372) (xy 46.579866 -53.452328) (xy 46.57471 -53.427376) (xy 46.566836 -53.385974)
			(xy 45.632878 -53.385974) (xy 45.625004 -53.427376) (xy 45.619848 -53.452328) (xy 45.602891 -53.500372)
			(xy 45.578769 -53.545249) (xy 45.54805 -53.585896) (xy 45.511462 -53.621352) (xy 45.469871 -53.650779)
			(xy 45.424259 -53.673481) (xy 45.375705 -53.68892) (xy 45.325359 -53.696732) (xy 45.274409 -53.696732)
			(xy 45.224063 -53.68892) (xy 45.175509 -53.673481) (xy 45.129897 -53.650779) (xy 45.088306 -53.621352)
			(xy 45.051718 -53.585896) (xy 45.020999 -53.545249) (xy 44.996877 -53.500372) (xy 44.97992 -53.452328)
			(xy 44.974764 -53.427376) (xy 44.96689 -53.385974) (xy 44.832778 -53.385974) (xy 44.824904 -53.427376)
			(xy 44.819752 -53.452328) (xy 44.802801 -53.500375) (xy 44.778682 -53.545253) (xy 44.747964 -53.5859)
			(xy 44.711374 -53.621354) (xy 44.669779 -53.650776) (xy 44.624164 -53.673469) (xy 44.575607 -53.688897)
			(xy 44.525259 -53.696695) (xy 44.499784 -53.697124) (xy 44.474612 -53.696658) (xy 44.424848 -53.689036)
			(xy 44.376815 -53.673955) (xy 44.331625 -53.651764) (xy 44.290323 -53.622977) (xy 44.253864 -53.588259)
			(xy 44.223092 -53.548414) (xy 44.198719 -53.504362) (xy 44.181308 -53.457124) (xy 44.171263 -53.407792)
			(xy 44.169584 -53.382672) (xy 44.143705 -53.377685) (xy 44.094615 -53.358535) (xy 44.050499 -53.329721)
			(xy 44.031408 -53.311552) (xy 43.984672 -53.264816) (xy 43.955462 -53.273452) (xy 43.928666 -53.281036)
			(xy 43.873578 -53.289196) (xy 43.845734 -53.289708) (xy 43.81848 -53.289247) (xy 43.764525 -53.281494)
			(xy 43.712223 -53.266141) (xy 43.662639 -53.2435) (xy 43.616781 -53.214033) (xy 43.575585 -53.17834)
			(xy 43.539887 -53.137146) (xy 43.510416 -53.091291) (xy 43.487771 -53.041709) (xy 43.472413 -52.989408)
			(xy 43.464655 -52.935454) (xy 43.464226 -52.9082) (xy 43.464613 -52.884307) (xy 43.470607 -52.836897)
			(xy 43.482463 -52.790604) (xy 43.490896 -52.768246) (xy 43.47831 -52.751421) (xy 43.458304 -52.714475)
			(xy 43.444655 -52.674739) (xy 43.437736 -52.633298) (xy 43.437302 -52.61229) (xy 43.437302 -51.648868)
			(xy 43.111928 -51.323494) (xy 42.33164 -51.323494) (xy 42.316663 -51.346905) (xy 42.281001 -51.389527)
			(xy 42.23953 -51.426521) (xy 42.193127 -51.457102) (xy 42.142777 -51.480624) (xy 42.089546 -51.496588)
			(xy 42.034561 -51.504655) (xy 41.978987 -51.504655) (xy 41.924002 -51.496588) (xy 41.870771 -51.480624)
			(xy 41.820421 -51.457102) (xy 41.774018 -51.426521) (xy 41.732547 -51.389527) (xy 41.696885 -51.346905)
			(xy 41.681908 -51.323494) (xy 39.516812 -51.323494) (xy 39.365682 -51.474624) (xy 39.365682 -53.820314)
			(xy 39.365109 -53.845274) (xy 39.355367 -53.894234) (xy 39.336261 -53.940352) (xy 39.308523 -53.981857)
			(xy 39.29126 -53.999892) (xy 38.658038 -54.633114) (xy 38.641088 -54.649306) (xy 38.602429 -54.67581)
			(xy 38.559565 -54.694772) (xy 38.53688 -54.700678) (xy 38.41242 -54.730142) (xy 38.398028 -54.733348)
			(xy 38.368743 -54.736785) (xy 38.354 -54.737) (xy 36.449 -54.737) (xy 36.424796 -54.736397) (xy 36.377271 -54.727184)
			(xy 36.332346 -54.709149) (xy 36.291644 -54.682941) (xy 36.27374 -54.666642) (xy 35.595306 -54.019196)
			(xy 35.580701 -54.004734) (xy 35.555899 -53.971962) (xy 35.5367 -53.935621) (xy 35.523607 -53.896663)
			(xy 35.516961 -53.856104) (xy 35.516566 -53.835554) (xy 35.516312 -50.920142) (xy 35.503612 -50.905664)
			(xy 35.485669 -50.884636) (xy 35.455406 -50.838378) (xy 35.432135 -50.788237) (xy 35.416344 -50.735263)
			(xy 35.408363 -50.680564) (xy 35.40836 -50.625287) (xy 35.416333 -50.570587) (xy 35.432117 -50.517611)
			(xy 35.455381 -50.467467) (xy 35.485638 -50.421205) (xy 35.503612 -50.400204) (xy 35.516312 -50.38598)
			(xy 35.516312 -50.1523) (xy 35.516058 -49.76241) (xy 35.516058 -49.187354) (xy 35.501072 -49.172368)
			(xy 35.480292 -49.150753) (xy 35.445053 -49.102248) (xy 35.417831 -49.048829) (xy 35.399296 -48.991812)
			(xy 35.389903 -48.932597) (xy 35.389312 -48.90262) (xy 35.389312 -48.902366) (xy 35.389762 -48.875663)
			(xy 35.397215 -48.82278) (xy 35.411972 -48.771453) (xy 35.433742 -48.722686) (xy 35.462102 -48.677432)
			(xy 35.496496 -48.636576) (xy 35.516058 -48.618394) (xy 35.516058 -48.476916) (xy 35.045142 -48.006)
			(xy 31.75 -48.006) (xy 31.725043 -48.005388) (xy 31.676089 -47.995651) (xy 31.629976 -47.97655) (xy 31.588474 -47.94882)
			(xy 31.570422 -47.931578) (xy 30.173422 -46.534578) (xy 30.156157 -46.516539) (xy 30.128389 -46.475048)
			(xy 30.109267 -46.42893) (xy 30.099527 -46.379963) (xy 30.099 -46.355) (xy 30.099 -38.481) (xy 29.5656 -38.481)
			(xy 29.540643 -38.480388) (xy 29.491689 -38.470651) (xy 29.445576 -38.45155) (xy 29.404074 -38.42382)
			(xy 29.386022 -38.406578) (xy 27.535378 -36.555934) (xy 27.518119 -36.537893) (xy 27.490363 -36.496399)
			(xy 27.471252 -36.450281) (xy 27.461523 -36.401317) (xy 27.460956 -36.376356) (xy 27.460956 -35.593782)
			(xy 27.420824 -35.585146) (xy 27.394196 -35.578974) (xy 27.342923 -35.560037) (xy 27.294876 -35.533978)
			(xy 27.251039 -35.501329) (xy 27.212309 -35.46276) (xy 27.179479 -35.419059) (xy 27.15322 -35.371121)
			(xy 27.13407 -35.319926) (xy 27.122421 -35.266523) (xy 27.118511 -35.212004) (xy 27.12242 -35.157485)
			(xy 27.134068 -35.104082) (xy 27.153217 -35.052887) (xy 27.179475 -35.004948) (xy 27.212304 -34.961247)
			(xy 27.251033 -34.922676) (xy 27.294869 -34.890027) (xy 27.342915 -34.863966) (xy 27.394188 -34.845028)
			(xy 27.420824 -34.838894) (xy 27.460956 -34.830258) (xy 27.460956 -32.950912) (xy 24.763222 -30.253178)
			(xy 24.745957 -30.235139) (xy 24.718189 -30.193648) (xy 24.699067 -30.14753) (xy 24.689327 -30.098563)
			(xy 24.6888 -30.0736) (xy 24.6888 -19.499834) (xy 24.665778 -19.484773) (xy 24.623914 -19.449083)
			(xy 24.587608 -19.40775) (xy 24.557614 -19.361633) (xy 24.534553 -19.311687) (xy 24.518904 -19.258947)
			(xy 24.51099 -19.204506) (xy 24.510492 -19.177) (xy 24.510492 -19.176746) (xy 24.510989 -19.148657)
			(xy 24.51923 -19.093085) (xy 24.535539 -19.039326) (xy 24.559564 -18.988543) (xy 24.574754 -18.96491)
			(xy 24.456644 -18.8468) (xy 16.564356 -18.8468) (xy 15.9512 -19.459956) (xy 15.9512 -30.208728) (xy 23.389336 -37.646864)
			(xy 23.406621 -37.664862) (xy 23.435932 -37.705244) (xy 23.458573 -37.74971) (xy 23.473988 -37.797168)
			(xy 23.4818 -37.846451) (xy 23.4823 -37.8714) (xy 23.4823 -40.259) (xy 23.481811 -40.283949) (xy 23.474005 -40.333234)
			(xy 23.458585 -40.38069) (xy 23.435932 -40.42515) (xy 23.406602 -40.465519) (xy 23.389336 -40.483536)
			(xy 21.890736 -41.982136) (xy 21.872738 -41.999421) (xy 21.832356 -42.028732) (xy 21.78789 -42.051373)
			(xy 21.740432 -42.066788) (xy 21.691149 -42.0746) (xy 21.6662 -42.0751) (xy 17.570196 -42.0751) (xy 15.8115 -43.833796)
			(xy 15.8115 -54.189122) (xy 23.44928 -54.189122) (xy 23.449817 -54.107074) (xy 23.457975 -53.94318)
			(xy 23.474267 -53.779895) (xy 23.498653 -53.617621) (xy 23.531072 -53.456759) (xy 23.571445 -53.297706)
			(xy 23.619671 -53.140856) (xy 23.675631 -52.986597) (xy 23.739188 -52.835309) (xy 23.810184 -52.687365)
			(xy 23.888444 -52.543133) (xy 23.973774 -52.402967) (xy 24.065964 -52.267215) (xy 24.164786 -52.136212)
			(xy 24.269995 -52.010281) (xy 24.381332 -51.889733) (xy 24.498521 -51.774867) (xy 24.621274 -51.665966)
			(xy 24.749286 -51.563299) (xy 24.882242 -51.467121) (xy 25.019812 -51.377667) (xy 25.161658 -51.295161)
			(xy 25.307429 -51.219804) (xy 25.456764 -51.151785) (xy 25.532842 -51.121056) (xy 25.546552 -51.115141)
			(xy 25.569931 -51.096582) (xy 25.586948 -51.072058) (xy 25.59615 -51.043662) (xy 25.596753 -51.013818)
			(xy 25.588704 -50.985074) (xy 25.57269 -50.959883) (xy 25.550079 -50.940395) (xy 25.536652 -50.933858)
			(xy 25.464831 -50.901553) (xy 25.324313 -50.830408) (xy 25.187721 -50.75199) (xy 25.055431 -50.666514)
			(xy 24.927807 -50.574217) (xy 24.805201 -50.475351) (xy 24.68795 -50.37019) (xy 24.576376 -50.259023)
			(xy 24.470788 -50.142156) (xy 24.371476 -50.019911) (xy 24.278714 -49.892625) (xy 24.192756 -49.760648)
			(xy 24.11384 -49.624343) (xy 24.042183 -49.484086) (xy 23.977983 -49.340263) (xy 23.921415 -49.19327)
			(xy 23.872637 -49.043513) (xy 23.831781 -48.891402) (xy 23.798962 -48.737358) (xy 23.774268 -48.581804)
			(xy 23.757769 -48.42517) (xy 23.749509 -48.267885) (xy 23.749 -48.189134) (xy 23.749 -46.588934)
			(xy 23.749498 -46.511651) (xy 23.757454 -46.357291) (xy 23.773347 -46.203545) (xy 23.797133 -46.050821)
			(xy 23.82875 -45.899525) (xy 23.868113 -45.750056) (xy 23.915118 -45.602812) (xy 23.969642 -45.458182)
			(xy 24.031538 -45.316552) (xy 24.100643 -45.178295) (xy 24.176774 -45.04378) (xy 24.259728 -44.913361)
			(xy 24.349287 -44.787386) (xy 24.445211 -44.666189) (xy 24.547248 -44.55009) (xy 24.655125 -44.439398)
			(xy 24.768558 -44.334406) (xy 24.887246 -44.235393) (xy 25.010873 -44.14262) (xy 25.139112 -44.056335)
			(xy 25.271623 -43.976766) (xy 25.408055 -43.904124) (xy 25.548045 -43.838602) (xy 25.691222 -43.780373)
			(xy 25.837207 -43.729592) (xy 25.985613 -43.686393) (xy 26.136045 -43.650891) (xy 26.288106 -43.623181)
			(xy 26.441392 -43.603335) (xy 26.595496 -43.591406) (xy 26.75001 -43.587427) (xy 26.904524 -43.591406)
			(xy 27.058628 -43.603335) (xy 27.211914 -43.623181) (xy 27.363975 -43.650891) (xy 27.514407 -43.686393)
			(xy 27.662813 -43.729592) (xy 27.808798 -43.780373) (xy 27.951975 -43.838602) (xy 28.091965 -43.904124)
			(xy 28.228397 -43.976766) (xy 28.360908 -44.056335) (xy 28.489147 -44.14262) (xy 28.612774 -44.235393)
			(xy 28.731462 -44.334406) (xy 28.844895 -44.439398) (xy 28.952772 -44.55009) (xy 29.054809 -44.666189)
			(xy 29.150733 -44.787386) (xy 29.240292 -44.913361) (xy 29.323246 -45.04378) (xy 29.399377 -45.178295)
			(xy 29.468482 -45.316552) (xy 29.530378 -45.458182) (xy 29.584902 -45.602812) (xy 29.631907 -45.750056)
			(xy 29.67127 -45.899525) (xy 29.702887 -46.050821) (xy 29.726673 -46.203545) (xy 29.742566 -46.357291)
			(xy 29.750522 -46.511651) (xy 29.75102 -46.588934) (xy 29.75102 -48.189134) (xy 29.750471 -48.267875)
			(xy 29.742209 -48.42514) (xy 29.725709 -48.581755) (xy 29.701017 -48.737289) (xy 29.668201 -48.891314)
			(xy 29.627351 -49.043405) (xy 29.578579 -49.193144) (xy 29.522021 -49.340119) (xy 29.45783 -49.483925)
			(xy 29.386186 -49.624166) (xy 29.307283 -49.760456) (xy 29.221341 -49.89242) (xy 29.128595 -50.019694)
			(xy 29.0293 -50.141928) (xy 28.923731 -50.258785) (xy 28.812178 -50.369944) (xy 28.694947 -50.475099)
			(xy 28.572363 -50.57396) (xy 28.444761 -50.666255) (xy 28.312494 -50.75173) (xy 28.175926 -50.830149)
			(xy 28.035432 -50.901297) (xy 27.963622 -50.933604) (xy 27.950153 -50.940124) (xy 27.927432 -50.959576)
			(xy 27.911321 -50.984774) (xy 27.9032 -51.01356) (xy 27.903766 -51.043464) (xy 27.91297 -51.071921)
			(xy 27.930024 -51.096493) (xy 27.953464 -51.11507) (xy 27.967178 -51.121056) (xy 28.043259 -51.15178)
			(xy 28.192599 -51.219794) (xy 28.338375 -51.295145) (xy 28.480226 -51.377648) (xy 28.617801 -51.467098)
			(xy 28.750762 -51.563273) (xy 28.878778 -51.665938) (xy 29.001535 -51.774838) (xy 29.118729 -51.889703)
			(xy 29.230069 -52.01025) (xy 29.335281 -52.136181) (xy 29.434105 -52.267186) (xy 29.526297 -52.402939)
			(xy 29.611629 -52.543106) (xy 29.689889 -52.687341) (xy 29.760886 -52.835286) (xy 29.824442 -52.986577)
			(xy 29.880402 -53.140839) (xy 29.928626 -53.297692) (xy 29.968996 -53.456747) (xy 30.001412 -53.617612)
			(xy 30.025794 -53.779889) (xy 30.042081 -53.943177) (xy 30.050234 -54.107073) (xy 30.05074 -54.189122)
			(xy 30.050254 -54.270134) (xy 30.042304 -54.431964) (xy 30.026422 -54.593208) (xy 30.002648 -54.753479)
			(xy 29.97104 -54.91239) (xy 29.931672 -55.069559) (xy 29.88464 -55.224607) (xy 29.830058 -55.377161)
			(xy 29.768056 -55.526853) (xy 29.698784 -55.673323) (xy 29.622409 -55.816217) (xy 29.539115 -55.955192)
			(xy 29.449103 -56.089913) (xy 29.352589 -56.220055) (xy 29.249805 -56.345305) (xy 29.141 -56.465361)
			(xy 29.026436 -56.579933) (xy 28.906388 -56.688747) (xy 28.781146 -56.79154) (xy 28.651011 -56.888063)
			(xy 28.516297 -56.978086) (xy 28.377328 -57.06139) (xy 28.234439 -57.137775) (xy 28.087974 -57.207058)
			(xy 27.938287 -57.269071) (xy 27.785737 -57.323664) (xy 27.630692 -57.370707) (xy 27.473526 -57.410087)
			(xy 27.314617 -57.441707) (xy 27.154348 -57.465492) (xy 26.993105 -57.481386) (xy 26.831276 -57.489348)
			(xy 26.750264 -57.489852) (xy 26.75001 -57.489852) (xy 26.668994 -57.489353) (xy 26.507157 -57.481402)
			(xy 26.345905 -57.46552) (xy 26.185626 -57.441745) (xy 26.026707 -57.410134) (xy 25.869531 -57.370764)
			(xy 25.714476 -57.323728) (xy 25.561915 -57.269141) (xy 25.412217 -57.207134) (xy 25.265741 -57.137856)
			(xy 25.122842 -57.061475) (xy 24.983862 -56.978174) (xy 24.849137 -56.888154) (xy 24.718992 -56.791631)
			(xy 24.593739 -56.688839) (xy 24.473681 -56.580025) (xy 24.359107 -56.465451) (xy 24.250292 -56.345393)
			(xy 24.1475 -56.22014) (xy 24.050978 -56.089995) (xy 23.960957 -55.95527) (xy 23.877656 -55.81629)
			(xy 23.801274 -55.67339) (xy 23.731997 -55.526915) (xy 23.66999 -55.377217) (xy 23.615402 -55.224656)
			(xy 23.568367 -55.069601) (xy 23.528996 -54.912425) (xy 23.497385 -54.753506) (xy 23.47361 -54.593227)
			(xy 23.457728 -54.431975) (xy 23.449777 -54.270138) (xy 23.44928 -54.189122) (xy 15.8115 -54.189122)
			(xy 15.8115 -58.166508) (xy 60.959492 -58.166508) (xy 60.959492 -57.366662) (xy 60.959966 -57.340674)
			(xy 60.968103 -57.289338) (xy 60.984169 -57.239907) (xy 61.007769 -57.193597) (xy 61.038323 -57.15155)
			(xy 61.075078 -57.114799) (xy 61.11713 -57.08425) (xy 61.163442 -57.060654) (xy 61.212875 -57.044594)
			(xy 61.264212 -57.036464) (xy 61.2902 -57.035954) (xy 61.317668 -57.036479) (xy 61.371851 -57.04555)
			(xy 61.423791 -57.063444) (xy 61.472065 -57.089668) (xy 61.515345 -57.123503) (xy 61.534294 -57.143396)
			(xy 61.55212 -57.162087) (xy 61.582322 -57.203984) (xy 61.605643 -57.250068) (xy 61.621515 -57.299217)
			(xy 61.629551 -57.350236) (xy 61.630052 -57.37606) (xy 61.629773 -57.39555) (xy 61.625189 -57.43426)
			(xy 61.620908 -57.453276) (xy 61.620908 -58.166508) (xy 61.620398 -58.192491) (xy 63.359983 -58.192491)
			(xy 63.359983 -58.140509) (xy 63.368116 -58.089167) (xy 63.38418 -58.03973) (xy 63.407782 -57.993415)
			(xy 63.438338 -57.951362) (xy 63.475097 -57.914608) (xy 63.517154 -57.884058) (xy 63.563473 -57.860463)
			(xy 63.612912 -57.844405) (xy 63.664255 -57.83628) (xy 63.690246 -57.8358) (xy 64.490092 -57.8358)
			(xy 64.516082 -57.836267) (xy 64.567423 -57.844397) (xy 64.61686 -57.860459) (xy 64.663175 -57.884057)
			(xy 64.705229 -57.91461) (xy 64.741985 -57.951365) (xy 64.772539 -57.993418) (xy 64.796138 -58.039733)
			(xy 64.812201 -58.089169) (xy 64.820333 -58.14051) (xy 64.820333 -58.19249) (xy 64.812201 -58.243831)
			(xy 64.796138 -58.293267) (xy 64.772539 -58.339582) (xy 64.741985 -58.381635) (xy 64.705229 -58.41839)
			(xy 64.663175 -58.448943) (xy 64.61686 -58.472541) (xy 64.567423 -58.488603) (xy 64.516082 -58.496733)
			(xy 64.490092 -58.497216) (xy 63.690246 -58.497216) (xy 63.664255 -58.49672) (xy 63.612912 -58.488595)
			(xy 63.563473 -58.472537) (xy 63.517154 -58.448942) (xy 63.475097 -58.418392) (xy 63.438338 -58.381638)
			(xy 63.407782 -58.339585) (xy 63.38418 -58.29327) (xy 63.368116 -58.243833) (xy 63.359983 -58.192491)
			(xy 61.620398 -58.192491) (xy 61.620398 -58.192495) (xy 61.612268 -58.24383) (xy 61.596207 -58.29326)
			(xy 61.572611 -58.33957) (xy 61.542061 -58.381618) (xy 61.50531 -58.418369) (xy 61.463262 -58.448919)
			(xy 61.416952 -58.472515) (xy 61.367522 -58.488576) (xy 61.316187 -58.496706) (xy 61.264213 -58.496706)
			(xy 61.212878 -58.488576) (xy 61.163448 -58.472515) (xy 61.117138 -58.448919) (xy 61.07509 -58.418369)
			(xy 61.038339 -58.381618) (xy 61.007789 -58.33957) (xy 60.984193 -58.29326) (xy 60.968132 -58.24383)
			(xy 60.960002 -58.192495) (xy 60.959492 -58.166508) (xy 15.8115 -58.166508) (xy 15.8115 -58.632344)
			(xy 16.171567 -58.992411) (xy 61.759802 -58.992411) (xy 61.759802 -58.940389) (xy 61.76794 -58.889008)
			(xy 61.784015 -58.839533) (xy 61.807633 -58.793181) (xy 61.83821 -58.751095) (xy 61.874995 -58.71431)
			(xy 61.917081 -58.683733) (xy 61.963433 -58.660115) (xy 62.012908 -58.64404) (xy 62.064289 -58.635902)
			(xy 62.0903 -58.635392) (xy 62.890146 -58.635392) (xy 62.916147 -58.635998) (xy 62.967508 -58.644139)
			(xy 63.016964 -58.660214) (xy 63.063296 -58.683827) (xy 63.105364 -58.714397) (xy 63.142133 -58.751171)
			(xy 63.172697 -58.793243) (xy 63.196303 -58.839579) (xy 63.212372 -58.889036) (xy 63.220506 -58.940399)
			(xy 63.220506 -58.992401) (xy 63.220505 -58.99241) (xy 64.159602 -58.99241) (xy 64.159602 -58.94039)
			(xy 64.16774 -58.889009) (xy 64.183815 -58.839535) (xy 64.207431 -58.793184) (xy 64.238008 -58.751098)
			(xy 64.274792 -58.714313) (xy 64.316877 -58.683735) (xy 64.363227 -58.660118) (xy 64.412702 -58.644042)
			(xy 64.464082 -58.635903) (xy 64.490092 -58.635392) (xy 65.289938 -58.635392) (xy 65.31594 -58.635997)
			(xy 65.367302 -58.644137) (xy 65.416758 -58.660212) (xy 65.463091 -58.683825) (xy 65.505161 -58.714394)
			(xy 65.541931 -58.751168) (xy 65.572495 -58.793241) (xy 65.596103 -58.839577) (xy 65.612171 -58.889035)
			(xy 65.620306 -58.940398) (xy 65.620306 -58.992402) (xy 65.612171 -59.043765) (xy 65.596103 -59.093223)
			(xy 65.572495 -59.139559) (xy 65.541931 -59.181632) (xy 65.505161 -59.218406) (xy 65.463091 -59.248975)
			(xy 65.416758 -59.272588) (xy 65.367302 -59.288663) (xy 65.31594 -59.296803) (xy 65.289938 -59.297316)
			(xy 64.490092 -59.297316) (xy 64.464082 -59.296897) (xy 64.412702 -59.288758) (xy 64.363227 -59.272682)
			(xy 64.316877 -59.249065) (xy 64.274792 -59.218487) (xy 64.238008 -59.181702) (xy 64.207431 -59.139616)
			(xy 64.183815 -59.093265) (xy 64.16774 -59.043791) (xy 64.159602 -58.99241) (xy 63.220505 -58.99241)
			(xy 63.212372 -59.043763) (xy 63.196303 -59.093221) (xy 63.172697 -59.139557) (xy 63.142133 -59.181629)
			(xy 63.105364 -59.218403) (xy 63.063296 -59.248973) (xy 63.016964 -59.272586) (xy 62.967508 -59.288661)
			(xy 62.916147 -59.296802) (xy 62.890146 -59.297316) (xy 62.0903 -59.297316) (xy 62.064289 -59.296898)
			(xy 62.012908 -59.28876) (xy 61.963433 -59.272685) (xy 61.917081 -59.249067) (xy 61.874995 -59.21849)
			(xy 61.83821 -59.181705) (xy 61.807633 -59.139619) (xy 61.784015 -59.093267) (xy 61.76794 -59.043792)
			(xy 61.759802 -58.992411) (xy 16.171567 -58.992411) (xy 16.971671 -59.792515) (xy 63.359676 -59.792515)
			(xy 63.359676 -59.740485) (xy 63.367816 -59.689095) (xy 63.383895 -59.639612) (xy 63.407519 -59.593254)
			(xy 63.438104 -59.551162) (xy 63.474897 -59.514374) (xy 63.516993 -59.483794) (xy 63.563355 -59.460178)
			(xy 63.61284 -59.444105) (xy 63.664231 -59.435972) (xy 63.690246 -59.435492) (xy 64.490092 -59.435492)
			(xy 64.516098 -59.436067) (xy 64.56747 -59.444202) (xy 64.616937 -59.460274) (xy 64.66328 -59.483886)
			(xy 64.705359 -59.514457) (xy 64.742138 -59.551235) (xy 64.77271 -59.593313) (xy 64.796323 -59.639656)
			(xy 64.812396 -59.689122) (xy 64.820533 -59.740494) (xy 64.820533 -59.792506) (xy 64.812396 -59.843878)
			(xy 64.796323 -59.893344) (xy 64.77271 -59.939687) (xy 64.742138 -59.981765) (xy 64.705359 -60.018543)
			(xy 64.66328 -60.049114) (xy 64.616937 -60.072726) (xy 64.56747 -60.088798) (xy 64.516098 -60.096933)
			(xy 64.490092 -60.097416) (xy 63.690246 -60.097416) (xy 63.664231 -60.097028) (xy 63.61284 -60.088895)
			(xy 63.563355 -60.072822) (xy 63.516993 -60.049206) (xy 63.474897 -60.018626) (xy 63.438104 -59.981838)
			(xy 63.407519 -59.939746) (xy 63.383895 -59.893388) (xy 63.367816 -59.843905) (xy 63.359676 -59.792515)
			(xy 16.971671 -59.792515) (xy 17.528556 -60.3494) (xy 60.569868 -60.3494) (xy 60.573857 -60.296174)
			(xy 60.585733 -60.244137) (xy 60.605233 -60.194451) (xy 60.631919 -60.148227) (xy 60.665197 -60.106496)
			(xy 60.704323 -60.07019) (xy 60.748422 -60.040121) (xy 60.796511 -60.016961) (xy 60.847514 -60.001226)
			(xy 60.900292 -59.993268) (xy 60.92698 -59.992768) (xy 60.949767 -59.993141) (xy 60.994967 -59.998968)
			(xy 61.03906 -60.010491) (xy 61.06033 -60.018676) (xy 61.555376 -60.018676) (xy 61.564012 -60.015374)
			(xy 61.594178 -60.00485) (xy 61.657039 -59.993478) (xy 61.68898 -59.992768) (xy 61.717333 -59.993267)
			(xy 61.773326 -60.002234) (xy 61.827196 -60.019945) (xy 61.877586 -60.045954) (xy 61.923227 -60.079606)
			(xy 61.943488 -60.099448) (xy 61.962622 -60.116719) (xy 61.995857 -60.156112) (xy 62.022581 -60.200183)
			(xy 62.042146 -60.247865) (xy 62.054078 -60.298005) (xy 62.058089 -60.34939) (xy 62.054081 -60.400774)
			(xy 62.042152 -60.450915) (xy 62.022591 -60.498599) (xy 61.99587 -60.542671) (xy 61.962636 -60.582066)
			(xy 61.943488 -60.59932) (xy 61.923242 -60.619175) (xy 61.877589 -60.652806) (xy 61.827194 -60.678797)
			(xy 61.773323 -60.696496) (xy 61.717332 -60.705456) (xy 61.68898 -60.706) (xy 61.657039 -60.705289)
			(xy 61.594177 -60.693921) (xy 61.564012 -60.683394) (xy 61.555376 -60.680092) (xy 61.06033 -60.680092)
			(xy 61.039069 -60.688303) (xy 60.994975 -60.699837) (xy 60.949769 -60.705644) (xy 60.92698 -60.706)
			(xy 60.900292 -60.705532) (xy 60.847514 -60.697574) (xy 60.796511 -60.681839) (xy 60.748422 -60.658679)
			(xy 60.704323 -60.62861) (xy 60.665197 -60.592304) (xy 60.631919 -60.550573) (xy 60.605233 -60.504349)
			(xy 60.585733 -60.454663) (xy 60.573857 -60.402626) (xy 60.569868 -60.3494) (xy 17.528556 -60.3494)
			(xy 18.178526 -60.99937) (xy 18.185384 -61.002926) (xy 18.210806 -61.016827) (xy 18.2575 -61.051131)
			(xy 18.298469 -61.0921) (xy 18.332773 -61.138794) (xy 18.346674 -61.164216) (xy 18.35023 -61.171074)
			(xy 18.451322 -61.272166) (xy 20.34921 -61.272166) (xy 20.359878 -61.235336) (xy 20.367907 -61.209184)
			(xy 20.390415 -61.159323) (xy 20.419814 -61.113189) (xy 20.455503 -61.071728) (xy 20.496749 -61.03579)
			(xy 20.542705 -61.006114) (xy 20.59243 -60.983307) (xy 20.644903 -60.967837) (xy 20.699047 -60.960022)
			(xy 20.753753 -60.960022) (xy 20.807897 -60.967837) (xy 20.86037 -60.983307) (xy 20.910095 -61.006114)
			(xy 20.956051 -61.03579) (xy 20.997297 -61.071728) (xy 21.032986 -61.113189) (xy 21.062385 -61.159323)
			(xy 21.084893 -61.209184) (xy 21.092922 -61.235336) (xy 21.10359 -61.272166) (xy 29.640276 -61.272166)
			(xy 29.658494 -61.25142) (xy 29.699884 -61.214881) (xy 29.746109 -61.184689) (xy 29.796203 -61.161476)
			(xy 29.84912 -61.145725) (xy 29.903754 -61.137767) (xy 29.958966 -61.137767) (xy 30.0136 -61.145725)
			(xy 30.066517 -61.161476) (xy 30.116611 -61.184689) (xy 30.162836 -61.214881) (xy 30.204226 -61.25142)
			(xy 30.222444 -61.272166) (xy 40.490648 -61.272166) (xy 40.515603 -61.272782) (xy 40.564553 -61.282526)
			(xy 40.610662 -61.301631) (xy 40.652159 -61.329363) (xy 40.670226 -61.346588) (xy 42.023538 -62.6999)
			(xy 42.040793 -62.717943) (xy 42.068542 -62.759438) (xy 42.087646 -62.805556) (xy 42.097367 -62.854518)
			(xy 42.09796 -62.879478) (xy 42.09796 -62.881256) (xy 42.088562 -64.328802) (xy 42.34688 -64.5922)
			(xy 43.930316 -64.593724) (xy 43.94327 -64.56172) (xy 43.954283 -64.535515) (xy 43.982935 -64.486423)
			(xy 44.018551 -64.442124) (xy 44.060342 -64.403596) (xy 44.107385 -64.371693) (xy 44.15864 -64.347118)
			(xy 44.212972 -64.330417) (xy 44.26918 -64.321958) (xy 44.2976 -64.321436) (xy 44.326072 -64.321964)
			(xy 44.382384 -64.330432) (xy 44.43681 -64.347178) (xy 44.488141 -64.371831) (xy 44.535236 -64.403843)
			(xy 44.577048 -64.442501) (xy 44.612646 -64.486947) (xy 44.64124 -64.536192) (xy 44.652184 -64.562482)
			(xy 44.664884 -64.594486) (xy 45.10278 -64.59474) (xy 45.363384 -64.594994) (xy 45.378624 -64.575182)
			(xy 45.396821 -64.55249) (xy 45.438924 -64.512362) (xy 45.486627 -64.479084) (xy 45.538826 -64.453427)
			(xy 45.594312 -64.435984) (xy 45.651802 -64.42716) (xy 45.680884 -64.426592) (xy 45.710042 -64.427143)
			(xy 45.76768 -64.436014) (xy 45.823298 -64.45355) (xy 45.875599 -64.479345) (xy 45.923367 -64.512797)
			(xy 45.96549 -64.553127) (xy 45.983652 -64.575944) (xy 45.998892 -64.595756) (xy 46.134782 -64.595756)
			(xy 46.342554 -64.59601) (xy 47.448978 -64.597026) (xy 47.458122 -64.59347) (xy 47.480703 -64.584859)
			(xy 47.527493 -64.572756) (xy 47.575435 -64.566655) (xy 47.5996 -64.566292) (xy 47.599854 -64.566292)
			(xy 47.624161 -64.566707) (xy 47.672374 -64.572943) (xy 47.719407 -64.585244) (xy 47.742094 -64.593978)
			(xy 47.75073 -64.597534) (xy 49.12614 -64.598804) (xy 49.14138 -64.582548) (xy 49.159492 -64.563829)
			(xy 49.199915 -64.53098) (xy 49.244431 -64.503936) (xy 49.292213 -64.483201) (xy 49.342372 -64.469161)
			(xy 49.393975 -64.462076) (xy 49.420018 -64.461644) (xy 49.446122 -64.462072) (xy 49.497844 -64.469191)
			(xy 49.548112 -64.483294) (xy 49.595988 -64.504117) (xy 49.64058 -64.531271) (xy 49.681053 -64.564251)
			(xy 49.699164 -64.583056) (xy 49.71415 -64.599312) (xy 49.77384 -64.599312) (xy 52.100734 -64.601598)
			(xy 52.115466 -64.588136) (xy 52.136723 -64.569089) (xy 52.18387 -64.536921) (xy 52.235288 -64.512144)
			(xy 52.289825 -64.495312) (xy 52.346262 -64.4868) (xy 52.3748 -64.486282) (xy 52.403406 -64.486815)
			(xy 52.459971 -64.495398) (xy 52.514622 -64.512327) (xy 52.566135 -64.537222) (xy 52.613355 -64.569527)
			(xy 52.634642 -64.588644) (xy 52.649374 -64.602106) (xy 54.71414 -64.604138) (xy 54.838346 -64.604138)
		)
		(stroke
			(width 0)
			(type solid)
		)
		(fill yes)
		(layer "In6.Cu")
		(net "P1V0_AUX")
	)
	(gr_poly
		(pts
			(xy 9.749028 -114.799872) (xy 9.749526 -114.744681) (xy 9.757554 -114.634591) (xy 9.773568 -114.525376)
			(xy 9.797484 -114.417615) (xy 9.829176 -114.31188) (xy 9.868475 -114.20873) (xy 9.915173 -114.108712)
			(xy 9.969022 -114.012356) (xy 9.998964 -113.96599) (xy 9.996593 -113.950606) (xy 9.994051 -113.919579)
			(xy 9.993884 -113.904014) (xy 9.993884 -113.90376) (xy 9.994347 -113.876507) (xy 10.002104 -113.822556)
			(xy 10.01746 -113.770259) (xy 10.040103 -113.720679) (xy 10.069571 -113.674826) (xy 10.105265 -113.633633)
			(xy 10.146457 -113.59794) (xy 10.19231 -113.568472) (xy 10.241891 -113.54583) (xy 10.294188 -113.530474)
			(xy 10.348139 -113.522717) (xy 10.375392 -113.522252) (xy 10.39173 -113.522426) (xy 10.424287 -113.525226)
			(xy 10.440416 -113.52784) (xy 10.486395 -113.498623) (xy 10.581842 -113.446092) (xy 10.680812 -113.400546)
			(xy 10.782796 -113.362219) (xy 10.887268 -113.331309) (xy 10.993688 -113.307977) (xy 11.101508 -113.292341)
			(xy 11.210172 -113.284483) (xy 11.264646 -113.284) (xy 12.765278 -113.284) (xy 12.818115 -113.284465)
			(xy 12.923533 -113.29184) (xy 13.02818 -113.30654) (xy 13.13155 -113.328495) (xy 13.233138 -113.357598)
			(xy 13.332452 -113.393708) (xy 13.42901 -113.436648) (xy 13.522341 -113.486211) (xy 13.611992 -113.542156)
			(xy 13.65504 -113.572798) (xy 13.67633 -113.568172) (xy 13.719616 -113.563212) (xy 13.7414 -113.562892)
			(xy 13.768651 -113.563378) (xy 13.822599 -113.571134) (xy 13.874894 -113.586489) (xy 13.924471 -113.609131)
			(xy 13.970321 -113.638597) (xy 14.011512 -113.674288) (xy 14.047203 -113.715479) (xy 14.076669 -113.761329)
			(xy 14.099311 -113.810906) (xy 14.108106 -113.840859) (xy 20.444184 -113.840859) (xy 20.444184 -113.786321)
			(xy 20.451946 -113.732337) (xy 20.467311 -113.680007) (xy 20.489968 -113.630397) (xy 20.519454 -113.584516)
			(xy 20.555169 -113.543299) (xy 20.596386 -113.507584) (xy 20.642267 -113.478098) (xy 20.691877 -113.455441)
			(xy 20.744207 -113.440076) (xy 20.798191 -113.432314) (xy 20.82546 -113.431828) (xy 21.71446 -113.431828)
			(xy 21.741732 -113.432309) (xy 21.795722 -113.440066) (xy 21.848058 -113.455428) (xy 21.897675 -113.478083)
			(xy 21.943562 -113.507569) (xy 21.984786 -113.543285) (xy 22.020507 -113.584506) (xy 22.049998 -113.63039)
			(xy 22.072658 -113.680004) (xy 22.088025 -113.732339) (xy 22.095788 -113.786328) (xy 22.095788 -113.840872)
			(xy 22.088025 -113.894861) (xy 22.072658 -113.947196) (xy 22.049998 -113.99681) (xy 22.020507 -114.042694)
			(xy 21.984786 -114.083915) (xy 21.943562 -114.119631) (xy 21.897675 -114.149117) (xy 21.848058 -114.171772)
			(xy 21.795722 -114.187134) (xy 21.741732 -114.194891) (xy 21.71446 -114.195352) (xy 20.82546 -114.195352)
			(xy 20.798191 -114.194866) (xy 20.744207 -114.187104) (xy 20.691877 -114.171739) (xy 20.642267 -114.149082)
			(xy 20.596386 -114.119596) (xy 20.555169 -114.083881) (xy 20.519454 -114.042664) (xy 20.489968 -113.996783)
			(xy 20.467311 -113.947173) (xy 20.451946 -113.894843) (xy 20.444184 -113.840859) (xy 14.108106 -113.840859)
			(xy 14.114666 -113.863201) (xy 14.122422 -113.917149) (xy 14.122908 -113.9444) (xy 14.122908 -113.945162)
			(xy 14.122169 -113.979388) (xy 14.109902 -114.046732) (xy 14.098524 -114.07902) (xy 14.123914 -114.127002)
			(xy 14.16857 -114.22596) (xy 14.206034 -114.327858) (xy 14.236115 -114.432174) (xy 14.258659 -114.538375)
			(xy 14.273551 -114.645915) (xy 14.277594 -114.70005) (xy 14.278864 -114.719862) (xy 14.329156 -114.767614)
			(xy 14.349222 -114.767868) (xy 14.376342 -114.768545) (xy 14.429986 -114.776626) (xy 14.481944 -114.792224)
			(xy 14.531169 -114.815024) (xy 14.576669 -114.844567) (xy 14.617525 -114.880256) (xy 14.652914 -114.921373)
			(xy 14.682122 -114.967088) (xy 14.70456 -115.016479) (xy 14.719777 -115.06855) (xy 14.727464 -115.122252)
			(xy 14.727936 -115.149376) (xy 14.727936 -116.038376) (xy 15.764764 -116.038376) (xy 15.764764 -115.149376)
			(xy 15.76525 -115.122107) (xy 15.773012 -115.068123) (xy 15.788377 -115.015793) (xy 15.811034 -114.966183)
			(xy 15.84052 -114.920302) (xy 15.876235 -114.879085) (xy 15.917452 -114.84337) (xy 15.963333 -114.813884)
			(xy 16.012943 -114.791227) (xy 16.065273 -114.775862) (xy 16.119257 -114.7681) (xy 16.173795 -114.7681)
			(xy 16.227779 -114.775862) (xy 16.280109 -114.791227) (xy 16.329719 -114.813884) (xy 16.3756 -114.84337)
			(xy 16.416817 -114.879085) (xy 16.452532 -114.920302) (xy 16.482018 -114.966183) (xy 16.504675 -115.015793)
			(xy 16.510811 -115.036691) (xy 23.190153 -115.036691) (xy 23.190153 -114.982149) (xy 23.197916 -114.928162)
			(xy 23.213282 -114.875829) (xy 23.23594 -114.826216) (xy 23.265428 -114.780333) (xy 23.301145 -114.739113)
			(xy 23.342366 -114.703395) (xy 23.38825 -114.673908) (xy 23.437863 -114.651251) (xy 23.490196 -114.635885)
			(xy 23.544183 -114.628123) (xy 23.571454 -114.62766) (xy 24.460454 -114.62766) (xy 24.487723 -114.628143)
			(xy 24.541707 -114.635905) (xy 24.594036 -114.651271) (xy 24.643646 -114.673927) (xy 24.689527 -114.703413)
			(xy 24.730744 -114.739129) (xy 24.766459 -114.780347) (xy 24.795945 -114.826227) (xy 24.818601 -114.875838)
			(xy 24.833966 -114.928167) (xy 24.841728 -114.982151) (xy 24.841728 -115.036689) (xy 24.833966 -115.090673)
			(xy 24.818601 -115.143002) (xy 24.795945 -115.192613) (xy 24.766459 -115.238493) (xy 24.730744 -115.279711)
			(xy 24.689527 -115.315427) (xy 24.643646 -115.344913) (xy 24.594036 -115.367569) (xy 24.541707 -115.382935)
			(xy 24.487723 -115.390697) (xy 24.460454 -115.391184) (xy 23.571454 -115.391184) (xy 23.544183 -115.390717)
			(xy 23.490196 -115.382955) (xy 23.437863 -115.367589) (xy 23.38825 -115.344932) (xy 23.342366 -115.315445)
			(xy 23.301145 -115.279727) (xy 23.265428 -115.238507) (xy 23.23594 -115.192624) (xy 23.213282 -115.143011)
			(xy 23.197916 -115.090678) (xy 23.190153 -115.036691) (xy 16.510811 -115.036691) (xy 16.52004 -115.068123)
			(xy 16.527802 -115.122107) (xy 16.528288 -115.149376) (xy 16.528288 -116.038376) (xy 16.527802 -116.065645)
			(xy 16.52004 -116.119629) (xy 16.504675 -116.171959) (xy 16.482018 -116.221569) (xy 16.452532 -116.26745)
			(xy 16.416817 -116.308667) (xy 16.3756 -116.344382) (xy 16.329719 -116.373868) (xy 16.280109 -116.396525)
			(xy 16.227779 -116.41189) (xy 16.173795 -116.419652) (xy 16.119257 -116.419652) (xy 16.065273 -116.41189)
			(xy 16.012943 -116.396525) (xy 15.963333 -116.373868) (xy 15.917452 -116.344382) (xy 15.876235 -116.308667)
			(xy 15.84052 -116.26745) (xy 15.811034 -116.221569) (xy 15.788377 -116.171959) (xy 15.773012 -116.119629)
			(xy 15.76525 -116.065645) (xy 15.764764 -116.038376) (xy 14.727936 -116.038376) (xy 14.727397 -116.066929)
			(xy 14.718877 -116.123396) (xy 14.702037 -116.177963) (xy 14.677255 -116.229411) (xy 14.645083 -116.276593)
			(xy 14.60624 -116.318453) (xy 14.561593 -116.354059) (xy 14.512139 -116.382614) (xy 14.458982 -116.403481)
			(xy 14.403309 -116.416195) (xy 14.374876 -116.418868) (xy 14.359732 -116.420576) (xy 14.331382 -116.431712)
			(xy 14.307573 -116.450708) (xy 14.29042 -116.475877) (xy 14.281447 -116.504985) (xy 14.280896 -116.520214)
			(xy 14.280896 -117.3734) (xy 30.609032 -117.3734) (xy 30.609032 -114.77498) (xy 30.609527 -114.705883)
			(xy 30.617514 -114.567919) (xy 30.633457 -114.430646) (xy 30.657302 -114.294524) (xy 30.68897 -114.160006)
			(xy 30.728355 -114.027543) (xy 30.775326 -113.897575) (xy 30.829726 -113.770537) (xy 30.891372 -113.646854)
			(xy 30.96006 -113.526938) (xy 31.03556 -113.41119) (xy 31.11762 -113.299996) (xy 31.205965 -113.193728)
			(xy 31.300301 -113.09274) (xy 31.400313 -112.99737) (xy 31.505667 -112.907936) (xy 31.616011 -112.824737)
			(xy 31.730976 -112.74805) (xy 31.850179 -112.678132) (xy 31.973221 -112.615216) (xy 32.099692 -112.559512)
			(xy 32.22917 -112.511206) (xy 32.361221 -112.47046) (xy 32.495406 -112.43741) (xy 32.631276 -112.412165)
			(xy 32.768377 -112.394811) (xy 32.906251 -112.385405) (xy 33.044439 -112.383979) (xy 33.182478 -112.390536)
			(xy 33.319908 -112.405057) (xy 33.45627 -112.427491) (xy 33.591108 -112.457765) (xy 33.723973 -112.495776)
			(xy 33.85442 -112.541398) (xy 33.982014 -112.59448) (xy 34.106329 -112.654842) (xy 34.22695 -112.722285)
			(xy 34.343474 -112.796582) (xy 34.455511 -112.877486) (xy 34.562689 -112.964726) (xy 34.664648 -113.058011)
			(xy 34.761049 -113.15703) (xy 34.851569 -113.261452) (xy 34.935907 -113.370928) (xy 35.01378 -113.485093)
			(xy 35.084929 -113.603565) (xy 35.149115 -113.72595) (xy 35.206126 -113.851837) (xy 35.25577 -113.980808)
			(xy 35.297881 -114.11243) (xy 35.332319 -114.246265) (xy 35.346132 -114.31397) (xy 35.372445 -114.321878)
			(xy 35.422644 -114.34421) (xy 35.469118 -114.373517) (xy 35.510903 -114.409192) (xy 35.547133 -114.450496)
			(xy 35.577058 -114.496574) (xy 35.600058 -114.546471) (xy 35.615656 -114.599153) (xy 35.62353 -114.653529)
			(xy 35.624008 -114.681) (xy 35.623474 -114.709917) (xy 35.614747 -114.767088) (xy 35.597493 -114.822288)
			(xy 35.572108 -114.874252) (xy 35.539171 -114.921791) (xy 35.499439 -114.963815) (xy 35.476942 -114.98199)
			(xy 35.465134 -114.991886) (xy 35.447612 -115.017209) (xy 35.438433 -115.046603) (xy 35.438433 -115.077397)
			(xy 35.447612 -115.106791) (xy 35.465134 -115.132114) (xy 35.476942 -115.14201) (xy 35.499432 -115.160197)
			(xy 35.539181 -115.202211) (xy 35.572133 -115.249744) (xy 35.597531 -115.301706) (xy 35.614793 -115.356907)
			(xy 35.623525 -115.414081) (xy 35.624008 -115.443) (xy 35.623488 -115.471719) (xy 35.614873 -115.528507)
			(xy 35.597838 -115.583361) (xy 35.572768 -115.635039) (xy 35.540231 -115.682373) (xy 35.500962 -115.724291)
			(xy 35.47872 -115.742466) (xy 35.468178 -115.751378) (xy 35.451892 -115.773652) (xy 35.442156 -115.79947)
			(xy 35.43968 -115.826951) (xy 35.444644 -115.854094) (xy 35.456687 -115.87892) (xy 35.465512 -115.889532)
			(xy 35.483322 -115.910534) (xy 35.513349 -115.956693) (xy 35.536434 -116.006685) (xy 35.552101 -116.059475)
			(xy 35.560023 -116.113967) (xy 35.560508 -116.1415) (xy 35.560057 -116.168261) (xy 35.552581 -116.221258)
			(xy 35.537774 -116.272691) (xy 35.515928 -116.321551) (xy 35.48747 -116.36688) (xy 35.452959 -116.407789)
			(xy 35.413072 -116.443477) (xy 35.39109 -116.458746) (xy 35.39109 -117.3734) (xy 43.318938 -117.3734)
			(xy 43.318938 -114.766344) (xy 43.297493 -114.75102) (xy 43.258633 -114.715412) (xy 43.225052 -114.674788)
			(xy 43.197389 -114.629923) (xy 43.176174 -114.581674) (xy 43.161812 -114.530962) (xy 43.154575 -114.478754)
			(xy 43.154092 -114.4524) (xy 43.154573 -114.425208) (xy 43.162294 -114.371375) (xy 43.17758 -114.319183)
			(xy 43.20012 -114.26969) (xy 43.229458 -114.223899) (xy 43.265 -114.182736) (xy 43.306027 -114.147036)
			(xy 43.32859 -114.131852) (xy 43.335256 -114.070124) (xy 43.355477 -113.947611) (xy 43.383487 -113.826642)
			(xy 43.419173 -113.70771) (xy 43.462387 -113.591303) (xy 43.512954 -113.477896) (xy 43.570666 -113.367952)
			(xy 43.635288 -113.261923) (xy 43.706554 -113.160241) (xy 43.784174 -113.063322) (xy 43.867831 -112.971562)
			(xy 43.957182 -112.885338) (xy 44.051861 -112.805001) (xy 44.151481 -112.73088) (xy 44.255636 -112.663278)
			(xy 44.363899 -112.602472) (xy 44.475827 -112.54871) (xy 44.590962 -112.502212) (xy 44.708834 -112.463169)
			(xy 44.828961 -112.43174) (xy 44.950851 -112.408053) (xy 45.074005 -112.392206) (xy 45.197921 -112.384264)
			(xy 45.260006 -112.383824) (xy 45.323533 -112.384344) (xy 45.450315 -112.392654) (xy 45.576282 -112.409238)
			(xy 45.700894 -112.434025) (xy 45.823619 -112.466909) (xy 45.94393 -112.50775) (xy 46.061312 -112.556371)
			(xy 46.175263 -112.612566) (xy 46.285295 -112.676093) (xy 46.390937 -112.74668) (xy 46.491735 -112.824026)
			(xy 46.58726 -112.907798) (xy 46.6771 -112.997639) (xy 46.760873 -113.093163) (xy 46.838218 -113.193962)
			(xy 46.908806 -113.299603) (xy 46.972333 -113.409635) (xy 47.028528 -113.523586) (xy 47.07715 -113.640968)
			(xy 47.11799 -113.761279) (xy 47.150874 -113.884004) (xy 47.175662 -114.008616) (xy 47.192246 -114.134583)
			(xy 47.200556 -114.261365) (xy 47.201074 -114.324892) (xy 47.201074 -114.36223) (xy 47.22114 -114.37747)
			(xy 47.244101 -114.395624) (xy 47.284705 -114.43778) (xy 47.318394 -114.485643) (xy 47.344378 -114.53809)
			(xy 47.362047 -114.593891) (xy 47.370986 -114.651735) (xy 47.371508 -114.681) (xy 47.371036 -114.70837)
			(xy 47.363213 -114.762548) (xy 47.347726 -114.815052) (xy 47.324894 -114.864804) (xy 47.295186 -114.910781)
			(xy 47.277528 -114.931698) (xy 47.268289 -114.943024) (xy 47.256108 -114.969582) (xy 47.251934 -114.9985)
			(xy 47.256108 -115.027418) (xy 47.268289 -115.053976) (xy 47.277528 -115.065302) (xy 47.295171 -115.086234)
			(xy 47.324899 -115.132201) (xy 47.347747 -115.181947) (xy 47.363245 -115.234449) (xy 47.371075 -115.288629)
			(xy 47.371075 -115.343371) (xy 47.363245 -115.397551) (xy 47.347747 -115.450053) (xy 47.324899 -115.499799)
			(xy 47.295171 -115.545766) (xy 47.277528 -115.566698) (xy 47.268289 -115.578024) (xy 47.256108 -115.604582)
			(xy 47.251934 -115.6335) (xy 47.256108 -115.662418) (xy 47.268289 -115.688976) (xy 47.277528 -115.700302)
			(xy 47.295169 -115.721234) (xy 47.324892 -115.767201) (xy 47.347734 -115.816948) (xy 47.363222 -115.869451)
			(xy 47.37104 -115.92363) (xy 47.371508 -115.951) (xy 47.371051 -115.977837) (xy 47.363524 -116.03098)
			(xy 47.348618 -116.082543) (xy 47.32663 -116.131506) (xy 47.297992 -116.176902) (xy 47.263271 -116.217833)
			(xy 47.223153 -116.25349) (xy 47.201074 -116.268754) (xy 47.201074 -117.3734) (xy 63.51905 -117.3734)
			(xy 63.51905 -114.525044) (xy 63.519529 -114.460365) (xy 63.527339 -114.331244) (xy 63.542931 -114.20283)
			(xy 63.566248 -114.075591) (xy 63.597205 -113.949992) (xy 63.63569 -113.826492) (xy 63.68156 -113.705541)
			(xy 63.73465 -113.58758) (xy 63.794765 -113.47304) (xy 63.861687 -113.362338) (xy 63.93517 -113.255879)
			(xy 64.014947 -113.154051) (xy 64.100727 -113.057225) (xy 64.192197 -112.965756) (xy 64.289022 -112.879976)
			(xy 64.39085 -112.800199) (xy 64.49731 -112.726716) (xy 64.608011 -112.659794) (xy 64.722552 -112.599679)
			(xy 64.840513 -112.546589) (xy 64.961464 -112.500719) (xy 65.084964 -112.462235) (xy 65.210563 -112.431278)
			(xy 65.337802 -112.407961) (xy 65.466216 -112.392369) (xy 65.595337 -112.384559) (xy 65.660016 -112.384078)
			(xy 65.66027 -112.384078) (xy 65.720289 -112.384488) (xy 65.84014 -112.391214) (xy 65.959424 -112.404652)
			(xy 66.018664 -112.414304) (xy 66.036855 -112.391861) (xy 66.078856 -112.352198) (xy 66.126356 -112.319319)
			(xy 66.178269 -112.293975) (xy 66.233409 -112.276744) (xy 66.290516 -112.268022) (xy 66.3194 -112.267492)
			(xy 66.346651 -112.267978) (xy 66.400599 -112.275734) (xy 66.452894 -112.291089) (xy 66.502471 -112.313731)
			(xy 66.548321 -112.343197) (xy 66.589512 -112.378888) (xy 66.625203 -112.420079) (xy 66.654669 -112.465929)
			(xy 66.677311 -112.515506) (xy 66.692666 -112.567801) (xy 66.700422 -112.621749) (xy 66.700908 -112.649)
			(xy 66.700908 -112.65408) (xy 66.759163 -112.68708) (xy 66.87188 -112.759359) (xy 66.979859 -112.838542)
			(xy 67.082678 -112.924319) (xy 67.179934 -113.016354) (xy 67.271249 -113.114288) (xy 67.356263 -113.217738)
			(xy 67.434646 -113.326299) (xy 67.506091 -113.439547) (xy 67.570317 -113.557039) (xy 67.627075 -113.678315)
			(xy 67.676142 -113.802902) (xy 67.717326 -113.930311) (xy 67.750467 -114.060046) (xy 67.775434 -114.191599)
			(xy 67.79213 -114.324454) (xy 67.80049 -114.458094) (xy 67.800982 -114.525044) (xy 67.800982 -117.3734)
			(xy 75.724004 -117.3734) (xy 75.724004 -114.799872) (xy 75.72447 -114.745753) (xy 75.732179 -114.637791)
			(xy 75.747571 -114.530654) (xy 75.770568 -114.424888) (xy 75.801051 -114.321033) (xy 75.838866 -114.219616)
			(xy 75.88382 -114.121156) (xy 75.935683 -114.026154) (xy 75.994192 -113.935094) (xy 76.059049 -113.84844)
			(xy 76.129922 -113.766634) (xy 76.206451 -113.690092) (xy 76.288245 -113.619206) (xy 76.374888 -113.554335)
			(xy 76.465939 -113.495811) (xy 76.560932 -113.443931) (xy 76.659385 -113.398961) (xy 76.760795 -113.36113)
			(xy 76.864646 -113.330629) (xy 76.970408 -113.307616) (xy 77.077543 -113.292206) (xy 77.185504 -113.284478)
			(xy 77.239622 -113.284) (xy 78.74 -113.284) (xy 78.794131 -113.284472) (xy 78.902118 -113.292195)
			(xy 79.009279 -113.307603) (xy 79.115068 -113.330616) (xy 79.218945 -113.361118) (xy 79.320382 -113.398952)
			(xy 79.418861 -113.443926) (xy 79.51388 -113.495812) (xy 79.604956 -113.554344) (xy 79.691625 -113.619224)
			(xy 79.773444 -113.690121) (xy 79.849996 -113.766675) (xy 79.920893 -113.848495) (xy 79.985771 -113.935165)
			(xy 80.044302 -114.026242) (xy 80.096185 -114.121263) (xy 80.141158 -114.219742) (xy 80.178991 -114.32118)
			(xy 80.20949 -114.425058) (xy 80.232502 -114.530846) (xy 80.247907 -114.638008) (xy 80.255629 -114.745995)
			(xy 80.256126 -114.800126) (xy 80.256126 -115.673124) (xy 80.275814 -115.691307) (xy 80.310408 -115.732238)
			(xy 80.338938 -115.777605) (xy 80.360842 -115.826517) (xy 80.375689 -115.878011) (xy 80.383189 -115.931076)
			(xy 80.383193 -115.984668) (xy 80.375701 -116.037734) (xy 80.360861 -116.089231) (xy 80.338964 -116.138145)
			(xy 80.310441 -116.183517) (xy 80.275853 -116.224453) (xy 80.256126 -116.242592) (xy 80.256126 -118.720616)
			(xy 83.769962 -118.720616) (xy 83.785387 -118.720026) (xy 83.814807 -118.710726) (xy 83.840119 -118.69308)
			(xy 83.859022 -118.668694) (xy 83.869798 -118.639782) (xy 83.871468 -118.608972) (xy 83.86826 -118.59387)
			(xy 83.862789 -118.570826) (xy 83.856924 -118.523826) (xy 83.856576 -118.500144) (xy 83.857026 -118.473348)
			(xy 83.864518 -118.420283) (xy 83.87936 -118.368788) (xy 83.90126 -118.319875) (xy 83.929789 -118.274508)
			(xy 83.964384 -118.233578) (xy 83.984084 -118.21541) (xy 83.984084 -114.799872) (xy 83.984551 -114.747028)
			(xy 83.991928 -114.641597) (xy 84.006631 -114.536936) (xy 84.028587 -114.433553) (xy 84.057692 -114.331951)
			(xy 84.093802 -114.232623) (xy 84.136742 -114.13605) (xy 84.186305 -114.042704) (xy 84.24225 -113.953036)
			(xy 84.304303 -113.867482) (xy 84.372165 -113.786459) (xy 84.445506 -113.710358) (xy 84.484464 -113.674652)
			(xy 84.487437 -113.646488) (xy 84.500641 -113.591417) (xy 84.52184 -113.538903) (xy 84.550567 -113.490099)
			(xy 84.586191 -113.446076) (xy 84.627931 -113.407802) (xy 84.67487 -113.376118) (xy 84.725976 -113.351718)
			(xy 84.780126 -113.335141) (xy 84.836133 -113.326748) (xy 84.864448 -113.326164) (xy 84.891798 -113.326657)
			(xy 84.945932 -113.334505) (xy 84.998393 -113.349993) (xy 85.023452 -113.360962) (xy 85.081131 -113.342462)
			(xy 85.198793 -113.313639) (xy 85.318381 -113.29431) (xy 85.439132 -113.284598) (xy 85.499702 -113.284)
			(xy 88.000078 -113.284) (xy 88.045548 -113.283492) (xy 88.1361 -113.275103) (xy 88.225492 -113.258395)
			(xy 88.312961 -113.233509) (xy 88.397761 -113.200659) (xy 88.479168 -113.160125) (xy 88.556488 -113.112253)
			(xy 88.62906 -113.05745) (xy 88.696267 -112.996185) (xy 88.757534 -112.92898) (xy 88.812338 -112.856409)
			(xy 88.860213 -112.779091) (xy 88.900749 -112.697685) (xy 88.933601 -112.612886) (xy 88.958489 -112.525418)
			(xy 88.975199 -112.436026) (xy 88.983591 -112.345474) (xy 88.984074 -112.300004) (xy 88.984074 -111.417608)
			(xy 88.964391 -111.399425) (xy 88.929806 -111.358495) (xy 88.901286 -111.313131) (xy 88.87939 -111.264223)
			(xy 88.864551 -111.212734) (xy 88.857059 -111.159675) (xy 88.857061 -111.10609) (xy 88.864558 -111.053032)
			(xy 88.879402 -111.001544) (xy 88.901302 -110.952639) (xy 88.929826 -110.907277) (xy 88.964415 -110.86635)
			(xy 88.984074 -110.84814) (xy 88.984074 -106.337608) (xy 88.964391 -106.319425) (xy 88.929806 -106.278495)
			(xy 88.901286 -106.233131) (xy 88.87939 -106.184223) (xy 88.864551 -106.132734) (xy 88.857059 -106.079675)
			(xy 88.857061 -106.02609) (xy 88.864558 -105.973032) (xy 88.879402 -105.921544) (xy 88.901302 -105.872639)
			(xy 88.929826 -105.827277) (xy 88.964415 -105.78635) (xy 88.984074 -105.76814) (xy 88.984074 -101.257608)
			(xy 88.964391 -101.239425) (xy 88.929806 -101.198495) (xy 88.901286 -101.153131) (xy 88.87939 -101.104223)
			(xy 88.864551 -101.052734) (xy 88.857059 -100.999675) (xy 88.857061 -100.94609) (xy 88.864558 -100.893032)
			(xy 88.879402 -100.841544) (xy 88.901302 -100.792639) (xy 88.929826 -100.747277) (xy 88.964415 -100.70635)
			(xy 88.984074 -100.68814) (xy 88.984074 -96.177608) (xy 88.964391 -96.159425) (xy 88.929806 -96.118495)
			(xy 88.901286 -96.073131) (xy 88.87939 -96.024223) (xy 88.864551 -95.972734) (xy 88.857059 -95.919675)
			(xy 88.857061 -95.86609) (xy 88.864558 -95.813032) (xy 88.879402 -95.761544) (xy 88.901302 -95.712639)
			(xy 88.929826 -95.667277) (xy 88.964415 -95.62635) (xy 88.984074 -95.60814) (xy 88.984074 -91.097608)
			(xy 88.964391 -91.079425) (xy 88.929806 -91.038495) (xy 88.901286 -90.993131) (xy 88.87939 -90.944223)
			(xy 88.864551 -90.892734) (xy 88.857059 -90.839675) (xy 88.857061 -90.78609) (xy 88.864558 -90.733032)
			(xy 88.879402 -90.681544) (xy 88.901302 -90.632639) (xy 88.929826 -90.587277) (xy 88.964415 -90.54635)
			(xy 88.984074 -90.52814) (xy 88.984074 -86.216744) (xy 88.983555 -86.202844) (xy 88.975972 -86.176096)
			(xy 88.961463 -86.152379) (xy 88.941103 -86.133446) (xy 88.916395 -86.120699) (xy 88.889166 -86.115078)
			(xy 88.86143 -86.116999) (xy 88.848184 -86.12124) (xy 88.817082 -86.131673) (xy 88.752458 -86.142917)
			(xy 88.71966 -86.143592) (xy 88.692864 -86.143143) (xy 88.639798 -86.135653) (xy 88.588302 -86.120811)
			(xy 88.53939 -86.098911) (xy 88.494022 -86.070382) (xy 88.453093 -86.035786) (xy 88.434926 -86.016084)
			(xy 87.749634 -86.016084) (xy 87.695522 -86.015578) (xy 87.587576 -86.007814) (xy 87.480458 -85.992371)
			(xy 87.374714 -85.96933) (xy 87.270883 -85.938808) (xy 87.169492 -85.900959) (xy 87.071058 -85.855976)
			(xy 86.976082 -85.804089) (xy 86.885048 -85.745562) (xy 86.798419 -85.680692) (xy 86.716636 -85.609811)
			(xy 86.640116 -85.533278) (xy 86.569248 -85.451483) (xy 86.504393 -85.364843) (xy 86.445881 -85.273799)
			(xy 86.39401 -85.178815) (xy 86.349044 -85.080374) (xy 86.311212 -84.978976) (xy 86.280707 -84.87514)
			(xy 86.257683 -84.769392) (xy 86.242259 -84.662272) (xy 86.234513 -84.554324) (xy 86.234016 -84.500212)
			(xy 86.234016 -81.999836) (xy 86.234549 -81.943052) (xy 86.243072 -81.829805) (xy 86.260043 -81.717513)
			(xy 86.285368 -81.606805) (xy 86.318903 -81.498302) (xy 86.360461 -81.392611) (xy 86.409809 -81.290326)
			(xy 86.466671 -81.192019) (xy 86.530729 -81.098241) (xy 86.601621 -81.009518) (xy 86.639908 -80.96758)
			(xy 86.640443 -80.940363) (xy 86.648283 -80.886494) (xy 86.663701 -80.834287) (xy 86.686383 -80.784801)
			(xy 86.715869 -80.739042) (xy 86.75156 -80.697939) (xy 86.792732 -80.662327) (xy 86.838548 -80.632929)
			(xy 86.888077 -80.610343) (xy 86.940314 -80.595026) (xy 86.994198 -80.58729) (xy 87.021416 -80.586834)
			(xy 87.021924 -80.586834) (xy 87.054114 -80.587523) (xy 87.117573 -80.598376) (xy 87.148162 -80.608424)
			(xy 87.195651 -80.588374) (xy 87.292843 -80.553998) (xy 87.392144 -80.526299) (xy 87.493097 -80.505406)
			(xy 87.595235 -80.491416) (xy 87.698088 -80.484392) (xy 87.749634 -80.483964) (xy 88.984074 -80.483964)
			(xy 88.984074 -76.684886) (xy 88.964392 -76.666703) (xy 88.929811 -76.625774) (xy 88.901293 -76.58041)
			(xy 88.879401 -76.531504) (xy 88.864564 -76.480016) (xy 88.857074 -76.426959) (xy 88.857078 -76.373377)
			(xy 88.864577 -76.320321) (xy 88.879423 -76.268836) (xy 88.901323 -76.219933) (xy 88.929848 -76.174574)
			(xy 88.964437 -76.133651) (xy 88.984074 -76.115418) (xy 88.984074 -71.604886) (xy 88.964392 -71.586703)
			(xy 88.929811 -71.545774) (xy 88.901293 -71.50041) (xy 88.879401 -71.451504) (xy 88.864564 -71.400016)
			(xy 88.857074 -71.346959) (xy 88.857078 -71.293377) (xy 88.864577 -71.240321) (xy 88.879423 -71.188836)
			(xy 88.901323 -71.139933) (xy 88.929848 -71.094574) (xy 88.964437 -71.053651) (xy 88.984074 -71.035418)
			(xy 88.984074 -68.888102) (xy 88.592406 -68.496434) (xy 68.007484 -68.496434) (xy 67.989266 -68.51718)
			(xy 67.947876 -68.553719) (xy 67.901651 -68.583911) (xy 67.851557 -68.607124) (xy 67.79864 -68.622875)
			(xy 67.744006 -68.630833) (xy 67.688794 -68.630833) (xy 67.63416 -68.622875) (xy 67.581243 -68.607124)
			(xy 67.531149 -68.583911) (xy 67.484924 -68.553719) (xy 67.443534 -68.51718) (xy 67.425316 -68.496434)
			(xy 66.195702 -68.496434) (xy 65.87363 -68.818506) (xy 65.87363 -72.193658) (xy 65.886361 -72.220336)
			(xy 65.904353 -72.276641) (xy 65.913458 -72.335045) (xy 65.913458 -72.394155) (xy 65.904353 -72.452559)
			(xy 65.886361 -72.508864) (xy 65.87363 -72.535542) (xy 65.87363 -73.111106) (xy 65.873018 -73.136063)
			(xy 65.86328 -73.185017) (xy 65.84418 -73.231131) (xy 65.816452 -73.272634) (xy 65.799208 -73.290684)
			(xy 65.003934 -74.085958) (xy 64.985892 -74.103215) (xy 64.944397 -74.130967) (xy 64.898279 -74.150075)
			(xy 64.849316 -74.159803) (xy 64.824356 -74.16038) (xy 57.029858 -74.16038) (xy 57.005798 -74.176389)
			(xy 56.953868 -74.201741) (xy 56.898709 -74.218971) (xy 56.841582 -74.227686) (xy 56.783794 -74.227686)
			(xy 56.726667 -74.218971) (xy 56.671508 -74.201741) (xy 56.619578 -74.176389) (xy 56.595518 -74.16038)
			(xy 55.569612 -74.16038) (xy 55.544659 -74.15976) (xy 55.495715 -74.150007) (xy 55.449614 -74.130894)
			(xy 55.408127 -74.103155) (xy 55.390034 -74.085958) (xy 54.90972 -73.605644) (xy 54.892458 -73.587604)
			(xy 54.864696 -73.546112) (xy 54.84558 -73.499993) (xy 54.835847 -73.451028) (xy 54.835298 -73.426066)
			(xy 54.835298 -65.547748) (xy 54.810914 -65.532762) (xy 54.798322 -65.524768) (xy 54.774895 -65.506306)
			(xy 54.764178 -65.495932) (xy 54.38013 -65.111884) (xy 52.670202 -65.11036) (xy 52.655216 -65.126616)
			(xy 52.637077 -65.145603) (xy 52.596491 -65.17892) (xy 52.55172 -65.206358) (xy 52.503611 -65.2274)
			(xy 52.453071 -65.241648) (xy 52.401055 -65.248832) (xy 52.3748 -65.249298) (xy 52.348502 -65.248857)
			(xy 52.296406 -65.24163) (xy 52.245796 -65.227313) (xy 52.197634 -65.206178) (xy 52.152833 -65.178626)
			(xy 52.112243 -65.145178) (xy 52.09413 -65.126108) (xy 52.07889 -65.109598) (xy 49.696116 -65.107312)
			(xy 49.681638 -65.121028) (xy 49.660291 -65.14038) (xy 49.61286 -65.173092) (xy 49.561051 -65.198302)
			(xy 49.506041 -65.215437) (xy 49.44908 -65.224109) (xy 49.420272 -65.22466) (xy 49.419764 -65.22466)
			(xy 49.390882 -65.224132) (xy 49.333778 -65.215425) (xy 49.278642 -65.198202) (xy 49.226736 -65.172857)
			(xy 49.179248 -65.139969) (xy 49.15789 -65.12052) (xy 49.143412 -65.106804) (xy 47.948088 -65.105788)
			(xy 47.93361 -65.132204) (xy 47.919081 -65.157394) (xy 47.883579 -65.203448) (xy 47.841497 -65.243579)
			(xy 47.793812 -65.276857) (xy 47.741627 -65.302511) (xy 47.686153 -65.319946) (xy 47.628675 -65.328758)
			(xy 47.5996 -65.329308) (xy 47.570459 -65.328757) (xy 47.512854 -65.319897) (xy 47.457266 -65.302383)
			(xy 47.404986 -65.276622) (xy 47.35723 -65.243213) (xy 47.315108 -65.202932) (xy 47.279599 -65.156716)
			(xy 47.265082 -65.131442) (xy 47.250604 -65.105026) (xy 45.922692 -65.103756) (xy 45.908976 -65.113916)
			(xy 45.884103 -65.131711) (xy 45.829876 -65.159984) (xy 45.771833 -65.179243) (xy 45.711461 -65.188996)
			(xy 45.680884 -65.189608) (xy 45.650191 -65.188994) (xy 45.589596 -65.17917) (xy 45.531354 -65.159777)
			(xy 45.476965 -65.131316) (xy 45.45203 -65.113408) (xy 45.438568 -65.103248) (xy 42.4942 -65.100454)
			(xy 42.4942 -70.837044) (xy 43.666156 -72.009) (xy 50.165 -72.009) (xy 50.189957 -72.009612) (xy 50.238911 -72.019349)
			(xy 50.285024 -72.03845) (xy 50.326526 -72.06618) (xy 50.344578 -72.083422) (xy 52.122578 -73.861422)
			(xy 52.139843 -73.879461) (xy 52.167611 -73.920952) (xy 52.186733 -73.96707) (xy 52.196473 -74.016037)
			(xy 52.197 -74.041) (xy 52.197 -76.189586) (xy 52.218862 -76.207792) (xy 52.257462 -76.249583) (xy 52.289424 -76.296647)
			(xy 52.314037 -76.347937) (xy 52.330755 -76.402316) (xy 52.339206 -76.458575) (xy 52.339748 -76.48702)
			(xy 52.339482 -76.507633) (xy 52.335026 -76.548619) (xy 52.330858 -76.568808) (xy 52.329588 -76.574396)
			(xy 52.323238 -76.602082) (xy 53.826156 -78.105) (xy 54.065932 -78.105) (xy 54.090936 -78.091116)
			(xy 54.144157 -78.070177) (xy 54.199909 -78.057422) (xy 54.25694 -78.053139) (xy 54.313971 -78.057422)
			(xy 54.369723 -78.070177) (xy 54.422944 -78.091116) (xy 54.447948 -78.105) (xy 56.536844 -78.105)
			(xy 57.351422 -77.290422) (xy 57.369461 -77.273157) (xy 57.410952 -77.245389) (xy 57.45707 -77.226267)
			(xy 57.506037 -77.216527) (xy 57.531 -77.216) (xy 58.101738 -77.216) (xy 58.1152 -77.215492) (xy 58.128662 -77.216)
			(xy 60.173362 -77.216) (xy 60.18276 -77.177138) (xy 60.189905 -77.149771) (xy 60.211167 -77.09736)
			(xy 60.239935 -77.048662) (xy 60.275576 -77.004745) (xy 60.31731 -76.966571) (xy 60.364223 -76.934977)
			(xy 60.415286 -76.910655) (xy 60.46938 -76.894138) (xy 60.52532 -76.885788) (xy 60.58188 -76.885788)
			(xy 60.63782 -76.894138) (xy 60.691914 -76.910655) (xy 60.742977 -76.934977) (xy 60.78989 -76.966571)
			(xy 60.831624 -77.004745) (xy 60.867265 -77.048662) (xy 60.896033 -77.09736) (xy 60.917295 -77.149771)
			(xy 60.92444 -77.177138) (xy 60.933838 -77.216) (xy 62.173866 -77.216) (xy 62.19205 -77.196316) (xy 62.232981 -77.16173)
			(xy 62.278347 -77.133208) (xy 62.327256 -77.111312) (xy 62.378746 -77.09647) (xy 62.431807 -77.088976)
			(xy 62.485393 -77.088976) (xy 62.538454 -77.09647) (xy 62.589944 -77.111312) (xy 62.638853 -77.133208)
			(xy 62.684219 -77.16173) (xy 62.72515 -77.196316) (xy 62.743334 -77.216) (xy 62.915292 -77.216) (xy 62.933414 -77.19269)
			(xy 62.975638 -77.151422) (xy 63.02372 -77.117158) (xy 63.076509 -77.090716) (xy 63.132744 -77.072729)
			(xy 63.191079 -77.063627) (xy 63.2206 -77.063092) (xy 63.220854 -77.063092) (xy 63.248938 -77.063615)
			(xy 63.304494 -77.071891) (xy 63.358239 -77.088214) (xy 63.409015 -77.112231) (xy 63.455726 -77.143424)
			(xy 63.476886 -77.161898) (xy 63.486792 -77.171042) (xy 63.52667 -77.211174) (xy 63.955422 -76.782422)
			(xy 63.973461 -76.765157) (xy 64.014952 -76.737389) (xy 64.06107 -76.718267) (xy 64.110037 -76.708527)
			(xy 64.135 -76.708) (xy 71.882 -76.708) (xy 71.906957 -76.708612) (xy 71.955911 -76.718349) (xy 72.002024 -76.73745)
			(xy 72.043526 -76.76518) (xy 72.061578 -76.782422) (xy 72.241156 -76.962) (xy 77.597 -76.962) (xy 77.621957 -76.962612)
			(xy 77.670911 -76.972349) (xy 77.717024 -76.99145) (xy 77.758526 -77.01918) (xy 77.776578 -77.036422)
			(xy 78.665578 -77.925422) (xy 78.682843 -77.943461) (xy 78.710611 -77.984952) (xy 78.729733 -78.03107)
			(xy 78.739473 -78.080037) (xy 78.74 -78.105) (xy 78.74 -79.648812) (xy 78.769972 -79.662274) (xy 78.794713 -79.673959)
			(xy 78.840854 -79.703364) (xy 78.882321 -79.739059) (xy 78.918264 -79.780311) (xy 78.947945 -79.826276)
			(xy 78.970756 -79.876008) (xy 78.986228 -79.92849) (xy 78.994044 -79.982643) (xy 78.994508 -80.01)
			(xy 78.994022 -80.037251) (xy 78.986266 -80.091199) (xy 78.970911 -80.143494) (xy 78.948269 -80.193071)
			(xy 78.918803 -80.238921) (xy 78.883112 -80.280112) (xy 78.841921 -80.315803) (xy 78.796071 -80.345269)
			(xy 78.746494 -80.367911) (xy 78.694199 -80.383266) (xy 78.640251 -80.391022) (xy 78.613 -80.391508)
			(xy 78.612746 -80.391508) (xy 78.584657 -80.391011) (xy 78.529085 -80.38277) (xy 78.475326 -80.366461)
			(xy 78.424543 -80.342436) (xy 78.40091 -80.327246) (xy 78.030578 -80.697578) (xy 78.012539 -80.714843)
			(xy 77.971048 -80.742611) (xy 77.92493 -80.761733) (xy 77.875963 -80.771473) (xy 77.851 -80.772)
			(xy 70.531482 -80.772) (xy 70.510186 -80.791093) (xy 70.46295 -80.823342) (xy 70.411434 -80.848187)
			(xy 70.356789 -80.865073) (xy 70.300237 -80.873622) (xy 70.27164 -80.874108) (xy 70.244873 -80.873632)
			(xy 70.191871 -80.866104) (xy 70.140439 -80.851245) (xy 70.091588 -80.829348) (xy 70.046274 -80.800842)
			(xy 70.025514 -80.783938) (xy 70.01129 -80.772) (xy 69.977 -80.772) (xy 69.952043 -80.771388) (xy 69.903089 -80.761651)
			(xy 69.856976 -80.74255) (xy 69.815474 -80.71482) (xy 69.797422 -80.697578) (xy 68.855844 -79.756)
			(xy 60.938156 -79.756) (xy 59.361578 -81.332578) (xy 59.343539 -81.349843) (xy 59.302048 -81.377611)
			(xy 59.25593 -81.396733) (xy 59.206963 -81.406473) (xy 59.182 -81.407) (xy 52.959 -81.407) (xy 52.934043 -81.406388)
			(xy 52.885089 -81.396651) (xy 52.838976 -81.37755) (xy 52.797474 -81.34982) (xy 52.779422 -81.332578)
			(xy 49.772062 -78.325218) (xy 49.751906 -78.340399) (xy 49.708354 -78.365885) (xy 49.661822 -78.385405)
			(xy 49.613121 -78.398619) (xy 49.563104 -78.405296) (xy 49.537874 -78.405736) (xy 49.510623 -78.405248)
			(xy 49.456677 -78.397489) (xy 49.404384 -78.382132) (xy 49.354808 -78.35949) (xy 49.308959 -78.330023)
			(xy 49.267769 -78.294332) (xy 49.232078 -78.253143) (xy 49.202611 -78.207294) (xy 49.179969 -78.157718)
			(xy 49.164611 -78.105425) (xy 49.156852 -78.051479) (xy 49.156366 -78.024228) (xy 49.156836 -77.996851)
			(xy 49.164662 -77.942658) (xy 49.180156 -77.890142) (xy 49.202999 -77.84038) (xy 49.232724 -77.794396)
			(xy 49.268718 -77.753135) (xy 49.310242 -77.717445) (xy 49.356443 -77.688059) (xy 49.406371 -77.665581)
			(xy 49.459 -77.650473) (xy 49.486058 -77.646276) (xy 49.53 -77.64018) (xy 49.53 -75.924156) (xy 48.535844 -74.93)
			(xy 46.323758 -74.93) (xy 46.306975 -74.950668) (xy 46.268633 -74.987605) (xy 46.225531 -75.018855)
			(xy 46.178504 -75.043813) (xy 46.128466 -75.061994) (xy 46.076386 -75.073046) (xy 46.023276 -75.076754)
			(xy 45.970166 -75.073046) (xy 45.918086 -75.061994) (xy 45.868048 -75.043813) (xy 45.821021 -75.018855)
			(xy 45.777919 -74.987605) (xy 45.739577 -74.950668) (xy 45.722794 -74.93) (xy 41.91 -74.93) (xy 41.885043 -74.929388)
			(xy 41.836089 -74.919651) (xy 41.789976 -74.90055) (xy 41.748474 -74.87282) (xy 41.730422 -74.855578)
			(xy 41.30167 -74.426826) (xy 41.273222 -74.4347) (xy 41.248859 -74.440873) (xy 41.199038 -74.447501)
			(xy 41.173908 -74.447908) (xy 41.1734 -74.447908) (xy 41.146149 -74.447422) (xy 41.092201 -74.439666)
			(xy 41.039906 -74.424311) (xy 40.990329 -74.401669) (xy 40.944479 -74.372203) (xy 40.903288 -74.336512)
			(xy 40.867597 -74.295321) (xy 40.838131 -74.249471) (xy 40.815489 -74.199894) (xy 40.800134 -74.147599)
			(xy 40.792378 -74.093651) (xy 40.791892 -74.0664) (xy 40.791892 -74.065892) (xy 40.792311 -74.040763)
			(xy 40.798938 -73.990943) (xy 40.8051 -73.966578) (xy 40.812974 -73.93813) (xy 31.263844 -64.389)
			(xy 23.541228 -64.389) (xy 23.527004 -64.415924) (xy 23.513642 -64.439993) (xy 23.481056 -64.484363)
			(xy 23.442432 -64.523589) (xy 23.398572 -64.556858) (xy 23.350386 -64.583478) (xy 23.298875 -64.602897)
			(xy 23.245107 -64.614713) (xy 23.1902 -64.618678) (xy 23.135293 -64.614713) (xy 23.081525 -64.602897)
			(xy 23.030014 -64.583478) (xy 22.981828 -64.556858) (xy 22.937968 -64.523589) (xy 22.899344 -64.484363)
			(xy 22.866758 -64.439993) (xy 22.853396 -64.415924) (xy 22.839172 -64.389) (xy 17.855438 -64.389)
			(xy 17.84604 -64.427862) (xy 17.838895 -64.455229) (xy 17.817633 -64.50764) (xy 17.788865 -64.556338)
			(xy 17.753224 -64.600255) (xy 17.71149 -64.638429) (xy 17.664577 -64.670023) (xy 17.613514 -64.694345)
			(xy 17.55942 -64.710862) (xy 17.50348 -64.719212) (xy 17.4752 -64.719708) (xy 17.448987 -64.719274)
			(xy 17.397055 -64.712102) (xy 17.346593 -64.697891) (xy 17.298549 -64.67691) (xy 17.253828 -64.649553)
			(xy 17.21327 -64.616335) (xy 17.177638 -64.57788) (xy 17.162272 -64.55664) (xy 17.153007 -64.544294)
			(xy 17.12861 -64.525409) (xy 17.099688 -64.51467) (xy 17.068878 -64.513056) (xy 17.038991 -64.520714)
			(xy 17.012755 -64.536947) (xy 17.002252 -64.548258) (xy 16.98404 -64.568609) (xy 16.942799 -64.604409)
			(xy 16.896877 -64.633965) (xy 16.847211 -64.656676) (xy 16.794815 -64.672076) (xy 16.74076 -64.679853)
			(xy 16.713454 -64.680338) (xy 16.687192 -64.679897) (xy 16.635165 -64.672688) (xy 16.584618 -64.658412)
			(xy 16.536507 -64.63734) (xy 16.49174 -64.609868) (xy 16.451163 -64.576517) (xy 16.415543 -64.537917)
			(xy 16.385553 -64.494797) (xy 16.361759 -64.447971) (xy 16.352774 -64.42329) (xy 16.340836 -64.389)
			(xy 12.7 -64.389) (xy 12.675043 -64.388388) (xy 12.626089 -64.378651) (xy 12.579976 -64.35955) (xy 12.538474 -64.33182)
			(xy 12.520422 -64.314578) (xy 10.273284 -62.06744) (xy 10.239756 -62.086744) (xy 10.218014 -62.09875)
			(xy 10.172087 -62.117656) (xy 10.124096 -62.130446) (xy 10.074851 -62.136903) (xy 10.050018 -62.13729)
			(xy 10.022765 -62.136828) (xy 9.968813 -62.129073) (xy 9.916514 -62.113718) (xy 9.866933 -62.091077)
			(xy 9.821079 -62.061609) (xy 9.779885 -62.025915) (xy 9.744191 -61.984721) (xy 9.714723 -61.938867)
			(xy 9.692082 -61.889286) (xy 9.676727 -61.836987) (xy 9.668972 -61.783035) (xy 9.66851 -61.755782)
			(xy 9.66851 -61.755528) (xy 9.669061 -61.725929) (xy 9.678197 -61.66744) (xy 9.69627 -61.611069)
			(xy 9.722845 -61.558171) (xy 9.73963 -61.533786) (xy 9.726422 -61.520578) (xy 9.709157 -61.502539)
			(xy 9.681389 -61.461048) (xy 9.662267 -61.41493) (xy 9.652527 -61.365963) (xy 9.652 -61.341) (xy 9.652 -58.869072)
			(xy 8.690864 -57.907936) (xy 8.673579 -57.889938) (xy 8.644268 -57.849556) (xy 8.621627 -57.80509)
			(xy 8.606212 -57.757632) (xy 8.5984 -57.708349) (xy 8.5979 -57.6834) (xy 8.5979 -35.2806) (xy 8.598389 -35.255651)
			(xy 8.606195 -35.206366) (xy 8.621615 -35.15891) (xy 8.644268 -35.11445) (xy 8.673598 -35.074081)
			(xy 8.690864 -35.056064) (xy 12.151614 -31.595314) (xy 12.141454 -31.565342) (xy 12.131994 -31.535622)
			(xy 12.121788 -31.474097) (xy 12.121134 -31.442914) (xy 12.121596 -31.415662) (xy 12.129352 -31.361711)
			(xy 12.144707 -31.309414) (xy 12.16735 -31.259835) (xy 12.196818 -31.213983) (xy 12.232512 -31.172792)
			(xy 12.273706 -31.137101) (xy 12.31956 -31.107636) (xy 12.369141 -31.084997) (xy 12.421439 -31.069646)
			(xy 12.47539 -31.061894) (xy 12.502642 -31.061406) (xy 12.533823 -31.062073) (xy 12.595343 -31.072291)
			(xy 12.62507 -31.081726) (xy 12.655042 -31.091886) (xy 12.87399 -30.872938) (xy 12.87018 -30.847538)
			(xy 12.868131 -30.833084) (xy 12.865969 -30.80397) (xy 12.865862 -30.789372) (xy 12.86635 -30.762121)
			(xy 12.874109 -30.708175) (xy 12.889466 -30.655882) (xy 12.912109 -30.606306) (xy 12.941575 -30.560457)
			(xy 12.977266 -30.519268) (xy 13.018456 -30.483577) (xy 13.064305 -30.45411) (xy 13.11388 -30.431467)
			(xy 13.166173 -30.41611) (xy 13.220119 -30.40835) (xy 13.24737 -30.407864) (xy 13.261968 -30.407959)
			(xy 13.291084 -30.410117) (xy 13.305536 -30.412182) (xy 13.330936 -30.415992) (xy 13.567664 -30.179264)
			(xy 13.585662 -30.161979) (xy 13.626044 -30.132668) (xy 13.67051 -30.110027) (xy 13.717968 -30.094612)
			(xy 13.767251 -30.0868) (xy 13.7922 -30.0863) (xy 15.4432 -30.0863) (xy 15.4432 -19.3548) (xy 15.443812 -19.329843)
			(xy 15.453549 -19.280889) (xy 15.47265 -19.234776) (xy 15.50038 -19.193274) (xy 15.517622 -19.175222)
			(xy 16.279622 -18.413222) (xy 16.297661 -18.395957) (xy 16.339152 -18.368189) (xy 16.38527 -18.349067)
			(xy 16.434237 -18.339327) (xy 16.4592 -18.3388) (xy 24.5618 -18.3388) (xy 24.586757 -18.339412) (xy 24.635711 -18.349149)
			(xy 24.681824 -18.36825) (xy 24.723326 -18.39598) (xy 24.741378 -18.413222) (xy 25.047956 -18.7198)
			(xy 29.215334 -18.7198) (xy 29.226256 -18.683986) (xy 29.234627 -18.65832) (xy 29.257592 -18.609462)
			(xy 29.287214 -18.564329) (xy 29.322903 -18.523822) (xy 29.363944 -18.488749) (xy 29.40952 -18.459812)
			(xy 29.458719 -18.437588) (xy 29.51056 -18.422521) (xy 29.564007 -18.414912) (xy 29.617993 -18.414912)
			(xy 29.67144 -18.422521) (xy 29.723281 -18.437588) (xy 29.77248 -18.459812) (xy 29.818056 -18.488749)
			(xy 29.859097 -18.523822) (xy 29.894786 -18.564329) (xy 29.924408 -18.609462) (xy 29.947373 -18.65832)
			(xy 29.955744 -18.683986) (xy 29.966666 -18.7198) (xy 32.862266 -18.7198) (xy 32.880451 -18.700118)
			(xy 32.921384 -18.665533) (xy 32.96675 -18.63701) (xy 33.015658 -18.61511) (xy 33.067147 -18.600261)
			(xy 33.120206 -18.592756) (xy 33.147 -18.592292) (xy 33.174251 -18.592778) (xy 33.228199 -18.600534)
			(xy 33.280494 -18.615889) (xy 33.330071 -18.638531) (xy 33.375921 -18.667997) (xy 33.417112 -18.703688)
			(xy 33.452803 -18.744879) (xy 33.482269 -18.790729) (xy 33.504911 -18.840306) (xy 33.520266 -18.892601)
			(xy 33.528022 -18.946549) (xy 33.528508 -18.9738) (xy 33.528063 -18.999298) (xy 33.521229 -19.049835)
			(xy 33.507724 -19.09901) (xy 33.487787 -19.145949) (xy 33.475168 -19.16811) (xy 33.455102 -19.202146)
			(xy 33.732978 -19.480022) (xy 33.750243 -19.498061) (xy 33.778011 -19.539552) (xy 33.797133 -19.58567)
			(xy 33.806873 -19.634637) (xy 33.8074 -19.6596) (xy 33.8074 -24.482675) (xy 40.239076 -24.482675)
			(xy 40.239076 -24.428125) (xy 40.246839 -24.374131) (xy 40.262209 -24.321791) (xy 40.284871 -24.272172)
			(xy 40.314365 -24.226283) (xy 40.350089 -24.185059) (xy 40.391317 -24.149339) (xy 40.437209 -24.119851)
			(xy 40.486831 -24.097194) (xy 40.539172 -24.08183) (xy 40.593167 -24.074073) (xy 40.620442 -24.073612)
			(xy 41.509442 -24.073612) (xy 41.536708 -24.074153) (xy 41.590683 -24.081919) (xy 41.643004 -24.097287)
			(xy 41.692605 -24.119944) (xy 41.738478 -24.149429) (xy 41.779688 -24.185142) (xy 41.815396 -24.226356)
			(xy 41.844876 -24.272232) (xy 41.867528 -24.321836) (xy 41.88289 -24.374158) (xy 41.89065 -24.428134)
			(xy 41.89065 -24.482666) (xy 41.890649 -24.482675) (xy 42.632776 -24.482675) (xy 42.632776 -24.428125)
			(xy 42.640539 -24.374132) (xy 42.655909 -24.321792) (xy 42.67857 -24.272173) (xy 42.708064 -24.226285)
			(xy 42.743788 -24.185061) (xy 42.785015 -24.149341) (xy 42.830907 -24.119852) (xy 42.880528 -24.097195)
			(xy 42.932869 -24.081831) (xy 42.986863 -24.074073) (xy 43.014138 -24.073612) (xy 43.903138 -24.073612)
			(xy 43.930404 -24.074153) (xy 43.98438 -24.081918) (xy 44.036701 -24.097286) (xy 44.086303 -24.119943)
			(xy 44.132176 -24.149428) (xy 44.173386 -24.185141) (xy 44.209095 -24.226354) (xy 44.238575 -24.27223)
			(xy 44.261227 -24.321835) (xy 44.27659 -24.374158) (xy 44.28435 -24.428134) (xy 44.28435 -24.482666)
			(xy 44.27659 -24.536642) (xy 44.261227 -24.588965) (xy 44.238575 -24.63857) (xy 44.209095 -24.684446)
			(xy 44.173386 -24.725659) (xy 44.132176 -24.761372) (xy 44.086303 -24.790857) (xy 44.036701 -24.813514)
			(xy 43.98438 -24.828882) (xy 43.930404 -24.836647) (xy 43.903138 -24.837136) (xy 43.014138 -24.837136)
			(xy 42.986863 -24.836727) (xy 42.932869 -24.828969) (xy 42.880528 -24.813605) (xy 42.830907 -24.790948)
			(xy 42.785015 -24.761459) (xy 42.743788 -24.725739) (xy 42.708064 -24.684515) (xy 42.67857 -24.638627)
			(xy 42.655909 -24.589008) (xy 42.640539 -24.536668) (xy 42.632776 -24.482675) (xy 41.890649 -24.482675)
			(xy 41.88289 -24.536642) (xy 41.867528 -24.588964) (xy 41.844876 -24.638568) (xy 41.815396 -24.684444)
			(xy 41.779688 -24.725658) (xy 41.738478 -24.761371) (xy 41.692605 -24.790856) (xy 41.643004 -24.813513)
			(xy 41.590683 -24.828881) (xy 41.536708 -24.836647) (xy 41.509442 -24.837136) (xy 40.620442 -24.837136)
			(xy 40.593167 -24.836727) (xy 40.539172 -24.82897) (xy 40.486831 -24.813606) (xy 40.437209 -24.790949)
			(xy 40.391317 -24.761461) (xy 40.350089 -24.725741) (xy 40.314365 -24.684517) (xy 40.284871 -24.638628)
			(xy 40.262209 -24.589009) (xy 40.246839 -24.536669) (xy 40.239076 -24.482675) (xy 33.8074 -24.482675)
			(xy 33.8074 -26.6446) (xy 33.806788 -26.669557) (xy 33.797051 -26.718511) (xy 33.77795 -26.764624)
			(xy 33.75022 -26.806126) (xy 33.732978 -26.824178) (xy 33.658705 -26.898451) (xy 62.226946 -26.898451)
			(xy 62.226946 -26.843949) (xy 62.234702 -26.790001) (xy 62.250056 -26.737705) (xy 62.272695 -26.688127)
			(xy 62.302159 -26.642275) (xy 62.337849 -26.601083) (xy 62.379037 -26.565388) (xy 62.424885 -26.535918)
			(xy 62.47446 -26.513272) (xy 62.526754 -26.497912) (xy 62.580701 -26.490149) (xy 62.607952 -26.48966)
			(xy 63.496952 -26.48966) (xy 63.524205 -26.490184) (xy 63.578156 -26.497935) (xy 63.630456 -26.513285)
			(xy 63.680038 -26.535923) (xy 63.725893 -26.565387) (xy 63.767088 -26.601078) (xy 63.802784 -26.642269)
			(xy 63.832254 -26.68812) (xy 63.854898 -26.737699) (xy 63.870255 -26.789997) (xy 63.878013 -26.843947)
			(xy 63.878013 -26.898453) (xy 63.870255 -26.952403) (xy 63.863218 -26.976368) (xy 64.442847 -26.976368)
			(xy 64.442847 -26.921832) (xy 64.450609 -26.867852) (xy 64.465973 -26.815525) (xy 64.488628 -26.765918)
			(xy 64.518112 -26.72004) (xy 64.553826 -26.678824) (xy 64.595041 -26.643111) (xy 64.64092 -26.613627)
			(xy 64.690527 -26.590972) (xy 64.742854 -26.575608) (xy 64.796834 -26.567847) (xy 64.824102 -26.567384)
			(xy 65.713102 -26.567384) (xy 65.740375 -26.567779) (xy 65.794364 -26.575542) (xy 65.8467 -26.590909)
			(xy 65.896316 -26.613568) (xy 65.942202 -26.643057) (xy 65.983424 -26.678777) (xy 66.019144 -26.72)
			(xy 66.048633 -26.765886) (xy 66.071292 -26.815502) (xy 66.086659 -26.867838) (xy 66.094421 -26.921827)
			(xy 66.094421 -26.976373) (xy 66.086659 -27.030362) (xy 66.071292 -27.082698) (xy 66.048633 -27.132314)
			(xy 66.019144 -27.1782) (xy 65.983424 -27.219423) (xy 65.942202 -27.255143) (xy 65.896316 -27.284632)
			(xy 65.8467 -27.307291) (xy 65.794364 -27.322658) (xy 65.740375 -27.330421) (xy 65.713102 -27.330908)
			(xy 64.824102 -27.330908) (xy 64.796834 -27.330353) (xy 64.742854 -27.322592) (xy 64.690527 -27.307228)
			(xy 64.64092 -27.284573) (xy 64.595041 -27.255089) (xy 64.553826 -27.219376) (xy 64.518112 -27.17816)
			(xy 64.488628 -27.132282) (xy 64.465973 -27.082675) (xy 64.450609 -27.030348) (xy 64.442847 -26.976368)
			(xy 63.863218 -26.976368) (xy 63.854898 -27.004701) (xy 63.832254 -27.05428) (xy 63.802784 -27.100131)
			(xy 63.767088 -27.141322) (xy 63.725893 -27.177013) (xy 63.680038 -27.206477) (xy 63.630456 -27.229115)
			(xy 63.578156 -27.244465) (xy 63.524205 -27.252216) (xy 63.496952 -27.252676) (xy 62.607952 -27.252676)
			(xy 62.580701 -27.252251) (xy 62.526754 -27.244488) (xy 62.47446 -27.229128) (xy 62.424885 -27.206482)
			(xy 62.379037 -27.177012) (xy 62.337849 -27.141317) (xy 62.302159 -27.100125) (xy 62.272695 -27.054273)
			(xy 62.250056 -27.004695) (xy 62.234702 -26.952399) (xy 62.226946 -26.898451) (xy 33.658705 -26.898451)
			(xy 32.469582 -28.087574) (xy 32.487108 -28.120848) (xy 32.501104 -28.148509) (xy 32.52092 -28.207245)
			(xy 32.530959 -28.268416) (xy 32.531558 -28.29941) (xy 32.531558 -28.299664) (xy 32.531023 -28.328517)
			(xy 32.522319 -28.385562) (xy 32.50512 -28.440645) (xy 32.479819 -28.492508) (xy 32.446992 -28.539968)
			(xy 32.40739 -28.581939) (xy 32.385 -28.600146) (xy 32.385 -37.7952) (xy 32.384388 -37.820157) (xy 32.374651 -37.869111)
			(xy 32.35555 -37.915224) (xy 32.32782 -37.956726) (xy 32.310578 -37.974778) (xy 31.878778 -38.406578)
			(xy 31.860739 -38.423843) (xy 31.819248 -38.451611) (xy 31.77313 -38.470733) (xy 31.724163 -38.480473)
			(xy 31.6992 -38.481) (xy 30.607 -38.481) (xy 30.607 -46.249844) (xy 31.855156 -47.498) (xy 35.075876 -47.498)
			(xy 35.09391 -47.477934) (xy 35.516058 -47.055786) (xy 35.515804 -44.819316) (xy 35.516424 -44.794363)
			(xy 35.526175 -44.745418) (xy 35.545287 -44.699315) (xy 35.573025 -44.657826) (xy 35.590226 -44.639738)
			(xy 36.3728 -43.857164) (xy 36.3728 -43.261788) (xy 36.358916 -43.236784) (xy 36.337977 -43.183564)
			(xy 36.325224 -43.127813) (xy 36.320943 -43.070783) (xy 36.325229 -43.013753) (xy 36.337987 -42.958003)
			(xy 36.358931 -42.904785) (xy 36.3728 -42.879772) (xy 36.3728 -42.345356) (xy 35.589972 -41.562528)
			(xy 35.572714 -41.544487) (xy 35.544959 -41.502993) (xy 35.52585 -41.456874) (xy 35.516122 -41.407911)
			(xy 35.51555 -41.38295) (xy 35.514788 -32.29229) (xy 35.5154 -32.267334) (xy 35.525139 -32.21838)
			(xy 35.544241 -32.172267) (xy 35.571971 -32.130767) (xy 35.58921 -32.112712) (xy 37.551106 -30.150816)
			(xy 37.569147 -30.133558) (xy 37.610641 -30.105804) (xy 37.65676 -30.086698) (xy 37.705724 -30.076975)
			(xy 37.730684 -30.076394) (xy 57.771284 -30.076394) (xy 57.796237 -30.077013) (xy 57.845183 -30.086765)
			(xy 57.891286 -30.105876) (xy 57.932775 -30.133613) (xy 57.950862 -30.150816) (xy 59.489086 -31.68904)
			(xy 59.520328 -31.67634) (xy 59.543309 -31.667357) (xy 59.591003 -31.654711) (xy 59.639929 -31.648316)
			(xy 59.6646 -31.647892) (xy 59.691851 -31.648378) (xy 59.745799 -31.656134) (xy 59.798094 -31.671489)
			(xy 59.847671 -31.694131) (xy 59.893521 -31.723597) (xy 59.934712 -31.759288) (xy 59.970403 -31.800479)
			(xy 59.999869 -31.846329) (xy 60.022511 -31.895906) (xy 60.037866 -31.948201) (xy 60.045622 -32.002149)
			(xy 60.046108 -32.0294) (xy 60.046108 -32.032194) (xy 60.046406 -32.045588) (xy 60.053167 -32.071502)
			(xy 60.066436 -32.094765) (xy 60.085298 -32.113777) (xy 60.108457 -32.127228) (xy 60.134317 -32.134192)
			(xy 60.147708 -32.134556) (xy 62.159896 -32.134556) (xy 62.185533 -32.119738) (xy 62.240349 -32.097347)
			(xy 62.297966 -32.083693) (xy 62.357 -32.079105) (xy 62.416034 -32.083693) (xy 62.473651 -32.097347)
			(xy 62.528467 -32.119738) (xy 62.554104 -32.134556) (xy 72.87768 -32.134556) (xy 72.902637 -32.135135)
			(xy 72.951589 -32.144889) (xy 72.997697 -32.164006) (xy 73.039189 -32.191752) (xy 73.057258 -32.208978)
			(xy 73.455022 -32.606742) (xy 73.490074 -32.58185) (xy 73.514402 -32.565264) (xy 73.567087 -32.53898)
			(xy 73.623184 -32.521098) (xy 73.681361 -32.512042) (xy 73.7108 -32.511492) (xy 73.738051 -32.511978)
			(xy 73.791999 -32.519734) (xy 73.844294 -32.535089) (xy 73.893871 -32.557731) (xy 73.939721 -32.587197)
			(xy 73.980912 -32.622888) (xy 74.016603 -32.664079) (xy 74.046069 -32.709929) (xy 74.068711 -32.759506)
			(xy 74.084066 -32.811801) (xy 74.091822 -32.865749) (xy 74.092308 -32.893) (xy 74.091761 -32.922439)
			(xy 74.082711 -32.980617) (xy 74.064825 -33.036713) (xy 74.038529 -33.089393) (xy 74.02195 -33.113726)
			(xy 73.997058 -33.148778) (xy 75.810618 -34.962338) (xy 83.910678 -34.962338) (xy 83.924902 -34.935414)
			(xy 83.938231 -34.911242) (xy 83.97079 -34.86667) (xy 84.009431 -34.827255) (xy 84.053349 -34.793819)
			(xy 84.101627 -34.76706) (xy 84.153257 -34.747538) (xy 84.207161 -34.735659) (xy 84.262214 -34.731672)
			(xy 84.317267 -34.735659) (xy 84.371171 -34.747538) (xy 84.422801 -34.76706) (xy 84.471079 -34.793819)
			(xy 84.514997 -34.827255) (xy 84.553638 -34.86667) (xy 84.586197 -34.911242) (xy 84.599526 -34.935414)
			(xy 84.61375 -34.962338) (xy 88.48471 -34.962338) (xy 88.984074 -34.462974) (xy 88.984074 -30.964886)
			(xy 88.964392 -30.946703) (xy 88.929811 -30.905774) (xy 88.901293 -30.86041) (xy 88.879401 -30.811504)
			(xy 88.864564 -30.760016) (xy 88.857074 -30.706959) (xy 88.857078 -30.653377) (xy 88.864577 -30.600321)
			(xy 88.879423 -30.548836) (xy 88.901323 -30.499933) (xy 88.929848 -30.454574) (xy 88.964437 -30.413651)
			(xy 88.984074 -30.395418) (xy 88.984074 -25.884886) (xy 88.964392 -25.866703) (xy 88.929811 -25.825774)
			(xy 88.901293 -25.78041) (xy 88.879401 -25.731504) (xy 88.864564 -25.680016) (xy 88.857074 -25.626959)
			(xy 88.857078 -25.573377) (xy 88.864577 -25.520321) (xy 88.879423 -25.468836) (xy 88.901323 -25.419933)
			(xy 88.929848 -25.374574) (xy 88.964437 -25.333651) (xy 88.984074 -25.315418) (xy 88.984074 -20.804886)
			(xy 88.964392 -20.786703) (xy 88.929811 -20.745774) (xy 88.901293 -20.70041) (xy 88.879401 -20.651504)
			(xy 88.864564 -20.600016) (xy 88.857074 -20.546959) (xy 88.857078 -20.493377) (xy 88.864577 -20.440321)
			(xy 88.879423 -20.388836) (xy 88.901323 -20.339933) (xy 88.929848 -20.294574) (xy 88.964437 -20.253651)
			(xy 88.984074 -20.235418) (xy 88.984074 -15.724886) (xy 88.964392 -15.706703) (xy 88.929811 -15.665774)
			(xy 88.901293 -15.62041) (xy 88.879401 -15.571504) (xy 88.864564 -15.520016) (xy 88.857074 -15.466959)
			(xy 88.857078 -15.413377) (xy 88.864577 -15.360321) (xy 88.879423 -15.308836) (xy 88.901323 -15.259933)
			(xy 88.929848 -15.214574) (xy 88.964437 -15.173651) (xy 88.984074 -15.155418) (xy 88.984074 -10.644886)
			(xy 88.964392 -10.626703) (xy 88.929811 -10.585774) (xy 88.901293 -10.54041) (xy 88.879401 -10.491504)
			(xy 88.864564 -10.440016) (xy 88.857074 -10.386959) (xy 88.857078 -10.333377) (xy 88.864577 -10.280321)
			(xy 88.879423 -10.228836) (xy 88.901323 -10.179933) (xy 88.929848 -10.134574) (xy 88.964437 -10.093651)
			(xy 88.984074 -10.075418) (xy 88.984074 -5.564886) (xy 88.964392 -5.546703) (xy 88.929811 -5.505774)
			(xy 88.901293 -5.46041) (xy 88.879401 -5.411504) (xy 88.864564 -5.360016) (xy 88.857074 -5.306959)
			(xy 88.857078 -5.253377) (xy 88.864577 -5.200321) (xy 88.879423 -5.148836) (xy 88.901323 -5.099933)
			(xy 88.929848 -5.054574) (xy 88.964437 -5.013651) (xy 88.984074 -4.995418) (xy 88.984074 -1.999996)
			(xy 88.983565 -1.954527) (xy 88.975174 -1.863977) (xy 88.958463 -1.774588) (xy 88.933576 -1.687122)
			(xy 88.900725 -1.602325) (xy 88.86019 -1.520922) (xy 88.812317 -1.443605) (xy 88.757514 -1.371036)
			(xy 88.696248 -1.303833) (xy 88.629044 -1.24257) (xy 88.556473 -1.187769) (xy 88.479156 -1.139897)
			(xy 88.397751 -1.099364) (xy 88.312953 -1.066515) (xy 88.225487 -1.041631) (xy 88.136097 -1.024923)
			(xy 88.045547 -1.016534) (xy 88.000078 -1.016) (xy 87.208106 -1.016) (xy 87.189922 -1.035684) (xy 87.148991 -1.07027)
			(xy 87.103625 -1.098792) (xy 87.054716 -1.120688) (xy 87.003226 -1.13553) (xy 86.950165 -1.143024)
			(xy 86.896579 -1.143024) (xy 86.843518 -1.13553) (xy 86.792028 -1.120688) (xy 86.743119 -1.098792)
			(xy 86.697753 -1.07027) (xy 86.656822 -1.035684) (xy 86.638638 -1.016) (xy 82.128106 -1.016) (xy 82.109922 -1.035684)
			(xy 82.068991 -1.07027) (xy 82.023625 -1.098792) (xy 81.974716 -1.120688) (xy 81.923226 -1.13553)
			(xy 81.870165 -1.143024) (xy 81.816579 -1.143024) (xy 81.763518 -1.13553) (xy 81.712028 -1.120688)
			(xy 81.663119 -1.098792) (xy 81.617753 -1.07027) (xy 81.576822 -1.035684) (xy 81.558638 -1.016) (xy 77.048106 -1.016)
			(xy 77.029922 -1.035684) (xy 76.988991 -1.07027) (xy 76.943625 -1.098792) (xy 76.894716 -1.120688)
			(xy 76.843226 -1.13553) (xy 76.790165 -1.143024) (xy 76.736579 -1.143024) (xy 76.683518 -1.13553)
			(xy 76.632028 -1.120688) (xy 76.583119 -1.098792) (xy 76.537753 -1.07027) (xy 76.496822 -1.035684)
			(xy 76.478638 -1.016) (xy 71.968106 -1.016) (xy 71.949922 -1.035684) (xy 71.908991 -1.07027) (xy 71.863625 -1.098792)
			(xy 71.814716 -1.120688) (xy 71.763226 -1.13553) (xy 71.710165 -1.143024) (xy 71.656579 -1.143024)
			(xy 71.603518 -1.13553) (xy 71.552028 -1.120688) (xy 71.503119 -1.098792) (xy 71.457753 -1.07027)
			(xy 71.416822 -1.035684) (xy 71.398638 -1.016) (xy 66.888106 -1.016) (xy 66.869922 -1.035684) (xy 66.828991 -1.07027)
			(xy 66.783625 -1.098792) (xy 66.734716 -1.120688) (xy 66.683226 -1.13553) (xy 66.630165 -1.143024)
			(xy 66.576579 -1.143024) (xy 66.523518 -1.13553) (xy 66.472028 -1.120688) (xy 66.423119 -1.098792)
			(xy 66.377753 -1.07027) (xy 66.336822 -1.035684) (xy 66.318638 -1.016) (xy 61.808106 -1.016) (xy 61.789922 -1.035684)
			(xy 61.748991 -1.07027) (xy 61.703625 -1.098792) (xy 61.654716 -1.120688) (xy 61.603226 -1.13553)
			(xy 61.550165 -1.143024) (xy 61.496579 -1.143024) (xy 61.443518 -1.13553) (xy 61.392028 -1.120688)
			(xy 61.343119 -1.098792) (xy 61.297753 -1.07027) (xy 61.256822 -1.035684) (xy 61.238638 -1.016) (xy 56.728106 -1.016)
			(xy 56.709922 -1.035684) (xy 56.668991 -1.07027) (xy 56.623625 -1.098792) (xy 56.574716 -1.120688)
			(xy 56.523226 -1.13553) (xy 56.470165 -1.143024) (xy 56.416579 -1.143024) (xy 56.363518 -1.13553)
			(xy 56.312028 -1.120688) (xy 56.263119 -1.098792) (xy 56.217753 -1.07027) (xy 56.176822 -1.035684)
			(xy 56.158638 -1.016) (xy 51.648106 -1.016) (xy 51.629922 -1.035684) (xy 51.588991 -1.07027) (xy 51.543625 -1.098792)
			(xy 51.494716 -1.120688) (xy 51.443226 -1.13553) (xy 51.390165 -1.143024) (xy 51.336579 -1.143024)
			(xy 51.283518 -1.13553) (xy 51.232028 -1.120688) (xy 51.183119 -1.098792) (xy 51.137753 -1.07027)
			(xy 51.096822 -1.035684) (xy 51.078638 -1.016) (xy 46.568106 -1.016) (xy 46.549922 -1.035684) (xy 46.508991 -1.07027)
			(xy 46.463625 -1.098792) (xy 46.414716 -1.120688) (xy 46.363226 -1.13553) (xy 46.310165 -1.143024)
			(xy 46.256579 -1.143024) (xy 46.203518 -1.13553) (xy 46.152028 -1.120688) (xy 46.103119 -1.098792)
			(xy 46.057753 -1.07027) (xy 46.016822 -1.035684) (xy 45.998638 -1.016) (xy 41.488106 -1.016) (xy 41.469922 -1.035684)
			(xy 41.428991 -1.07027) (xy 41.383625 -1.098792) (xy 41.334716 -1.120688) (xy 41.283226 -1.13553)
			(xy 41.230165 -1.143024) (xy 41.176579 -1.143024) (xy 41.123518 -1.13553) (xy 41.072028 -1.120688)
			(xy 41.023119 -1.098792) (xy 40.977753 -1.07027) (xy 40.936822 -1.035684) (xy 40.918638 -1.016) (xy 36.408106 -1.016)
			(xy 36.389922 -1.035684) (xy 36.348991 -1.07027) (xy 36.303625 -1.098792) (xy 36.254716 -1.120688)
			(xy 36.203226 -1.13553) (xy 36.150165 -1.143024) (xy 36.096579 -1.143024) (xy 36.043518 -1.13553)
			(xy 35.992028 -1.120688) (xy 35.943119 -1.098792) (xy 35.897753 -1.07027) (xy 35.856822 -1.035684)
			(xy 35.838638 -1.016) (xy 31.328106 -1.016) (xy 31.309922 -1.035684) (xy 31.268991 -1.07027) (xy 31.223625 -1.098792)
			(xy 31.174716 -1.120688) (xy 31.123226 -1.13553) (xy 31.070165 -1.143024) (xy 31.016579 -1.143024)
			(xy 30.963518 -1.13553) (xy 30.912028 -1.120688) (xy 30.863119 -1.098792) (xy 30.817753 -1.07027)
			(xy 30.776822 -1.035684) (xy 30.758638 -1.016) (xy 26.248106 -1.016) (xy 26.229922 -1.035684) (xy 26.188991 -1.07027)
			(xy 26.143625 -1.098792) (xy 26.094716 -1.120688) (xy 26.043226 -1.13553) (xy 25.990165 -1.143024)
			(xy 25.936579 -1.143024) (xy 25.883518 -1.13553) (xy 25.832028 -1.120688) (xy 25.783119 -1.098792)
			(xy 25.737753 -1.07027) (xy 25.696822 -1.035684) (xy 25.678638 -1.016) (xy 21.168106 -1.016) (xy 21.149922 -1.035684)
			(xy 21.108991 -1.07027) (xy 21.063625 -1.098792) (xy 21.014716 -1.120688) (xy 20.963226 -1.13553)
			(xy 20.910165 -1.143024) (xy 20.856579 -1.143024) (xy 20.803518 -1.13553) (xy 20.752028 -1.120688)
			(xy 20.703119 -1.098792) (xy 20.657753 -1.07027) (xy 20.616822 -1.035684) (xy 20.598638 -1.016) (xy 16.088106 -1.016)
			(xy 16.069922 -1.035684) (xy 16.028991 -1.07027) (xy 15.983625 -1.098792) (xy 15.934716 -1.120688)
			(xy 15.883226 -1.13553) (xy 15.830165 -1.143024) (xy 15.776579 -1.143024) (xy 15.723518 -1.13553)
			(xy 15.672028 -1.120688) (xy 15.623119 -1.098792) (xy 15.577753 -1.07027) (xy 15.536822 -1.035684)
			(xy 15.518638 -1.016) (xy 11.008106 -1.016) (xy 10.989922 -1.035684) (xy 10.948991 -1.07027) (xy 10.903625 -1.098792)
			(xy 10.854716 -1.120688) (xy 10.803226 -1.13553) (xy 10.750165 -1.143024) (xy 10.696579 -1.143024)
			(xy 10.643518 -1.13553) (xy 10.592028 -1.120688) (xy 10.543119 -1.098792) (xy 10.497753 -1.07027)
			(xy 10.456822 -1.035684) (xy 10.438638 -1.016) (xy 5.928106 -1.016) (xy 5.909922 -1.035684) (xy 5.868991 -1.07027)
			(xy 5.823625 -1.098792) (xy 5.774716 -1.120688) (xy 5.723226 -1.13553) (xy 5.670165 -1.143024) (xy 5.616579 -1.143024)
			(xy 5.563518 -1.13553) (xy 5.512028 -1.120688) (xy 5.463119 -1.098792) (xy 5.417753 -1.07027) (xy 5.376822 -1.035684)
			(xy 5.358638 -1.016) (xy 1.999996 -1.016) (xy 1.955458 -1.016498) (xy 1.866747 -1.024551) (xy 1.779126 -1.040589)
			(xy 1.693314 -1.06448) (xy 1.610012 -1.09603) (xy 1.529902 -1.134979) (xy 1.453641 -1.181008) (xy 1.381852 -1.233742)
			(xy 1.315122 -1.292749) (xy 1.253999 -1.357545) (xy 1.198983 -1.4276) (xy 1.150523 -1.502341) (xy 1.109016 -1.581156)
			(xy 1.074803 -1.6634) (xy 1.048163 -1.748399) (xy 1.029315 -1.835458) (xy 1.023366 -1.8796) (xy 1.041969 -1.8977)
			(xy 1.074605 -1.938059) (xy 1.101469 -1.982468) (xy 1.122067 -2.030109) (xy 1.136018 -2.080102) (xy 1.143065 -2.131525)
			(xy 1.143508 -2.157476) (xy 1.143058 -2.184271) (xy 1.135565 -2.237336) (xy 1.120722 -2.28883) (xy 1.09882 -2.337741)
			(xy 1.070289 -2.383105) (xy 1.035692 -2.424032) (xy 1.016 -2.44221) (xy 1.016 -4.69011) (xy 3.634743 -4.69011)
			(xy 3.638781 -4.606614) (xy 3.65086 -4.523897) (xy 3.670865 -4.442732) (xy 3.69861 -4.363877) (xy 3.733837 -4.288068)
			(xy 3.776216 -4.216013) (xy 3.825351 -4.148384) (xy 3.880784 -4.085813) (xy 3.941997 -4.028884) (xy 4.008419 -3.978129)
			(xy 4.079429 -3.934021) (xy 4.154365 -3.896973) (xy 4.232527 -3.867331) (xy 4.313184 -3.84537) (xy 4.395585 -3.831296)
			(xy 4.478959 -3.825241) (xy 4.562529 -3.827261) (xy 4.645513 -3.837337) (xy 4.727138 -3.855375) (xy 4.80664 -3.881207)
			(xy 4.883279 -3.914592) (xy 4.956337 -3.955217) (xy 5.025133 -4.002704) (xy 5.089025 -4.056609) (xy 5.147417 -4.116428)
			(xy 5.199762 -4.181604) (xy 5.245572 -4.251528) (xy 5.284421 -4.325547) (xy 5.315943 -4.402969) (xy 5.339847 -4.483073)
			(xy 5.355907 -4.565109) (xy 5.363975 -4.648313) (xy 5.36448 -4.69011) (xy 10.635237 -4.69011) (xy 10.639274 -4.606638)
			(xy 10.651349 -4.523946) (xy 10.671348 -4.442805) (xy 10.699086 -4.363973) (xy 10.734302 -4.288186)
			(xy 10.776668 -4.216152) (xy 10.825789 -4.148543) (xy 10.881206 -4.08599) (xy 10.942401 -4.029078)
			(xy 11.008803 -3.978338) (xy 11.079793 -3.934243) (xy 11.154707 -3.897206) (xy 11.232845 -3.867572)
			(xy 11.313479 -3.845618) (xy 11.395856 -3.831548) (xy 11.479206 -3.825495) (xy 11.562751 -3.827514)
			(xy 11.645711 -3.837588) (xy 11.727311 -3.85562) (xy 11.80679 -3.881445) (xy 11.883406 -3.914819)
			(xy 11.956443 -3.955433) (xy 12.025219 -4.002906) (xy 12.089092 -4.056795) (xy 12.147467 -4.116597)
			(xy 12.199797 -4.181754) (xy 12.245594 -4.251657) (xy 12.28443 -4.325654) (xy 12.315944 -4.403054)
			(xy 12.33984 -4.483134) (xy 12.355896 -4.565146) (xy 12.363962 -4.648325) (xy 12.364466 -4.69011)
			(xy 12.363962 -4.731895) (xy 12.355896 -4.815074) (xy 12.33984 -4.897086) (xy 12.315944 -4.977166)
			(xy 12.28443 -5.054566) (xy 12.265749 -5.09016) (xy 66.234821 -5.09016) (xy 66.238859 -5.006664)
			(xy 66.250938 -4.923947) (xy 66.270943 -4.842782) (xy 66.298688 -4.763927) (xy 66.333915 -4.688118)
			(xy 66.376294 -4.616063) (xy 66.425429 -4.548434) (xy 66.480862 -4.485863) (xy 66.542075 -4.428934)
			(xy 66.608497 -4.378179) (xy 66.679507 -4.334071) (xy 66.754443 -4.297023) (xy 66.832605 -4.267381)
			(xy 66.913262 -4.24542) (xy 66.995663 -4.231346) (xy 67.079037 -4.225291) (xy 67.162607 -4.227311)
			(xy 67.245591 -4.237387) (xy 67.327216 -4.255425) (xy 67.406718 -4.281257) (xy 67.483357 -4.314642)
			(xy 67.556415 -4.355267) (xy 67.625211 -4.402754) (xy 67.689103 -4.456659) (xy 67.747495 -4.516478)
			(xy 67.79984 -4.581654) (xy 67.84565 -4.651578) (xy 67.884499 -4.725597) (xy 67.916021 -4.803019)
			(xy 67.939925 -4.883123) (xy 67.955985 -4.965159) (xy 67.964053 -5.048363) (xy 67.964558 -5.09016)
			(xy 73.235315 -5.09016) (xy 73.239352 -5.006688) (xy 73.251427 -4.923996) (xy 73.271426 -4.842855)
			(xy 73.299164 -4.764023) (xy 73.33438 -4.688236) (xy 73.376746 -4.616202) (xy 73.425867 -4.548593)
			(xy 73.481284 -4.48604) (xy 73.542479 -4.429128) (xy 73.608881 -4.378388) (xy 73.679871 -4.334293)
			(xy 73.754785 -4.297256) (xy 73.832923 -4.267622) (xy 73.913557 -4.245668) (xy 73.995934 -4.231598)
			(xy 74.079284 -4.225545) (xy 74.162829 -4.227564) (xy 74.245789 -4.237638) (xy 74.327389 -4.25567)
			(xy 74.406868 -4.281495) (xy 74.483484 -4.314869) (xy 74.556521 -4.355483) (xy 74.625297 -4.402956)
			(xy 74.68917 -4.456845) (xy 74.747545 -4.516647) (xy 74.799875 -4.581804) (xy 74.845672 -4.651707)
			(xy 74.865827 -4.69011) (xy 77.634849 -4.69011) (xy 77.638887 -4.606614) (xy 77.650966 -4.523897)
			(xy 77.670971 -4.442732) (xy 77.698716 -4.363877) (xy 77.733943 -4.288068) (xy 77.776322 -4.216013)
			(xy 77.825457 -4.148384) (xy 77.88089 -4.085813) (xy 77.942103 -4.028884) (xy 78.008525 -3.978129)
			(xy 78.079535 -3.934021) (xy 78.154471 -3.896973) (xy 78.232633 -3.867331) (xy 78.31329 -3.84537)
			(xy 78.395691 -3.831296) (xy 78.479065 -3.825241) (xy 78.562635 -3.827261) (xy 78.645619 -3.837337)
			(xy 78.727244 -3.855375) (xy 78.806746 -3.881207) (xy 78.883385 -3.914592) (xy 78.956443 -3.955217)
			(xy 79.025239 -4.002704) (xy 79.089131 -4.056609) (xy 79.147523 -4.116428) (xy 79.199868 -4.181604)
			(xy 79.245678 -4.251528) (xy 79.284527 -4.325547) (xy 79.316049 -4.402969) (xy 79.339953 -4.483073)
			(xy 79.356013 -4.565109) (xy 79.364081 -4.648313) (xy 79.364586 -4.69011) (xy 84.635343 -4.69011)
			(xy 84.63938 -4.606638) (xy 84.651455 -4.523946) (xy 84.671454 -4.442805) (xy 84.699192 -4.363973)
			(xy 84.734408 -4.288186) (xy 84.776774 -4.216152) (xy 84.825895 -4.148543) (xy 84.881312 -4.08599)
			(xy 84.942507 -4.029078) (xy 85.008909 -3.978338) (xy 85.079899 -3.934243) (xy 85.154813 -3.897206)
			(xy 85.232951 -3.867572) (xy 85.313585 -3.845618) (xy 85.395962 -3.831548) (xy 85.479312 -3.825495)
			(xy 85.562857 -3.827514) (xy 85.645817 -3.837588) (xy 85.727417 -3.85562) (xy 85.806896 -3.881445)
			(xy 85.883512 -3.914819) (xy 85.956549 -3.955433) (xy 86.025325 -4.002906) (xy 86.089198 -4.056795)
			(xy 86.147573 -4.116597) (xy 86.199903 -4.181754) (xy 86.2457 -4.251657) (xy 86.284536 -4.325654)
			(xy 86.31605 -4.403054) (xy 86.339946 -4.483134) (xy 86.356002 -4.565146) (xy 86.364068 -4.648325)
			(xy 86.364572 -4.69011) (xy 86.364068 -4.731895) (xy 86.356002 -4.815074) (xy 86.339946 -4.897086)
			(xy 86.31605 -4.977166) (xy 86.284536 -5.054566) (xy 86.2457 -5.128563) (xy 86.199903 -5.198466)
			(xy 86.147573 -5.263623) (xy 86.089198 -5.323425) (xy 86.025325 -5.377314) (xy 85.956549 -5.424787)
			(xy 85.883512 -5.465401) (xy 85.806896 -5.498775) (xy 85.727417 -5.5246) (xy 85.645817 -5.542632)
			(xy 85.562857 -5.552706) (xy 85.479312 -5.554725) (xy 85.395962 -5.548672) (xy 85.313585 -5.534602)
			(xy 85.232951 -5.512648) (xy 85.154813 -5.483014) (xy 85.079899 -5.445977) (xy 85.008909 -5.401882)
			(xy 84.942507 -5.351142) (xy 84.881312 -5.29423) (xy 84.825895 -5.231677) (xy 84.776774 -5.164068)
			(xy 84.734408 -5.092034) (xy 84.699192 -5.016247) (xy 84.671454 -4.937415) (xy 84.651455 -4.856274)
			(xy 84.63938 -4.773582) (xy 84.635343 -4.69011) (xy 79.364586 -4.69011) (xy 79.364081 -4.731907)
			(xy 79.356013 -4.815111) (xy 79.339953 -4.897147) (xy 79.316049 -4.977251) (xy 79.284527 -5.054673)
			(xy 79.245678 -5.128692) (xy 79.199868 -5.198616) (xy 79.147523 -5.263792) (xy 79.089131 -5.323611)
			(xy 79.025239 -5.377516) (xy 78.956443 -5.425003) (xy 78.883385 -5.465628) (xy 78.806746 -5.499013)
			(xy 78.727244 -5.524845) (xy 78.645619 -5.542883) (xy 78.562635 -5.552959) (xy 78.479065 -5.554979)
			(xy 78.395691 -5.548924) (xy 78.31329 -5.53485) (xy 78.232633 -5.512889) (xy 78.154471 -5.483247)
			(xy 78.079535 -5.446199) (xy 78.008525 -5.402091) (xy 77.942103 -5.351336) (xy 77.88089 -5.294407)
			(xy 77.825457 -5.231836) (xy 77.776322 -5.164207) (xy 77.733943 -5.092152) (xy 77.698716 -5.016343)
			(xy 77.670971 -4.937488) (xy 77.650966 -4.856323) (xy 77.638887 -4.773606) (xy 77.634849 -4.69011)
			(xy 74.865827 -4.69011) (xy 74.884508 -4.725704) (xy 74.916022 -4.803104) (xy 74.939918 -4.883184)
			(xy 74.955974 -4.965196) (xy 74.96404 -5.048375) (xy 74.964544 -5.09016) (xy 74.96404 -5.131945)
			(xy 74.955974 -5.215124) (xy 74.939918 -5.297136) (xy 74.916022 -5.377216) (xy 74.884508 -5.454616)
			(xy 74.845672 -5.528613) (xy 74.799875 -5.598516) (xy 74.747545 -5.663673) (xy 74.68917 -5.723475)
			(xy 74.625297 -5.777364) (xy 74.556521 -5.824837) (xy 74.483484 -5.865451) (xy 74.406868 -5.898825)
			(xy 74.327389 -5.92465) (xy 74.245789 -5.942682) (xy 74.162829 -5.952756) (xy 74.079284 -5.954775)
			(xy 73.995934 -5.948722) (xy 73.913557 -5.934652) (xy 73.832923 -5.912698) (xy 73.754785 -5.883064)
			(xy 73.679871 -5.846027) (xy 73.608881 -5.801932) (xy 73.542479 -5.751192) (xy 73.481284 -5.69428)
			(xy 73.425867 -5.631727) (xy 73.376746 -5.564118) (xy 73.33438 -5.492084) (xy 73.299164 -5.416297)
			(xy 73.271426 -5.337465) (xy 73.251427 -5.256324) (xy 73.239352 -5.173632) (xy 73.235315 -5.09016)
			(xy 67.964558 -5.09016) (xy 67.964053 -5.131957) (xy 67.955985 -5.215161) (xy 67.939925 -5.297197)
			(xy 67.916021 -5.377301) (xy 67.884499 -5.454723) (xy 67.84565 -5.528742) (xy 67.79984 -5.598666)
			(xy 67.747495 -5.663842) (xy 67.689103 -5.723661) (xy 67.625211 -5.777566) (xy 67.556415 -5.825053)
			(xy 67.483357 -5.865678) (xy 67.406718 -5.899063) (xy 67.327216 -5.924895) (xy 67.245591 -5.942933)
			(xy 67.162607 -5.953009) (xy 67.079037 -5.955029) (xy 66.995663 -5.948974) (xy 66.913262 -5.9349)
			(xy 66.832605 -5.912939) (xy 66.754443 -5.883297) (xy 66.679507 -5.846249) (xy 66.608497 -5.802141)
			(xy 66.542075 -5.751386) (xy 66.480862 -5.694457) (xy 66.425429 -5.631886) (xy 66.376294 -5.564257)
			(xy 66.333915 -5.492202) (xy 66.298688 -5.416393) (xy 66.270943 -5.337538) (xy 66.250938 -5.256373)
			(xy 66.238859 -5.173656) (xy 66.234821 -5.09016) (xy 12.265749 -5.09016) (xy 12.245594 -5.128563)
			(xy 12.199797 -5.198466) (xy 12.147467 -5.263623) (xy 12.089092 -5.323425) (xy 12.025219 -5.377314)
			(xy 11.956443 -5.424787) (xy 11.883406 -5.465401) (xy 11.80679 -5.498775) (xy 11.727311 -5.5246)
			(xy 11.645711 -5.542632) (xy 11.562751 -5.552706) (xy 11.479206 -5.554725) (xy 11.395856 -5.548672)
			(xy 11.313479 -5.534602) (xy 11.232845 -5.512648) (xy 11.154707 -5.483014) (xy 11.079793 -5.445977)
			(xy 11.008803 -5.401882) (xy 10.942401 -5.351142) (xy 10.881206 -5.29423) (xy 10.825789 -5.231677)
			(xy 10.776668 -5.164068) (xy 10.734302 -5.092034) (xy 10.699086 -5.016247) (xy 10.671348 -4.937415)
			(xy 10.651349 -4.856274) (xy 10.639274 -4.773582) (xy 10.635237 -4.69011) (xy 5.36448 -4.69011) (xy 5.363975 -4.731907)
			(xy 5.355907 -4.815111) (xy 5.339847 -4.897147) (xy 5.315943 -4.977251) (xy 5.284421 -5.054673) (xy 5.245572 -5.128692)
			(xy 5.199762 -5.198616) (xy 5.147417 -5.263792) (xy 5.089025 -5.323611) (xy 5.025133 -5.377516) (xy 4.956337 -5.425003)
			(xy 4.883279 -5.465628) (xy 4.80664 -5.499013) (xy 4.727138 -5.524845) (xy 4.645513 -5.542883) (xy 4.562529 -5.552959)
			(xy 4.478959 -5.554979) (xy 4.395585 -5.548924) (xy 4.313184 -5.53485) (xy 4.232527 -5.512889) (xy 4.154365 -5.483247)
			(xy 4.079429 -5.446199) (xy 4.008419 -5.402091) (xy 3.941997 -5.351336) (xy 3.880784 -5.294407) (xy 3.825351 -5.231836)
			(xy 3.776216 -5.164207) (xy 3.733837 -5.092152) (xy 3.69861 -5.016343) (xy 3.670865 -4.937488) (xy 3.65086 -4.856323)
			(xy 3.638781 -4.773606) (xy 3.634743 -4.69011) (xy 1.016 -4.69011) (xy 1.016 -6.952742) (xy 1.035684 -6.970926)
			(xy 1.07027 -7.011857) (xy 1.098792 -7.057223) (xy 1.120688 -7.106132) (xy 1.13553 -7.157622) (xy 1.143024 -7.210683)
			(xy 1.143024 -7.264269) (xy 1.13553 -7.31733) (xy 1.120688 -7.36882) (xy 1.098792 -7.417729) (xy 1.07027 -7.463095)
			(xy 1.035684 -7.504026) (xy 1.016 -7.52221) (xy 1.016 -12.032742) (xy 1.035684 -12.050926) (xy 1.07027 -12.091857)
			(xy 1.098792 -12.137223) (xy 1.120688 -12.186132) (xy 1.13553 -12.237622) (xy 1.143024 -12.290683)
			(xy 1.143024 -12.344269) (xy 1.13553 -12.39733) (xy 1.120688 -12.44882) (xy 1.098792 -12.497729)
			(xy 1.07027 -12.543095) (xy 1.035684 -12.584026) (xy 1.016 -12.60221) (xy 1.016 -13.417248) (xy 41.210697 -13.417248)
			(xy 41.210697 -13.342672) (xy 41.218492 -13.268505) (xy 41.233997 -13.195559) (xy 41.257043 -13.124633)
			(xy 41.287375 -13.056505) (xy 41.324663 -12.991921) (xy 41.368498 -12.931588) (xy 41.418399 -12.876167)
			(xy 41.473819 -12.826266) (xy 41.534152 -12.782432) (xy 41.598737 -12.745144) (xy 41.666865 -12.714812)
			(xy 41.737791 -12.691767) (xy 41.810737 -12.676262) (xy 41.884904 -12.668467) (xy 41.922192 -12.667996)
			(xy 43.922188 -12.667996) (xy 43.959474 -12.668551) (xy 44.033637 -12.676344) (xy 44.106579 -12.691848)
			(xy 44.177502 -12.714891) (xy 44.245627 -12.745221) (xy 44.310208 -12.782506) (xy 44.370538 -12.826338)
			(xy 44.425956 -12.876235) (xy 44.475855 -12.931652) (xy 44.519687 -12.991982) (xy 44.556974 -13.056563)
			(xy 44.587305 -13.124687) (xy 44.610349 -13.195609) (xy 44.625854 -13.268551) (xy 44.633649 -13.342714)
			(xy 44.633649 -13.417286) (xy 44.625854 -13.491449) (xy 44.610349 -13.564391) (xy 44.587305 -13.635313)
			(xy 44.556974 -13.703437) (xy 44.519687 -13.768018) (xy 44.475855 -13.828348) (xy 44.425956 -13.883765)
			(xy 44.370538 -13.933662) (xy 44.310208 -13.977494) (xy 44.245627 -14.014779) (xy 44.177502 -14.045109)
			(xy 44.106579 -14.068152) (xy 44.033637 -14.083656) (xy 43.959474 -14.091449) (xy 43.922188 -14.09192)
			(xy 41.922192 -14.09192) (xy 41.884904 -14.091453) (xy 41.810737 -14.083658) (xy 41.737791 -14.068153)
			(xy 41.666865 -14.045108) (xy 41.598737 -14.014776) (xy 41.534152 -13.977488) (xy 41.473819 -13.933654)
			(xy 41.418399 -13.883753) (xy 41.368498 -13.828332) (xy 41.324663 -13.767999) (xy 41.287375 -13.703415)
			(xy 41.257043 -13.635287) (xy 41.233997 -13.564361) (xy 41.218492 -13.491415) (xy 41.210697 -13.417248)
			(xy 1.016 -13.417248) (xy 1.016 -14.917388) (xy 38.210708 -14.917388) (xy 38.210708 -14.842812) (xy 38.218503 -14.768646)
			(xy 38.234008 -14.6957) (xy 38.257053 -14.624775) (xy 38.287386 -14.556647) (xy 38.324673 -14.492062)
			(xy 38.368507 -14.43173) (xy 38.418408 -14.376309) (xy 38.473828 -14.326409) (xy 38.534161 -14.282574)
			(xy 38.598745 -14.245287) (xy 38.666873 -14.214954) (xy 38.737798 -14.191909) (xy 38.810744 -14.176403)
			(xy 38.88491 -14.168608) (xy 38.922198 -14.16812) (xy 40.922194 -14.16812) (xy 40.959481 -14.168627)
			(xy 41.033646 -14.176422) (xy 41.106591 -14.191926) (xy 41.177515 -14.21497) (xy 41.245641 -14.245301)
			(xy 41.310224 -14.282588) (xy 41.370556 -14.326421) (xy 41.425975 -14.37632) (xy 41.475875 -14.431739)
			(xy 41.519709 -14.492071) (xy 41.556996 -14.556653) (xy 41.587328 -14.62478) (xy 41.610373 -14.695704)
			(xy 41.625877 -14.768648) (xy 41.633673 -14.842813) (xy 41.633673 -14.917387) (xy 44.210708 -14.917387)
			(xy 44.210708 -14.842813) (xy 44.218503 -14.768647) (xy 44.234008 -14.695702) (xy 44.257052 -14.624777)
			(xy 44.287384 -14.55665) (xy 44.324671 -14.492066) (xy 44.368504 -14.431734) (xy 44.418404 -14.376314)
			(xy 44.473823 -14.326413) (xy 44.534154 -14.282578) (xy 44.598737 -14.24529) (xy 44.666864 -14.214957)
			(xy 44.737788 -14.191911) (xy 44.810733 -14.176405) (xy 44.884899 -14.168609) (xy 44.922186 -14.16812)
			(xy 46.922182 -14.16812) (xy 46.959469 -14.168626) (xy 47.033636 -14.17642) (xy 47.106581 -14.191923)
			(xy 47.177506 -14.214967) (xy 47.245634 -14.245298) (xy 47.310218 -14.282584) (xy 47.370551 -14.326417)
			(xy 47.425971 -14.376316) (xy 47.475872 -14.431735) (xy 47.519706 -14.492067) (xy 47.556994 -14.55665)
			(xy 47.587327 -14.624777) (xy 47.610372 -14.695702) (xy 47.625877 -14.768647) (xy 47.633673 -14.842813)
			(xy 47.633673 -14.917387) (xy 47.625877 -14.991553) (xy 47.610372 -15.064498) (xy 47.587327 -15.135423)
			(xy 47.556994 -15.20355) (xy 47.519706 -15.268133) (xy 47.475872 -15.328465) (xy 47.425971 -15.383884)
			(xy 47.370551 -15.433783) (xy 47.310218 -15.477616) (xy 47.245634 -15.514902) (xy 47.177506 -15.545233)
			(xy 47.106581 -15.568277) (xy 47.033636 -15.58378) (xy 46.959469 -15.591574) (xy 46.922182 -15.592044)
			(xy 44.922186 -15.592044) (xy 44.884899 -15.591591) (xy 44.810733 -15.583795) (xy 44.737788 -15.568289)
			(xy 44.666864 -15.545243) (xy 44.598737 -15.51491) (xy 44.534154 -15.477622) (xy 44.473823 -15.433787)
			(xy 44.418404 -15.383886) (xy 44.368504 -15.328466) (xy 44.324671 -15.268134) (xy 44.287384 -15.20355)
			(xy 44.257052 -15.135423) (xy 44.234008 -15.064498) (xy 44.218503 -14.991553) (xy 44.210708 -14.917387)
			(xy 41.633673 -14.917387) (xy 41.625877 -14.991552) (xy 41.610373 -15.064496) (xy 41.587328 -15.13542)
			(xy 41.556996 -15.203547) (xy 41.519709 -15.268129) (xy 41.475875 -15.328461) (xy 41.425975 -15.38388)
			(xy 41.370556 -15.433779) (xy 41.310224 -15.477612) (xy 41.245641 -15.514899) (xy 41.177515 -15.54523)
			(xy 41.106591 -15.568274) (xy 41.033646 -15.583778) (xy 40.959481 -15.591573) (xy 40.922194 -15.592044)
			(xy 38.922198 -15.592044) (xy 38.88491 -15.591592) (xy 38.810744 -15.583797) (xy 38.737798 -15.568291)
			(xy 38.666873 -15.545246) (xy 38.598745 -15.514913) (xy 38.534161 -15.477626) (xy 38.473828 -15.433791)
			(xy 38.418408 -15.383891) (xy 38.368507 -15.32847) (xy 38.324673 -15.268138) (xy 38.287386 -15.203553)
			(xy 38.257053 -15.135425) (xy 38.234008 -15.0645) (xy 38.218503 -14.991554) (xy 38.210708 -14.917388)
			(xy 1.016 -14.917388) (xy 1.016 -17.112742) (xy 1.035684 -17.130926) (xy 1.07027 -17.171857) (xy 1.098792 -17.217223)
			(xy 1.120688 -17.266132) (xy 1.13553 -17.317622) (xy 1.143024 -17.370683) (xy 1.143024 -17.38737)
			(xy 4.838435 -17.38737) (xy 4.838435 -17.25823) (xy 4.846385 -17.129335) (xy 4.862255 -17.001175)
			(xy 4.885984 -16.874234) (xy 4.917483 -16.748995) (xy 4.956632 -16.625932) (xy 5.003283 -16.505513)
			(xy 5.057258 -16.388194) (xy 5.118353 -16.27442) (xy 5.186336 -16.164623) (xy 5.26095 -16.05922)
			(xy 5.341911 -15.95861) (xy 5.428911 -15.863175) (xy 5.521622 -15.773276) (xy 5.619692 -15.689255)
			(xy 5.722747 -15.611431) (xy 5.830398 -15.540099) (xy 5.942237 -15.475529) (xy 6.057838 -15.417967)
			(xy 6.176763 -15.36763) (xy 6.298562 -15.32471) (xy 6.422772 -15.289369) (xy 6.548921 -15.261742)
			(xy 6.676533 -15.241933) (xy 6.805122 -15.230017) (xy 6.9342 -15.226041) (xy 7.063278 -15.230017)
			(xy 7.191867 -15.241933) (xy 7.319479 -15.261742) (xy 7.445628 -15.289369) (xy 7.569838 -15.32471)
			(xy 7.691637 -15.36763) (xy 7.810562 -15.417967) (xy 7.926163 -15.475529) (xy 8.038002 -15.540099)
			(xy 8.145653 -15.611431) (xy 8.248708 -15.689255) (xy 8.346778 -15.773276) (xy 8.439489 -15.863175)
			(xy 8.526489 -15.95861) (xy 8.60745 -16.05922) (xy 8.682064 -16.164623) (xy 8.750047 -16.27442) (xy 8.811142 -16.388194)
			(xy 8.865117 -16.505513) (xy 8.911768 -16.625932) (xy 8.950917 -16.748995) (xy 8.982416 -16.874234)
			(xy 8.996233 -16.94815) (xy 25.574752 -16.94815) (xy 25.574752 -16.05915) (xy 25.575238 -16.031899)
			(xy 25.582994 -15.977951) (xy 25.598349 -15.925656) (xy 25.620991 -15.876079) (xy 25.650457 -15.830229)
			(xy 25.686148 -15.789038) (xy 25.727339 -15.753347) (xy 25.773189 -15.723881) (xy 25.822766 -15.701239)
			(xy 25.875061 -15.685884) (xy 25.929009 -15.678128) (xy 25.983511 -15.678128) (xy 26.037459 -15.685884)
			(xy 26.089754 -15.701239) (xy 26.139331 -15.723881) (xy 26.185181 -15.753347) (xy 26.226372 -15.789038)
			(xy 26.262063 -15.830229) (xy 26.291529 -15.876079) (xy 26.314171 -15.925656) (xy 26.329526 -15.977951)
			(xy 26.337282 -16.031899) (xy 26.337768 -16.05915) (xy 26.337768 -16.94815) (xy 26.337282 -16.975401)
			(xy 26.329526 -17.029349) (xy 26.314171 -17.081644) (xy 26.291529 -17.131221) (xy 26.262063 -17.177071)
			(xy 26.226372 -17.218262) (xy 26.185181 -17.253953) (xy 26.139331 -17.283419) (xy 26.089754 -17.306061)
			(xy 26.037459 -17.321416) (xy 25.983511 -17.329172) (xy 25.929009 -17.329172) (xy 25.875061 -17.321416)
			(xy 25.822766 -17.306061) (xy 25.773189 -17.283419) (xy 25.727339 -17.253953) (xy 25.686148 -17.218262)
			(xy 25.650457 -17.177071) (xy 25.620991 -17.131221) (xy 25.598349 -17.081644) (xy 25.582994 -17.029349)
			(xy 25.575238 -16.975401) (xy 25.574752 -16.94815) (xy 8.996233 -16.94815) (xy 9.006145 -17.001175)
			(xy 9.022015 -17.129335) (xy 9.029965 -17.25823) (xy 9.030462 -17.3228) (xy 9.029965 -17.38737) (xy 9.022015 -17.516265)
			(xy 9.006145 -17.644425) (xy 8.982416 -17.771366) (xy 8.950917 -17.896605) (xy 8.911768 -18.019668)
			(xy 8.865117 -18.140087) (xy 8.811142 -18.257406) (xy 8.750047 -18.37118) (xy 8.682064 -18.480977)
			(xy 8.60745 -18.58638) (xy 8.526489 -18.68699) (xy 8.439489 -18.782425) (xy 8.346778 -18.872324)
			(xy 8.248708 -18.956345) (xy 8.145653 -19.034169) (xy 8.038002 -19.105501) (xy 7.926163 -19.170071)
			(xy 7.810562 -19.227633) (xy 7.691637 -19.27797) (xy 7.569838 -19.32089) (xy 7.445628 -19.356231)
			(xy 7.319479 -19.383858) (xy 7.191867 -19.403667) (xy 7.063278 -19.415583) (xy 6.9342 -19.41956)
			(xy 6.805122 -19.415583) (xy 6.676533 -19.403667) (xy 6.548921 -19.383858) (xy 6.422772 -19.356231)
			(xy 6.298562 -19.32089) (xy 6.176763 -19.27797) (xy 6.057838 -19.227633) (xy 5.942237 -19.170071)
			(xy 5.830398 -19.105501) (xy 5.722747 -19.034169) (xy 5.619692 -18.956345) (xy 5.521622 -18.872324)
			(xy 5.428911 -18.782425) (xy 5.341911 -18.68699) (xy 5.26095 -18.58638) (xy 5.186336 -18.480977)
			(xy 5.118353 -18.37118) (xy 5.057258 -18.257406) (xy 5.003283 -18.140087) (xy 4.956632 -18.019668)
			(xy 4.917483 -17.896605) (xy 4.885984 -17.771366) (xy 4.862255 -17.644425) (xy 4.846385 -17.516265)
			(xy 4.838435 -17.38737) (xy 1.143024 -17.38737) (xy 1.143024 -17.424269) (xy 1.13553 -17.47733) (xy 1.120688 -17.52882)
			(xy 1.098792 -17.577729) (xy 1.07027 -17.623095) (xy 1.035684 -17.664026) (xy 1.016 -17.68221) (xy 1.016 -22.192742)
			(xy 1.035684 -22.210926) (xy 1.07027 -22.251857) (xy 1.098792 -22.297223) (xy 1.120688 -22.346132)
			(xy 1.13553 -22.397622) (xy 1.143024 -22.450683) (xy 1.143024 -22.504269) (xy 1.13553 -22.55733)
			(xy 1.120688 -22.60882) (xy 1.098792 -22.657729) (xy 1.07027 -22.703095) (xy 1.035684 -22.744026)
			(xy 1.016 -22.76221) (xy 1.016 -27.272742) (xy 1.035684 -27.290926) (xy 1.07027 -27.331857) (xy 1.098792 -27.377223)
			(xy 1.120688 -27.426132) (xy 1.13553 -27.477622) (xy 1.143024 -27.530683) (xy 1.143024 -27.584269)
			(xy 1.13553 -27.63733) (xy 1.120688 -27.68882) (xy 1.098792 -27.737729) (xy 1.07027 -27.783095) (xy 1.035684 -27.824026)
			(xy 1.016 -27.84221) (xy 1.016 -32.352742) (xy 1.035684 -32.370926) (xy 1.07027 -32.411857) (xy 1.098792 -32.457223)
			(xy 1.120688 -32.506132) (xy 1.13553 -32.557622) (xy 1.143024 -32.610683) (xy 1.143024 -32.664269)
			(xy 1.13553 -32.71733) (xy 1.120688 -32.76882) (xy 1.098792 -32.817729) (xy 1.07027 -32.863095) (xy 1.035684 -32.904026)
			(xy 1.016 -32.92221) (xy 1.016 -37.432742) (xy 1.035684 -37.450926) (xy 1.07027 -37.491857) (xy 1.098792 -37.537223)
			(xy 1.120688 -37.586132) (xy 1.13553 -37.637622) (xy 1.143024 -37.690683) (xy 1.143024 -37.744269)
			(xy 1.13553 -37.79733) (xy 1.120688 -37.84882) (xy 1.098792 -37.897729) (xy 1.07027 -37.943095) (xy 1.035684 -37.984026)
			(xy 1.016 -38.00221) (xy 1.016 -42.512742) (xy 1.035684 -42.530926) (xy 1.07027 -42.571857) (xy 1.098792 -42.617223)
			(xy 1.120688 -42.666132) (xy 1.13553 -42.717622) (xy 1.143024 -42.770683) (xy 1.143024 -42.824269)
			(xy 1.13553 -42.87733) (xy 1.120688 -42.92882) (xy 1.098792 -42.977729) (xy 1.07027 -43.023095) (xy 1.035684 -43.064026)
			(xy 1.016 -43.08221) (xy 1.016 -47.592742) (xy 1.035684 -47.610926) (xy 1.07027 -47.651857) (xy 1.098792 -47.697223)
			(xy 1.120688 -47.746132) (xy 1.13553 -47.797622) (xy 1.143024 -47.850683) (xy 1.143024 -47.904269)
			(xy 1.13553 -47.95733) (xy 1.120688 -48.00882) (xy 1.098792 -48.057729) (xy 1.07027 -48.103095) (xy 1.035684 -48.144026)
			(xy 1.016 -48.16221) (xy 1.016 -52.672742) (xy 1.035684 -52.690926) (xy 1.07027 -52.731857) (xy 1.098792 -52.777223)
			(xy 1.120688 -52.826132) (xy 1.13553 -52.877622) (xy 1.143024 -52.930683) (xy 1.143024 -52.984269)
			(xy 1.13553 -53.03733) (xy 1.120688 -53.08882) (xy 1.098792 -53.137729) (xy 1.07027 -53.183095) (xy 1.035684 -53.224026)
			(xy 1.016 -53.24221) (xy 1.016 -57.752742) (xy 1.035684 -57.770926) (xy 1.07027 -57.811857) (xy 1.098792 -57.857223)
			(xy 1.120688 -57.906132) (xy 1.13553 -57.957622) (xy 1.143024 -58.010683) (xy 1.143024 -58.064269)
			(xy 1.13553 -58.11733) (xy 1.120688 -58.16882) (xy 1.098792 -58.217729) (xy 1.07027 -58.263095) (xy 1.035684 -58.304026)
			(xy 1.016 -58.32221) (xy 1.016 -62.832742) (xy 1.035684 -62.850926) (xy 1.07027 -62.891857) (xy 1.098792 -62.937223)
			(xy 1.120688 -62.986132) (xy 1.13553 -63.037622) (xy 1.143024 -63.090683) (xy 1.143024 -63.144269)
			(xy 1.13553 -63.19733) (xy 1.120688 -63.24882) (xy 1.098792 -63.297729) (xy 1.07027 -63.343095) (xy 1.035684 -63.384026)
			(xy 1.016 -63.40221) (xy 1.016 -67.912742) (xy 1.035684 -67.930926) (xy 1.07027 -67.971857) (xy 1.098792 -68.017223)
			(xy 1.120688 -68.066132) (xy 1.13553 -68.117622) (xy 1.143024 -68.170683) (xy 1.143024 -68.224269)
			(xy 1.13553 -68.27733) (xy 1.120688 -68.32882) (xy 1.098792 -68.377729) (xy 1.07027 -68.423095) (xy 1.035684 -68.464026)
			(xy 1.016 -68.48221) (xy 1.016 -72.992742) (xy 1.035684 -73.010926) (xy 1.07027 -73.051857) (xy 1.098792 -73.097223)
			(xy 1.120688 -73.146132) (xy 1.13553 -73.197622) (xy 1.143024 -73.250683) (xy 1.143024 -73.304269)
			(xy 1.13553 -73.35733) (xy 1.120688 -73.40882) (xy 1.098792 -73.457729) (xy 1.07027 -73.503095) (xy 1.035684 -73.544026)
			(xy 1.016 -73.56221) (xy 1.016 -75.635104) (xy 15.73277 -75.635104) (xy 15.736751 -75.545198) (xy 15.748662 -75.455997)
			(xy 15.76841 -75.368196) (xy 15.79584 -75.282485) (xy 15.830739 -75.199534) (xy 15.872832 -75.119991)
			(xy 15.92179 -75.04448) (xy 15.977231 -74.973591) (xy 16.038719 -74.90788) (xy 16.105775 -74.84786)
			(xy 16.177873 -74.794001) (xy 16.254449 -74.746725) (xy 16.334903 -74.706402) (xy 16.418606 -74.673347)
			(xy 16.504903 -74.647819) (xy 16.593119 -74.630019) (xy 16.682562 -74.620084) (xy 16.772534 -74.618093)
			(xy 16.862329 -74.624062) (xy 16.951246 -74.637943) (xy 17.038588 -74.659629) (xy 17.123671 -74.688949)
			(xy 17.20583 -74.725673) (xy 17.284422 -74.769516) (xy 17.358832 -74.820133) (xy 17.428477 -74.877128)
			(xy 17.492812 -74.940055) (xy 17.551334 -75.008422) (xy 17.603584 -75.081694) (xy 17.649155 -75.159297)
			(xy 17.687688 -75.240623) (xy 17.718883 -75.325037) (xy 17.742496 -75.411878) (xy 17.758341 -75.500466)
			(xy 17.766294 -75.590107) (xy 17.766792 -75.635104) (xy 35.491431 -75.635104) (xy 35.495409 -75.535111)
			(xy 35.507319 -75.435751) (xy 35.527086 -75.33765) (xy 35.554585 -75.241431) (xy 35.589641 -75.1477)
			(xy 35.632033 -75.057051) (xy 35.681494 -74.970057) (xy 35.73771 -74.887267) (xy 35.800326 -74.809205)
			(xy 35.868945 -74.736365) (xy 35.943136 -74.669207) (xy 36.022427 -74.608155) (xy 36.106318 -74.553597)
			(xy 36.194279 -74.505876) (xy 36.285753 -74.465294) (xy 36.380162 -74.432108) (xy 36.476909 -74.406528)
			(xy 36.575383 -74.388715) (xy 36.674961 -74.378783) (xy 36.775013 -74.376793) (xy 36.874907 -74.382759)
			(xy 36.974011 -74.396643) (xy 37.071699 -74.418356) (xy 37.167353 -74.447762) (xy 37.260368 -74.484675)
			(xy 37.350156 -74.528861) (xy 37.43615 -74.580042) (xy 37.517806 -74.637892) (xy 37.594607 -74.702048)
			(xy 37.666069 -74.772102) (xy 37.731739 -74.847613) (xy 37.791201 -74.928103) (xy 37.844081 -75.013062)
			(xy 37.890044 -75.101954) (xy 37.928799 -75.194217) (xy 37.960101 -75.289267) (xy 37.983753 -75.386504)
			(xy 37.999604 -75.485313) (xy 38.007554 -75.585068) (xy 38.008052 -75.635104) (xy 38.007554 -75.68514)
			(xy 37.999604 -75.784895) (xy 37.983753 -75.883704) (xy 37.960101 -75.980941) (xy 37.928799 -76.075991)
			(xy 37.890044 -76.168254) (xy 37.844081 -76.257146) (xy 37.791201 -76.342105) (xy 37.731739 -76.422595)
			(xy 37.666069 -76.498106) (xy 37.594607 -76.56816) (xy 37.517806 -76.632316) (xy 37.43615 -76.690166)
			(xy 37.350156 -76.741347) (xy 37.260368 -76.785533) (xy 37.167353 -76.822446) (xy 37.071699 -76.851852)
			(xy 36.974011 -76.873565) (xy 36.874907 -76.887449) (xy 36.775013 -76.893415) (xy 36.674961 -76.891425)
			(xy 36.575383 -76.881493) (xy 36.476909 -76.86368) (xy 36.380162 -76.8381) (xy 36.285753 -76.804914)
			(xy 36.194279 -76.764332) (xy 36.106318 -76.716611) (xy 36.022427 -76.662053) (xy 35.943136 -76.601001)
			(xy 35.868945 -76.533843) (xy 35.800326 -76.461003) (xy 35.73771 -76.382941) (xy 35.681494 -76.300151)
			(xy 35.632033 -76.213157) (xy 35.589641 -76.122508) (xy 35.554585 -76.028777) (xy 35.527086 -75.932558)
			(xy 35.507319 -75.834457) (xy 35.495409 -75.735097) (xy 35.491431 -75.635104) (xy 17.766792 -75.635104)
			(xy 17.766294 -75.680101) (xy 17.758341 -75.769742) (xy 17.742496 -75.85833) (xy 17.718883 -75.945171)
			(xy 17.687688 -76.029585) (xy 17.649155 -76.110911) (xy 17.603584 -76.188514) (xy 17.551334 -76.261786)
			(xy 17.492812 -76.330153) (xy 17.428477 -76.39308) (xy 17.358832 -76.450075) (xy 17.284422 -76.500692)
			(xy 17.20583 -76.544535) (xy 17.123671 -76.581259) (xy 17.038588 -76.610579) (xy 16.951246 -76.632265)
			(xy 16.862329 -76.646146) (xy 16.772534 -76.652115) (xy 16.682562 -76.650124) (xy 16.593119 -76.640189)
			(xy 16.504903 -76.622389) (xy 16.418606 -76.596861) (xy 16.334903 -76.563806) (xy 16.254449 -76.523483)
			(xy 16.177873 -76.476207) (xy 16.105775 -76.422348) (xy 16.038719 -76.362328) (xy 15.977231 -76.296617)
			(xy 15.92179 -76.225728) (xy 15.872832 -76.150217) (xy 15.830739 -76.070674) (xy 15.79584 -75.987723)
			(xy 15.76841 -75.902012) (xy 15.748662 -75.814211) (xy 15.736751 -75.72501) (xy 15.73277 -75.635104)
			(xy 1.016 -75.635104) (xy 1.016 -78.072742) (xy 1.035684 -78.090926) (xy 1.07027 -78.131857) (xy 1.098792 -78.177223)
			(xy 1.120688 -78.226132) (xy 1.13553 -78.277622) (xy 1.143024 -78.330683) (xy 1.143024 -78.384269)
			(xy 1.13553 -78.43733) (xy 1.120688 -78.48882) (xy 1.098792 -78.537729) (xy 1.07027 -78.583095) (xy 1.035684 -78.624026)
			(xy 1.016 -78.64221) (xy 1.016 -80.483964) (xy 2.249932 -80.483964) (xy 2.304063 -80.484447) (xy 2.41205 -80.49217)
			(xy 2.519211 -80.507578) (xy 2.624999 -80.530591) (xy 2.728876 -80.561092) (xy 2.830313 -80.598926)
			(xy 2.928792 -80.6439) (xy 3.023812 -80.695785) (xy 3.114888 -80.754316) (xy 3.201556 -80.819196)
			(xy 3.283376 -80.890093) (xy 3.359929 -80.966646) (xy 3.430826 -81.048465) (xy 3.495705 -81.135134)
			(xy 3.554236 -81.22621) (xy 3.606121 -81.32123) (xy 3.651095 -81.419709) (xy 3.688929 -81.521146)
			(xy 3.71943 -81.625023) (xy 3.742442 -81.730811) (xy 3.75785 -81.837972) (xy 3.765573 -81.945959)
			(xy 3.766058 -82.00009) (xy 3.766058 -82.344006) (xy 3.785742 -82.36219) (xy 3.820327 -82.403121)
			(xy 3.848849 -82.448487) (xy 3.870745 -82.497396) (xy 3.885587 -82.548886) (xy 3.893081 -82.601947)
			(xy 3.893081 -82.655533) (xy 3.885587 -82.708594) (xy 3.870745 -82.760084) (xy 3.848849 -82.808993)
			(xy 3.820327 -82.854359) (xy 3.785742 -82.89529) (xy 3.766058 -82.913474) (xy 3.766058 -84.499958)
			(xy 3.765575 -84.554089) (xy 3.757852 -84.662076) (xy 3.742445 -84.769237) (xy 3.719432 -84.875026)
			(xy 3.688931 -84.978903) (xy 3.651097 -85.08034) (xy 3.606123 -85.17882) (xy 3.554239 -85.27384)
			(xy 3.495707 -85.364916) (xy 3.430828 -85.451585) (xy 3.359931 -85.533405) (xy 3.283378 -85.609958)
			(xy 3.201558 -85.680855) (xy 3.11489 -85.745735) (xy 3.023813 -85.804266) (xy 2.928793 -85.856151)
			(xy 2.830314 -85.901126) (xy 2.728877 -85.93896) (xy 2.625 -85.969461) (xy 2.519211 -85.992474) (xy 2.41205 -86.007882)
			(xy 2.304063 -86.015605) (xy 2.249932 -86.016084) (xy 1.016 -86.016084) (xy 1.016 -86.61527) (xy 1.035684 -86.633454)
			(xy 1.07027 -86.674385) (xy 1.098792 -86.719751) (xy 1.120688 -86.76866) (xy 1.13553 -86.82015) (xy 1.143024 -86.873211)
			(xy 1.143024 -86.926797) (xy 1.13553 -86.979858) (xy 1.120688 -87.031348) (xy 1.098792 -87.080257)
			(xy 1.07027 -87.125623) (xy 1.035684 -87.166554) (xy 1.016 -87.184738) (xy 1.016 -91.69527) (xy 1.035684 -91.713454)
			(xy 1.07027 -91.754385) (xy 1.098792 -91.799751) (xy 1.120688 -91.84866) (xy 1.13553 -91.90015) (xy 1.143024 -91.953211)
			(xy 1.143024 -92.006797) (xy 1.13553 -92.059858) (xy 1.120688 -92.111348) (xy 1.098792 -92.160257)
			(xy 1.07027 -92.205623) (xy 1.035684 -92.246554) (xy 1.016 -92.264738) (xy 1.016 -96.77527) (xy 1.035684 -96.793454)
			(xy 1.07027 -96.834385) (xy 1.098792 -96.879751) (xy 1.120688 -96.92866) (xy 1.13553 -96.98015) (xy 1.143024 -97.033211)
			(xy 1.143024 -97.086797) (xy 1.13553 -97.139858) (xy 1.120688 -97.191348) (xy 1.098792 -97.240257)
			(xy 1.07027 -97.285623) (xy 1.035684 -97.326554) (xy 1.016 -97.344738) (xy 1.016 -97.978249) (xy 45.046914 -97.978249)
			(xy 45.046914 -97.923751) (xy 45.05467 -97.869809) (xy 45.070024 -97.817519) (xy 45.092663 -97.767947)
			(xy 45.122126 -97.722101) (xy 45.157814 -97.680914) (xy 45.199001 -97.645226) (xy 45.244847 -97.615763)
			(xy 45.294419 -97.593124) (xy 45.346709 -97.57777) (xy 45.400651 -97.570014) (xy 45.4279 -97.569528)
			(xy 46.3169 -97.569528) (xy 46.344154 -97.569942) (xy 46.398107 -97.577699) (xy 46.450406 -97.593056)
			(xy 46.499988 -97.615699) (xy 46.545843 -97.645168) (xy 46.587037 -97.680863) (xy 46.622732 -97.722057)
			(xy 46.652201 -97.767912) (xy 46.674844 -97.817494) (xy 46.690201 -97.869793) (xy 46.697958 -97.923746)
			(xy 46.697958 -97.978254) (xy 46.690201 -98.032207) (xy 46.674844 -98.084506) (xy 46.652201 -98.134088)
			(xy 46.622732 -98.179943) (xy 46.587037 -98.221137) (xy 46.545843 -98.256832) (xy 46.499988 -98.286301)
			(xy 46.450406 -98.308944) (xy 46.398107 -98.324301) (xy 46.344154 -98.332058) (xy 46.3169 -98.332544)
			(xy 45.4279 -98.332544) (xy 45.400651 -98.331986) (xy 45.346709 -98.32423) (xy 45.294419 -98.308876)
			(xy 45.244847 -98.286237) (xy 45.199001 -98.256774) (xy 45.157814 -98.221086) (xy 45.122126 -98.179899)
			(xy 45.092663 -98.134053) (xy 45.070024 -98.084481) (xy 45.05467 -98.032191) (xy 45.046914 -97.978249)
			(xy 1.016 -97.978249) (xy 1.016 -98.410049) (xy 40.017714 -98.410049) (xy 40.017714 -98.355551) (xy 40.02547 -98.301609)
			(xy 40.040824 -98.249319) (xy 40.063463 -98.199747) (xy 40.092926 -98.153901) (xy 40.128614 -98.112714)
			(xy 40.169801 -98.077026) (xy 40.215647 -98.047563) (xy 40.265219 -98.024924) (xy 40.317509 -98.00957)
			(xy 40.371451 -98.001814) (xy 40.3987 -98.001328) (xy 41.2877 -98.001328) (xy 41.314954 -98.001742)
			(xy 41.368907 -98.009499) (xy 41.421206 -98.024856) (xy 41.470788 -98.047499) (xy 41.516643 -98.076968)
			(xy 41.557837 -98.112663) (xy 41.593532 -98.153857) (xy 41.623001 -98.199712) (xy 41.645644 -98.249294)
			(xy 41.661001 -98.301593) (xy 41.668758 -98.355546) (xy 41.668758 -98.410054) (xy 41.661001 -98.464007)
			(xy 41.645644 -98.516306) (xy 41.623001 -98.565888) (xy 41.593532 -98.611743) (xy 41.557837 -98.652937)
			(xy 41.516643 -98.688632) (xy 41.470788 -98.718101) (xy 41.421206 -98.740744) (xy 41.368907 -98.756101)
			(xy 41.314954 -98.763858) (xy 41.2877 -98.764344) (xy 40.3987 -98.764344) (xy 40.371451 -98.763786)
			(xy 40.317509 -98.75603) (xy 40.265219 -98.740676) (xy 40.215647 -98.718037) (xy 40.169801 -98.688574)
			(xy 40.128614 -98.652886) (xy 40.092926 -98.611699) (xy 40.063463 -98.565853) (xy 40.040824 -98.516281)
			(xy 40.02547 -98.463991) (xy 40.017714 -98.410049) (xy 1.016 -98.410049) (xy 1.016 -101.85527) (xy 1.035684 -101.873454)
			(xy 1.07027 -101.914385) (xy 1.098792 -101.959751) (xy 1.120688 -102.00866) (xy 1.13553 -102.06015)
			(xy 1.143024 -102.113211) (xy 1.143024 -102.166797) (xy 1.13553 -102.219858) (xy 1.120688 -102.271348)
			(xy 1.098792 -102.320257) (xy 1.07027 -102.365623) (xy 1.035684 -102.406554) (xy 1.016 -102.424738)
			(xy 1.016 -104.205349) (xy 54.921178 -104.205349) (xy 54.921178 -104.150851) (xy 54.928933 -104.096908)
			(xy 54.944285 -104.044617) (xy 54.966923 -103.995043) (xy 54.996385 -103.949195) (xy 55.032071 -103.908006)
			(xy 55.073255 -103.872315) (xy 55.119099 -103.842847) (xy 55.16867 -103.820203) (xy 55.220959 -103.804843)
			(xy 55.274901 -103.797081) (xy 55.30215 -103.796592) (xy 56.19115 -103.796592) (xy 56.218405 -103.797052)
			(xy 56.272362 -103.804803) (xy 56.324665 -103.820155) (xy 56.374252 -103.842794) (xy 56.420111 -103.872261)
			(xy 56.46131 -103.907955) (xy 56.497009 -103.949149) (xy 56.526482 -103.995004) (xy 56.549128 -104.044588)
			(xy 56.564486 -104.09689) (xy 56.572245 -104.150845) (xy 56.572245 -104.205355) (xy 56.564486 -104.25931)
			(xy 56.549128 -104.311612) (xy 56.526482 -104.361196) (xy 56.497009 -104.407051) (xy 56.46131 -104.448245)
			(xy 56.420111 -104.483939) (xy 56.374252 -104.513406) (xy 56.324665 -104.536045) (xy 56.272362 -104.551397)
			(xy 56.218405 -104.559148) (xy 56.19115 -104.559608) (xy 55.30215 -104.559608) (xy 55.274901 -104.559119)
			(xy 55.220959 -104.551357) (xy 55.16867 -104.535997) (xy 55.119099 -104.513353) (xy 55.073255 -104.483885)
			(xy 55.032071 -104.448194) (xy 54.996385 -104.407005) (xy 54.966923 -104.361157) (xy 54.944285 -104.311583)
			(xy 54.928933 -104.259292) (xy 54.921178 -104.205349) (xy 1.016 -104.205349) (xy 1.016 -106.93527)
			(xy 1.035684 -106.953454) (xy 1.07027 -106.994385) (xy 1.098792 -107.039751) (xy 1.120688 -107.08866)
			(xy 1.13553 -107.14015) (xy 1.143024 -107.193211) (xy 1.143024 -107.246797) (xy 1.13553 -107.299858)
			(xy 1.120688 -107.351348) (xy 1.098792 -107.400257) (xy 1.07027 -107.445623) (xy 1.035684 -107.486554)
			(xy 1.016 -107.504738) (xy 1.016 -107.774051) (xy 13.017478 -107.774051) (xy 13.017478 -107.719549)
			(xy 13.025234 -107.665601) (xy 13.040589 -107.613306) (xy 13.063231 -107.563729) (xy 13.092697 -107.517879)
			(xy 13.128388 -107.476688) (xy 13.169579 -107.440997) (xy 13.215429 -107.411531) (xy 13.265006 -107.388889)
			(xy 13.317301 -107.373534) (xy 13.371249 -107.365778) (xy 13.3985 -107.365292) (xy 14.2875 -107.365292)
			(xy 14.314751 -107.365778) (xy 14.368699 -107.373534) (xy 14.420994 -107.388889) (xy 14.470571 -107.411531)
			(xy 14.516421 -107.440997) (xy 14.557612 -107.476688) (xy 14.593303 -107.517879) (xy 14.622769 -107.563729)
			(xy 14.645411 -107.613306) (xy 14.660766 -107.665601) (xy 14.668522 -107.719549) (xy 14.668522 -107.77382)
			(xy 17.94482 -107.77382) (xy 17.94482 -107.71928) (xy 17.952582 -107.665296) (xy 17.967948 -107.612966)
			(xy 17.990604 -107.563355) (xy 18.02009 -107.517474) (xy 18.055806 -107.476256) (xy 18.097024 -107.44054)
			(xy 18.142905 -107.411054) (xy 18.192516 -107.388398) (xy 18.244846 -107.373032) (xy 18.29883 -107.36527)
			(xy 18.3261 -107.364784) (xy 19.2151 -107.364784) (xy 19.242369 -107.365278) (xy 19.296352 -107.37304)
			(xy 19.348681 -107.388405) (xy 19.398291 -107.411061) (xy 19.444171 -107.440547) (xy 19.485388 -107.476262)
			(xy 19.521103 -107.517479) (xy 19.550589 -107.563359) (xy 19.573245 -107.612969) (xy 19.58861 -107.665298)
			(xy 19.596372 -107.719281) (xy 19.596372 -107.773819) (xy 19.58861 -107.827802) (xy 19.573245 -107.880131)
			(xy 19.550589 -107.929741) (xy 19.521103 -107.975621) (xy 19.485388 -108.016838) (xy 19.444171 -108.052553)
			(xy 19.398291 -108.082039) (xy 19.348681 -108.104695) (xy 19.296352 -108.12006) (xy 19.242369 -108.127822)
			(xy 19.2151 -108.128308) (xy 18.3261 -108.128308) (xy 18.29883 -108.12783) (xy 18.244846 -108.120068)
			(xy 18.192516 -108.104702) (xy 18.142905 -108.082046) (xy 18.097024 -108.05256) (xy 18.055806 -108.016844)
			(xy 18.02009 -107.975626) (xy 17.990604 -107.929745) (xy 17.967948 -107.880134) (xy 17.952582 -107.827804)
			(xy 17.94482 -107.77382) (xy 14.668522 -107.77382) (xy 14.668522 -107.774051) (xy 14.660766 -107.827999)
			(xy 14.645411 -107.880294) (xy 14.622769 -107.929871) (xy 14.593303 -107.975721) (xy 14.557612 -108.016912)
			(xy 14.516421 -108.052603) (xy 14.470571 -108.082069) (xy 14.420994 -108.104711) (xy 14.368699 -108.120066)
			(xy 14.314751 -108.127822) (xy 14.2875 -108.128308) (xy 13.3985 -108.128308) (xy 13.371249 -108.127822)
			(xy 13.317301 -108.120066) (xy 13.265006 -108.104711) (xy 13.215429 -108.082069) (xy 13.169579 -108.052603)
			(xy 13.128388 -108.016912) (xy 13.092697 -107.975721) (xy 13.063231 -107.929871) (xy 13.040589 -107.880294)
			(xy 13.025234 -107.827999) (xy 13.017478 -107.774051) (xy 1.016 -107.774051) (xy 1.016 -109.570609)
			(xy 15.016716 -109.570609) (xy 15.016716 -109.516071) (xy 15.024478 -109.462088) (xy 15.039843 -109.409759)
			(xy 15.062499 -109.360149) (xy 15.091985 -109.314268) (xy 15.127699 -109.273051) (xy 15.168917 -109.237336)
			(xy 15.214797 -109.20785) (xy 15.264407 -109.185194) (xy 15.316736 -109.169828) (xy 15.370719 -109.162067)
			(xy 15.397988 -109.16158) (xy 16.286988 -109.16158) (xy 16.314259 -109.162039) (xy 16.368247 -109.169801)
			(xy 16.42058 -109.185167) (xy 16.470193 -109.207825) (xy 16.516078 -109.237313) (xy 16.557298 -109.27303)
			(xy 16.593016 -109.314251) (xy 16.622504 -109.360135) (xy 16.645162 -109.409748) (xy 16.660528 -109.462081)
			(xy 16.668291 -109.516069) (xy 16.668291 -109.570611) (xy 16.660528 -109.624599) (xy 16.645162 -109.676932)
			(xy 16.622504 -109.726545) (xy 16.593016 -109.772429) (xy 16.557298 -109.81365) (xy 16.516078 -109.849367)
			(xy 16.470193 -109.878855) (xy 16.42058 -109.901513) (xy 16.368247 -109.916879) (xy 16.314259 -109.924641)
			(xy 16.286988 -109.925104) (xy 15.397988 -109.925104) (xy 15.370719 -109.924613) (xy 15.316736 -109.916852)
			(xy 15.264407 -109.901486) (xy 15.214797 -109.87883) (xy 15.168917 -109.849344) (xy 15.127699 -109.813629)
			(xy 15.091985 -109.772412) (xy 15.062499 -109.726531) (xy 15.039843 -109.676921) (xy 15.024478 -109.624592)
			(xy 15.016716 -109.570609) (xy 1.016 -109.570609) (xy 1.016 -109.998056) (xy 84.426541 -109.998056)
			(xy 84.426541 -109.868916) (xy 84.434491 -109.740021) (xy 84.450361 -109.611861) (xy 84.47409 -109.48492)
			(xy 84.505589 -109.359681) (xy 84.544738 -109.236618) (xy 84.591389 -109.116199) (xy 84.645364 -108.99888)
			(xy 84.706459 -108.885106) (xy 84.774442 -108.775309) (xy 84.849056 -108.669906) (xy 84.930017 -108.569296)
			(xy 85.017017 -108.473861) (xy 85.109728 -108.383962) (xy 85.207798 -108.299941) (xy 85.310853 -108.222117)
			(xy 85.418504 -108.150785) (xy 85.530343 -108.086215) (xy 85.645944 -108.028653) (xy 85.764869 -107.978316)
			(xy 85.886668 -107.935396) (xy 86.010878 -107.900055) (xy 86.137027 -107.872428) (xy 86.264639 -107.852619)
			(xy 86.393228 -107.840703) (xy 86.522306 -107.836727) (xy 86.651384 -107.840703) (xy 86.779973 -107.852619)
			(xy 86.907585 -107.872428) (xy 87.033734 -107.900055) (xy 87.157944 -107.935396) (xy 87.279743 -107.978316)
			(xy 87.398668 -108.028653) (xy 87.514269 -108.086215) (xy 87.626108 -108.150785) (xy 87.733759 -108.222117)
			(xy 87.836814 -108.299941) (xy 87.934884 -108.383962) (xy 88.027595 -108.473861) (xy 88.114595 -108.569296)
			(xy 88.195556 -108.669906) (xy 88.27017 -108.775309) (xy 88.338153 -108.885106) (xy 88.399248 -108.99888)
			(xy 88.453223 -109.116199) (xy 88.499874 -109.236618) (xy 88.539023 -109.359681) (xy 88.570522 -109.48492)
			(xy 88.594251 -109.611861) (xy 88.610121 -109.740021) (xy 88.618071 -109.868916) (xy 88.618568 -109.933486)
			(xy 88.618071 -109.998056) (xy 88.610121 -110.126951) (xy 88.594251 -110.255111) (xy 88.570522 -110.382052)
			(xy 88.539023 -110.507291) (xy 88.499874 -110.630354) (xy 88.453223 -110.750773) (xy 88.399248 -110.868092)
			(xy 88.338153 -110.981866) (xy 88.27017 -111.091663) (xy 88.195556 -111.197066) (xy 88.114595 -111.297676)
			(xy 88.027595 -111.393111) (xy 87.934884 -111.48301) (xy 87.836814 -111.567031) (xy 87.733759 -111.644855)
			(xy 87.626108 -111.716187) (xy 87.514269 -111.780757) (xy 87.398668 -111.838319) (xy 87.279743 -111.888656)
			(xy 87.157944 -111.931576) (xy 87.033734 -111.966917) (xy 86.907585 -111.994544) (xy 86.779973 -112.014353)
			(xy 86.651384 -112.026269) (xy 86.522306 -112.030246) (xy 86.393228 -112.026269) (xy 86.264639 -112.014353)
			(xy 86.137027 -111.994544) (xy 86.010878 -111.966917) (xy 85.886668 -111.931576) (xy 85.764869 -111.888656)
			(xy 85.645944 -111.838319) (xy 85.530343 -111.780757) (xy 85.418504 -111.716187) (xy 85.310853 -111.644855)
			(xy 85.207798 -111.567031) (xy 85.109728 -111.48301) (xy 85.017017 -111.393111) (xy 84.930017 -111.297676)
			(xy 84.849056 -111.197066) (xy 84.774442 -111.091663) (xy 84.706459 -110.981866) (xy 84.645364 -110.868092)
			(xy 84.591389 -110.750773) (xy 84.544738 -110.630354) (xy 84.505589 -110.507291) (xy 84.47409 -110.382052)
			(xy 84.450361 -110.255111) (xy 84.434491 -110.126951) (xy 84.426541 -109.998056) (xy 1.016 -109.998056)
			(xy 1.016 -112.01527) (xy 1.035682 -112.033455) (xy 1.070266 -112.074389) (xy 1.098788 -112.119755)
			(xy 1.120689 -112.168662) (xy 1.135537 -112.220151) (xy 1.143041 -112.273211) (xy 1.143508 -112.300004)
			(xy 1.143029 -112.327502) (xy 1.1396 -112.35115) (xy 53.778158 -112.35115) (xy 53.778158 -112.29665)
			(xy 53.785913 -112.242703) (xy 53.801267 -112.19041) (xy 53.823905 -112.140833) (xy 53.853369 -112.094983)
			(xy 53.889057 -112.053792) (xy 53.930243 -112.018099) (xy 53.976089 -111.988629) (xy 54.025663 -111.965984)
			(xy 54.077955 -111.950624) (xy 54.1319 -111.942861) (xy 54.15915 -111.942372) (xy 55.04815 -111.942372)
			(xy 55.075404 -111.942872) (xy 55.129357 -111.950623) (xy 55.181658 -111.965974) (xy 55.231242 -111.988612)
			(xy 55.277099 -112.018077) (xy 55.318296 -112.053769) (xy 55.353993 -112.094961) (xy 55.383464 -112.140814)
			(xy 55.406109 -112.190395) (xy 55.421467 -112.242694) (xy 55.429225 -112.296646) (xy 55.429225 -112.351154)
			(xy 55.421467 -112.405106) (xy 55.406109 -112.457405) (xy 55.383464 -112.506986) (xy 55.353993 -112.552839)
			(xy 55.318296 -112.594031) (xy 55.277099 -112.629723) (xy 55.231242 -112.659188) (xy 55.181658 -112.681826)
			(xy 55.129357 -112.697177) (xy 55.075404 -112.704928) (xy 55.04815 -112.705388) (xy 54.15915 -112.705388)
			(xy 54.1319 -112.704939) (xy 54.077955 -112.697176) (xy 54.025663 -112.681816) (xy 53.976089 -112.659171)
			(xy 53.930243 -112.629701) (xy 53.889057 -112.594008) (xy 53.853369 -112.552817) (xy 53.823905 -112.506967)
			(xy 53.801267 -112.45739) (xy 53.785913 -112.405097) (xy 53.778158 -112.35115) (xy 1.1396 -112.35115)
			(xy 1.135137 -112.381929) (xy 1.119517 -112.434661) (xy 1.096492 -112.484605) (xy 1.066537 -112.530728)
			(xy 1.048766 -112.551718) (xy 1.060222 -112.593211) (xy 1.089432 -112.674191) (xy 1.125604 -112.75231)
			(xy 1.168462 -112.82697) (xy 1.217678 -112.8976) (xy 1.272877 -112.963661) (xy 1.333635 -113.024648)
			(xy 1.399489 -113.080094) (xy 1.469934 -113.129575) (xy 1.544433 -113.172713) (xy 1.559952 -113.17997)
			(xy 23.969706 -113.17997) (xy 23.969706 -113.12543) (xy 23.977468 -113.071446) (xy 23.992833 -113.019115)
			(xy 24.015489 -112.969504) (xy 24.044974 -112.923622) (xy 24.080689 -112.882403) (xy 24.121906 -112.846686)
			(xy 24.167787 -112.817198) (xy 24.217397 -112.79454) (xy 24.269726 -112.779172) (xy 24.32371 -112.771408)
			(xy 24.35098 -112.77092) (xy 25.23998 -112.77092) (xy 25.267251 -112.771418) (xy 25.321237 -112.779178)
			(xy 25.37357 -112.794541) (xy 25.423183 -112.817197) (xy 25.469067 -112.846682) (xy 25.510288 -112.882398)
			(xy 25.546006 -112.923617) (xy 25.575494 -112.969499) (xy 25.598152 -113.019111) (xy 25.613518 -113.071443)
			(xy 25.62128 -113.125429) (xy 25.62128 -113.179971) (xy 25.613518 -113.233957) (xy 25.598152 -113.286289)
			(xy 25.575494 -113.335901) (xy 25.546006 -113.381783) (xy 25.510288 -113.423002) (xy 25.469067 -113.458718)
			(xy 25.423183 -113.488203) (xy 25.37357 -113.510859) (xy 25.321237 -113.526222) (xy 25.267251 -113.533982)
			(xy 25.23998 -113.534444) (xy 24.35098 -113.534444) (xy 24.32371 -113.533992) (xy 24.269726 -113.526228)
			(xy 24.217397 -113.51086) (xy 24.167787 -113.488202) (xy 24.121906 -113.458714) (xy 24.080689 -113.422997)
			(xy 24.044974 -113.381778) (xy 24.015489 -113.335896) (xy 23.992833 -113.286285) (xy 23.977468 -113.233954)
			(xy 23.969706 -113.17997) (xy 1.559952 -113.17997) (xy 1.622415 -113.209178) (xy 1.703285 -113.238691)
			(xy 1.786423 -113.261027) (xy 1.871195 -113.276015) (xy 1.956953 -113.28354) (xy 1.999996 -113.284)
			(xy 4.500372 -113.284) (xy 4.561173 -113.284629) (xy 4.682381 -113.294415) (xy 4.802417 -113.313869)
			(xy 4.920511 -113.342868) (xy 4.9784 -113.36147) (xy 5.003378 -113.350547) (xy 5.055677 -113.335157)
			(xy 5.109638 -113.32739) (xy 5.136896 -113.326926) (xy 5.13715 -113.326926) (xy 5.165504 -113.327441)
			(xy 5.221589 -113.335826) (xy 5.275815 -113.35242) (xy 5.326988 -113.376856) (xy 5.373981 -113.408596)
			(xy 5.415759 -113.446943) (xy 5.451401 -113.491049) (xy 5.480124 -113.539946) (xy 5.501293 -113.592554)
			(xy 5.514443 -113.647716) (xy 5.517388 -113.675922) (xy 5.559695 -113.714947) (xy 5.638923 -113.798452)
			(xy 5.71159 -113.887724) (xy 5.777278 -113.982251) (xy 5.835607 -114.081486) (xy 5.886243 -114.18486)
			(xy 5.928894 -114.291776) (xy 5.963313 -114.401619) (xy 5.989304 -114.513755) (xy 6.006715 -114.62754)
			(xy 6.015446 -114.742317) (xy 6.01599 -114.799872) (xy 6.01599 -118.209314) (xy 6.035929 -118.227508)
			(xy 6.07099 -118.268546) (xy 6.099917 -118.314117) (xy 6.12213 -118.363311) (xy 6.137186 -118.415145)
			(xy 6.144785 -118.468584) (xy 6.145276 -118.495572) (xy 6.144877 -118.520176) (xy 6.138507 -118.568972)
			(xy 6.132576 -118.592854) (xy 6.129529 -118.605826) (xy 6.129567 -118.632465) (xy 6.1365 -118.658185)
			(xy 6.149854 -118.681235) (xy 6.16872 -118.700041) (xy 6.191812 -118.713323) (xy 6.217554 -118.720175)
			(xy 6.230874 -118.720616) (xy 9.749028 -118.720616)
		)
		(stroke
			(width 0)
			(type solid)
		)
		(fill yes)
		(layer "In6.Cu")
		(net "P3V3_AUX")
	)
	(gr_poly
		(pts
			(xy 121.000012 -119.892064) (xy 121.055819 -119.891554) (xy 121.16712 -119.883212) (xy 121.277487 -119.866576)
			(xy 121.386302 -119.841739) (xy 121.492956 -119.808839) (xy 121.596854 -119.768061) (xy 121.697414 -119.719632)
			(xy 121.794073 -119.663824) (xy 121.886292 -119.600949) (xy 121.973554 -119.531358) (xy 122.055371 -119.45544)
			(xy 122.131287 -119.373621) (xy 122.200875 -119.286356) (xy 122.263748 -119.194136) (xy 122.319553 -119.097475)
			(xy 122.367978 -118.996914) (xy 122.408754 -118.893015) (xy 122.44165 -118.786359) (xy 122.466484 -118.677544)
			(xy 122.483117 -118.567176) (xy 122.491456 -118.455875) (xy 122.492008 -118.400068) (xy 122.492008 129.499868)
			(xy 122.4915 129.555676) (xy 122.483161 129.666981) (xy 122.466528 129.777352) (xy 122.441693 129.886171)
			(xy 122.408795 129.992829) (xy 122.368019 130.096731) (xy 122.319592 130.197295) (xy 122.263785 130.293959)
			(xy 122.200911 130.386183) (xy 122.13132 130.473449) (xy 122.055402 130.555271) (xy 121.973583 130.631191)
			(xy 121.886318 130.700784) (xy 121.794097 130.763662) (xy 121.697434 130.819471) (xy 121.596872 130.867901)
			(xy 121.492971 130.908681) (xy 121.386313 130.941581) (xy 121.277495 130.96642) (xy 121.167125 130.983056)
			(xy 121.05582 130.991398) (xy 121.000012 130.991864) (xy 94.000066 130.991864) (xy 93.94426 130.991341)
			(xy 93.832961 130.982998) (xy 93.722596 130.96636) (xy 93.613784 130.941522) (xy 93.507131 130.908622)
			(xy 93.403236 130.867843) (xy 93.302679 130.819414) (xy 93.206021 130.763606) (xy 93.113805 130.700731)
			(xy 93.026545 130.631141) (xy 92.94473 130.555224) (xy 92.868816 130.473405) (xy 92.79923 130.386142)
			(xy 92.736359 130.293923) (xy 92.680555 130.197263) (xy 92.632131 130.096703) (xy 92.591357 129.992806)
			(xy 92.558461 129.886153) (xy 92.533627 129.777339) (xy 92.516995 129.666973) (xy 92.508656 129.555674)
			(xy 92.50807 129.499868) (xy 92.50807 126.435304) (xy 115.904253 126.435304) (xy 115.904253 126.564444)
			(xy 115.912203 126.693339) (xy 115.928073 126.821499) (xy 115.951802 126.94844) (xy 115.983301 127.073679)
			(xy 116.02245 127.196742) (xy 116.069101 127.317161) (xy 116.123076 127.43448) (xy 116.184171 127.548254)
			(xy 116.252154 127.658051) (xy 116.326768 127.763454) (xy 116.407729 127.864064) (xy 116.494729 127.959499)
			(xy 116.58744 128.049398) (xy 116.68551 128.133419) (xy 116.788565 128.211243) (xy 116.896216 128.282575)
			(xy 117.008055 128.347145) (xy 117.123656 128.404707) (xy 117.242581 128.455044) (xy 117.36438 128.497964)
			(xy 117.48859 128.533305) (xy 117.614739 128.560932) (xy 117.742351 128.580741) (xy 117.87094 128.592657)
			(xy 118.000018 128.596634) (xy 118.129096 128.592657) (xy 118.257685 128.580741) (xy 118.385297 128.560932)
			(xy 118.511446 128.533305) (xy 118.635656 128.497964) (xy 118.757455 128.455044) (xy 118.87638 128.404707)
			(xy 118.991981 128.347145) (xy 119.10382 128.282575) (xy 119.211471 128.211243) (xy 119.314526 128.133419)
			(xy 119.412596 128.049398) (xy 119.505307 127.959499) (xy 119.592307 127.864064) (xy 119.673268 127.763454)
			(xy 119.747882 127.658051) (xy 119.815865 127.548254) (xy 119.87696 127.43448) (xy 119.930935 127.317161)
			(xy 119.977586 127.196742) (xy 120.016735 127.073679) (xy 120.048234 126.94844) (xy 120.071963 126.821499)
			(xy 120.087833 126.693339) (xy 120.095783 126.564444) (xy 120.09628 126.499874) (xy 120.095783 126.435304)
			(xy 120.087833 126.306409) (xy 120.071963 126.178249) (xy 120.048234 126.051308) (xy 120.016735 125.926069)
			(xy 119.977586 125.803006) (xy 119.930935 125.682587) (xy 119.87696 125.565268) (xy 119.815865 125.451494)
			(xy 119.747882 125.341697) (xy 119.673268 125.236294) (xy 119.592307 125.135684) (xy 119.505307 125.040249)
			(xy 119.412596 124.95035) (xy 119.314526 124.866329) (xy 119.211471 124.788505) (xy 119.10382 124.717173)
			(xy 118.991981 124.652603) (xy 118.87638 124.595041) (xy 118.757455 124.544704) (xy 118.635656 124.501784)
			(xy 118.511446 124.466443) (xy 118.385297 124.438816) (xy 118.257685 124.419007) (xy 118.129096 124.407091)
			(xy 118.000018 124.403115) (xy 117.87094 124.407091) (xy 117.742351 124.419007) (xy 117.614739 124.438816)
			(xy 117.48859 124.466443) (xy 117.36438 124.501784) (xy 117.242581 124.544704) (xy 117.123656 124.595041)
			(xy 117.008055 124.652603) (xy 116.896216 124.717173) (xy 116.788565 124.788505) (xy 116.68551 124.866329)
			(xy 116.58744 124.95035) (xy 116.494729 125.040249) (xy 116.407729 125.135684) (xy 116.326768 125.236294)
			(xy 116.252154 125.341697) (xy 116.184171 125.451494) (xy 116.123076 125.565268) (xy 116.069101 125.682587)
			(xy 116.02245 125.803006) (xy 115.983301 125.926069) (xy 115.951802 126.051308) (xy 115.928073 126.178249)
			(xy 115.912203 126.306409) (xy 115.904253 126.435304) (xy 92.50807 126.435304) (xy 92.50807 122.226375)
			(xy 99.070401 122.226375) (xy 99.070401 122.312125) (xy 99.078313 122.397508) (xy 99.094069 122.481798)
			(xy 99.117536 122.564274) (xy 99.148512 122.644233) (xy 99.186734 122.720993) (xy 99.231875 122.793899)
			(xy 99.283551 122.862328) (xy 99.34132 122.925698) (xy 99.40469 122.983467) (xy 99.473119 123.035143)
			(xy 99.546025 123.080284) (xy 99.622785 123.118506) (xy 99.702744 123.149482) (xy 99.78522 123.172949)
			(xy 99.86951 123.188705) (xy 99.954893 123.196617) (xy 100.040643 123.196617) (xy 100.126026 123.188705)
			(xy 100.210316 123.172949) (xy 100.292792 123.149482) (xy 100.372751 123.118506) (xy 100.449511 123.080284)
			(xy 100.522417 123.035143) (xy 100.590846 122.983467) (xy 100.654216 122.925698) (xy 100.711985 122.862328)
			(xy 100.763661 122.793899) (xy 100.808802 122.720993) (xy 100.847024 122.644233) (xy 100.878 122.564274)
			(xy 100.901467 122.481798) (xy 100.917223 122.397508) (xy 100.925135 122.312125) (xy 100.92563 122.26925)
			(xy 100.925135 122.226375) (xy 101.610401 122.226375) (xy 101.610401 122.312125) (xy 101.618313 122.397508)
			(xy 101.634069 122.481798) (xy 101.657536 122.564274) (xy 101.688512 122.644233) (xy 101.726734 122.720993)
			(xy 101.771875 122.793899) (xy 101.823551 122.862328) (xy 101.88132 122.925698) (xy 101.94469 122.983467)
			(xy 102.013119 123.035143) (xy 102.086025 123.080284) (xy 102.162785 123.118506) (xy 102.242744 123.149482)
			(xy 102.32522 123.172949) (xy 102.40951 123.188705) (xy 102.494893 123.196617) (xy 102.580643 123.196617)
			(xy 102.666026 123.188705) (xy 102.750316 123.172949) (xy 102.832792 123.149482) (xy 102.912751 123.118506)
			(xy 102.989511 123.080284) (xy 103.062417 123.035143) (xy 103.130846 122.983467) (xy 103.194216 122.925698)
			(xy 103.251985 122.862328) (xy 103.303661 122.793899) (xy 103.348802 122.720993) (xy 103.387024 122.644233)
			(xy 103.418 122.564274) (xy 103.441467 122.481798) (xy 103.457223 122.397508) (xy 103.465135 122.312125)
			(xy 103.46563 122.26925) (xy 103.465135 122.226375) (xy 103.457223 122.140992) (xy 103.441467 122.056702)
			(xy 103.418 121.974226) (xy 103.387024 121.894267) (xy 103.348802 121.817507) (xy 103.303661 121.744601)
			(xy 103.251985 121.676172) (xy 103.194216 121.612802) (xy 103.130846 121.555033) (xy 103.062417 121.503357)
			(xy 102.989511 121.458216) (xy 102.912751 121.419994) (xy 102.832792 121.389018) (xy 102.750316 121.365551)
			(xy 102.666026 121.349795) (xy 102.580643 121.341883) (xy 102.494893 121.341883) (xy 102.40951 121.349795)
			(xy 102.32522 121.365551) (xy 102.242744 121.389018) (xy 102.162785 121.419994) (xy 102.086025 121.458216)
			(xy 102.013119 121.503357) (xy 101.94469 121.555033) (xy 101.88132 121.612802) (xy 101.823551 121.676172)
			(xy 101.771875 121.744601) (xy 101.726734 121.817507) (xy 101.688512 121.894267) (xy 101.657536 121.974226)
			(xy 101.634069 122.056702) (xy 101.618313 122.140992) (xy 101.610401 122.226375) (xy 100.925135 122.226375)
			(xy 100.917223 122.140992) (xy 100.901467 122.056702) (xy 100.878 121.974226) (xy 100.847024 121.894267)
			(xy 100.808802 121.817507) (xy 100.763661 121.744601) (xy 100.711985 121.676172) (xy 100.654216 121.612802)
			(xy 100.590846 121.555033) (xy 100.522417 121.503357) (xy 100.449511 121.458216) (xy 100.372751 121.419994)
			(xy 100.292792 121.389018) (xy 100.210316 121.365551) (xy 100.126026 121.349795) (xy 100.040643 121.341883)
			(xy 99.954893 121.341883) (xy 99.86951 121.349795) (xy 99.78522 121.365551) (xy 99.702744 121.389018)
			(xy 99.622785 121.419994) (xy 99.546025 121.458216) (xy 99.473119 121.503357) (xy 99.40469 121.555033)
			(xy 99.34132 121.612802) (xy 99.283551 121.676172) (xy 99.231875 121.744601) (xy 99.186734 121.817507)
			(xy 99.148512 121.894267) (xy 99.117536 121.974226) (xy 99.094069 122.056702) (xy 99.078313 122.140992)
			(xy 99.070401 122.226375) (xy 92.50807 122.226375) (xy 92.50807 117.881334) (xy 100.454746 117.881334)
			(xy 100.454746 117.935866) (xy 100.462507 117.989844) (xy 100.47787 118.042168) (xy 100.500522 118.091773)
			(xy 100.530003 118.13765) (xy 100.565713 118.178864) (xy 100.606924 118.214578) (xy 100.652799 118.244063)
			(xy 100.702402 118.266719) (xy 100.754725 118.282087) (xy 100.808702 118.289851) (xy 100.835968 118.29034)
			(xy 101.699568 118.29034) (xy 101.726842 118.289923) (xy 101.780835 118.282164) (xy 101.833175 118.266799)
			(xy 101.882795 118.244142) (xy 101.928685 118.214654) (xy 101.969912 118.178934) (xy 102.005635 118.137711)
			(xy 102.035127 118.091823) (xy 102.057788 118.042205) (xy 102.073157 117.989867) (xy 102.08092 117.935874)
			(xy 102.08092 117.881326) (xy 102.073157 117.827333) (xy 102.057788 117.774995) (xy 102.035127 117.725377)
			(xy 102.005635 117.679489) (xy 101.969912 117.638266) (xy 101.928685 117.602546) (xy 101.882795 117.573058)
			(xy 101.833175 117.550401) (xy 101.780836 117.535036) (xy 101.726842 117.527277) (xy 101.699568 117.526816)
			(xy 100.835968 117.526816) (xy 100.808702 117.527349) (xy 100.754725 117.535113) (xy 100.702402 117.550481)
			(xy 100.652799 117.573137) (xy 100.606924 117.602622) (xy 100.565713 117.638336) (xy 100.530003 117.67955)
			(xy 100.500522 117.725427) (xy 100.47787 117.775032) (xy 100.462507 117.827356) (xy 100.454746 117.881334)
			(xy 92.50807 117.881334) (xy 92.50807 115.606627) (xy 93.714049 115.606627) (xy 93.714049 115.692377)
			(xy 93.721961 115.77776) (xy 93.737717 115.86205) (xy 93.761184 115.944526) (xy 93.79216 116.024485)
			(xy 93.830382 116.101245) (xy 93.875523 116.174151) (xy 93.927199 116.24258) (xy 93.984968 116.30595)
			(xy 94.048338 116.363719) (xy 94.116767 116.415395) (xy 94.189673 116.460536) (xy 94.266433 116.498758)
			(xy 94.346392 116.529734) (xy 94.428868 116.553201) (xy 94.513158 116.568957) (xy 94.598541 116.576869)
			(xy 94.684291 116.576869) (xy 94.769674 116.568957) (xy 94.853964 116.553201) (xy 94.93644 116.529734)
			(xy 95.016399 116.498758) (xy 95.093159 116.460536) (xy 95.166065 116.415395) (xy 95.234494 116.363719)
			(xy 95.297864 116.30595) (xy 95.355633 116.24258) (xy 95.407309 116.174151) (xy 95.45245 116.101245)
			(xy 95.490672 116.024485) (xy 95.521648 115.944526) (xy 95.545115 115.86205) (xy 95.560871 115.77776)
			(xy 95.568783 115.692377) (xy 95.569278 115.649502) (xy 95.568783 115.606627) (xy 96.254049 115.606627)
			(xy 96.254049 115.692377) (xy 96.261961 115.77776) (xy 96.277717 115.86205) (xy 96.301184 115.944526)
			(xy 96.33216 116.024485) (xy 96.370382 116.101245) (xy 96.415523 116.174151) (xy 96.467199 116.24258)
			(xy 96.524968 116.30595) (xy 96.588338 116.363719) (xy 96.656767 116.415395) (xy 96.729673 116.460536)
			(xy 96.806433 116.498758) (xy 96.886392 116.529734) (xy 96.968868 116.553201) (xy 97.053158 116.568957)
			(xy 97.138541 116.576869) (xy 97.224291 116.576869) (xy 97.309674 116.568957) (xy 97.393964 116.553201)
			(xy 97.47644 116.529734) (xy 97.556399 116.498758) (xy 97.633159 116.460536) (xy 97.706065 116.415395)
			(xy 97.774494 116.363719) (xy 97.837864 116.30595) (xy 97.895633 116.24258) (xy 97.947309 116.174151)
			(xy 97.99245 116.101245) (xy 98.030672 116.024485) (xy 98.061648 115.944526) (xy 98.081039 115.876375)
			(xy 99.070401 115.876375) (xy 99.070401 115.962125) (xy 99.078313 116.047508) (xy 99.094069 116.131798)
			(xy 99.117536 116.214274) (xy 99.148512 116.294233) (xy 99.186734 116.370993) (xy 99.231875 116.443899)
			(xy 99.283551 116.512328) (xy 99.34132 116.575698) (xy 99.40469 116.633467) (xy 99.473119 116.685143)
			(xy 99.546025 116.730284) (xy 99.622785 116.768506) (xy 99.702744 116.799482) (xy 99.78522 116.822949)
			(xy 99.86951 116.838705) (xy 99.954893 116.846617) (xy 100.040643 116.846617) (xy 100.126026 116.838705)
			(xy 100.210316 116.822949) (xy 100.292792 116.799482) (xy 100.372751 116.768506) (xy 100.449511 116.730284)
			(xy 100.522417 116.685143) (xy 100.590846 116.633467) (xy 100.654216 116.575698) (xy 100.711985 116.512328)
			(xy 100.763661 116.443899) (xy 100.808802 116.370993) (xy 100.847024 116.294233) (xy 100.878 116.214274)
			(xy 100.901467 116.131798) (xy 100.917223 116.047508) (xy 100.925135 115.962125) (xy 100.92563 115.91925)
			(xy 100.925135 115.876375) (xy 101.610401 115.876375) (xy 101.610401 115.962125) (xy 101.618313 116.047508)
			(xy 101.634069 116.131798) (xy 101.657536 116.214274) (xy 101.688512 116.294233) (xy 101.726734 116.370993)
			(xy 101.771875 116.443899) (xy 101.823551 116.512328) (xy 101.88132 116.575698) (xy 101.94469 116.633467)
			(xy 102.013119 116.685143) (xy 102.086025 116.730284) (xy 102.162785 116.768506) (xy 102.242744 116.799482)
			(xy 102.32522 116.822949) (xy 102.40951 116.838705) (xy 102.494893 116.846617) (xy 102.580643 116.846617)
			(xy 102.666026 116.838705) (xy 102.750316 116.822949) (xy 102.832792 116.799482) (xy 102.912751 116.768506)
			(xy 102.989511 116.730284) (xy 103.062417 116.685143) (xy 103.130846 116.633467) (xy 103.194216 116.575698)
			(xy 103.251985 116.512328) (xy 103.303661 116.443899) (xy 103.348802 116.370993) (xy 103.387024 116.294233)
			(xy 103.418 116.214274) (xy 103.441467 116.131798) (xy 103.457223 116.047508) (xy 103.465135 115.962125)
			(xy 103.46563 115.91925) (xy 103.465135 115.876375) (xy 103.457223 115.790992) (xy 103.441467 115.706702)
			(xy 103.418 115.624226) (xy 103.387024 115.544267) (xy 103.348802 115.467507) (xy 103.303661 115.394601)
			(xy 103.251985 115.326172) (xy 103.194216 115.262802) (xy 103.130846 115.205033) (xy 103.062417 115.153357)
			(xy 102.989511 115.108216) (xy 102.912751 115.069994) (xy 102.832792 115.039018) (xy 102.750316 115.015551)
			(xy 102.666026 114.999795) (xy 102.580643 114.991883) (xy 102.494893 114.991883) (xy 102.40951 114.999795)
			(xy 102.32522 115.015551) (xy 102.242744 115.039018) (xy 102.162785 115.069994) (xy 102.086025 115.108216)
			(xy 102.013119 115.153357) (xy 101.94469 115.205033) (xy 101.88132 115.262802) (xy 101.823551 115.326172)
			(xy 101.771875 115.394601) (xy 101.726734 115.467507) (xy 101.688512 115.544267) (xy 101.657536 115.624226)
			(xy 101.634069 115.706702) (xy 101.618313 115.790992) (xy 101.610401 115.876375) (xy 100.925135 115.876375)
			(xy 100.917223 115.790992) (xy 100.901467 115.706702) (xy 100.878 115.624226) (xy 100.847024 115.544267)
			(xy 100.808802 115.467507) (xy 100.763661 115.394601) (xy 100.711985 115.326172) (xy 100.654216 115.262802)
			(xy 100.590846 115.205033) (xy 100.522417 115.153357) (xy 100.449511 115.108216) (xy 100.372751 115.069994)
			(xy 100.292792 115.039018) (xy 100.210316 115.015551) (xy 100.126026 114.999795) (xy 100.040643 114.991883)
			(xy 99.954893 114.991883) (xy 99.86951 114.999795) (xy 99.78522 115.015551) (xy 99.702744 115.039018)
			(xy 99.622785 115.069994) (xy 99.546025 115.108216) (xy 99.473119 115.153357) (xy 99.40469 115.205033)
			(xy 99.34132 115.262802) (xy 99.283551 115.326172) (xy 99.231875 115.394601) (xy 99.186734 115.467507)
			(xy 99.148512 115.544267) (xy 99.117536 115.624226) (xy 99.094069 115.706702) (xy 99.078313 115.790992)
			(xy 99.070401 115.876375) (xy 98.081039 115.876375) (xy 98.085115 115.86205) (xy 98.100871 115.77776)
			(xy 98.108783 115.692377) (xy 98.109278 115.649502) (xy 98.108783 115.606627) (xy 98.100871 115.521244)
			(xy 98.085115 115.436954) (xy 98.061648 115.354478) (xy 98.030672 115.274519) (xy 97.99245 115.197759)
			(xy 97.947309 115.124853) (xy 97.895633 115.056424) (xy 97.837864 114.993054) (xy 97.774494 114.935285)
			(xy 97.706065 114.883609) (xy 97.633159 114.838468) (xy 97.556399 114.800246) (xy 97.47644 114.76927)
			(xy 97.393964 114.745803) (xy 97.309674 114.730047) (xy 97.224291 114.722135) (xy 97.138541 114.722135)
			(xy 97.053158 114.730047) (xy 96.968868 114.745803) (xy 96.886392 114.76927) (xy 96.806433 114.800246)
			(xy 96.729673 114.838468) (xy 96.656767 114.883609) (xy 96.588338 114.935285) (xy 96.524968 114.993054)
			(xy 96.467199 115.056424) (xy 96.415523 115.124853) (xy 96.370382 115.197759) (xy 96.33216 115.274519)
			(xy 96.301184 115.354478) (xy 96.277717 115.436954) (xy 96.261961 115.521244) (xy 96.254049 115.606627)
			(xy 95.568783 115.606627) (xy 95.560871 115.521244) (xy 95.545115 115.436954) (xy 95.521648 115.354478)
			(xy 95.490672 115.274519) (xy 95.45245 115.197759) (xy 95.407309 115.124853) (xy 95.355633 115.056424)
			(xy 95.297864 114.993054) (xy 95.234494 114.935285) (xy 95.166065 114.883609) (xy 95.093159 114.838468)
			(xy 95.016399 114.800246) (xy 94.93644 114.76927) (xy 94.853964 114.745803) (xy 94.769674 114.730047)
			(xy 94.684291 114.722135) (xy 94.598541 114.722135) (xy 94.513158 114.730047) (xy 94.428868 114.745803)
			(xy 94.346392 114.76927) (xy 94.266433 114.800246) (xy 94.189673 114.838468) (xy 94.116767 114.883609)
			(xy 94.048338 114.935285) (xy 93.984968 114.993054) (xy 93.927199 115.056424) (xy 93.875523 115.124853)
			(xy 93.830382 115.197759) (xy 93.79216 115.274519) (xy 93.761184 115.354478) (xy 93.737717 115.436954)
			(xy 93.721961 115.521244) (xy 93.714049 115.606627) (xy 92.50807 115.606627) (xy 92.50807 111.261526)
			(xy 95.098272 111.261526) (xy 95.098272 111.316074) (xy 95.106035 111.370066) (xy 95.121403 111.422404)
			(xy 95.144064 111.472023) (xy 95.173555 111.517911) (xy 95.209277 111.559134) (xy 95.250502 111.594855)
			(xy 95.296392 111.624344) (xy 95.346011 111.647003) (xy 95.398349 111.662369) (xy 95.452342 111.67013)
			(xy 95.479616 111.670592) (xy 96.343216 111.670592) (xy 96.370482 111.670045) (xy 96.42446 111.662282)
			(xy 96.476784 111.646916) (xy 96.526388 111.624261) (xy 96.572263 111.594777) (xy 96.613476 111.559064)
			(xy 96.649186 111.51785) (xy 96.678668 111.471974) (xy 96.701322 111.422369) (xy 96.716685 111.370044)
			(xy 96.724446 111.316067) (xy 96.724446 111.261534) (xy 96.716685 111.207556) (xy 96.701322 111.155231)
			(xy 96.678668 111.105626) (xy 96.649186 111.05975) (xy 96.613476 111.018536) (xy 96.572263 110.982823)
			(xy 96.526388 110.953339) (xy 96.476784 110.930684) (xy 96.42446 110.915318) (xy 96.370482 110.907555)
			(xy 96.343216 110.907068) (xy 95.479616 110.907068) (xy 95.452342 110.90747) (xy 95.398349 110.915231)
			(xy 95.346011 110.930597) (xy 95.296392 110.953256) (xy 95.250502 110.982745) (xy 95.209277 111.018466)
			(xy 95.173555 111.059689) (xy 95.144064 111.105577) (xy 95.121403 111.155196) (xy 95.106035 111.207534)
			(xy 95.098272 111.261526) (xy 92.50807 111.261526) (xy 92.50807 109.256627) (xy 93.714049 109.256627)
			(xy 93.714049 109.342377) (xy 93.721961 109.42776) (xy 93.737717 109.51205) (xy 93.761184 109.594526)
			(xy 93.79216 109.674485) (xy 93.830382 109.751245) (xy 93.875523 109.824151) (xy 93.927199 109.89258)
			(xy 93.984968 109.95595) (xy 94.048338 110.013719) (xy 94.116767 110.065395) (xy 94.189673 110.110536)
			(xy 94.266433 110.148758) (xy 94.346392 110.179734) (xy 94.428868 110.203201) (xy 94.513158 110.218957)
			(xy 94.598541 110.226869) (xy 94.684291 110.226869) (xy 94.769674 110.218957) (xy 94.853964 110.203201)
			(xy 94.93644 110.179734) (xy 95.016399 110.148758) (xy 95.093159 110.110536) (xy 95.166065 110.065395)
			(xy 95.234494 110.013719) (xy 95.297864 109.95595) (xy 95.355633 109.89258) (xy 95.407309 109.824151)
			(xy 95.45245 109.751245) (xy 95.490672 109.674485) (xy 95.521648 109.594526) (xy 95.545115 109.51205)
			(xy 95.560871 109.42776) (xy 95.568783 109.342377) (xy 95.569278 109.299502) (xy 95.568783 109.256627)
			(xy 96.254049 109.256627) (xy 96.254049 109.342377) (xy 96.261961 109.42776) (xy 96.277717 109.51205)
			(xy 96.301184 109.594526) (xy 96.33216 109.674485) (xy 96.370382 109.751245) (xy 96.415523 109.824151)
			(xy 96.467199 109.89258) (xy 96.524968 109.95595) (xy 96.588338 110.013719) (xy 96.656767 110.065395)
			(xy 96.729673 110.110536) (xy 96.806433 110.148758) (xy 96.886392 110.179734) (xy 96.968868 110.203201)
			(xy 97.053158 110.218957) (xy 97.138541 110.226869) (xy 97.224291 110.226869) (xy 97.309674 110.218957)
			(xy 97.393964 110.203201) (xy 97.47644 110.179734) (xy 97.556399 110.148758) (xy 97.633159 110.110536)
			(xy 97.706065 110.065395) (xy 97.774494 110.013719) (xy 97.837864 109.95595) (xy 97.895633 109.89258)
			(xy 97.947309 109.824151) (xy 97.99245 109.751245) (xy 98.030672 109.674485) (xy 98.061648 109.594526)
			(xy 98.085115 109.51205) (xy 98.100871 109.42776) (xy 98.108783 109.342377) (xy 98.109278 109.299502)
			(xy 98.108783 109.256627) (xy 98.100871 109.171244) (xy 98.085115 109.086954) (xy 98.061648 109.004478)
			(xy 98.030672 108.924519) (xy 97.99245 108.847759) (xy 97.947309 108.774853) (xy 97.895633 108.706424)
			(xy 97.837864 108.643054) (xy 97.774494 108.585285) (xy 97.706065 108.533609) (xy 97.633159 108.488468)
			(xy 97.556399 108.450246) (xy 97.47644 108.41927) (xy 97.393964 108.395803) (xy 97.309674 108.380047)
			(xy 97.224291 108.372135) (xy 97.138541 108.372135) (xy 97.053158 108.380047) (xy 96.968868 108.395803)
			(xy 96.886392 108.41927) (xy 96.806433 108.450246) (xy 96.729673 108.488468) (xy 96.656767 108.533609)
			(xy 96.588338 108.585285) (xy 96.524968 108.643054) (xy 96.467199 108.706424) (xy 96.415523 108.774853)
			(xy 96.370382 108.847759) (xy 96.33216 108.924519) (xy 96.301184 109.004478) (xy 96.277717 109.086954)
			(xy 96.261961 109.171244) (xy 96.254049 109.256627) (xy 95.568783 109.256627) (xy 95.560871 109.171244)
			(xy 95.545115 109.086954) (xy 95.521648 109.004478) (xy 95.490672 108.924519) (xy 95.45245 108.847759)
			(xy 95.407309 108.774853) (xy 95.355633 108.706424) (xy 95.297864 108.643054) (xy 95.234494 108.585285)
			(xy 95.166065 108.533609) (xy 95.093159 108.488468) (xy 95.016399 108.450246) (xy 94.93644 108.41927)
			(xy 94.853964 108.395803) (xy 94.769674 108.380047) (xy 94.684291 108.372135) (xy 94.598541 108.372135)
			(xy 94.513158 108.380047) (xy 94.428868 108.395803) (xy 94.346392 108.41927) (xy 94.266433 108.450246)
			(xy 94.189673 108.488468) (xy 94.116767 108.533609) (xy 94.048338 108.585285) (xy 93.984968 108.643054)
			(xy 93.927199 108.706424) (xy 93.875523 108.774853) (xy 93.830382 108.847759) (xy 93.79216 108.924519)
			(xy 93.761184 109.004478) (xy 93.737717 109.086954) (xy 93.721961 109.171244) (xy 93.714049 109.256627)
			(xy 92.50807 109.256627) (xy 92.50807 56.800039) (xy 93.729289 56.800039) (xy 93.729289 56.885789)
			(xy 93.737201 56.971172) (xy 93.752957 57.055462) (xy 93.776424 57.137938) (xy 93.8074 57.217897)
			(xy 93.845622 57.294657) (xy 93.890763 57.367563) (xy 93.942439 57.435992) (xy 94.000208 57.499362)
			(xy 94.063578 57.557131) (xy 94.132007 57.608807) (xy 94.204913 57.653948) (xy 94.281673 57.69217)
			(xy 94.361632 57.723146) (xy 94.444108 57.746613) (xy 94.528398 57.762369) (xy 94.613781 57.770281)
			(xy 94.699531 57.770281) (xy 94.784914 57.762369) (xy 94.869204 57.746613) (xy 94.95168 57.723146)
			(xy 95.031639 57.69217) (xy 95.108399 57.653948) (xy 95.181305 57.608807) (xy 95.249734 57.557131)
			(xy 95.313104 57.499362) (xy 95.370873 57.435992) (xy 95.422549 57.367563) (xy 95.46769 57.294657)
			(xy 95.505912 57.217897) (xy 95.536888 57.137938) (xy 95.560355 57.055462) (xy 95.576111 56.971172)
			(xy 95.584023 56.885789) (xy 95.584518 56.842914) (xy 95.584023 56.800039) (xy 96.269289 56.800039)
			(xy 96.269289 56.885789) (xy 96.277201 56.971172) (xy 96.292957 57.055462) (xy 96.316424 57.137938)
			(xy 96.3474 57.217897) (xy 96.385622 57.294657) (xy 96.430763 57.367563) (xy 96.482439 57.435992)
			(xy 96.540208 57.499362) (xy 96.603578 57.557131) (xy 96.672007 57.608807) (xy 96.744913 57.653948)
			(xy 96.821673 57.69217) (xy 96.901632 57.723146) (xy 96.984108 57.746613) (xy 97.068398 57.762369)
			(xy 97.153781 57.770281) (xy 97.239531 57.770281) (xy 97.324914 57.762369) (xy 97.409204 57.746613)
			(xy 97.49168 57.723146) (xy 97.571639 57.69217) (xy 97.648399 57.653948) (xy 97.721305 57.608807)
			(xy 97.789734 57.557131) (xy 97.853104 57.499362) (xy 97.910873 57.435992) (xy 97.962549 57.367563)
			(xy 98.00769 57.294657) (xy 98.045912 57.217897) (xy 98.076888 57.137938) (xy 98.100355 57.055462)
			(xy 98.116111 56.971172) (xy 98.124023 56.885789) (xy 98.124518 56.842914) (xy 98.124023 56.800039)
			(xy 98.116111 56.714656) (xy 98.100355 56.630366) (xy 98.076888 56.54789) (xy 98.045912 56.467931)
			(xy 98.00769 56.391171) (xy 97.962549 56.318265) (xy 97.910873 56.249836) (xy 97.853104 56.186466)
			(xy 97.789734 56.128697) (xy 97.721305 56.077021) (xy 97.648399 56.03188) (xy 97.571639 55.993658)
			(xy 97.49168 55.962682) (xy 97.409204 55.939215) (xy 97.324914 55.923459) (xy 97.239531 55.915547)
			(xy 97.153781 55.915547) (xy 97.068398 55.923459) (xy 96.984108 55.939215) (xy 96.901632 55.962682)
			(xy 96.821673 55.993658) (xy 96.744913 56.03188) (xy 96.672007 56.077021) (xy 96.603578 56.128697)
			(xy 96.540208 56.186466) (xy 96.482439 56.249836) (xy 96.430763 56.318265) (xy 96.385622 56.391171)
			(xy 96.3474 56.467931) (xy 96.316424 56.54789) (xy 96.292957 56.630366) (xy 96.277201 56.714656)
			(xy 96.269289 56.800039) (xy 95.584023 56.800039) (xy 95.576111 56.714656) (xy 95.560355 56.630366)
			(xy 95.536888 56.54789) (xy 95.505912 56.467931) (xy 95.46769 56.391171) (xy 95.422549 56.318265)
			(xy 95.370873 56.249836) (xy 95.313104 56.186466) (xy 95.249734 56.128697) (xy 95.181305 56.077021)
			(xy 95.108399 56.03188) (xy 95.031639 55.993658) (xy 94.95168 55.962682) (xy 94.869204 55.939215)
			(xy 94.784914 55.923459) (xy 94.699531 55.915547) (xy 94.613781 55.915547) (xy 94.528398 55.923459)
			(xy 94.444108 55.939215) (xy 94.361632 55.962682) (xy 94.281673 55.993658) (xy 94.204913 56.03188)
			(xy 94.132007 56.077021) (xy 94.063578 56.128697) (xy 94.000208 56.186466) (xy 93.942439 56.249836)
			(xy 93.890763 56.318265) (xy 93.845622 56.391171) (xy 93.8074 56.467931) (xy 93.776424 56.54789)
			(xy 93.752957 56.630366) (xy 93.737201 56.714656) (xy 93.729289 56.800039) (xy 92.50807 56.800039)
			(xy 92.50807 54.826334) (xy 95.113638 54.826334) (xy 95.113638 54.880866) (xy 95.121398 54.934844)
			(xy 95.136761 54.987168) (xy 95.159413 55.036774) (xy 95.188894 55.082651) (xy 95.224603 55.123866)
			(xy 95.265814 55.15958) (xy 95.311688 55.189066) (xy 95.36129 55.211724) (xy 95.413613 55.227092)
			(xy 95.46759 55.234859) (xy 95.494856 55.235348) (xy 96.358456 55.235348) (xy 96.38573 55.234915)
			(xy 96.439724 55.227158) (xy 96.492064 55.211795) (xy 96.541684 55.189139) (xy 96.587575 55.159652)
			(xy 96.628802 55.123933) (xy 96.664525 55.08271) (xy 96.694018 55.036823) (xy 96.71668 54.987205)
			(xy 96.732049 54.934867) (xy 96.739812 54.880874) (xy 96.739812 54.826326) (xy 96.732049 54.772333)
			(xy 96.71668 54.719995) (xy 96.694018 54.670377) (xy 96.664525 54.62449) (xy 96.628802 54.583267)
			(xy 96.587575 54.547548) (xy 96.541684 54.518061) (xy 96.492064 54.495405) (xy 96.439724 54.480042)
			(xy 96.38573 54.472285) (xy 96.358456 54.471824) (xy 95.494856 54.471824) (xy 95.46759 54.472341)
			(xy 95.413613 54.480108) (xy 95.36129 54.495476) (xy 95.311688 54.518134) (xy 95.265814 54.54762)
			(xy 95.224603 54.583334) (xy 95.188894 54.624549) (xy 95.159413 54.670426) (xy 95.136761 54.720032)
			(xy 95.121399 54.772356) (xy 95.113638 54.826334) (xy 92.50807 54.826334) (xy 92.50807 50.450039)
			(xy 93.729289 50.450039) (xy 93.729289 50.535789) (xy 93.737201 50.621172) (xy 93.752957 50.705462)
			(xy 93.776424 50.787938) (xy 93.8074 50.867897) (xy 93.845622 50.944657) (xy 93.890763 51.017563)
			(xy 93.942439 51.085992) (xy 94.000208 51.149362) (xy 94.063578 51.207131) (xy 94.132007 51.258807)
			(xy 94.204913 51.303948) (xy 94.281673 51.34217) (xy 94.361632 51.373146) (xy 94.444108 51.396613)
			(xy 94.528398 51.412369) (xy 94.613781 51.420281) (xy 94.699531 51.420281) (xy 94.784914 51.412369)
			(xy 94.869204 51.396613) (xy 94.95168 51.373146) (xy 95.031639 51.34217) (xy 95.108399 51.303948)
			(xy 95.181305 51.258807) (xy 95.249734 51.207131) (xy 95.313104 51.149362) (xy 95.370873 51.085992)
			(xy 95.422549 51.017563) (xy 95.46769 50.944657) (xy 95.505912 50.867897) (xy 95.536888 50.787938)
			(xy 95.560355 50.705462) (xy 95.576111 50.621172) (xy 95.584023 50.535789) (xy 95.584518 50.492914)
			(xy 95.584023 50.450039) (xy 96.269289 50.450039) (xy 96.269289 50.535789) (xy 96.277201 50.621172)
			(xy 96.292957 50.705462) (xy 96.316424 50.787938) (xy 96.3474 50.867897) (xy 96.385622 50.944657)
			(xy 96.430763 51.017563) (xy 96.482439 51.085992) (xy 96.540208 51.149362) (xy 96.603578 51.207131)
			(xy 96.672007 51.258807) (xy 96.744913 51.303948) (xy 96.821673 51.34217) (xy 96.901632 51.373146)
			(xy 96.984108 51.396613) (xy 97.068398 51.412369) (xy 97.153781 51.420281) (xy 97.239531 51.420281)
			(xy 97.324914 51.412369) (xy 97.409204 51.396613) (xy 97.49168 51.373146) (xy 97.571639 51.34217)
			(xy 97.648399 51.303948) (xy 97.721305 51.258807) (xy 97.789734 51.207131) (xy 97.853104 51.149362)
			(xy 97.910873 51.085992) (xy 97.962549 51.017563) (xy 98.00769 50.944657) (xy 98.045912 50.867897)
			(xy 98.076888 50.787938) (xy 98.100355 50.705462) (xy 98.116111 50.621172) (xy 98.124023 50.535789)
			(xy 98.124518 50.492914) (xy 98.124023 50.450039) (xy 98.116111 50.364656) (xy 98.100355 50.280366)
			(xy 98.076888 50.19789) (xy 98.045912 50.117931) (xy 98.00769 50.041171) (xy 97.962549 49.968265)
			(xy 97.910873 49.899836) (xy 97.853104 49.836466) (xy 97.789734 49.778697) (xy 97.721305 49.727021)
			(xy 97.648399 49.68188) (xy 97.571639 49.643658) (xy 97.49168 49.612682) (xy 97.409204 49.589215)
			(xy 97.324914 49.573459) (xy 97.239531 49.565547) (xy 97.153781 49.565547) (xy 97.068398 49.573459)
			(xy 96.984108 49.589215) (xy 96.901632 49.612682) (xy 96.821673 49.643658) (xy 96.744913 49.68188)
			(xy 96.672007 49.727021) (xy 96.603578 49.778697) (xy 96.540208 49.836466) (xy 96.482439 49.899836)
			(xy 96.430763 49.968265) (xy 96.385622 50.041171) (xy 96.3474 50.117931) (xy 96.316424 50.19789)
			(xy 96.292957 50.280366) (xy 96.277201 50.364656) (xy 96.269289 50.450039) (xy 95.584023 50.450039)
			(xy 95.576111 50.364656) (xy 95.560355 50.280366) (xy 95.536888 50.19789) (xy 95.505912 50.117931)
			(xy 95.46769 50.041171) (xy 95.422549 49.968265) (xy 95.370873 49.899836) (xy 95.313104 49.836466)
			(xy 95.249734 49.778697) (xy 95.181305 49.727021) (xy 95.108399 49.68188) (xy 95.031639 49.643658)
			(xy 94.95168 49.612682) (xy 94.869204 49.589215) (xy 94.784914 49.573459) (xy 94.699531 49.565547)
			(xy 94.613781 49.565547) (xy 94.528398 49.573459) (xy 94.444108 49.589215) (xy 94.361632 49.612682)
			(xy 94.281673 49.643658) (xy 94.204913 49.68188) (xy 94.132007 49.727021) (xy 94.063578 49.778697)
			(xy 94.000208 49.836466) (xy 93.942439 49.899836) (xy 93.890763 49.968265) (xy 93.845622 50.041171)
			(xy 93.8074 50.117931) (xy 93.776424 50.19789) (xy 93.752957 50.280366) (xy 93.737201 50.364656)
			(xy 93.729289 50.450039) (xy 92.50807 50.450039) (xy 92.50807 44.925539) (xy 93.706937 44.925539)
			(xy 93.706937 45.011289) (xy 93.714849 45.096672) (xy 93.730605 45.180962) (xy 93.754072 45.263438)
			(xy 93.785048 45.343397) (xy 93.82327 45.420157) (xy 93.868411 45.493063) (xy 93.920087 45.561492)
			(xy 93.977856 45.624862) (xy 94.041226 45.682631) (xy 94.109655 45.734307) (xy 94.182561 45.779448)
			(xy 94.259321 45.81767) (xy 94.33928 45.848646) (xy 94.421756 45.872113) (xy 94.506046 45.887869)
			(xy 94.591429 45.895781) (xy 94.677179 45.895781) (xy 94.762562 45.887869) (xy 94.846852 45.872113)
			(xy 94.929328 45.848646) (xy 95.009287 45.81767) (xy 95.086047 45.779448) (xy 95.158953 45.734307)
			(xy 95.227382 45.682631) (xy 95.290752 45.624862) (xy 95.348521 45.561492) (xy 95.400197 45.493063)
			(xy 95.445338 45.420157) (xy 95.48356 45.343397) (xy 95.514536 45.263438) (xy 95.538003 45.180962)
			(xy 95.553759 45.096672) (xy 95.561671 45.011289) (xy 95.562166 44.968414) (xy 95.561671 44.925539)
			(xy 96.246937 44.925539) (xy 96.246937 45.011289) (xy 96.254849 45.096672) (xy 96.270605 45.180962)
			(xy 96.294072 45.263438) (xy 96.325048 45.343397) (xy 96.36327 45.420157) (xy 96.408411 45.493063)
			(xy 96.460087 45.561492) (xy 96.517856 45.624862) (xy 96.581226 45.682631) (xy 96.649655 45.734307)
			(xy 96.722561 45.779448) (xy 96.799321 45.81767) (xy 96.87928 45.848646) (xy 96.961756 45.872113)
			(xy 97.046046 45.887869) (xy 97.131429 45.895781) (xy 97.217179 45.895781) (xy 97.302562 45.887869)
			(xy 97.386852 45.872113) (xy 97.469328 45.848646) (xy 97.549287 45.81767) (xy 97.626047 45.779448)
			(xy 97.698953 45.734307) (xy 97.767382 45.682631) (xy 97.830752 45.624862) (xy 97.888521 45.561492)
			(xy 97.940197 45.493063) (xy 97.985338 45.420157) (xy 98.02356 45.343397) (xy 98.054536 45.263438)
			(xy 98.078003 45.180962) (xy 98.093759 45.096672) (xy 98.101671 45.011289) (xy 98.102166 44.968414)
			(xy 98.101671 44.925539) (xy 98.093759 44.840156) (xy 98.078003 44.755866) (xy 98.054536 44.67339)
			(xy 98.02356 44.593431) (xy 97.985338 44.516671) (xy 97.940197 44.443765) (xy 97.888521 44.375336)
			(xy 97.830752 44.311966) (xy 97.767382 44.254197) (xy 97.698953 44.202521) (xy 97.626047 44.15738)
			(xy 97.549287 44.119158) (xy 97.469328 44.088182) (xy 97.386852 44.064715) (xy 97.302562 44.048959)
			(xy 97.217179 44.041047) (xy 97.131429 44.041047) (xy 97.046046 44.048959) (xy 96.961756 44.064715)
			(xy 96.87928 44.088182) (xy 96.799321 44.119158) (xy 96.722561 44.15738) (xy 96.649655 44.202521)
			(xy 96.581226 44.254197) (xy 96.517856 44.311966) (xy 96.460087 44.375336) (xy 96.408411 44.443765)
			(xy 96.36327 44.516671) (xy 96.325048 44.593431) (xy 96.294072 44.67339) (xy 96.270605 44.755866)
			(xy 96.254849 44.840156) (xy 96.246937 44.925539) (xy 95.561671 44.925539) (xy 95.553759 44.840156)
			(xy 95.538003 44.755866) (xy 95.514536 44.67339) (xy 95.48356 44.593431) (xy 95.445338 44.516671)
			(xy 95.400197 44.443765) (xy 95.348521 44.375336) (xy 95.290752 44.311966) (xy 95.227382 44.254197)
			(xy 95.158953 44.202521) (xy 95.086047 44.15738) (xy 95.009287 44.119158) (xy 94.929328 44.088182)
			(xy 94.846852 44.064715) (xy 94.762562 44.048959) (xy 94.677179 44.041047) (xy 94.591429 44.041047)
			(xy 94.506046 44.048959) (xy 94.421756 44.064715) (xy 94.33928 44.088182) (xy 94.259321 44.119158)
			(xy 94.182561 44.15738) (xy 94.109655 44.202521) (xy 94.041226 44.254197) (xy 93.977856 44.311966)
			(xy 93.920087 44.375336) (xy 93.868411 44.443765) (xy 93.82327 44.516671) (xy 93.785048 44.593431)
			(xy 93.754072 44.67339) (xy 93.730605 44.755866) (xy 93.714849 44.840156) (xy 93.706937 44.925539)
			(xy 92.50807 44.925539) (xy 92.50807 40.580426) (xy 95.09116 40.580426) (xy 95.09116 40.634974) (xy 95.098923 40.688967)
			(xy 95.114291 40.741306) (xy 95.136951 40.790925) (xy 95.166442 40.836814) (xy 95.202164 40.878039)
			(xy 95.243389 40.91376) (xy 95.289279 40.943251) (xy 95.338898 40.965911) (xy 95.391237 40.981278)
			(xy 95.44523 40.989041) (xy 95.472504 40.989504) (xy 96.336104 40.989504) (xy 96.36337 40.988933)
			(xy 96.417347 40.981172) (xy 96.469671 40.965808) (xy 96.519275 40.943154) (xy 96.56515 40.913671)
			(xy 96.606363 40.87796) (xy 96.642074 40.836747) (xy 96.671556 40.790871) (xy 96.69421 40.741267)
			(xy 96.709573 40.688944) (xy 96.717334 40.634966) (xy 96.717334 40.580434) (xy 96.709573 40.526456)
			(xy 96.69421 40.474133) (xy 96.671556 40.424529) (xy 96.642074 40.378653) (xy 96.606363 40.33744)
			(xy 96.56515 40.301729) (xy 96.519275 40.272246) (xy 96.469671 40.249592) (xy 96.417347 40.234228)
			(xy 96.36337 40.226467) (xy 96.336104 40.22598) (xy 95.472504 40.22598) (xy 95.44523 40.226359) (xy 95.391237 40.234122)
			(xy 95.338898 40.249489) (xy 95.289279 40.272149) (xy 95.243389 40.30164) (xy 95.202164 40.337361)
			(xy 95.166442 40.378586) (xy 95.136951 40.424475) (xy 95.114291 40.474094) (xy 95.098923 40.526433)
			(xy 95.09116 40.580426) (xy 92.50807 40.580426) (xy 92.50807 38.575539) (xy 93.706937 38.575539)
			(xy 93.706937 38.661289) (xy 93.714849 38.746672) (xy 93.730605 38.830962) (xy 93.754072 38.913438)
			(xy 93.785048 38.993397) (xy 93.82327 39.070157) (xy 93.868411 39.143063) (xy 93.920087 39.211492)
			(xy 93.977856 39.274862) (xy 94.041226 39.332631) (xy 94.109655 39.384307) (xy 94.182561 39.429448)
			(xy 94.259321 39.46767) (xy 94.33928 39.498646) (xy 94.421756 39.522113) (xy 94.506046 39.537869)
			(xy 94.591429 39.545781) (xy 94.677179 39.545781) (xy 94.762562 39.537869) (xy 94.846852 39.522113)
			(xy 94.929328 39.498646) (xy 95.009287 39.46767) (xy 95.086047 39.429448) (xy 95.158953 39.384307)
			(xy 95.227382 39.332631) (xy 95.290752 39.274862) (xy 95.348521 39.211492) (xy 95.400197 39.143063)
			(xy 95.445338 39.070157) (xy 95.48356 38.993397) (xy 95.514536 38.913438) (xy 95.538003 38.830962)
			(xy 95.553759 38.746672) (xy 95.561671 38.661289) (xy 95.562166 38.618414) (xy 95.561671 38.575539)
			(xy 96.246937 38.575539) (xy 96.246937 38.661289) (xy 96.254849 38.746672) (xy 96.270605 38.830962)
			(xy 96.294072 38.913438) (xy 96.325048 38.993397) (xy 96.36327 39.070157) (xy 96.408411 39.143063)
			(xy 96.460087 39.211492) (xy 96.517856 39.274862) (xy 96.581226 39.332631) (xy 96.649655 39.384307)
			(xy 96.722561 39.429448) (xy 96.799321 39.46767) (xy 96.87928 39.498646) (xy 96.961756 39.522113)
			(xy 97.046046 39.537869) (xy 97.131429 39.545781) (xy 97.217179 39.545781) (xy 97.302562 39.537869)
			(xy 97.386852 39.522113) (xy 97.469328 39.498646) (xy 97.549287 39.46767) (xy 97.626047 39.429448)
			(xy 97.698953 39.384307) (xy 97.767382 39.332631) (xy 97.830752 39.274862) (xy 97.888521 39.211492)
			(xy 97.940197 39.143063) (xy 97.985338 39.070157) (xy 98.02356 38.993397) (xy 98.054536 38.913438)
			(xy 98.078003 38.830962) (xy 98.093759 38.746672) (xy 98.101671 38.661289) (xy 98.102166 38.618414)
			(xy 98.101671 38.575539) (xy 98.093759 38.490156) (xy 98.078003 38.405866) (xy 98.054536 38.32339)
			(xy 98.02356 38.243431) (xy 97.985338 38.166671) (xy 97.940197 38.093765) (xy 97.888521 38.025336)
			(xy 97.830752 37.961966) (xy 97.767382 37.904197) (xy 97.698953 37.852521) (xy 97.626047 37.80738)
			(xy 97.549287 37.769158) (xy 97.469328 37.738182) (xy 97.386852 37.714715) (xy 97.302562 37.698959)
			(xy 97.217179 37.691047) (xy 97.131429 37.691047) (xy 97.046046 37.698959) (xy 96.961756 37.714715)
			(xy 96.87928 37.738182) (xy 96.799321 37.769158) (xy 96.722561 37.80738) (xy 96.649655 37.852521)
			(xy 96.581226 37.904197) (xy 96.517856 37.961966) (xy 96.460087 38.025336) (xy 96.408411 38.093765)
			(xy 96.36327 38.166671) (xy 96.325048 38.243431) (xy 96.294072 38.32339) (xy 96.270605 38.405866)
			(xy 96.254849 38.490156) (xy 96.246937 38.575539) (xy 95.561671 38.575539) (xy 95.553759 38.490156)
			(xy 95.538003 38.405866) (xy 95.514536 38.32339) (xy 95.48356 38.243431) (xy 95.445338 38.166671)
			(xy 95.400197 38.093765) (xy 95.348521 38.025336) (xy 95.290752 37.961966) (xy 95.227382 37.904197)
			(xy 95.158953 37.852521) (xy 95.086047 37.80738) (xy 95.009287 37.769158) (xy 94.929328 37.738182)
			(xy 94.846852 37.714715) (xy 94.762562 37.698959) (xy 94.677179 37.691047) (xy 94.591429 37.691047)
			(xy 94.506046 37.698959) (xy 94.421756 37.714715) (xy 94.33928 37.738182) (xy 94.259321 37.769158)
			(xy 94.182561 37.80738) (xy 94.109655 37.852521) (xy 94.041226 37.904197) (xy 93.977856 37.961966)
			(xy 93.920087 38.025336) (xy 93.868411 38.093765) (xy 93.82327 38.166671) (xy 93.785048 38.243431)
			(xy 93.754072 38.32339) (xy 93.730605 38.405866) (xy 93.714849 38.490156) (xy 93.706937 38.575539)
			(xy 92.50807 38.575539) (xy 92.50807 32.685787) (xy 99.092753 32.685787) (xy 99.092753 32.771537)
			(xy 99.100665 32.85692) (xy 99.116421 32.94121) (xy 99.139888 33.023686) (xy 99.170864 33.103645)
			(xy 99.209086 33.180405) (xy 99.254227 33.253311) (xy 99.305903 33.32174) (xy 99.363672 33.38511)
			(xy 99.427042 33.442879) (xy 99.495471 33.494555) (xy 99.568377 33.539696) (xy 99.645137 33.577918)
			(xy 99.725096 33.608894) (xy 99.807572 33.632361) (xy 99.891862 33.648117) (xy 99.977245 33.656029)
			(xy 100.062995 33.656029) (xy 100.148378 33.648117) (xy 100.232668 33.632361) (xy 100.315144 33.608894)
			(xy 100.395103 33.577918) (xy 100.471863 33.539696) (xy 100.544769 33.494555) (xy 100.613198 33.442879)
			(xy 100.676568 33.38511) (xy 100.734337 33.32174) (xy 100.786013 33.253311) (xy 100.831154 33.180405)
			(xy 100.869376 33.103645) (xy 100.900352 33.023686) (xy 100.923819 32.94121) (xy 100.939575 32.85692)
			(xy 100.947487 32.771537) (xy 100.947982 32.728662) (xy 100.947487 32.685787) (xy 101.632753 32.685787)
			(xy 101.632753 32.771537) (xy 101.640665 32.85692) (xy 101.656421 32.94121) (xy 101.679888 33.023686)
			(xy 101.710864 33.103645) (xy 101.749086 33.180405) (xy 101.794227 33.253311) (xy 101.845903 33.32174)
			(xy 101.903672 33.38511) (xy 101.967042 33.442879) (xy 102.035471 33.494555) (xy 102.108377 33.539696)
			(xy 102.185137 33.577918) (xy 102.265096 33.608894) (xy 102.347572 33.632361) (xy 102.431862 33.648117)
			(xy 102.517245 33.656029) (xy 102.602995 33.656029) (xy 102.688378 33.648117) (xy 102.772668 33.632361)
			(xy 102.855144 33.608894) (xy 102.935103 33.577918) (xy 103.011863 33.539696) (xy 103.084769 33.494555)
			(xy 103.153198 33.442879) (xy 103.216568 33.38511) (xy 103.274337 33.32174) (xy 103.326013 33.253311)
			(xy 103.371154 33.180405) (xy 103.409376 33.103645) (xy 103.440352 33.023686) (xy 103.463819 32.94121)
			(xy 103.479575 32.85692) (xy 103.487487 32.771537) (xy 103.487982 32.728662) (xy 103.487487 32.685787)
			(xy 103.479575 32.600404) (xy 103.463819 32.516114) (xy 103.440352 32.433638) (xy 103.409376 32.353679)
			(xy 103.371154 32.276919) (xy 103.326013 32.204013) (xy 103.274337 32.135584) (xy 103.216568 32.072214)
			(xy 103.153198 32.014445) (xy 103.084769 31.962769) (xy 103.011863 31.917628) (xy 102.935103 31.879406)
			(xy 102.855144 31.84843) (xy 102.772668 31.824963) (xy 102.688378 31.809207) (xy 102.602995 31.801295)
			(xy 102.517245 31.801295) (xy 102.431862 31.809207) (xy 102.347572 31.824963) (xy 102.265096 31.84843)
			(xy 102.185137 31.879406) (xy 102.108377 31.917628) (xy 102.035471 31.962769) (xy 101.967042 32.014445)
			(xy 101.903672 32.072214) (xy 101.845903 32.135584) (xy 101.794227 32.204013) (xy 101.749086 32.276919)
			(xy 101.710864 32.353679) (xy 101.679888 32.433638) (xy 101.656421 32.516114) (xy 101.640665 32.600404)
			(xy 101.632753 32.685787) (xy 100.947487 32.685787) (xy 100.939575 32.600404) (xy 100.923819 32.516114)
			(xy 100.900352 32.433638) (xy 100.869376 32.353679) (xy 100.831154 32.276919) (xy 100.786013 32.204013)
			(xy 100.734337 32.135584) (xy 100.676568 32.072214) (xy 100.613198 32.014445) (xy 100.544769 31.962769)
			(xy 100.471863 31.917628) (xy 100.395103 31.879406) (xy 100.315144 31.84843) (xy 100.232668 31.824963)
			(xy 100.148378 31.809207) (xy 100.062995 31.801295) (xy 99.977245 31.801295) (xy 99.891862 31.809207)
			(xy 99.807572 31.824963) (xy 99.725096 31.84843) (xy 99.645137 31.879406) (xy 99.568377 31.917628)
			(xy 99.495471 31.962769) (xy 99.427042 32.014445) (xy 99.363672 32.072214) (xy 99.305903 32.135584)
			(xy 99.254227 32.204013) (xy 99.209086 32.276919) (xy 99.170864 32.353679) (xy 99.139888 32.433638)
			(xy 99.116421 32.516114) (xy 99.100665 32.600404) (xy 99.092753 32.685787) (xy 92.50807 32.685787)
			(xy 92.50807 30.712026) (xy 100.476968 30.712026) (xy 100.476968 30.766574) (xy 100.484731 30.820568)
			(xy 100.5001 30.872907) (xy 100.522761 30.922526) (xy 100.552253 30.968414) (xy 100.587976 31.009639)
			(xy 100.629202 31.045359) (xy 100.675092 31.074849) (xy 100.724712 31.097507) (xy 100.777052 31.112873)
			(xy 100.831046 31.120634) (xy 100.85832 31.121096) (xy 101.72192 31.121096) (xy 101.749186 31.12054)
			(xy 101.803163 31.112777) (xy 101.855485 31.097411) (xy 101.905088 31.074756) (xy 101.950963 31.045272)
			(xy 101.992174 31.00956) (xy 102.027884 30.968347) (xy 102.057366 30.922471) (xy 102.080018 30.872866)
			(xy 102.095381 30.820543) (xy 102.103142 30.766566) (xy 102.103142 30.712034) (xy 102.095381 30.658057)
			(xy 102.080018 30.605734) (xy 102.057366 30.556129) (xy 102.027884 30.510253) (xy 101.992174 30.46904)
			(xy 101.950963 30.433328) (xy 101.905088 30.403844) (xy 101.855485 30.381189) (xy 101.803163 30.365823)
			(xy 101.749186 30.35806) (xy 101.72192 30.357572) (xy 100.85832 30.357572) (xy 100.831046 30.357966)
			(xy 100.777052 30.365727) (xy 100.724712 30.381093) (xy 100.675092 30.403751) (xy 100.629202 30.433241)
			(xy 100.587976 30.468961) (xy 100.552253 30.510186) (xy 100.522761 30.556074) (xy 100.5001 30.605693)
			(xy 100.484731 30.658032) (xy 100.476968 30.712026) (xy 92.50807 30.712026) (xy 92.50807 26.335787)
			(xy 99.092753 26.335787) (xy 99.092753 26.421537) (xy 99.100665 26.50692) (xy 99.116421 26.59121)
			(xy 99.139888 26.673686) (xy 99.170864 26.753645) (xy 99.209086 26.830405) (xy 99.254227 26.903311)
			(xy 99.305903 26.97174) (xy 99.363672 27.03511) (xy 99.427042 27.092879) (xy 99.495471 27.144555)
			(xy 99.568377 27.189696) (xy 99.645137 27.227918) (xy 99.725096 27.258894) (xy 99.807572 27.282361)
			(xy 99.891862 27.298117) (xy 99.977245 27.306029) (xy 100.062995 27.306029) (xy 100.148378 27.298117)
			(xy 100.232668 27.282361) (xy 100.315144 27.258894) (xy 100.395103 27.227918) (xy 100.471863 27.189696)
			(xy 100.544769 27.144555) (xy 100.613198 27.092879) (xy 100.676568 27.03511) (xy 100.734337 26.97174)
			(xy 100.786013 26.903311) (xy 100.831154 26.830405) (xy 100.869376 26.753645) (xy 100.900352 26.673686)
			(xy 100.923819 26.59121) (xy 100.939575 26.50692) (xy 100.947487 26.421537) (xy 100.947982 26.378662)
			(xy 100.947487 26.335787) (xy 101.632753 26.335787) (xy 101.632753 26.421537) (xy 101.640665 26.50692)
			(xy 101.656421 26.59121) (xy 101.679888 26.673686) (xy 101.710864 26.753645) (xy 101.749086 26.830405)
			(xy 101.794227 26.903311) (xy 101.845903 26.97174) (xy 101.903672 27.03511) (xy 101.967042 27.092879)
			(xy 102.035471 27.144555) (xy 102.108377 27.189696) (xy 102.185137 27.227918) (xy 102.265096 27.258894)
			(xy 102.347572 27.282361) (xy 102.431862 27.298117) (xy 102.517245 27.306029) (xy 102.602995 27.306029)
			(xy 102.688378 27.298117) (xy 102.772668 27.282361) (xy 102.855144 27.258894) (xy 102.935103 27.227918)
			(xy 103.011863 27.189696) (xy 103.084769 27.144555) (xy 103.153198 27.092879) (xy 103.216568 27.03511)
			(xy 103.274337 26.97174) (xy 103.326013 26.903311) (xy 103.371154 26.830405) (xy 103.409376 26.753645)
			(xy 103.440352 26.673686) (xy 103.463819 26.59121) (xy 103.479575 26.50692) (xy 103.487487 26.421537)
			(xy 103.487982 26.378662) (xy 103.487487 26.335787) (xy 103.479575 26.250404) (xy 103.463819 26.166114)
			(xy 103.440352 26.083638) (xy 103.409376 26.003679) (xy 103.371154 25.926919) (xy 103.326013 25.854013)
			(xy 103.274337 25.785584) (xy 103.216568 25.722214) (xy 103.153198 25.664445) (xy 103.084769 25.612769)
			(xy 103.011863 25.567628) (xy 102.935103 25.529406) (xy 102.855144 25.49843) (xy 102.772668 25.474963)
			(xy 102.688378 25.459207) (xy 102.602995 25.451295) (xy 102.517245 25.451295) (xy 102.431862 25.459207)
			(xy 102.347572 25.474963) (xy 102.265096 25.49843) (xy 102.185137 25.529406) (xy 102.108377 25.567628)
			(xy 102.035471 25.612769) (xy 101.967042 25.664445) (xy 101.903672 25.722214) (xy 101.845903 25.785584)
			(xy 101.794227 25.854013) (xy 101.749086 25.926919) (xy 101.710864 26.003679) (xy 101.679888 26.083638)
			(xy 101.656421 26.166114) (xy 101.640665 26.250404) (xy 101.632753 26.335787) (xy 100.947487 26.335787)
			(xy 100.939575 26.250404) (xy 100.923819 26.166114) (xy 100.900352 26.083638) (xy 100.869376 26.003679)
			(xy 100.831154 25.926919) (xy 100.786013 25.854013) (xy 100.734337 25.785584) (xy 100.676568 25.722214)
			(xy 100.613198 25.664445) (xy 100.544769 25.612769) (xy 100.471863 25.567628) (xy 100.395103 25.529406)
			(xy 100.315144 25.49843) (xy 100.232668 25.474963) (xy 100.148378 25.459207) (xy 100.062995 25.451295)
			(xy 99.977245 25.451295) (xy 99.891862 25.459207) (xy 99.807572 25.474963) (xy 99.725096 25.49843)
			(xy 99.645137 25.529406) (xy 99.568377 25.567628) (xy 99.495471 25.612769) (xy 99.427042 25.664445)
			(xy 99.363672 25.722214) (xy 99.305903 25.785584) (xy 99.254227 25.854013) (xy 99.209086 25.926919)
			(xy 99.170864 26.003679) (xy 99.139888 26.083638) (xy 99.116421 26.166114) (xy 99.100665 26.250404)
			(xy 99.092753 26.335787) (xy 92.50807 26.335787) (xy 92.50807 20.841513) (xy 99.085133 20.841513)
			(xy 99.085133 20.927263) (xy 99.093045 21.012646) (xy 99.108801 21.096936) (xy 99.132268 21.179412)
			(xy 99.163244 21.259371) (xy 99.201466 21.336131) (xy 99.246607 21.409037) (xy 99.298283 21.477466)
			(xy 99.356052 21.540836) (xy 99.419422 21.598605) (xy 99.487851 21.650281) (xy 99.560757 21.695422)
			(xy 99.637517 21.733644) (xy 99.717476 21.76462) (xy 99.799952 21.788087) (xy 99.884242 21.803843)
			(xy 99.969625 21.811755) (xy 100.055375 21.811755) (xy 100.140758 21.803843) (xy 100.225048 21.788087)
			(xy 100.307524 21.76462) (xy 100.387483 21.733644) (xy 100.464243 21.695422) (xy 100.537149 21.650281)
			(xy 100.605578 21.598605) (xy 100.668948 21.540836) (xy 100.726717 21.477466) (xy 100.778393 21.409037)
			(xy 100.823534 21.336131) (xy 100.861756 21.259371) (xy 100.892732 21.179412) (xy 100.916199 21.096936)
			(xy 100.931955 21.012646) (xy 100.939867 20.927263) (xy 100.940362 20.884388) (xy 100.939867 20.841513)
			(xy 101.625133 20.841513) (xy 101.625133 20.927263) (xy 101.633045 21.012646) (xy 101.648801 21.096936)
			(xy 101.672268 21.179412) (xy 101.703244 21.259371) (xy 101.741466 21.336131) (xy 101.786607 21.409037)
			(xy 101.838283 21.477466) (xy 101.896052 21.540836) (xy 101.959422 21.598605) (xy 102.027851 21.650281)
			(xy 102.100757 21.695422) (xy 102.177517 21.733644) (xy 102.257476 21.76462) (xy 102.339952 21.788087)
			(xy 102.424242 21.803843) (xy 102.509625 21.811755) (xy 102.595375 21.811755) (xy 102.680758 21.803843)
			(xy 102.765048 21.788087) (xy 102.847524 21.76462) (xy 102.927483 21.733644) (xy 103.004243 21.695422)
			(xy 103.077149 21.650281) (xy 103.145578 21.598605) (xy 103.208948 21.540836) (xy 103.266717 21.477466)
			(xy 103.318393 21.409037) (xy 103.363534 21.336131) (xy 103.401756 21.259371) (xy 103.432732 21.179412)
			(xy 103.456199 21.096936) (xy 103.471955 21.012646) (xy 103.479867 20.927263) (xy 103.480362 20.884388)
			(xy 103.479867 20.841513) (xy 104.165133 20.841513) (xy 104.165133 20.927263) (xy 104.173045 21.012646)
			(xy 104.188801 21.096936) (xy 104.212268 21.179412) (xy 104.243244 21.259371) (xy 104.281466 21.336131)
			(xy 104.326607 21.409037) (xy 104.378283 21.477466) (xy 104.436052 21.540836) (xy 104.499422 21.598605)
			(xy 104.567851 21.650281) (xy 104.640757 21.695422) (xy 104.717517 21.733644) (xy 104.797476 21.76462)
			(xy 104.879952 21.788087) (xy 104.964242 21.803843) (xy 105.049625 21.811755) (xy 105.135375 21.811755)
			(xy 105.220758 21.803843) (xy 105.305048 21.788087) (xy 105.387524 21.76462) (xy 105.467483 21.733644)
			(xy 105.544243 21.695422) (xy 105.617149 21.650281) (xy 105.685578 21.598605) (xy 105.748948 21.540836)
			(xy 105.806717 21.477466) (xy 105.858393 21.409037) (xy 105.903534 21.336131) (xy 105.941756 21.259371)
			(xy 105.972732 21.179412) (xy 105.996199 21.096936) (xy 106.011955 21.012646) (xy 106.019867 20.927263)
			(xy 106.020362 20.884388) (xy 106.019867 20.841513) (xy 106.011955 20.75613) (xy 105.996199 20.67184)
			(xy 105.972732 20.589364) (xy 105.941756 20.509405) (xy 105.903534 20.432645) (xy 105.858393 20.359739)
			(xy 105.806717 20.29131) (xy 105.748948 20.22794) (xy 105.685578 20.170171) (xy 105.617149 20.118495)
			(xy 105.544243 20.073354) (xy 105.467483 20.035132) (xy 105.387524 20.004156) (xy 105.305048 19.980689)
			(xy 105.220758 19.964933) (xy 105.135375 19.957021) (xy 105.049625 19.957021) (xy 104.964242 19.964933)
			(xy 104.879952 19.980689) (xy 104.797476 20.004156) (xy 104.717517 20.035132) (xy 104.640757 20.073354)
			(xy 104.567851 20.118495) (xy 104.499422 20.170171) (xy 104.436052 20.22794) (xy 104.378283 20.29131)
			(xy 104.326607 20.359739) (xy 104.281466 20.432645) (xy 104.243244 20.509405) (xy 104.212268 20.589364)
			(xy 104.188801 20.67184) (xy 104.173045 20.75613) (xy 104.165133 20.841513) (xy 103.479867 20.841513)
			(xy 103.471955 20.75613) (xy 103.456199 20.67184) (xy 103.432732 20.589364) (xy 103.401756 20.509405)
			(xy 103.363534 20.432645) (xy 103.318393 20.359739) (xy 103.266717 20.29131) (xy 103.208948 20.22794)
			(xy 103.145578 20.170171) (xy 103.077149 20.118495) (xy 103.004243 20.073354) (xy 102.927483 20.035132)
			(xy 102.847524 20.004156) (xy 102.765048 19.980689) (xy 102.680758 19.964933) (xy 102.595375 19.957021)
			(xy 102.509625 19.957021) (xy 102.424242 19.964933) (xy 102.339952 19.980689) (xy 102.257476 20.004156)
			(xy 102.177517 20.035132) (xy 102.100757 20.073354) (xy 102.027851 20.118495) (xy 101.959422 20.170171)
			(xy 101.896052 20.22794) (xy 101.838283 20.29131) (xy 101.786607 20.359739) (xy 101.741466 20.432645)
			(xy 101.703244 20.509405) (xy 101.672268 20.589364) (xy 101.648801 20.67184) (xy 101.633045 20.75613)
			(xy 101.625133 20.841513) (xy 100.939867 20.841513) (xy 100.931955 20.75613) (xy 100.916199 20.67184)
			(xy 100.892732 20.589364) (xy 100.861756 20.509405) (xy 100.823534 20.432645) (xy 100.778393 20.359739)
			(xy 100.726717 20.29131) (xy 100.668948 20.22794) (xy 100.605578 20.170171) (xy 100.537149 20.118495)
			(xy 100.464243 20.073354) (xy 100.387483 20.035132) (xy 100.307524 20.004156) (xy 100.225048 19.980689)
			(xy 100.140758 19.964933) (xy 100.055375 19.957021) (xy 99.969625 19.957021) (xy 99.884242 19.964933)
			(xy 99.799952 19.980689) (xy 99.717476 20.004156) (xy 99.637517 20.035132) (xy 99.560757 20.073354)
			(xy 99.487851 20.118495) (xy 99.419422 20.170171) (xy 99.356052 20.22794) (xy 99.298283 20.29131)
			(xy 99.246607 20.359739) (xy 99.201466 20.432645) (xy 99.163244 20.509405) (xy 99.132268 20.589364)
			(xy 99.108801 20.67184) (xy 99.093045 20.75613) (xy 99.085133 20.841513) (xy 92.50807 20.841513)
			(xy 92.50807 14.491513) (xy 99.085133 14.491513) (xy 99.085133 14.577263) (xy 99.093045 14.662646)
			(xy 99.108801 14.746936) (xy 99.132268 14.829412) (xy 99.163244 14.909371) (xy 99.201466 14.986131)
			(xy 99.246607 15.059037) (xy 99.298283 15.127466) (xy 99.356052 15.190836) (xy 99.419422 15.248605)
			(xy 99.487851 15.300281) (xy 99.560757 15.345422) (xy 99.637517 15.383644) (xy 99.717476 15.41462)
			(xy 99.799952 15.438087) (xy 99.884242 15.453843) (xy 99.969625 15.461755) (xy 100.055375 15.461755)
			(xy 100.140758 15.453843) (xy 100.225048 15.438087) (xy 100.307524 15.41462) (xy 100.387483 15.383644)
			(xy 100.464243 15.345422) (xy 100.537149 15.300281) (xy 100.605578 15.248605) (xy 100.668948 15.190836)
			(xy 100.726717 15.127466) (xy 100.778393 15.059037) (xy 100.823534 14.986131) (xy 100.861756 14.909371)
			(xy 100.892732 14.829412) (xy 100.916199 14.746936) (xy 100.931955 14.662646) (xy 100.939867 14.577263)
			(xy 100.940362 14.534388) (xy 100.939867 14.491513) (xy 101.625133 14.491513) (xy 101.625133 14.577263)
			(xy 101.633045 14.662646) (xy 101.648801 14.746936) (xy 101.672268 14.829412) (xy 101.703244 14.909371)
			(xy 101.741466 14.986131) (xy 101.786607 15.059037) (xy 101.838283 15.127466) (xy 101.896052 15.190836)
			(xy 101.959422 15.248605) (xy 102.027851 15.300281) (xy 102.100757 15.345422) (xy 102.177517 15.383644)
			(xy 102.257476 15.41462) (xy 102.339952 15.438087) (xy 102.424242 15.453843) (xy 102.509625 15.461755)
			(xy 102.595375 15.461755) (xy 102.680758 15.453843) (xy 102.765048 15.438087) (xy 102.847524 15.41462)
			(xy 102.927483 15.383644) (xy 103.004243 15.345422) (xy 103.077149 15.300281) (xy 103.145578 15.248605)
			(xy 103.208948 15.190836) (xy 103.266717 15.127466) (xy 103.318393 15.059037) (xy 103.363534 14.986131)
			(xy 103.401756 14.909371) (xy 103.432732 14.829412) (xy 103.456199 14.746936) (xy 103.471955 14.662646)
			(xy 103.479867 14.577263) (xy 103.480362 14.534388) (xy 103.479867 14.491513) (xy 104.165133 14.491513)
			(xy 104.165133 14.577263) (xy 104.173045 14.662646) (xy 104.188801 14.746936) (xy 104.212268 14.829412)
			(xy 104.243244 14.909371) (xy 104.281466 14.986131) (xy 104.326607 15.059037) (xy 104.378283 15.127466)
			(xy 104.436052 15.190836) (xy 104.499422 15.248605) (xy 104.567851 15.300281) (xy 104.640757 15.345422)
			(xy 104.717517 15.383644) (xy 104.797476 15.41462) (xy 104.879952 15.438087) (xy 104.964242 15.453843)
			(xy 105.049625 15.461755) (xy 105.135375 15.461755) (xy 105.220758 15.453843) (xy 105.305048 15.438087)
			(xy 105.387524 15.41462) (xy 105.467483 15.383644) (xy 105.544243 15.345422) (xy 105.617149 15.300281)
			(xy 105.685578 15.248605) (xy 105.748948 15.190836) (xy 105.806717 15.127466) (xy 105.858393 15.059037)
			(xy 105.903534 14.986131) (xy 105.941756 14.909371) (xy 105.972732 14.829412) (xy 105.996199 14.746936)
			(xy 106.011955 14.662646) (xy 106.019867 14.577263) (xy 106.020362 14.534388) (xy 106.019867 14.491513)
			(xy 106.011955 14.40613) (xy 105.996199 14.32184) (xy 105.972732 14.239364) (xy 105.941756 14.159405)
			(xy 105.903534 14.082645) (xy 105.858393 14.009739) (xy 105.806717 13.94131) (xy 105.748948 13.87794)
			(xy 105.685578 13.820171) (xy 105.617149 13.768495) (xy 105.544243 13.723354) (xy 105.467483 13.685132)
			(xy 105.387524 13.654156) (xy 105.305048 13.630689) (xy 105.220758 13.614933) (xy 105.135375 13.607021)
			(xy 105.049625 13.607021) (xy 104.964242 13.614933) (xy 104.879952 13.630689) (xy 104.797476 13.654156)
			(xy 104.717517 13.685132) (xy 104.640757 13.723354) (xy 104.567851 13.768495) (xy 104.499422 13.820171)
			(xy 104.436052 13.87794) (xy 104.378283 13.94131) (xy 104.326607 14.009739) (xy 104.281466 14.082645)
			(xy 104.243244 14.159405) (xy 104.212268 14.239364) (xy 104.188801 14.32184) (xy 104.173045 14.40613)
			(xy 104.165133 14.491513) (xy 103.479867 14.491513) (xy 103.471955 14.40613) (xy 103.456199 14.32184)
			(xy 103.432732 14.239364) (xy 103.401756 14.159405) (xy 103.363534 14.082645) (xy 103.318393 14.009739)
			(xy 103.266717 13.94131) (xy 103.208948 13.87794) (xy 103.145578 13.820171) (xy 103.077149 13.768495)
			(xy 103.004243 13.723354) (xy 102.927483 13.685132) (xy 102.847524 13.654156) (xy 102.765048 13.630689)
			(xy 102.680758 13.614933) (xy 102.595375 13.607021) (xy 102.509625 13.607021) (xy 102.424242 13.614933)
			(xy 102.339952 13.630689) (xy 102.257476 13.654156) (xy 102.177517 13.685132) (xy 102.100757 13.723354)
			(xy 102.027851 13.768495) (xy 101.959422 13.820171) (xy 101.896052 13.87794) (xy 101.838283 13.94131)
			(xy 101.786607 14.009739) (xy 101.741466 14.082645) (xy 101.703244 14.159405) (xy 101.672268 14.239364)
			(xy 101.648801 14.32184) (xy 101.633045 14.40613) (xy 101.625133 14.491513) (xy 100.939867 14.491513)
			(xy 100.931955 14.40613) (xy 100.916199 14.32184) (xy 100.892732 14.239364) (xy 100.861756 14.159405)
			(xy 100.823534 14.082645) (xy 100.778393 14.009739) (xy 100.726717 13.94131) (xy 100.668948 13.87794)
			(xy 100.605578 13.820171) (xy 100.537149 13.768495) (xy 100.464243 13.723354) (xy 100.387483 13.685132)
			(xy 100.307524 13.654156) (xy 100.225048 13.630689) (xy 100.140758 13.614933) (xy 100.055375 13.607021)
			(xy 99.969625 13.607021) (xy 99.884242 13.614933) (xy 99.799952 13.630689) (xy 99.717476 13.654156)
			(xy 99.637517 13.685132) (xy 99.560757 13.723354) (xy 99.487851 13.768495) (xy 99.419422 13.820171)
			(xy 99.356052 13.87794) (xy 99.298283 13.94131) (xy 99.246607 14.009739) (xy 99.201466 14.082645)
			(xy 99.163244 14.159405) (xy 99.132268 14.239364) (xy 99.108801 14.32184) (xy 99.093045 14.40613)
			(xy 99.085133 14.491513) (xy 92.50807 14.491513) (xy 92.50807 -1.181049) (xy 93.729289 -1.181049)
			(xy 93.729289 -1.095299) (xy 93.737201 -1.009916) (xy 93.752957 -0.925626) (xy 93.776424 -0.84315)
			(xy 93.8074 -0.763191) (xy 93.845622 -0.686431) (xy 93.890763 -0.613525) (xy 93.942439 -0.545096)
			(xy 94.000208 -0.481726) (xy 94.063578 -0.423957) (xy 94.132007 -0.372281) (xy 94.204913 -0.32714)
			(xy 94.281673 -0.288918) (xy 94.361632 -0.257942) (xy 94.444108 -0.234475) (xy 94.528398 -0.218719)
			(xy 94.613781 -0.210807) (xy 94.699531 -0.210807) (xy 94.784914 -0.218719) (xy 94.869204 -0.234475)
			(xy 94.95168 -0.257942) (xy 95.031639 -0.288918) (xy 95.108399 -0.32714) (xy 95.181305 -0.372281)
			(xy 95.249734 -0.423957) (xy 95.313104 -0.481726) (xy 95.370873 -0.545096) (xy 95.422549 -0.613525)
			(xy 95.46769 -0.686431) (xy 95.505912 -0.763191) (xy 95.536888 -0.84315) (xy 95.560355 -0.925626)
			(xy 95.576111 -1.009916) (xy 95.584023 -1.095299) (xy 95.584518 -1.138174) (xy 95.584023 -1.181049)
			(xy 96.269289 -1.181049) (xy 96.269289 -1.095299) (xy 96.277201 -1.009916) (xy 96.292957 -0.925626)
			(xy 96.316424 -0.84315) (xy 96.3474 -0.763191) (xy 96.385622 -0.686431) (xy 96.430763 -0.613525)
			(xy 96.482439 -0.545096) (xy 96.540208 -0.481726) (xy 96.603578 -0.423957) (xy 96.672007 -0.372281)
			(xy 96.744913 -0.32714) (xy 96.821673 -0.288918) (xy 96.901632 -0.257942) (xy 96.984108 -0.234475)
			(xy 97.068398 -0.218719) (xy 97.153781 -0.210807) (xy 97.239531 -0.210807) (xy 97.324914 -0.218719)
			(xy 97.409204 -0.234475) (xy 97.49168 -0.257942) (xy 97.571639 -0.288918) (xy 97.648399 -0.32714)
			(xy 97.721305 -0.372281) (xy 97.789734 -0.423957) (xy 97.853104 -0.481726) (xy 97.910873 -0.545096)
			(xy 97.962549 -0.613525) (xy 98.00769 -0.686431) (xy 98.045912 -0.763191) (xy 98.076888 -0.84315)
			(xy 98.100355 -0.925626) (xy 98.116111 -1.009916) (xy 98.124023 -1.095299) (xy 98.124518 -1.138174)
			(xy 98.124023 -1.181049) (xy 98.116111 -1.266432) (xy 98.100355 -1.350722) (xy 98.076888 -1.433198)
			(xy 98.045912 -1.513157) (xy 98.00769 -1.589917) (xy 97.962549 -1.662823) (xy 97.910873 -1.731252)
			(xy 97.853104 -1.794622) (xy 97.789734 -1.852391) (xy 97.721305 -1.904067) (xy 97.648399 -1.949208)
			(xy 97.571639 -1.98743) (xy 97.49168 -2.018406) (xy 97.409204 -2.041873) (xy 97.324914 -2.057629)
			(xy 97.239531 -2.065541) (xy 97.153781 -2.065541) (xy 97.068398 -2.057629) (xy 96.984108 -2.041873)
			(xy 96.901632 -2.018406) (xy 96.821673 -1.98743) (xy 96.744913 -1.949208) (xy 96.672007 -1.904067)
			(xy 96.603578 -1.852391) (xy 96.540208 -1.794622) (xy 96.482439 -1.731252) (xy 96.430763 -1.662823)
			(xy 96.385622 -1.589917) (xy 96.3474 -1.513157) (xy 96.316424 -1.433198) (xy 96.292957 -1.350722)
			(xy 96.277201 -1.266432) (xy 96.269289 -1.181049) (xy 95.584023 -1.181049) (xy 95.576111 -1.266432)
			(xy 95.560355 -1.350722) (xy 95.536888 -1.433198) (xy 95.505912 -1.513157) (xy 95.46769 -1.589917)
			(xy 95.422549 -1.662823) (xy 95.370873 -1.731252) (xy 95.313104 -1.794622) (xy 95.249734 -1.852391)
			(xy 95.181305 -1.904067) (xy 95.108399 -1.949208) (xy 95.031639 -1.98743) (xy 94.95168 -2.018406)
			(xy 94.869204 -2.041873) (xy 94.784914 -2.057629) (xy 94.699531 -2.065541) (xy 94.613781 -2.065541)
			(xy 94.528398 -2.057629) (xy 94.444108 -2.041873) (xy 94.361632 -2.018406) (xy 94.281673 -1.98743)
			(xy 94.204913 -1.949208) (xy 94.132007 -1.904067) (xy 94.063578 -1.852391) (xy 94.000208 -1.794622)
			(xy 93.942439 -1.731252) (xy 93.890763 -1.662823) (xy 93.845622 -1.589917) (xy 93.8074 -1.513157)
			(xy 93.776424 -1.433198) (xy 93.752957 -1.350722) (xy 93.737201 -1.266432) (xy 93.729289 -1.181049)
			(xy 92.50807 -1.181049) (xy 92.50807 -3.154767) (xy 95.113626 -3.154767) (xy 95.113626 -3.100233)
			(xy 95.121387 -3.046253) (xy 95.13675 -2.993928) (xy 95.159403 -2.944321) (xy 95.188884 -2.898442)
			(xy 95.224595 -2.857226) (xy 95.265807 -2.821511) (xy 95.311682 -2.792024) (xy 95.361286 -2.769365)
			(xy 95.41361 -2.753996) (xy 95.467589 -2.746229) (xy 95.494856 -2.74574) (xy 96.358456 -2.74574)
			(xy 96.385729 -2.746196) (xy 96.439721 -2.753954) (xy 96.492059 -2.769316) (xy 96.541678 -2.791971)
			(xy 96.587568 -2.821458) (xy 96.628793 -2.857176) (xy 96.664516 -2.898397) (xy 96.694008 -2.944283)
			(xy 96.716668 -2.993899) (xy 96.732037 -3.046236) (xy 96.7398 -3.100227) (xy 96.7398 -3.154773) (xy 96.732037 -3.208764)
			(xy 96.716668 -3.261101) (xy 96.694008 -3.310717) (xy 96.664516 -3.356603) (xy 96.628793 -3.397824)
			(xy 96.587568 -3.433542) (xy 96.541678 -3.463029) (xy 96.492059 -3.485684) (xy 96.439721 -3.501046)
			(xy 96.385729 -3.508804) (xy 96.358456 -3.509264) (xy 95.494856 -3.509264) (xy 95.467589 -3.508771)
			(xy 95.41361 -3.501004) (xy 95.361286 -3.485635) (xy 95.311682 -3.462976) (xy 95.265807 -3.433489)
			(xy 95.224595 -3.397774) (xy 95.188884 -3.356558) (xy 95.159403 -3.310679) (xy 95.13675 -3.261072)
			(xy 95.121387 -3.208747) (xy 95.113626 -3.154767) (xy 92.50807 -3.154767) (xy 92.50807 -7.531049)
			(xy 93.729289 -7.531049) (xy 93.729289 -7.445299) (xy 93.737201 -7.359916) (xy 93.752957 -7.275626)
			(xy 93.776424 -7.19315) (xy 93.8074 -7.113191) (xy 93.845622 -7.036431) (xy 93.890763 -6.963525)
			(xy 93.942439 -6.895096) (xy 94.000208 -6.831726) (xy 94.063578 -6.773957) (xy 94.132007 -6.722281)
			(xy 94.204913 -6.67714) (xy 94.281673 -6.638918) (xy 94.361632 -6.607942) (xy 94.444108 -6.584475)
			(xy 94.528398 -6.568719) (xy 94.613781 -6.560807) (xy 94.699531 -6.560807) (xy 94.784914 -6.568719)
			(xy 94.869204 -6.584475) (xy 94.95168 -6.607942) (xy 95.031639 -6.638918) (xy 95.108399 -6.67714)
			(xy 95.181305 -6.722281) (xy 95.249734 -6.773957) (xy 95.313104 -6.831726) (xy 95.370873 -6.895096)
			(xy 95.422549 -6.963525) (xy 95.46769 -7.036431) (xy 95.505912 -7.113191) (xy 95.536888 -7.19315)
			(xy 95.560355 -7.275626) (xy 95.576111 -7.359916) (xy 95.584023 -7.445299) (xy 95.584518 -7.488174)
			(xy 95.584023 -7.531049) (xy 96.269289 -7.531049) (xy 96.269289 -7.445299) (xy 96.277201 -7.359916)
			(xy 96.292957 -7.275626) (xy 96.316424 -7.19315) (xy 96.3474 -7.113191) (xy 96.385622 -7.036431)
			(xy 96.430763 -6.963525) (xy 96.482439 -6.895096) (xy 96.540208 -6.831726) (xy 96.603578 -6.773957)
			(xy 96.672007 -6.722281) (xy 96.744913 -6.67714) (xy 96.821673 -6.638918) (xy 96.901632 -6.607942)
			(xy 96.984108 -6.584475) (xy 97.068398 -6.568719) (xy 97.153781 -6.560807) (xy 97.239531 -6.560807)
			(xy 97.324914 -6.568719) (xy 97.409204 -6.584475) (xy 97.49168 -6.607942) (xy 97.571639 -6.638918)
			(xy 97.648399 -6.67714) (xy 97.721305 -6.722281) (xy 97.789734 -6.773957) (xy 97.853104 -6.831726)
			(xy 97.910873 -6.895096) (xy 97.962549 -6.963525) (xy 98.00769 -7.036431) (xy 98.045912 -7.113191)
			(xy 98.076888 -7.19315) (xy 98.100355 -7.275626) (xy 98.116111 -7.359916) (xy 98.124023 -7.445299)
			(xy 98.124518 -7.488174) (xy 98.124023 -7.531049) (xy 98.116111 -7.616432) (xy 98.100355 -7.700722)
			(xy 98.076888 -7.783198) (xy 98.045912 -7.863157) (xy 98.00769 -7.939917) (xy 97.962549 -8.012823)
			(xy 97.910873 -8.081252) (xy 97.853104 -8.144622) (xy 97.789734 -8.202391) (xy 97.721305 -8.254067)
			(xy 97.648399 -8.299208) (xy 97.571639 -8.33743) (xy 97.49168 -8.368406) (xy 97.409204 -8.391873)
			(xy 97.324914 -8.407629) (xy 97.239531 -8.415541) (xy 97.153781 -8.415541) (xy 97.068398 -8.407629)
			(xy 96.984108 -8.391873) (xy 96.901632 -8.368406) (xy 96.821673 -8.33743) (xy 96.744913 -8.299208)
			(xy 96.672007 -8.254067) (xy 96.603578 -8.202391) (xy 96.540208 -8.144622) (xy 96.482439 -8.081252)
			(xy 96.430763 -8.012823) (xy 96.385622 -7.939917) (xy 96.3474 -7.863157) (xy 96.316424 -7.783198)
			(xy 96.292957 -7.700722) (xy 96.277201 -7.616432) (xy 96.269289 -7.531049) (xy 95.584023 -7.531049)
			(xy 95.576111 -7.616432) (xy 95.560355 -7.700722) (xy 95.536888 -7.783198) (xy 95.505912 -7.863157)
			(xy 95.46769 -7.939917) (xy 95.422549 -8.012823) (xy 95.370873 -8.081252) (xy 95.313104 -8.144622)
			(xy 95.249734 -8.202391) (xy 95.181305 -8.254067) (xy 95.108399 -8.299208) (xy 95.031639 -8.33743)
			(xy 94.95168 -8.368406) (xy 94.869204 -8.391873) (xy 94.784914 -8.407629) (xy 94.699531 -8.415541)
			(xy 94.613781 -8.415541) (xy 94.528398 -8.407629) (xy 94.444108 -8.391873) (xy 94.361632 -8.368406)
			(xy 94.281673 -8.33743) (xy 94.204913 -8.299208) (xy 94.132007 -8.254067) (xy 94.063578 -8.202391)
			(xy 94.000208 -8.144622) (xy 93.942439 -8.081252) (xy 93.890763 -8.012823) (xy 93.845622 -7.939917)
			(xy 93.8074 -7.863157) (xy 93.776424 -7.783198) (xy 93.752957 -7.700722) (xy 93.737201 -7.616432)
			(xy 93.729289 -7.531049) (xy 92.50807 -7.531049) (xy 92.50807 -13.055549) (xy 93.714049 -13.055549)
			(xy 93.714049 -12.969799) (xy 93.721961 -12.884416) (xy 93.737717 -12.800126) (xy 93.761184 -12.71765)
			(xy 93.79216 -12.637691) (xy 93.830382 -12.560931) (xy 93.875523 -12.488025) (xy 93.927199 -12.419596)
			(xy 93.984968 -12.356226) (xy 94.048338 -12.298457) (xy 94.116767 -12.246781) (xy 94.189673 -12.20164)
			(xy 94.266433 -12.163418) (xy 94.346392 -12.132442) (xy 94.428868 -12.108975) (xy 94.513158 -12.093219)
			(xy 94.598541 -12.085307) (xy 94.684291 -12.085307) (xy 94.769674 -12.093219) (xy 94.853964 -12.108975)
			(xy 94.93644 -12.132442) (xy 95.016399 -12.163418) (xy 95.093159 -12.20164) (xy 95.166065 -12.246781)
			(xy 95.234494 -12.298457) (xy 95.297864 -12.356226) (xy 95.355633 -12.419596) (xy 95.407309 -12.488025)
			(xy 95.45245 -12.560931) (xy 95.490672 -12.637691) (xy 95.521648 -12.71765) (xy 95.545115 -12.800126)
			(xy 95.560871 -12.884416) (xy 95.568783 -12.969799) (xy 95.569278 -13.012674) (xy 95.568783 -13.055549)
			(xy 96.254049 -13.055549) (xy 96.254049 -12.969799) (xy 96.261961 -12.884416) (xy 96.277717 -12.800126)
			(xy 96.301184 -12.71765) (xy 96.33216 -12.637691) (xy 96.370382 -12.560931) (xy 96.415523 -12.488025)
			(xy 96.467199 -12.419596) (xy 96.524968 -12.356226) (xy 96.588338 -12.298457) (xy 96.656767 -12.246781)
			(xy 96.729673 -12.20164) (xy 96.806433 -12.163418) (xy 96.886392 -12.132442) (xy 96.968868 -12.108975)
			(xy 97.053158 -12.093219) (xy 97.138541 -12.085307) (xy 97.224291 -12.085307) (xy 97.309674 -12.093219)
			(xy 97.393964 -12.108975) (xy 97.47644 -12.132442) (xy 97.556399 -12.163418) (xy 97.633159 -12.20164)
			(xy 97.706065 -12.246781) (xy 97.774494 -12.298457) (xy 97.837864 -12.356226) (xy 97.895633 -12.419596)
			(xy 97.947309 -12.488025) (xy 97.99245 -12.560931) (xy 98.030672 -12.637691) (xy 98.061648 -12.71765)
			(xy 98.085115 -12.800126) (xy 98.100871 -12.884416) (xy 98.108783 -12.969799) (xy 98.109278 -13.012674)
			(xy 98.108783 -13.055549) (xy 98.100871 -13.140932) (xy 98.085115 -13.225222) (xy 98.061648 -13.307698)
			(xy 98.030672 -13.387657) (xy 97.99245 -13.464417) (xy 97.947309 -13.537323) (xy 97.895633 -13.605752)
			(xy 97.837864 -13.669122) (xy 97.774494 -13.726891) (xy 97.706065 -13.778567) (xy 97.633159 -13.823708)
			(xy 97.556399 -13.86193) (xy 97.47644 -13.892906) (xy 97.393964 -13.916373) (xy 97.309674 -13.932129)
			(xy 97.224291 -13.940041) (xy 97.138541 -13.940041) (xy 97.053158 -13.932129) (xy 96.968868 -13.916373)
			(xy 96.886392 -13.892906) (xy 96.806433 -13.86193) (xy 96.729673 -13.823708) (xy 96.656767 -13.778567)
			(xy 96.588338 -13.726891) (xy 96.524968 -13.669122) (xy 96.467199 -13.605752) (xy 96.415523 -13.537323)
			(xy 96.370382 -13.464417) (xy 96.33216 -13.387657) (xy 96.301184 -13.307698) (xy 96.277717 -13.225222)
			(xy 96.261961 -13.140932) (xy 96.254049 -13.055549) (xy 95.568783 -13.055549) (xy 95.560871 -13.140932)
			(xy 95.545115 -13.225222) (xy 95.521648 -13.307698) (xy 95.490672 -13.387657) (xy 95.45245 -13.464417)
			(xy 95.407309 -13.537323) (xy 95.355633 -13.605752) (xy 95.297864 -13.669122) (xy 95.234494 -13.726891)
			(xy 95.166065 -13.778567) (xy 95.093159 -13.823708) (xy 95.016399 -13.86193) (xy 94.93644 -13.892906)
			(xy 94.853964 -13.916373) (xy 94.769674 -13.932129) (xy 94.684291 -13.940041) (xy 94.598541 -13.940041)
			(xy 94.513158 -13.932129) (xy 94.428868 -13.916373) (xy 94.346392 -13.892906) (xy 94.266433 -13.86193)
			(xy 94.189673 -13.823708) (xy 94.116767 -13.778567) (xy 94.048338 -13.726891) (xy 93.984968 -13.669122)
			(xy 93.927199 -13.605752) (xy 93.875523 -13.537323) (xy 93.830382 -13.464417) (xy 93.79216 -13.387657)
			(xy 93.761184 -13.307698) (xy 93.737717 -13.225222) (xy 93.721961 -13.140932) (xy 93.714049 -13.055549)
			(xy 92.50807 -13.055549) (xy 92.50807 -17.400568) (xy 95.098347 -17.400568) (xy 95.098347 -17.346032)
			(xy 95.106109 -17.29205) (xy 95.121474 -17.239722) (xy 95.14413 -17.190114) (xy 95.173616 -17.144235)
			(xy 95.209331 -17.103019) (xy 95.250548 -17.067306) (xy 95.296428 -17.037823) (xy 95.346037 -17.015169)
			(xy 95.398365 -16.999806) (xy 95.452348 -16.992046) (xy 95.479616 -16.991584) (xy 96.343216 -16.991584)
			(xy 96.370488 -16.99198) (xy 96.424476 -16.999744) (xy 96.47681 -17.015113) (xy 96.526424 -17.037773)
			(xy 96.572309 -17.067262) (xy 96.613529 -17.102982) (xy 96.649247 -17.144204) (xy 96.678735 -17.19009)
			(xy 96.701393 -17.239705) (xy 96.716759 -17.292039) (xy 96.724522 -17.346028) (xy 96.724522 -17.400572)
			(xy 96.716759 -17.454561) (xy 96.701393 -17.506895) (xy 96.678735 -17.55651) (xy 96.649247 -17.602396)
			(xy 96.613529 -17.643618) (xy 96.572309 -17.679338) (xy 96.526424 -17.708827) (xy 96.47681 -17.731487)
			(xy 96.424476 -17.746856) (xy 96.370488 -17.75462) (xy 96.343216 -17.755108) (xy 95.479616 -17.755108)
			(xy 95.452348 -17.754554) (xy 95.398365 -17.746794) (xy 95.346037 -17.731431) (xy 95.296428 -17.708777)
			(xy 95.250548 -17.679294) (xy 95.209331 -17.643581) (xy 95.173616 -17.602365) (xy 95.14413 -17.556486)
			(xy 95.121474 -17.506878) (xy 95.106109 -17.45455) (xy 95.098347 -17.400568) (xy 92.50807 -17.400568)
			(xy 92.50807 -19.405549) (xy 93.714049 -19.405549) (xy 93.714049 -19.319799) (xy 93.721961 -19.234416)
			(xy 93.737717 -19.150126) (xy 93.761184 -19.06765) (xy 93.79216 -18.987691) (xy 93.830382 -18.910931)
			(xy 93.875523 -18.838025) (xy 93.927199 -18.769596) (xy 93.984968 -18.706226) (xy 94.048338 -18.648457)
			(xy 94.116767 -18.596781) (xy 94.189673 -18.55164) (xy 94.266433 -18.513418) (xy 94.346392 -18.482442)
			(xy 94.428868 -18.458975) (xy 94.513158 -18.443219) (xy 94.598541 -18.435307) (xy 94.684291 -18.435307)
			(xy 94.769674 -18.443219) (xy 94.853964 -18.458975) (xy 94.93644 -18.482442) (xy 95.016399 -18.513418)
			(xy 95.093159 -18.55164) (xy 95.166065 -18.596781) (xy 95.234494 -18.648457) (xy 95.297864 -18.706226)
			(xy 95.355633 -18.769596) (xy 95.407309 -18.838025) (xy 95.45245 -18.910931) (xy 95.490672 -18.987691)
			(xy 95.521648 -19.06765) (xy 95.545115 -19.150126) (xy 95.560871 -19.234416) (xy 95.568783 -19.319799)
			(xy 95.569278 -19.362674) (xy 95.568783 -19.405549) (xy 96.254049 -19.405549) (xy 96.254049 -19.319799)
			(xy 96.261961 -19.234416) (xy 96.277717 -19.150126) (xy 96.301184 -19.06765) (xy 96.33216 -18.987691)
			(xy 96.370382 -18.910931) (xy 96.415523 -18.838025) (xy 96.467199 -18.769596) (xy 96.524968 -18.706226)
			(xy 96.588338 -18.648457) (xy 96.656767 -18.596781) (xy 96.729673 -18.55164) (xy 96.806433 -18.513418)
			(xy 96.886392 -18.482442) (xy 96.968868 -18.458975) (xy 97.053158 -18.443219) (xy 97.138541 -18.435307)
			(xy 97.224291 -18.435307) (xy 97.309674 -18.443219) (xy 97.393964 -18.458975) (xy 97.47644 -18.482442)
			(xy 97.556399 -18.513418) (xy 97.633159 -18.55164) (xy 97.706065 -18.596781) (xy 97.774494 -18.648457)
			(xy 97.837864 -18.706226) (xy 97.895633 -18.769596) (xy 97.947309 -18.838025) (xy 97.99245 -18.910931)
			(xy 98.030672 -18.987691) (xy 98.061648 -19.06765) (xy 98.085115 -19.150126) (xy 98.100871 -19.234416)
			(xy 98.108783 -19.319799) (xy 98.109278 -19.362674) (xy 98.108783 -19.405549) (xy 98.100871 -19.490932)
			(xy 98.085115 -19.575222) (xy 98.061648 -19.657698) (xy 98.030672 -19.737657) (xy 97.99245 -19.814417)
			(xy 97.947309 -19.887323) (xy 97.895633 -19.955752) (xy 97.837864 -20.019122) (xy 97.774494 -20.076891)
			(xy 97.706065 -20.128567) (xy 97.633159 -20.173708) (xy 97.556399 -20.21193) (xy 97.47644 -20.242906)
			(xy 97.393964 -20.266373) (xy 97.309674 -20.282129) (xy 97.224291 -20.290041) (xy 97.138541 -20.290041)
			(xy 97.053158 -20.282129) (xy 96.968868 -20.266373) (xy 96.886392 -20.242906) (xy 96.806433 -20.21193)
			(xy 96.729673 -20.173708) (xy 96.656767 -20.128567) (xy 96.588338 -20.076891) (xy 96.524968 -20.019122)
			(xy 96.467199 -19.955752) (xy 96.415523 -19.887323) (xy 96.370382 -19.814417) (xy 96.33216 -19.737657)
			(xy 96.301184 -19.657698) (xy 96.277717 -19.575222) (xy 96.261961 -19.490932) (xy 96.254049 -19.405549)
			(xy 95.568783 -19.405549) (xy 95.560871 -19.490932) (xy 95.545115 -19.575222) (xy 95.521648 -19.657698)
			(xy 95.490672 -19.737657) (xy 95.45245 -19.814417) (xy 95.407309 -19.887323) (xy 95.355633 -19.955752)
			(xy 95.297864 -20.019122) (xy 95.234494 -20.076891) (xy 95.166065 -20.128567) (xy 95.093159 -20.173708)
			(xy 95.016399 -20.21193) (xy 94.93644 -20.242906) (xy 94.853964 -20.266373) (xy 94.769674 -20.282129)
			(xy 94.684291 -20.290041) (xy 94.598541 -20.290041) (xy 94.513158 -20.282129) (xy 94.428868 -20.266373)
			(xy 94.346392 -20.242906) (xy 94.266433 -20.21193) (xy 94.189673 -20.173708) (xy 94.116767 -20.128567)
			(xy 94.048338 -20.076891) (xy 93.984968 -20.019122) (xy 93.927199 -19.955752) (xy 93.875523 -19.887323)
			(xy 93.830382 -19.814417) (xy 93.79216 -19.737657) (xy 93.761184 -19.657698) (xy 93.737717 -19.575222)
			(xy 93.721961 -19.490932) (xy 93.714049 -19.405549) (xy 92.50807 -19.405549) (xy 92.50807 -50.979527)
			(xy 99.085133 -50.979527) (xy 99.085133 -50.893777) (xy 99.093045 -50.808394) (xy 99.108801 -50.724104)
			(xy 99.132268 -50.641628) (xy 99.163244 -50.561669) (xy 99.201466 -50.484909) (xy 99.246607 -50.412003)
			(xy 99.298283 -50.343574) (xy 99.356052 -50.280204) (xy 99.419422 -50.222435) (xy 99.487851 -50.170759)
			(xy 99.560757 -50.125618) (xy 99.637517 -50.087396) (xy 99.717476 -50.05642) (xy 99.799952 -50.032953)
			(xy 99.884242 -50.017197) (xy 99.969625 -50.009285) (xy 100.055375 -50.009285) (xy 100.140758 -50.017197)
			(xy 100.225048 -50.032953) (xy 100.307524 -50.05642) (xy 100.387483 -50.087396) (xy 100.464243 -50.125618)
			(xy 100.537149 -50.170759) (xy 100.605578 -50.222435) (xy 100.668948 -50.280204) (xy 100.726717 -50.343574)
			(xy 100.778393 -50.412003) (xy 100.823534 -50.484909) (xy 100.861756 -50.561669) (xy 100.892732 -50.641628)
			(xy 100.916199 -50.724104) (xy 100.931955 -50.808394) (xy 100.939867 -50.893777) (xy 100.940362 -50.936652)
			(xy 100.939867 -50.979527) (xy 101.625133 -50.979527) (xy 101.625133 -50.893777) (xy 101.633045 -50.808394)
			(xy 101.648801 -50.724104) (xy 101.672268 -50.641628) (xy 101.703244 -50.561669) (xy 101.741466 -50.484909)
			(xy 101.786607 -50.412003) (xy 101.838283 -50.343574) (xy 101.896052 -50.280204) (xy 101.959422 -50.222435)
			(xy 102.027851 -50.170759) (xy 102.100757 -50.125618) (xy 102.177517 -50.087396) (xy 102.257476 -50.05642)
			(xy 102.339952 -50.032953) (xy 102.424242 -50.017197) (xy 102.509625 -50.009285) (xy 102.595375 -50.009285)
			(xy 102.680758 -50.017197) (xy 102.765048 -50.032953) (xy 102.847524 -50.05642) (xy 102.927483 -50.087396)
			(xy 103.004243 -50.125618) (xy 103.077149 -50.170759) (xy 103.145578 -50.222435) (xy 103.208948 -50.280204)
			(xy 103.266717 -50.343574) (xy 103.318393 -50.412003) (xy 103.363534 -50.484909) (xy 103.401756 -50.561669)
			(xy 103.432732 -50.641628) (xy 103.456199 -50.724104) (xy 103.471955 -50.808394) (xy 103.479867 -50.893777)
			(xy 103.480362 -50.936652) (xy 103.479867 -50.979527) (xy 104.165133 -50.979527) (xy 104.165133 -50.893777)
			(xy 104.173045 -50.808394) (xy 104.188801 -50.724104) (xy 104.212268 -50.641628) (xy 104.243244 -50.561669)
			(xy 104.281466 -50.484909) (xy 104.326607 -50.412003) (xy 104.378283 -50.343574) (xy 104.436052 -50.280204)
			(xy 104.499422 -50.222435) (xy 104.567851 -50.170759) (xy 104.640757 -50.125618) (xy 104.717517 -50.087396)
			(xy 104.797476 -50.05642) (xy 104.879952 -50.032953) (xy 104.964242 -50.017197) (xy 105.049625 -50.009285)
			(xy 105.135375 -50.009285) (xy 105.220758 -50.017197) (xy 105.305048 -50.032953) (xy 105.387524 -50.05642)
			(xy 105.467483 -50.087396) (xy 105.544243 -50.125618) (xy 105.617149 -50.170759) (xy 105.685578 -50.222435)
			(xy 105.748948 -50.280204) (xy 105.806717 -50.343574) (xy 105.858393 -50.412003) (xy 105.903534 -50.484909)
			(xy 105.941756 -50.561669) (xy 105.972732 -50.641628) (xy 105.996199 -50.724104) (xy 106.011955 -50.808394)
			(xy 106.019867 -50.893777) (xy 106.020362 -50.936652) (xy 106.019867 -50.979527) (xy 106.011955 -51.06491)
			(xy 105.996199 -51.1492) (xy 105.972732 -51.231676) (xy 105.941756 -51.311635) (xy 105.903534 -51.388395)
			(xy 105.858393 -51.461301) (xy 105.806717 -51.52973) (xy 105.748948 -51.5931) (xy 105.685578 -51.650869)
			(xy 105.617149 -51.702545) (xy 105.544243 -51.747686) (xy 105.467483 -51.785908) (xy 105.387524 -51.816884)
			(xy 105.305048 -51.840351) (xy 105.220758 -51.856107) (xy 105.135375 -51.864019) (xy 105.049625 -51.864019)
			(xy 104.964242 -51.856107) (xy 104.879952 -51.840351) (xy 104.797476 -51.816884) (xy 104.717517 -51.785908)
			(xy 104.640757 -51.747686) (xy 104.567851 -51.702545) (xy 104.499422 -51.650869) (xy 104.436052 -51.5931)
			(xy 104.378283 -51.52973) (xy 104.326607 -51.461301) (xy 104.281466 -51.388395) (xy 104.243244 -51.311635)
			(xy 104.212268 -51.231676) (xy 104.188801 -51.1492) (xy 104.173045 -51.06491) (xy 104.165133 -50.979527)
			(xy 103.479867 -50.979527) (xy 103.471955 -51.06491) (xy 103.456199 -51.1492) (xy 103.432732 -51.231676)
			(xy 103.401756 -51.311635) (xy 103.363534 -51.388395) (xy 103.318393 -51.461301) (xy 103.266717 -51.52973)
			(xy 103.208948 -51.5931) (xy 103.145578 -51.650869) (xy 103.077149 -51.702545) (xy 103.004243 -51.747686)
			(xy 102.927483 -51.785908) (xy 102.847524 -51.816884) (xy 102.765048 -51.840351) (xy 102.680758 -51.856107)
			(xy 102.595375 -51.864019) (xy 102.509625 -51.864019) (xy 102.424242 -51.856107) (xy 102.339952 -51.840351)
			(xy 102.257476 -51.816884) (xy 102.177517 -51.785908) (xy 102.100757 -51.747686) (xy 102.027851 -51.702545)
			(xy 101.959422 -51.650869) (xy 101.896052 -51.5931) (xy 101.838283 -51.52973) (xy 101.786607 -51.461301)
			(xy 101.741466 -51.388395) (xy 101.703244 -51.311635) (xy 101.672268 -51.231676) (xy 101.648801 -51.1492)
			(xy 101.633045 -51.06491) (xy 101.625133 -50.979527) (xy 100.939867 -50.979527) (xy 100.931955 -51.06491)
			(xy 100.916199 -51.1492) (xy 100.892732 -51.231676) (xy 100.861756 -51.311635) (xy 100.823534 -51.388395)
			(xy 100.778393 -51.461301) (xy 100.726717 -51.52973) (xy 100.668948 -51.5931) (xy 100.605578 -51.650869)
			(xy 100.537149 -51.702545) (xy 100.464243 -51.747686) (xy 100.387483 -51.785908) (xy 100.307524 -51.816884)
			(xy 100.225048 -51.840351) (xy 100.140758 -51.856107) (xy 100.055375 -51.864019) (xy 99.969625 -51.864019)
			(xy 99.884242 -51.856107) (xy 99.799952 -51.840351) (xy 99.717476 -51.816884) (xy 99.637517 -51.785908)
			(xy 99.560757 -51.747686) (xy 99.487851 -51.702545) (xy 99.419422 -51.650869) (xy 99.356052 -51.5931)
			(xy 99.298283 -51.52973) (xy 99.246607 -51.461301) (xy 99.201466 -51.388395) (xy 99.163244 -51.311635)
			(xy 99.132268 -51.231676) (xy 99.108801 -51.1492) (xy 99.093045 -51.06491) (xy 99.085133 -50.979527)
			(xy 92.50807 -50.979527) (xy 92.50807 -57.329527) (xy 99.085133 -57.329527) (xy 99.085133 -57.243777)
			(xy 99.093045 -57.158394) (xy 99.108801 -57.074104) (xy 99.132268 -56.991628) (xy 99.163244 -56.911669)
			(xy 99.201466 -56.834909) (xy 99.246607 -56.762003) (xy 99.298283 -56.693574) (xy 99.356052 -56.630204)
			(xy 99.419422 -56.572435) (xy 99.487851 -56.520759) (xy 99.560757 -56.475618) (xy 99.637517 -56.437396)
			(xy 99.717476 -56.40642) (xy 99.799952 -56.382953) (xy 99.884242 -56.367197) (xy 99.969625 -56.359285)
			(xy 100.055375 -56.359285) (xy 100.140758 -56.367197) (xy 100.225048 -56.382953) (xy 100.307524 -56.40642)
			(xy 100.387483 -56.437396) (xy 100.464243 -56.475618) (xy 100.537149 -56.520759) (xy 100.605578 -56.572435)
			(xy 100.668948 -56.630204) (xy 100.726717 -56.693574) (xy 100.778393 -56.762003) (xy 100.823534 -56.834909)
			(xy 100.861756 -56.911669) (xy 100.892732 -56.991628) (xy 100.916199 -57.074104) (xy 100.931955 -57.158394)
			(xy 100.939867 -57.243777) (xy 100.940362 -57.286652) (xy 100.939867 -57.329527) (xy 101.625133 -57.329527)
			(xy 101.625133 -57.243777) (xy 101.633045 -57.158394) (xy 101.648801 -57.074104) (xy 101.672268 -56.991628)
			(xy 101.703244 -56.911669) (xy 101.741466 -56.834909) (xy 101.786607 -56.762003) (xy 101.838283 -56.693574)
			(xy 101.896052 -56.630204) (xy 101.959422 -56.572435) (xy 102.027851 -56.520759) (xy 102.100757 -56.475618)
			(xy 102.177517 -56.437396) (xy 102.257476 -56.40642) (xy 102.339952 -56.382953) (xy 102.424242 -56.367197)
			(xy 102.509625 -56.359285) (xy 102.595375 -56.359285) (xy 102.680758 -56.367197) (xy 102.765048 -56.382953)
			(xy 102.847524 -56.40642) (xy 102.927483 -56.437396) (xy 103.004243 -56.475618) (xy 103.077149 -56.520759)
			(xy 103.145578 -56.572435) (xy 103.208948 -56.630204) (xy 103.266717 -56.693574) (xy 103.318393 -56.762003)
			(xy 103.363534 -56.834909) (xy 103.401756 -56.911669) (xy 103.432732 -56.991628) (xy 103.456199 -57.074104)
			(xy 103.471955 -57.158394) (xy 103.479867 -57.243777) (xy 103.480362 -57.286652) (xy 103.479867 -57.329527)
			(xy 104.165133 -57.329527) (xy 104.165133 -57.243777) (xy 104.173045 -57.158394) (xy 104.188801 -57.074104)
			(xy 104.212268 -56.991628) (xy 104.243244 -56.911669) (xy 104.281466 -56.834909) (xy 104.326607 -56.762003)
			(xy 104.378283 -56.693574) (xy 104.436052 -56.630204) (xy 104.499422 -56.572435) (xy 104.567851 -56.520759)
			(xy 104.640757 -56.475618) (xy 104.717517 -56.437396) (xy 104.797476 -56.40642) (xy 104.879952 -56.382953)
			(xy 104.964242 -56.367197) (xy 105.049625 -56.359285) (xy 105.135375 -56.359285) (xy 105.220758 -56.367197)
			(xy 105.305048 -56.382953) (xy 105.387524 -56.40642) (xy 105.467483 -56.437396) (xy 105.544243 -56.475618)
			(xy 105.617149 -56.520759) (xy 105.685578 -56.572435) (xy 105.748948 -56.630204) (xy 105.806717 -56.693574)
			(xy 105.858393 -56.762003) (xy 105.903534 -56.834909) (xy 105.941756 -56.911669) (xy 105.972732 -56.991628)
			(xy 105.996199 -57.074104) (xy 106.011955 -57.158394) (xy 106.019867 -57.243777) (xy 106.020362 -57.286652)
			(xy 106.019867 -57.329527) (xy 106.011955 -57.41491) (xy 105.996199 -57.4992) (xy 105.972732 -57.581676)
			(xy 105.941756 -57.661635) (xy 105.903534 -57.738395) (xy 105.858393 -57.811301) (xy 105.806717 -57.87973)
			(xy 105.748948 -57.9431) (xy 105.685578 -58.000869) (xy 105.617149 -58.052545) (xy 105.544243 -58.097686)
			(xy 105.467483 -58.135908) (xy 105.387524 -58.166884) (xy 105.305048 -58.190351) (xy 105.220758 -58.206107)
			(xy 105.135375 -58.214019) (xy 105.049625 -58.214019) (xy 104.964242 -58.206107) (xy 104.879952 -58.190351)
			(xy 104.797476 -58.166884) (xy 104.717517 -58.135908) (xy 104.640757 -58.097686) (xy 104.567851 -58.052545)
			(xy 104.499422 -58.000869) (xy 104.436052 -57.9431) (xy 104.378283 -57.87973) (xy 104.326607 -57.811301)
			(xy 104.281466 -57.738395) (xy 104.243244 -57.661635) (xy 104.212268 -57.581676) (xy 104.188801 -57.4992)
			(xy 104.173045 -57.41491) (xy 104.165133 -57.329527) (xy 103.479867 -57.329527) (xy 103.471955 -57.41491)
			(xy 103.456199 -57.4992) (xy 103.432732 -57.581676) (xy 103.401756 -57.661635) (xy 103.363534 -57.738395)
			(xy 103.318393 -57.811301) (xy 103.266717 -57.87973) (xy 103.208948 -57.9431) (xy 103.145578 -58.000869)
			(xy 103.077149 -58.052545) (xy 103.004243 -58.097686) (xy 102.927483 -58.135908) (xy 102.847524 -58.166884)
			(xy 102.765048 -58.190351) (xy 102.680758 -58.206107) (xy 102.595375 -58.214019) (xy 102.509625 -58.214019)
			(xy 102.424242 -58.206107) (xy 102.339952 -58.190351) (xy 102.257476 -58.166884) (xy 102.177517 -58.135908)
			(xy 102.100757 -58.097686) (xy 102.027851 -58.052545) (xy 101.959422 -58.000869) (xy 101.896052 -57.9431)
			(xy 101.838283 -57.87973) (xy 101.786607 -57.811301) (xy 101.741466 -57.738395) (xy 101.703244 -57.661635)
			(xy 101.672268 -57.581676) (xy 101.648801 -57.4992) (xy 101.633045 -57.41491) (xy 101.625133 -57.329527)
			(xy 100.939867 -57.329527) (xy 100.931955 -57.41491) (xy 100.916199 -57.4992) (xy 100.892732 -57.581676)
			(xy 100.861756 -57.661635) (xy 100.823534 -57.738395) (xy 100.778393 -57.811301) (xy 100.726717 -57.87973)
			(xy 100.668948 -57.9431) (xy 100.605578 -58.000869) (xy 100.537149 -58.052545) (xy 100.464243 -58.097686)
			(xy 100.387483 -58.135908) (xy 100.307524 -58.166884) (xy 100.225048 -58.190351) (xy 100.140758 -58.206107)
			(xy 100.055375 -58.214019) (xy 99.969625 -58.214019) (xy 99.884242 -58.206107) (xy 99.799952 -58.190351)
			(xy 99.717476 -58.166884) (xy 99.637517 -58.135908) (xy 99.560757 -58.097686) (xy 99.487851 -58.052545)
			(xy 99.419422 -58.000869) (xy 99.356052 -57.9431) (xy 99.298283 -57.87973) (xy 99.246607 -57.811301)
			(xy 99.201466 -57.738395) (xy 99.163244 -57.661635) (xy 99.132268 -57.581676) (xy 99.108801 -57.4992)
			(xy 99.093045 -57.41491) (xy 99.085133 -57.329527) (xy 92.50807 -57.329527) (xy 92.50807 -62.793575)
			(xy 99.085133 -62.793575) (xy 99.085133 -62.707825) (xy 99.093045 -62.622442) (xy 99.108801 -62.538152)
			(xy 99.132268 -62.455676) (xy 99.163244 -62.375717) (xy 99.201466 -62.298957) (xy 99.246607 -62.226051)
			(xy 99.298283 -62.157622) (xy 99.356052 -62.094252) (xy 99.419422 -62.036483) (xy 99.487851 -61.984807)
			(xy 99.560757 -61.939666) (xy 99.637517 -61.901444) (xy 99.717476 -61.870468) (xy 99.799952 -61.847001)
			(xy 99.884242 -61.831245) (xy 99.969625 -61.823333) (xy 100.055375 -61.823333) (xy 100.140758 -61.831245)
			(xy 100.225048 -61.847001) (xy 100.307524 -61.870468) (xy 100.387483 -61.901444) (xy 100.464243 -61.939666)
			(xy 100.537149 -61.984807) (xy 100.605578 -62.036483) (xy 100.668948 -62.094252) (xy 100.726717 -62.157622)
			(xy 100.778393 -62.226051) (xy 100.823534 -62.298957) (xy 100.861756 -62.375717) (xy 100.892732 -62.455676)
			(xy 100.916199 -62.538152) (xy 100.931955 -62.622442) (xy 100.939867 -62.707825) (xy 100.940362 -62.7507)
			(xy 100.939867 -62.793575) (xy 101.625133 -62.793575) (xy 101.625133 -62.707825) (xy 101.633045 -62.622442)
			(xy 101.648801 -62.538152) (xy 101.672268 -62.455676) (xy 101.703244 -62.375717) (xy 101.741466 -62.298957)
			(xy 101.786607 -62.226051) (xy 101.838283 -62.157622) (xy 101.896052 -62.094252) (xy 101.959422 -62.036483)
			(xy 102.027851 -61.984807) (xy 102.100757 -61.939666) (xy 102.177517 -61.901444) (xy 102.257476 -61.870468)
			(xy 102.339952 -61.847001) (xy 102.424242 -61.831245) (xy 102.509625 -61.823333) (xy 102.595375 -61.823333)
			(xy 102.680758 -61.831245) (xy 102.765048 -61.847001) (xy 102.847524 -61.870468) (xy 102.927483 -61.901444)
			(xy 103.004243 -61.939666) (xy 103.077149 -61.984807) (xy 103.145578 -62.036483) (xy 103.208948 -62.094252)
			(xy 103.266717 -62.157622) (xy 103.318393 -62.226051) (xy 103.363534 -62.298957) (xy 103.401756 -62.375717)
			(xy 103.432732 -62.455676) (xy 103.456199 -62.538152) (xy 103.471955 -62.622442) (xy 103.479867 -62.707825)
			(xy 103.480362 -62.7507) (xy 103.479867 -62.793575) (xy 104.165133 -62.793575) (xy 104.165133 -62.707825)
			(xy 104.173045 -62.622442) (xy 104.188801 -62.538152) (xy 104.212268 -62.455676) (xy 104.243244 -62.375717)
			(xy 104.281466 -62.298957) (xy 104.326607 -62.226051) (xy 104.378283 -62.157622) (xy 104.436052 -62.094252)
			(xy 104.499422 -62.036483) (xy 104.567851 -61.984807) (xy 104.640757 -61.939666) (xy 104.717517 -61.901444)
			(xy 104.797476 -61.870468) (xy 104.879952 -61.847001) (xy 104.964242 -61.831245) (xy 105.049625 -61.823333)
			(xy 105.135375 -61.823333) (xy 105.220758 -61.831245) (xy 105.305048 -61.847001) (xy 105.387524 -61.870468)
			(xy 105.467483 -61.901444) (xy 105.544243 -61.939666) (xy 105.617149 -61.984807) (xy 105.685578 -62.036483)
			(xy 105.748948 -62.094252) (xy 105.806717 -62.157622) (xy 105.858393 -62.226051) (xy 105.903534 -62.298957)
			(xy 105.941756 -62.375717) (xy 105.972732 -62.455676) (xy 105.996199 -62.538152) (xy 106.011955 -62.622442)
			(xy 106.019867 -62.707825) (xy 106.020362 -62.7507) (xy 106.019867 -62.793575) (xy 106.011955 -62.878958)
			(xy 105.996199 -62.963248) (xy 105.972732 -63.045724) (xy 105.941756 -63.125683) (xy 105.903534 -63.202443)
			(xy 105.858393 -63.275349) (xy 105.806717 -63.343778) (xy 105.748948 -63.407148) (xy 105.685578 -63.464917)
			(xy 105.617149 -63.516593) (xy 105.544243 -63.561734) (xy 105.467483 -63.599956) (xy 105.387524 -63.630932)
			(xy 105.305048 -63.654399) (xy 105.220758 -63.670155) (xy 105.135375 -63.678067) (xy 105.049625 -63.678067)
			(xy 104.964242 -63.670155) (xy 104.879952 -63.654399) (xy 104.797476 -63.630932) (xy 104.717517 -63.599956)
			(xy 104.640757 -63.561734) (xy 104.567851 -63.516593) (xy 104.499422 -63.464917) (xy 104.436052 -63.407148)
			(xy 104.378283 -63.343778) (xy 104.326607 -63.275349) (xy 104.281466 -63.202443) (xy 104.243244 -63.125683)
			(xy 104.212268 -63.045724) (xy 104.188801 -62.963248) (xy 104.173045 -62.878958) (xy 104.165133 -62.793575)
			(xy 103.479867 -62.793575) (xy 103.471955 -62.878958) (xy 103.456199 -62.963248) (xy 103.432732 -63.045724)
			(xy 103.401756 -63.125683) (xy 103.363534 -63.202443) (xy 103.318393 -63.275349) (xy 103.266717 -63.343778)
			(xy 103.208948 -63.407148) (xy 103.145578 -63.464917) (xy 103.077149 -63.516593) (xy 103.004243 -63.561734)
			(xy 102.927483 -63.599956) (xy 102.847524 -63.630932) (xy 102.765048 -63.654399) (xy 102.680758 -63.670155)
			(xy 102.595375 -63.678067) (xy 102.509625 -63.678067) (xy 102.424242 -63.670155) (xy 102.339952 -63.654399)
			(xy 102.257476 -63.630932) (xy 102.177517 -63.599956) (xy 102.100757 -63.561734) (xy 102.027851 -63.516593)
			(xy 101.959422 -63.464917) (xy 101.896052 -63.407148) (xy 101.838283 -63.343778) (xy 101.786607 -63.275349)
			(xy 101.741466 -63.202443) (xy 101.703244 -63.125683) (xy 101.672268 -63.045724) (xy 101.648801 -62.963248)
			(xy 101.633045 -62.878958) (xy 101.625133 -62.793575) (xy 100.939867 -62.793575) (xy 100.931955 -62.878958)
			(xy 100.916199 -62.963248) (xy 100.892732 -63.045724) (xy 100.861756 -63.125683) (xy 100.823534 -63.202443)
			(xy 100.778393 -63.275349) (xy 100.726717 -63.343778) (xy 100.668948 -63.407148) (xy 100.605578 -63.464917)
			(xy 100.537149 -63.516593) (xy 100.464243 -63.561734) (xy 100.387483 -63.599956) (xy 100.307524 -63.630932)
			(xy 100.225048 -63.654399) (xy 100.140758 -63.670155) (xy 100.055375 -63.678067) (xy 99.969625 -63.678067)
			(xy 99.884242 -63.670155) (xy 99.799952 -63.654399) (xy 99.717476 -63.630932) (xy 99.637517 -63.599956)
			(xy 99.560757 -63.561734) (xy 99.487851 -63.516593) (xy 99.419422 -63.464917) (xy 99.356052 -63.407148)
			(xy 99.298283 -63.343778) (xy 99.246607 -63.275349) (xy 99.201466 -63.202443) (xy 99.163244 -63.125683)
			(xy 99.132268 -63.045724) (xy 99.108801 -62.963248) (xy 99.093045 -62.878958) (xy 99.085133 -62.793575)
			(xy 92.50807 -62.793575) (xy 92.50807 -69.143575) (xy 99.085133 -69.143575) (xy 99.085133 -69.057825)
			(xy 99.093045 -68.972442) (xy 99.108801 -68.888152) (xy 99.132268 -68.805676) (xy 99.163244 -68.725717)
			(xy 99.201466 -68.648957) (xy 99.246607 -68.576051) (xy 99.298283 -68.507622) (xy 99.356052 -68.444252)
			(xy 99.419422 -68.386483) (xy 99.487851 -68.334807) (xy 99.560757 -68.289666) (xy 99.637517 -68.251444)
			(xy 99.717476 -68.220468) (xy 99.799952 -68.197001) (xy 99.884242 -68.181245) (xy 99.969625 -68.173333)
			(xy 100.055375 -68.173333) (xy 100.140758 -68.181245) (xy 100.225048 -68.197001) (xy 100.307524 -68.220468)
			(xy 100.387483 -68.251444) (xy 100.464243 -68.289666) (xy 100.537149 -68.334807) (xy 100.605578 -68.386483)
			(xy 100.668948 -68.444252) (xy 100.726717 -68.507622) (xy 100.778393 -68.576051) (xy 100.823534 -68.648957)
			(xy 100.861756 -68.725717) (xy 100.892732 -68.805676) (xy 100.916199 -68.888152) (xy 100.931955 -68.972442)
			(xy 100.939867 -69.057825) (xy 100.940362 -69.1007) (xy 100.939867 -69.143575) (xy 101.625133 -69.143575)
			(xy 101.625133 -69.057825) (xy 101.633045 -68.972442) (xy 101.648801 -68.888152) (xy 101.672268 -68.805676)
			(xy 101.703244 -68.725717) (xy 101.741466 -68.648957) (xy 101.786607 -68.576051) (xy 101.838283 -68.507622)
			(xy 101.896052 -68.444252) (xy 101.959422 -68.386483) (xy 102.027851 -68.334807) (xy 102.100757 -68.289666)
			(xy 102.177517 -68.251444) (xy 102.257476 -68.220468) (xy 102.339952 -68.197001) (xy 102.424242 -68.181245)
			(xy 102.509625 -68.173333) (xy 102.595375 -68.173333) (xy 102.680758 -68.181245) (xy 102.765048 -68.197001)
			(xy 102.847524 -68.220468) (xy 102.927483 -68.251444) (xy 103.004243 -68.289666) (xy 103.077149 -68.334807)
			(xy 103.145578 -68.386483) (xy 103.208948 -68.444252) (xy 103.266717 -68.507622) (xy 103.318393 -68.576051)
			(xy 103.363534 -68.648957) (xy 103.401756 -68.725717) (xy 103.432732 -68.805676) (xy 103.456199 -68.888152)
			(xy 103.471955 -68.972442) (xy 103.479867 -69.057825) (xy 103.480362 -69.1007) (xy 103.479867 -69.143575)
			(xy 104.165133 -69.143575) (xy 104.165133 -69.057825) (xy 104.173045 -68.972442) (xy 104.188801 -68.888152)
			(xy 104.212268 -68.805676) (xy 104.243244 -68.725717) (xy 104.281466 -68.648957) (xy 104.326607 -68.576051)
			(xy 104.378283 -68.507622) (xy 104.436052 -68.444252) (xy 104.499422 -68.386483) (xy 104.567851 -68.334807)
			(xy 104.640757 -68.289666) (xy 104.717517 -68.251444) (xy 104.797476 -68.220468) (xy 104.879952 -68.197001)
			(xy 104.964242 -68.181245) (xy 105.049625 -68.173333) (xy 105.135375 -68.173333) (xy 105.220758 -68.181245)
			(xy 105.305048 -68.197001) (xy 105.387524 -68.220468) (xy 105.467483 -68.251444) (xy 105.544243 -68.289666)
			(xy 105.617149 -68.334807) (xy 105.685578 -68.386483) (xy 105.748948 -68.444252) (xy 105.806717 -68.507622)
			(xy 105.858393 -68.576051) (xy 105.903534 -68.648957) (xy 105.941756 -68.725717) (xy 105.972732 -68.805676)
			(xy 105.996199 -68.888152) (xy 106.011955 -68.972442) (xy 106.019867 -69.057825) (xy 106.020362 -69.1007)
			(xy 106.019867 -69.143575) (xy 106.011955 -69.228958) (xy 105.996199 -69.313248) (xy 105.972732 -69.395724)
			(xy 105.941756 -69.475683) (xy 105.903534 -69.552443) (xy 105.858393 -69.625349) (xy 105.806717 -69.693778)
			(xy 105.748948 -69.757148) (xy 105.685578 -69.814917) (xy 105.617149 -69.866593) (xy 105.544243 -69.911734)
			(xy 105.467483 -69.949956) (xy 105.387524 -69.980932) (xy 105.305048 -70.004399) (xy 105.220758 -70.020155)
			(xy 105.135375 -70.028067) (xy 105.049625 -70.028067) (xy 104.964242 -70.020155) (xy 104.879952 -70.004399)
			(xy 104.797476 -69.980932) (xy 104.717517 -69.949956) (xy 104.640757 -69.911734) (xy 104.567851 -69.866593)
			(xy 104.499422 -69.814917) (xy 104.436052 -69.757148) (xy 104.378283 -69.693778) (xy 104.326607 -69.625349)
			(xy 104.281466 -69.552443) (xy 104.243244 -69.475683) (xy 104.212268 -69.395724) (xy 104.188801 -69.313248)
			(xy 104.173045 -69.228958) (xy 104.165133 -69.143575) (xy 103.479867 -69.143575) (xy 103.471955 -69.228958)
			(xy 103.456199 -69.313248) (xy 103.432732 -69.395724) (xy 103.401756 -69.475683) (xy 103.363534 -69.552443)
			(xy 103.318393 -69.625349) (xy 103.266717 -69.693778) (xy 103.208948 -69.757148) (xy 103.145578 -69.814917)
			(xy 103.077149 -69.866593) (xy 103.004243 -69.911734) (xy 102.927483 -69.949956) (xy 102.847524 -69.980932)
			(xy 102.765048 -70.004399) (xy 102.680758 -70.020155) (xy 102.595375 -70.028067) (xy 102.509625 -70.028067)
			(xy 102.424242 -70.020155) (xy 102.339952 -70.004399) (xy 102.257476 -69.980932) (xy 102.177517 -69.949956)
			(xy 102.100757 -69.911734) (xy 102.027851 -69.866593) (xy 101.959422 -69.814917) (xy 101.896052 -69.757148)
			(xy 101.838283 -69.693778) (xy 101.786607 -69.625349) (xy 101.741466 -69.552443) (xy 101.703244 -69.475683)
			(xy 101.672268 -69.395724) (xy 101.648801 -69.313248) (xy 101.633045 -69.228958) (xy 101.625133 -69.143575)
			(xy 100.939867 -69.143575) (xy 100.931955 -69.228958) (xy 100.916199 -69.313248) (xy 100.892732 -69.395724)
			(xy 100.861756 -69.475683) (xy 100.823534 -69.552443) (xy 100.778393 -69.625349) (xy 100.726717 -69.693778)
			(xy 100.668948 -69.757148) (xy 100.605578 -69.814917) (xy 100.537149 -69.866593) (xy 100.464243 -69.911734)
			(xy 100.387483 -69.949956) (xy 100.307524 -69.980932) (xy 100.225048 -70.004399) (xy 100.140758 -70.020155)
			(xy 100.055375 -70.028067) (xy 99.969625 -70.028067) (xy 99.884242 -70.020155) (xy 99.799952 -70.004399)
			(xy 99.717476 -69.980932) (xy 99.637517 -69.949956) (xy 99.560757 -69.911734) (xy 99.487851 -69.866593)
			(xy 99.419422 -69.814917) (xy 99.356052 -69.757148) (xy 99.298283 -69.693778) (xy 99.246607 -69.625349)
			(xy 99.201466 -69.552443) (xy 99.163244 -69.475683) (xy 99.132268 -69.395724) (xy 99.108801 -69.313248)
			(xy 99.093045 -69.228958) (xy 99.085133 -69.143575) (xy 92.50807 -69.143575) (xy 92.50807 -94.976137)
			(xy 93.729289 -94.976137) (xy 93.729289 -94.890387) (xy 93.737201 -94.805004) (xy 93.752957 -94.720714)
			(xy 93.776424 -94.638238) (xy 93.8074 -94.558279) (xy 93.845622 -94.481519) (xy 93.890763 -94.408613)
			(xy 93.942439 -94.340184) (xy 94.000208 -94.276814) (xy 94.063578 -94.219045) (xy 94.132007 -94.167369)
			(xy 94.204913 -94.122228) (xy 94.281673 -94.084006) (xy 94.361632 -94.05303) (xy 94.444108 -94.029563)
			(xy 94.528398 -94.013807) (xy 94.613781 -94.005895) (xy 94.699531 -94.005895) (xy 94.784914 -94.013807)
			(xy 94.869204 -94.029563) (xy 94.95168 -94.05303) (xy 95.031639 -94.084006) (xy 95.108399 -94.122228)
			(xy 95.181305 -94.167369) (xy 95.249734 -94.219045) (xy 95.313104 -94.276814) (xy 95.370873 -94.340184)
			(xy 95.422549 -94.408613) (xy 95.46769 -94.481519) (xy 95.505912 -94.558279) (xy 95.536888 -94.638238)
			(xy 95.560355 -94.720714) (xy 95.576111 -94.805004) (xy 95.584023 -94.890387) (xy 95.584518 -94.933262)
			(xy 95.584023 -94.976137) (xy 96.269289 -94.976137) (xy 96.269289 -94.890387) (xy 96.277201 -94.805004)
			(xy 96.292957 -94.720714) (xy 96.316424 -94.638238) (xy 96.3474 -94.558279) (xy 96.385622 -94.481519)
			(xy 96.430763 -94.408613) (xy 96.482439 -94.340184) (xy 96.540208 -94.276814) (xy 96.603578 -94.219045)
			(xy 96.672007 -94.167369) (xy 96.744913 -94.122228) (xy 96.821673 -94.084006) (xy 96.901632 -94.05303)
			(xy 96.984108 -94.029563) (xy 97.068398 -94.013807) (xy 97.153781 -94.005895) (xy 97.239531 -94.005895)
			(xy 97.324914 -94.013807) (xy 97.409204 -94.029563) (xy 97.49168 -94.05303) (xy 97.571639 -94.084006)
			(xy 97.648399 -94.122228) (xy 97.721305 -94.167369) (xy 97.789734 -94.219045) (xy 97.853104 -94.276814)
			(xy 97.910873 -94.340184) (xy 97.962549 -94.408613) (xy 98.00769 -94.481519) (xy 98.045912 -94.558279)
			(xy 98.076888 -94.638238) (xy 98.100355 -94.720714) (xy 98.116111 -94.805004) (xy 98.124023 -94.890387)
			(xy 98.124518 -94.933262) (xy 98.124023 -94.976137) (xy 98.116111 -95.06152) (xy 98.100355 -95.14581)
			(xy 98.076888 -95.228286) (xy 98.045912 -95.308245) (xy 98.00769 -95.385005) (xy 97.962549 -95.457911)
			(xy 97.910873 -95.52634) (xy 97.853104 -95.58971) (xy 97.789734 -95.647479) (xy 97.721305 -95.699155)
			(xy 97.648399 -95.744296) (xy 97.571639 -95.782518) (xy 97.49168 -95.813494) (xy 97.409204 -95.836961)
			(xy 97.324914 -95.852717) (xy 97.239531 -95.860629) (xy 97.153781 -95.860629) (xy 97.068398 -95.852717)
			(xy 96.984108 -95.836961) (xy 96.901632 -95.813494) (xy 96.821673 -95.782518) (xy 96.744913 -95.744296)
			(xy 96.672007 -95.699155) (xy 96.603578 -95.647479) (xy 96.540208 -95.58971) (xy 96.482439 -95.52634)
			(xy 96.430763 -95.457911) (xy 96.385622 -95.385005) (xy 96.3474 -95.308245) (xy 96.316424 -95.228286)
			(xy 96.292957 -95.14581) (xy 96.277201 -95.06152) (xy 96.269289 -94.976137) (xy 95.584023 -94.976137)
			(xy 95.576111 -95.06152) (xy 95.560355 -95.14581) (xy 95.536888 -95.228286) (xy 95.505912 -95.308245)
			(xy 95.46769 -95.385005) (xy 95.422549 -95.457911) (xy 95.370873 -95.52634) (xy 95.313104 -95.58971)
			(xy 95.249734 -95.647479) (xy 95.181305 -95.699155) (xy 95.108399 -95.744296) (xy 95.031639 -95.782518)
			(xy 94.95168 -95.813494) (xy 94.869204 -95.836961) (xy 94.784914 -95.852717) (xy 94.699531 -95.860629)
			(xy 94.613781 -95.860629) (xy 94.528398 -95.852717) (xy 94.444108 -95.836961) (xy 94.361632 -95.813494)
			(xy 94.281673 -95.782518) (xy 94.204913 -95.744296) (xy 94.132007 -95.699155) (xy 94.063578 -95.647479)
			(xy 94.000208 -95.58971) (xy 93.942439 -95.52634) (xy 93.890763 -95.457911) (xy 93.845622 -95.385005)
			(xy 93.8074 -95.308245) (xy 93.776424 -95.228286) (xy 93.752957 -95.14581) (xy 93.737201 -95.06152)
			(xy 93.729289 -94.976137) (xy 92.50807 -94.976137) (xy 92.50807 -96.949868) (xy 95.113614 -96.949868)
			(xy 95.113614 -96.895332) (xy 95.121375 -96.841351) (xy 95.136739 -96.789023) (xy 95.159392 -96.739415)
			(xy 95.188875 -96.693535) (xy 95.224586 -96.652317) (xy 95.2658 -96.616601) (xy 95.311676 -96.587113)
			(xy 95.361282 -96.564454) (xy 95.413608 -96.549084) (xy 95.467588 -96.541317) (xy 95.494856 -96.540828)
			(xy 96.358456 -96.540828) (xy 96.385728 -96.541308) (xy 96.439719 -96.549065) (xy 96.492055 -96.564427)
			(xy 96.541673 -96.587082) (xy 96.587561 -96.616568) (xy 96.628785 -96.652284) (xy 96.664506 -96.693504)
			(xy 96.693997 -96.739389) (xy 96.716657 -96.789004) (xy 96.732025 -96.841338) (xy 96.739788 -96.895328)
			(xy 96.739788 -96.949872) (xy 96.732025 -97.003862) (xy 96.716657 -97.056196) (xy 96.693997 -97.105811)
			(xy 96.664506 -97.151696) (xy 96.628785 -97.192916) (xy 96.587561 -97.228632) (xy 96.541673 -97.258118)
			(xy 96.492055 -97.280773) (xy 96.439719 -97.296135) (xy 96.385728 -97.303892) (xy 96.358456 -97.304352)
			(xy 95.494856 -97.304352) (xy 95.467588 -97.303883) (xy 95.413608 -97.296116) (xy 95.361282 -97.280746)
			(xy 95.311676 -97.258087) (xy 95.2658 -97.228599) (xy 95.224586 -97.192883) (xy 95.188875 -97.151665)
			(xy 95.159392 -97.105785) (xy 95.136739 -97.056177) (xy 95.121375 -97.003849) (xy 95.113614 -96.949868)
			(xy 92.50807 -96.949868) (xy 92.50807 -101.326137) (xy 93.729289 -101.326137) (xy 93.729289 -101.240387)
			(xy 93.737201 -101.155004) (xy 93.752957 -101.070714) (xy 93.776424 -100.988238) (xy 93.8074 -100.908279)
			(xy 93.845622 -100.831519) (xy 93.890763 -100.758613) (xy 93.942439 -100.690184) (xy 94.000208 -100.626814)
			(xy 94.063578 -100.569045) (xy 94.132007 -100.517369) (xy 94.204913 -100.472228) (xy 94.281673 -100.434006)
			(xy 94.361632 -100.40303) (xy 94.444108 -100.379563) (xy 94.528398 -100.363807) (xy 94.613781 -100.355895)
			(xy 94.699531 -100.355895) (xy 94.784914 -100.363807) (xy 94.869204 -100.379563) (xy 94.95168 -100.40303)
			(xy 95.031639 -100.434006) (xy 95.108399 -100.472228) (xy 95.181305 -100.517369) (xy 95.249734 -100.569045)
			(xy 95.313104 -100.626814) (xy 95.370873 -100.690184) (xy 95.422549 -100.758613) (xy 95.46769 -100.831519)
			(xy 95.505912 -100.908279) (xy 95.536888 -100.988238) (xy 95.560355 -101.070714) (xy 95.576111 -101.155004)
			(xy 95.584023 -101.240387) (xy 95.584518 -101.283262) (xy 95.584023 -101.326137) (xy 96.269289 -101.326137)
			(xy 96.269289 -101.240387) (xy 96.277201 -101.155004) (xy 96.292957 -101.070714) (xy 96.316424 -100.988238)
			(xy 96.3474 -100.908279) (xy 96.385622 -100.831519) (xy 96.430763 -100.758613) (xy 96.482439 -100.690184)
			(xy 96.540208 -100.626814) (xy 96.603578 -100.569045) (xy 96.672007 -100.517369) (xy 96.744913 -100.472228)
			(xy 96.821673 -100.434006) (xy 96.901632 -100.40303) (xy 96.984108 -100.379563) (xy 97.068398 -100.363807)
			(xy 97.153781 -100.355895) (xy 97.239531 -100.355895) (xy 97.324914 -100.363807) (xy 97.409204 -100.379563)
			(xy 97.49168 -100.40303) (xy 97.571639 -100.434006) (xy 97.648399 -100.472228) (xy 97.721305 -100.517369)
			(xy 97.789734 -100.569045) (xy 97.853104 -100.626814) (xy 97.910873 -100.690184) (xy 97.962549 -100.758613)
			(xy 98.00769 -100.831519) (xy 98.045912 -100.908279) (xy 98.076888 -100.988238) (xy 98.100355 -101.070714)
			(xy 98.116111 -101.155004) (xy 98.124023 -101.240387) (xy 98.124518 -101.283262) (xy 98.124023 -101.326137)
			(xy 98.122681 -101.340615) (xy 99.085133 -101.340615) (xy 99.085133 -101.254865) (xy 99.093045 -101.169482)
			(xy 99.108801 -101.085192) (xy 99.132268 -101.002716) (xy 99.163244 -100.922757) (xy 99.201466 -100.845997)
			(xy 99.246607 -100.773091) (xy 99.298283 -100.704662) (xy 99.356052 -100.641292) (xy 99.419422 -100.583523)
			(xy 99.487851 -100.531847) (xy 99.560757 -100.486706) (xy 99.637517 -100.448484) (xy 99.717476 -100.417508)
			(xy 99.799952 -100.394041) (xy 99.884242 -100.378285) (xy 99.969625 -100.370373) (xy 100.055375 -100.370373)
			(xy 100.140758 -100.378285) (xy 100.225048 -100.394041) (xy 100.307524 -100.417508) (xy 100.387483 -100.448484)
			(xy 100.464243 -100.486706) (xy 100.537149 -100.531847) (xy 100.605578 -100.583523) (xy 100.668948 -100.641292)
			(xy 100.726717 -100.704662) (xy 100.778393 -100.773091) (xy 100.823534 -100.845997) (xy 100.861756 -100.922757)
			(xy 100.892732 -101.002716) (xy 100.916199 -101.085192) (xy 100.931955 -101.169482) (xy 100.939867 -101.254865)
			(xy 100.940362 -101.29774) (xy 100.939867 -101.340615) (xy 101.625133 -101.340615) (xy 101.625133 -101.254865)
			(xy 101.633045 -101.169482) (xy 101.648801 -101.085192) (xy 101.672268 -101.002716) (xy 101.703244 -100.922757)
			(xy 101.741466 -100.845997) (xy 101.786607 -100.773091) (xy 101.838283 -100.704662) (xy 101.896052 -100.641292)
			(xy 101.959422 -100.583523) (xy 102.027851 -100.531847) (xy 102.100757 -100.486706) (xy 102.177517 -100.448484)
			(xy 102.257476 -100.417508) (xy 102.339952 -100.394041) (xy 102.424242 -100.378285) (xy 102.509625 -100.370373)
			(xy 102.595375 -100.370373) (xy 102.680758 -100.378285) (xy 102.765048 -100.394041) (xy 102.847524 -100.417508)
			(xy 102.927483 -100.448484) (xy 103.004243 -100.486706) (xy 103.077149 -100.531847) (xy 103.145578 -100.583523)
			(xy 103.208948 -100.641292) (xy 103.266717 -100.704662) (xy 103.318393 -100.773091) (xy 103.363534 -100.845997)
			(xy 103.401756 -100.922757) (xy 103.432732 -101.002716) (xy 103.456199 -101.085192) (xy 103.471955 -101.169482)
			(xy 103.479867 -101.254865) (xy 103.480362 -101.29774) (xy 103.479867 -101.340615) (xy 104.165133 -101.340615)
			(xy 104.165133 -101.254865) (xy 104.173045 -101.169482) (xy 104.188801 -101.085192) (xy 104.212268 -101.002716)
			(xy 104.243244 -100.922757) (xy 104.281466 -100.845997) (xy 104.326607 -100.773091) (xy 104.378283 -100.704662)
			(xy 104.436052 -100.641292) (xy 104.499422 -100.583523) (xy 104.567851 -100.531847) (xy 104.640757 -100.486706)
			(xy 104.717517 -100.448484) (xy 104.797476 -100.417508) (xy 104.879952 -100.394041) (xy 104.964242 -100.378285)
			(xy 105.049625 -100.370373) (xy 105.135375 -100.370373) (xy 105.220758 -100.378285) (xy 105.305048 -100.394041)
			(xy 105.387524 -100.417508) (xy 105.467483 -100.448484) (xy 105.544243 -100.486706) (xy 105.617149 -100.531847)
			(xy 105.685578 -100.583523) (xy 105.748948 -100.641292) (xy 105.806717 -100.704662) (xy 105.858393 -100.773091)
			(xy 105.903534 -100.845997) (xy 105.941756 -100.922757) (xy 105.972732 -101.002716) (xy 105.996199 -101.085192)
			(xy 106.011955 -101.169482) (xy 106.019867 -101.254865) (xy 106.020362 -101.29774) (xy 106.019867 -101.340615)
			(xy 106.011955 -101.425998) (xy 105.996199 -101.510288) (xy 105.972732 -101.592764) (xy 105.941756 -101.672723)
			(xy 105.903534 -101.749483) (xy 105.858393 -101.822389) (xy 105.806717 -101.890818) (xy 105.748948 -101.954188)
			(xy 105.685578 -102.011957) (xy 105.617149 -102.063633) (xy 105.544243 -102.108774) (xy 105.467483 -102.146996)
			(xy 105.387524 -102.177972) (xy 105.305048 -102.201439) (xy 105.220758 -102.217195) (xy 105.135375 -102.225107)
			(xy 105.049625 -102.225107) (xy 104.964242 -102.217195) (xy 104.879952 -102.201439) (xy 104.797476 -102.177972)
			(xy 104.717517 -102.146996) (xy 104.640757 -102.108774) (xy 104.567851 -102.063633) (xy 104.499422 -102.011957)
			(xy 104.436052 -101.954188) (xy 104.378283 -101.890818) (xy 104.326607 -101.822389) (xy 104.281466 -101.749483)
			(xy 104.243244 -101.672723) (xy 104.212268 -101.592764) (xy 104.188801 -101.510288) (xy 104.173045 -101.425998)
			(xy 104.165133 -101.340615) (xy 103.479867 -101.340615) (xy 103.471955 -101.425998) (xy 103.456199 -101.510288)
			(xy 103.432732 -101.592764) (xy 103.401756 -101.672723) (xy 103.363534 -101.749483) (xy 103.318393 -101.822389)
			(xy 103.266717 -101.890818) (xy 103.208948 -101.954188) (xy 103.145578 -102.011957) (xy 103.077149 -102.063633)
			(xy 103.004243 -102.108774) (xy 102.927483 -102.146996) (xy 102.847524 -102.177972) (xy 102.765048 -102.201439)
			(xy 102.680758 -102.217195) (xy 102.595375 -102.225107) (xy 102.509625 -102.225107) (xy 102.424242 -102.217195)
			(xy 102.339952 -102.201439) (xy 102.257476 -102.177972) (xy 102.177517 -102.146996) (xy 102.100757 -102.108774)
			(xy 102.027851 -102.063633) (xy 101.959422 -102.011957) (xy 101.896052 -101.954188) (xy 101.838283 -101.890818)
			(xy 101.786607 -101.822389) (xy 101.741466 -101.749483) (xy 101.703244 -101.672723) (xy 101.672268 -101.592764)
			(xy 101.648801 -101.510288) (xy 101.633045 -101.425998) (xy 101.625133 -101.340615) (xy 100.939867 -101.340615)
			(xy 100.931955 -101.425998) (xy 100.916199 -101.510288) (xy 100.892732 -101.592764) (xy 100.861756 -101.672723)
			(xy 100.823534 -101.749483) (xy 100.778393 -101.822389) (xy 100.726717 -101.890818) (xy 100.668948 -101.954188)
			(xy 100.605578 -102.011957) (xy 100.537149 -102.063633) (xy 100.464243 -102.108774) (xy 100.387483 -102.146996)
			(xy 100.307524 -102.177972) (xy 100.225048 -102.201439) (xy 100.140758 -102.217195) (xy 100.055375 -102.225107)
			(xy 99.969625 -102.225107) (xy 99.884242 -102.217195) (xy 99.799952 -102.201439) (xy 99.717476 -102.177972)
			(xy 99.637517 -102.146996) (xy 99.560757 -102.108774) (xy 99.487851 -102.063633) (xy 99.419422 -102.011957)
			(xy 99.356052 -101.954188) (xy 99.298283 -101.890818) (xy 99.246607 -101.822389) (xy 99.201466 -101.749483)
			(xy 99.163244 -101.672723) (xy 99.132268 -101.592764) (xy 99.108801 -101.510288) (xy 99.093045 -101.425998)
			(xy 99.085133 -101.340615) (xy 98.122681 -101.340615) (xy 98.116111 -101.41152) (xy 98.100355 -101.49581)
			(xy 98.076888 -101.578286) (xy 98.045912 -101.658245) (xy 98.00769 -101.735005) (xy 97.962549 -101.807911)
			(xy 97.910873 -101.87634) (xy 97.853104 -101.93971) (xy 97.789734 -101.997479) (xy 97.721305 -102.049155)
			(xy 97.648399 -102.094296) (xy 97.571639 -102.132518) (xy 97.49168 -102.163494) (xy 97.409204 -102.186961)
			(xy 97.324914 -102.202717) (xy 97.239531 -102.210629) (xy 97.153781 -102.210629) (xy 97.068398 -102.202717)
			(xy 96.984108 -102.186961) (xy 96.901632 -102.163494) (xy 96.821673 -102.132518) (xy 96.744913 -102.094296)
			(xy 96.672007 -102.049155) (xy 96.603578 -101.997479) (xy 96.540208 -101.93971) (xy 96.482439 -101.87634)
			(xy 96.430763 -101.807911) (xy 96.385622 -101.735005) (xy 96.3474 -101.658245) (xy 96.316424 -101.578286)
			(xy 96.292957 -101.49581) (xy 96.277201 -101.41152) (xy 96.269289 -101.326137) (xy 95.584023 -101.326137)
			(xy 95.576111 -101.41152) (xy 95.560355 -101.49581) (xy 95.536888 -101.578286) (xy 95.505912 -101.658245)
			(xy 95.46769 -101.735005) (xy 95.422549 -101.807911) (xy 95.370873 -101.87634) (xy 95.313104 -101.93971)
			(xy 95.249734 -101.997479) (xy 95.181305 -102.049155) (xy 95.108399 -102.094296) (xy 95.031639 -102.132518)
			(xy 94.95168 -102.163494) (xy 94.869204 -102.186961) (xy 94.784914 -102.202717) (xy 94.699531 -102.210629)
			(xy 94.613781 -102.210629) (xy 94.528398 -102.202717) (xy 94.444108 -102.186961) (xy 94.361632 -102.163494)
			(xy 94.281673 -102.132518) (xy 94.204913 -102.094296) (xy 94.132007 -102.049155) (xy 94.063578 -101.997479)
			(xy 94.000208 -101.93971) (xy 93.942439 -101.87634) (xy 93.890763 -101.807911) (xy 93.845622 -101.735005)
			(xy 93.8074 -101.658245) (xy 93.776424 -101.578286) (xy 93.752957 -101.49581) (xy 93.737201 -101.41152)
			(xy 93.729289 -101.326137) (xy 92.50807 -101.326137) (xy 92.50807 -107.690615) (xy 99.085133 -107.690615)
			(xy 99.085133 -107.604865) (xy 99.093045 -107.519482) (xy 99.108801 -107.435192) (xy 99.132268 -107.352716)
			(xy 99.163244 -107.272757) (xy 99.201466 -107.195997) (xy 99.246607 -107.123091) (xy 99.298283 -107.054662)
			(xy 99.356052 -106.991292) (xy 99.419422 -106.933523) (xy 99.487851 -106.881847) (xy 99.560757 -106.836706)
			(xy 99.637517 -106.798484) (xy 99.717476 -106.767508) (xy 99.799952 -106.744041) (xy 99.884242 -106.728285)
			(xy 99.969625 -106.720373) (xy 100.055375 -106.720373) (xy 100.140758 -106.728285) (xy 100.225048 -106.744041)
			(xy 100.307524 -106.767508) (xy 100.387483 -106.798484) (xy 100.464243 -106.836706) (xy 100.537149 -106.881847)
			(xy 100.605578 -106.933523) (xy 100.668948 -106.991292) (xy 100.726717 -107.054662) (xy 100.778393 -107.123091)
			(xy 100.823534 -107.195997) (xy 100.861756 -107.272757) (xy 100.892732 -107.352716) (xy 100.916199 -107.435192)
			(xy 100.931955 -107.519482) (xy 100.939867 -107.604865) (xy 100.940362 -107.64774) (xy 100.939867 -107.690615)
			(xy 101.625133 -107.690615) (xy 101.625133 -107.604865) (xy 101.633045 -107.519482) (xy 101.648801 -107.435192)
			(xy 101.672268 -107.352716) (xy 101.703244 -107.272757) (xy 101.741466 -107.195997) (xy 101.786607 -107.123091)
			(xy 101.838283 -107.054662) (xy 101.896052 -106.991292) (xy 101.959422 -106.933523) (xy 102.027851 -106.881847)
			(xy 102.100757 -106.836706) (xy 102.177517 -106.798484) (xy 102.257476 -106.767508) (xy 102.339952 -106.744041)
			(xy 102.424242 -106.728285) (xy 102.509625 -106.720373) (xy 102.595375 -106.720373) (xy 102.680758 -106.728285)
			(xy 102.765048 -106.744041) (xy 102.847524 -106.767508) (xy 102.927483 -106.798484) (xy 103.004243 -106.836706)
			(xy 103.077149 -106.881847) (xy 103.145578 -106.933523) (xy 103.208948 -106.991292) (xy 103.266717 -107.054662)
			(xy 103.318393 -107.123091) (xy 103.363534 -107.195997) (xy 103.401756 -107.272757) (xy 103.432732 -107.352716)
			(xy 103.456199 -107.435192) (xy 103.471955 -107.519482) (xy 103.479867 -107.604865) (xy 103.480362 -107.64774)
			(xy 103.479867 -107.690615) (xy 104.165133 -107.690615) (xy 104.165133 -107.604865) (xy 104.173045 -107.519482)
			(xy 104.188801 -107.435192) (xy 104.212268 -107.352716) (xy 104.243244 -107.272757) (xy 104.281466 -107.195997)
			(xy 104.326607 -107.123091) (xy 104.378283 -107.054662) (xy 104.436052 -106.991292) (xy 104.499422 -106.933523)
			(xy 104.567851 -106.881847) (xy 104.640757 -106.836706) (xy 104.717517 -106.798484) (xy 104.797476 -106.767508)
			(xy 104.879952 -106.744041) (xy 104.964242 -106.728285) (xy 105.049625 -106.720373) (xy 105.135375 -106.720373)
			(xy 105.220758 -106.728285) (xy 105.305048 -106.744041) (xy 105.387524 -106.767508) (xy 105.467483 -106.798484)
			(xy 105.544243 -106.836706) (xy 105.617149 -106.881847) (xy 105.685578 -106.933523) (xy 105.748948 -106.991292)
			(xy 105.806717 -107.054662) (xy 105.858393 -107.123091) (xy 105.903534 -107.195997) (xy 105.941756 -107.272757)
			(xy 105.972732 -107.352716) (xy 105.996199 -107.435192) (xy 106.011955 -107.519482) (xy 106.019867 -107.604865)
			(xy 106.020362 -107.64774) (xy 106.019867 -107.690615) (xy 106.011955 -107.775998) (xy 105.996199 -107.860288)
			(xy 105.972732 -107.942764) (xy 105.941756 -108.022723) (xy 105.903534 -108.099483) (xy 105.858393 -108.172389)
			(xy 105.806717 -108.240818) (xy 105.748948 -108.304188) (xy 105.685578 -108.361957) (xy 105.617149 -108.413633)
			(xy 105.544243 -108.458774) (xy 105.467483 -108.496996) (xy 105.387524 -108.527972) (xy 105.305048 -108.551439)
			(xy 105.220758 -108.567195) (xy 105.135375 -108.575107) (xy 105.049625 -108.575107) (xy 104.964242 -108.567195)
			(xy 104.879952 -108.551439) (xy 104.797476 -108.527972) (xy 104.717517 -108.496996) (xy 104.640757 -108.458774)
			(xy 104.567851 -108.413633) (xy 104.499422 -108.361957) (xy 104.436052 -108.304188) (xy 104.378283 -108.240818)
			(xy 104.326607 -108.172389) (xy 104.281466 -108.099483) (xy 104.243244 -108.022723) (xy 104.212268 -107.942764)
			(xy 104.188801 -107.860288) (xy 104.173045 -107.775998) (xy 104.165133 -107.690615) (xy 103.479867 -107.690615)
			(xy 103.471955 -107.775998) (xy 103.456199 -107.860288) (xy 103.432732 -107.942764) (xy 103.401756 -108.022723)
			(xy 103.363534 -108.099483) (xy 103.318393 -108.172389) (xy 103.266717 -108.240818) (xy 103.208948 -108.304188)
			(xy 103.145578 -108.361957) (xy 103.077149 -108.413633) (xy 103.004243 -108.458774) (xy 102.927483 -108.496996)
			(xy 102.847524 -108.527972) (xy 102.765048 -108.551439) (xy 102.680758 -108.567195) (xy 102.595375 -108.575107)
			(xy 102.509625 -108.575107) (xy 102.424242 -108.567195) (xy 102.339952 -108.551439) (xy 102.257476 -108.527972)
			(xy 102.177517 -108.496996) (xy 102.100757 -108.458774) (xy 102.027851 -108.413633) (xy 101.959422 -108.361957)
			(xy 101.896052 -108.304188) (xy 101.838283 -108.240818) (xy 101.786607 -108.172389) (xy 101.741466 -108.099483)
			(xy 101.703244 -108.022723) (xy 101.672268 -107.942764) (xy 101.648801 -107.860288) (xy 101.633045 -107.775998)
			(xy 101.625133 -107.690615) (xy 100.939867 -107.690615) (xy 100.931955 -107.775998) (xy 100.916199 -107.860288)
			(xy 100.892732 -107.942764) (xy 100.861756 -108.022723) (xy 100.823534 -108.099483) (xy 100.778393 -108.172389)
			(xy 100.726717 -108.240818) (xy 100.668948 -108.304188) (xy 100.605578 -108.361957) (xy 100.537149 -108.413633)
			(xy 100.464243 -108.458774) (xy 100.387483 -108.496996) (xy 100.307524 -108.527972) (xy 100.225048 -108.551439)
			(xy 100.140758 -108.567195) (xy 100.055375 -108.575107) (xy 99.969625 -108.575107) (xy 99.884242 -108.567195)
			(xy 99.799952 -108.551439) (xy 99.717476 -108.527972) (xy 99.637517 -108.496996) (xy 99.560757 -108.458774)
			(xy 99.487851 -108.413633) (xy 99.419422 -108.361957) (xy 99.356052 -108.304188) (xy 99.298283 -108.240818)
			(xy 99.246607 -108.172389) (xy 99.201466 -108.099483) (xy 99.163244 -108.022723) (xy 99.132268 -107.942764)
			(xy 99.108801 -107.860288) (xy 99.093045 -107.775998) (xy 99.085133 -107.690615) (xy 92.50807 -107.690615)
			(xy 92.50807 -115.464644) (xy 115.904253 -115.464644) (xy 115.904253 -115.335504) (xy 115.912203 -115.206609)
			(xy 115.928073 -115.078449) (xy 115.951802 -114.951508) (xy 115.983301 -114.826269) (xy 116.02245 -114.703206)
			(xy 116.069101 -114.582787) (xy 116.123076 -114.465468) (xy 116.184171 -114.351694) (xy 116.252154 -114.241897)
			(xy 116.326768 -114.136494) (xy 116.407729 -114.035884) (xy 116.494729 -113.940449) (xy 116.58744 -113.85055)
			(xy 116.68551 -113.766529) (xy 116.788565 -113.688705) (xy 116.896216 -113.617373) (xy 117.008055 -113.552803)
			(xy 117.123656 -113.495241) (xy 117.242581 -113.444904) (xy 117.36438 -113.401984) (xy 117.48859 -113.366643)
			(xy 117.614739 -113.339016) (xy 117.742351 -113.319207) (xy 117.87094 -113.307291) (xy 118.000018 -113.303315)
			(xy 118.129096 -113.307291) (xy 118.257685 -113.319207) (xy 118.385297 -113.339016) (xy 118.511446 -113.366643)
			(xy 118.635656 -113.401984) (xy 118.757455 -113.444904) (xy 118.87638 -113.495241) (xy 118.991981 -113.552803)
			(xy 119.10382 -113.617373) (xy 119.211471 -113.688705) (xy 119.314526 -113.766529) (xy 119.412596 -113.85055)
			(xy 119.505307 -113.940449) (xy 119.592307 -114.035884) (xy 119.673268 -114.136494) (xy 119.747882 -114.241897)
			(xy 119.815865 -114.351694) (xy 119.87696 -114.465468) (xy 119.930935 -114.582787) (xy 119.977586 -114.703206)
			(xy 120.016735 -114.826269) (xy 120.048234 -114.951508) (xy 120.071963 -115.078449) (xy 120.087833 -115.206609)
			(xy 120.095783 -115.335504) (xy 120.09628 -115.400074) (xy 120.095783 -115.464644) (xy 120.087833 -115.593539)
			(xy 120.071963 -115.721699) (xy 120.048234 -115.84864) (xy 120.016735 -115.973879) (xy 119.977586 -116.096942)
			(xy 119.930935 -116.217361) (xy 119.87696 -116.33468) (xy 119.815865 -116.448454) (xy 119.747882 -116.558251)
			(xy 119.673268 -116.663654) (xy 119.592307 -116.764264) (xy 119.505307 -116.859699) (xy 119.412596 -116.949598)
			(xy 119.314526 -117.033619) (xy 119.211471 -117.111443) (xy 119.10382 -117.182775) (xy 118.991981 -117.247345)
			(xy 118.87638 -117.304907) (xy 118.757455 -117.355244) (xy 118.635656 -117.398164) (xy 118.511446 -117.433505)
			(xy 118.385297 -117.461132) (xy 118.257685 -117.480941) (xy 118.129096 -117.492857) (xy 118.000018 -117.496834)
			(xy 117.87094 -117.492857) (xy 117.742351 -117.480941) (xy 117.614739 -117.461132) (xy 117.48859 -117.433505)
			(xy 117.36438 -117.398164) (xy 117.242581 -117.355244) (xy 117.123656 -117.304907) (xy 117.008055 -117.247345)
			(xy 116.896216 -117.182775) (xy 116.788565 -117.111443) (xy 116.68551 -117.033619) (xy 116.58744 -116.949598)
			(xy 116.494729 -116.859699) (xy 116.407729 -116.764264) (xy 116.326768 -116.663654) (xy 116.252154 -116.558251)
			(xy 116.184171 -116.448454) (xy 116.123076 -116.33468) (xy 116.069101 -116.217361) (xy 116.02245 -116.096942)
			(xy 115.983301 -115.973879) (xy 115.951802 -115.84864) (xy 115.928073 -115.721699) (xy 115.912203 -115.593539)
			(xy 115.904253 -115.464644) (xy 92.50807 -115.464644) (xy 92.50807 -118.400068) (xy 92.508591 -118.455876)
			(xy 92.516929 -118.567181) (xy 92.533562 -118.677551) (xy 92.558397 -118.78637) (xy 92.591294 -118.893028)
			(xy 92.63207 -118.99693) (xy 92.680497 -119.097494) (xy 92.736303 -119.194158) (xy 92.799176 -119.286381)
			(xy 92.868766 -119.373648) (xy 92.944683 -119.45547) (xy 93.026502 -119.531391) (xy 93.113766 -119.600984)
			(xy 93.205986 -119.663862) (xy 93.302648 -119.719673) (xy 93.40321 -119.768103) (xy 93.50711 -119.808884)
			(xy 93.613767 -119.841786) (xy 93.722584 -119.866625) (xy 93.832954 -119.883263) (xy 93.944258 -119.891607)
			(xy 94.000066 -119.892064)
		)
		(stroke
			(width 0)
			(type solid)
		)
		(fill yes)
		(layer "In6.Cu")
		(net "GND_P1")
	)
	(gr_arc
		(start 0.249936 -85.000084)
		(mid 0.073205 -85.073289)
		(end 0 -85.25002)
		(stroke
			(width 2.032)
			(type default)
		)
		(layer "In6.Cu")
	)
	(gr_line
		(start 0.249936 -85.000084)
		(end 2.249932 -85.000084)
		(stroke
			(width 2.032)
			(type default)
		)
		(layer "In6.Cu")
	)
	(gr_arc
		(start 1.999996 0)
		(mid 0.585785 -0.585785)
		(end 0 -1.999996)
		(stroke
			(width 2.032)
			(type default)
		)
		(layer "In6.Cu")
	)
	(gr_line
		(start 1.999996 0)
		(end 33.99028 0)
		(stroke
			(width 2.032)
			(type default)
		)
		(layer "In6.Cu")
	)
	(gr_arc
		(start 2.249932 -85.000084)
		(mid 2.603574 -84.8536)
		(end 2.750058 -84.499958)
		(stroke
			(width 2.032)
			(type default)
		)
		(layer "In6.Cu")
	)
	(gr_line
		(start 2.249932 -81.499964)
		(end 0.249936 -81.499964)
		(stroke
			(width 2.032)
			(type default)
		)
		(layer "In6.Cu")
	)
	(gr_line
		(start 2.750058 -84.499958)
		(end 2.750058 -82.00009)
		(stroke
			(width 2.032)
			(type default)
		)
		(layer "In6.Cu")
	)
	(gr_arc
		(start 2.750058 -82.00009)
		(mid 2.603574 -81.646448)
		(end 2.249932 -81.499964)
		(stroke
			(width 2.032)
			(type default)
		)
		(layer "In6.Cu")
	)
	(gr_line
		(start 4.500118 -114.3)
		(end 1.999996 -114.3)
		(stroke
			(width 2.032)
			(type default)
		)
		(layer "In6.Cu")
	)
	(gr_line
		(start 4.99999 -119.132096)
		(end 4.99999 -114.800126)
		(stroke
			(width 2.032)
			(type default)
		)
		(layer "In6.Cu")
	)
	(gr_arc
		(start 4.99999 -114.800126)
		(mid 4.853581 -114.446663)
		(end 4.500118 -114.3)
		(stroke
			(width 2.032)
			(type default)
		)
		(layer "In6.Cu")
	)
	(gr_line
		(start 5.732018 -120.400064)
		(end 4.99999 -119.132096)
		(stroke
			(width 2.032)
			(type default)
		)
		(layer "In6.Cu")
	)
	(gr_line
		(start 8.9154 -57.6834)
		(end 9.906 -58.674)
		(stroke
			(width 0.635)
			(type default)
		)
		(layer "In6.Cu")
	)
	(gr_line
		(start 8.9154 -35.2806)
		(end 8.9154 -57.6834)
		(stroke
			(width 0.635)
			(type default)
		)
		(layer "In6.Cu")
	)
	(gr_line
		(start 9.906 -61.341)
		(end 12.7 -64.135)
		(stroke
			(width 0.508)
			(type default)
		)
		(layer "In6.Cu")
	)
	(gr_line
		(start 9.906 -58.674)
		(end 9.906 -61.341)
		(stroke
			(width 0.508)
			(type default)
		)
		(layer "In6.Cu")
	)
	(gr_line
		(start 9.906 -58.674)
		(end 15.494 -58.674)
		(stroke
			(width 0.635)
			(type default)
		)
		(layer "In6.Cu")
	)
	(gr_line
		(start 10.014966 -120.400064)
		(end 5.732018 -120.400064)
		(stroke
			(width 2.032)
			(type default)
		)
		(layer "In6.Cu")
	)
	(gr_line
		(start 10.765028 -119.650002)
		(end 10.014966 -120.400064)
		(stroke
			(width 2.032)
			(type default)
		)
		(layer "In6.Cu")
	)
	(gr_line
		(start 10.765028 -114.800126)
		(end 10.765028 -119.650002)
		(stroke
			(width 2.032)
			(type default)
		)
		(layer "In6.Cu")
	)
	(gr_arc
		(start 11.2649 -114.3)
		(mid 10.911422 -114.446573)
		(end 10.765028 -114.800126)
		(stroke
			(width 2.032)
			(type default)
		)
		(layer "In6.Cu")
	)
	(gr_line
		(start 12.7 -64.135)
		(end 31.369 -64.135)
		(stroke
			(width 0.508)
			(type default)
		)
		(layer "In6.Cu")
	)
	(gr_line
		(start 12.765024 -114.3)
		(end 11.2649 -114.3)
		(stroke
			(width 2.032)
			(type default)
		)
		(layer "In6.Cu")
	)
	(gr_line
		(start 13.264896 -119.650002)
		(end 13.264896 -114.800126)
		(stroke
			(width 2.032)
			(type default)
		)
		(layer "In6.Cu")
	)
	(gr_arc
		(start 13.264896 -114.800126)
		(mid 13.118487 -114.446663)
		(end 12.765024 -114.3)
		(stroke
			(width 2.032)
			(type default)
		)
		(layer "In6.Cu")
	)
	(gr_line
		(start 13.7922 -30.4038)
		(end 8.9154 -35.2806)
		(stroke
			(width 0.635)
			(type default)
		)
		(layer "In6.Cu")
	)
	(gr_line
		(start 14.014958 -120.400064)
		(end 13.264896 -119.650002)
		(stroke
			(width 2.032)
			(type default)
		)
		(layer "In6.Cu")
	)
	(gr_line
		(start 15.494 -58.674)
		(end 18.346166 -61.526166)
		(stroke
			(width 0.508)
			(type default)
		)
		(layer "In6.Cu")
	)
	(gr_line
		(start 15.494 -43.702224)
		(end 15.494 -58.674)
		(stroke
			(width 0.635)
			(type default)
		)
		(layer "In6.Cu")
	)
	(gr_line
		(start 15.6972 -30.4038)
		(end 13.7922 -30.4038)
		(stroke
			(width 0.635)
			(type default)
		)
		(layer "In6.Cu")
	)
	(gr_line
		(start 15.6972 -30.4038)
		(end 23.1648 -37.8714)
		(stroke
			(width 0.635)
			(type default)
		)
		(layer "In6.Cu")
	)
	(gr_line
		(start 15.6972 -19.3548)
		(end 15.6972 -30.4038)
		(stroke
			(width 0.508)
			(type default)
		)
		(layer "In6.Cu")
	)
	(gr_line
		(start 16.4592 -18.5928)
		(end 15.6972 -19.3548)
		(stroke
			(width 0.508)
			(type default)
		)
		(layer "In6.Cu")
	)
	(gr_line
		(start 17.438624 -41.7576)
		(end 15.494 -43.702224)
		(stroke
			(width 0.635)
			(type default)
		)
		(layer "In6.Cu")
	)
	(gr_line
		(start 18.346166 -61.526166)
		(end 31.637732 -61.526166)
		(stroke
			(width 0.508)
			(type default)
		)
		(layer "In6.Cu")
	)
	(gr_line
		(start 21.6662 -41.7576)
		(end 17.438624 -41.7576)
		(stroke
			(width 0.635)
			(type default)
		)
		(layer "In6.Cu")
	)
	(gr_line
		(start 23.1648 -40.259)
		(end 21.6662 -41.7576)
		(stroke
			(width 0.635)
			(type default)
		)
		(layer "In6.Cu")
	)
	(gr_line
		(start 23.1648 -37.8714)
		(end 23.1648 -40.259)
		(stroke
			(width 0.635)
			(type default)
		)
		(layer "In6.Cu")
	)
	(gr_line
		(start 24.5618 -18.5928)
		(end 16.4592 -18.5928)
		(stroke
			(width 0.508)
			(type default)
		)
		(layer "In6.Cu")
	)
	(gr_line
		(start 24.9428 -30.0736)
		(end 24.9428 -18.9738)
		(stroke
			(width 0.508)
			(type default)
		)
		(layer "In6.Cu")
	)
	(gr_line
		(start 24.9428 -18.9738)
		(end 24.5618 -18.5928)
		(stroke
			(width 0.508)
			(type default)
		)
		(layer "In6.Cu")
	)
	(gr_line
		(start 24.9428 -18.9738)
		(end 32.8676 -18.9738)
		(stroke
			(width 0.508)
			(type default)
		)
		(layer "In6.Cu")
	)
	(gr_line
		(start 27.714956 -36.376356)
		(end 27.714956 -32.845756)
		(stroke
			(width 0.508)
			(type default)
		)
		(layer "In6.Cu")
	)
	(gr_line
		(start 27.714956 -32.845756)
		(end 24.9428 -30.0736)
		(stroke
			(width 0.508)
			(type default)
		)
		(layer "In6.Cu")
	)
	(gr_line
		(start 29.5656 -38.227)
		(end 27.714956 -36.376356)
		(stroke
			(width 0.508)
			(type default)
		)
		(layer "In6.Cu")
	)
	(gr_line
		(start 30.353 -46.355)
		(end 30.353 -40.110664)
		(stroke
			(width 0.508)
			(type default)
		)
		(layer "In6.Cu")
	)
	(gr_line
		(start 30.353 -40.110664)
		(end 30.353 -38.3286)
		(stroke
			(width 0.508)
			(type default)
		)
		(layer "In6.Cu")
	)
	(gr_line
		(start 30.87497 -120.400064)
		(end 14.014958 -120.400064)
		(stroke
			(width 2.032)
			(type default)
		)
		(layer "In6.Cu")
	)
	(gr_line
		(start 31.369 -64.135)
		(end 41.91 -74.676)
		(stroke
			(width 0.508)
			(type default)
		)
		(layer "In6.Cu")
	)
	(gr_line
		(start 31.625032 -119.650002)
		(end 30.87497 -120.400064)
		(stroke
			(width 2.032)
			(type default)
		)
		(layer "In6.Cu")
	)
	(gr_line
		(start 31.625032 -114.77498)
		(end 31.625032 -119.650002)
		(stroke
			(width 2.032)
			(type default)
		)
		(layer "In6.Cu")
	)
	(gr_line
		(start 31.6992 -38.227)
		(end 29.5656 -38.227)
		(stroke
			(width 0.508)
			(type default)
		)
		(layer "In6.Cu")
	)
	(gr_line
		(start 31.75 -47.752)
		(end 30.353 -46.355)
		(stroke
			(width 0.508)
			(type default)
		)
		(layer "In6.Cu")
	)
	(gr_line
		(start 32.131 -37.7952)
		(end 31.6992 -38.227)
		(stroke
			(width 0.508)
			(type default)
		)
		(layer "In6.Cu")
	)
	(gr_line
		(start 32.131 -28.067)
		(end 32.131 -37.7952)
		(stroke
			(width 0.508)
			(type default)
		)
		(layer "In6.Cu")
	)
	(gr_line
		(start 32.8676 -18.9738)
		(end 33.5534 -19.6596)
		(stroke
			(width 0.508)
			(type default)
		)
		(layer "In6.Cu")
	)
	(gr_line
		(start 33.5534 -26.6446)
		(end 32.131 -28.067)
		(stroke
			(width 0.508)
			(type default)
		)
		(layer "In6.Cu")
	)
	(gr_line
		(start 33.5534 -19.6596)
		(end 33.5534 -26.6446)
		(stroke
			(width 0.508)
			(type default)
		)
		(layer "In6.Cu")
	)
	(gr_line
		(start 33.99028 0)
		(end 88.000078 0)
		(stroke
			(width 2.032)
			(type default)
		)
		(layer "In6.Cu")
	)
	(gr_line
		(start 34.37509 -119.650002)
		(end 34.37509 -114.77498)
		(stroke
			(width 2.032)
			(type default)
		)
		(layer "In6.Cu")
	)
	(gr_arc
		(start 34.37509 -114.77498)
		(mid 32.999934 -113.399824)
		(end 31.625032 -114.77498)
		(stroke
			(width 2.032)
			(type default)
		)
		(layer "In6.Cu")
	)
	(gr_line
		(start 35.102292 -47.752)
		(end 35.687 -47.752)
		(stroke
			(width 0.508)
			(type default)
		)
		(layer "In6.Cu")
	)
	(gr_line
		(start 35.124898 -120.400064)
		(end 34.37509 -119.650002)
		(stroke
			(width 2.032)
			(type default)
		)
		(layer "In6.Cu")
	)
	(gr_line
		(start 35.150298 -47.752)
		(end 31.75 -47.752)
		(stroke
			(width 0.508)
			(type default)
		)
		(layer "In6.Cu")
	)
	(gr_line
		(start 35.273488 -47.657512)
		(end 35.687 -47.244)
		(stroke
			(width 0.508)
			(type default)
		)
		(layer "In6.Cu")
	)
	(gr_line
		(start 35.768788 -32.29229)
		(end 35.76955 -41.38295)
		(stroke
			(width 0.508)
			(type default)
		)
		(layer "In6.Cu")
	)
	(gr_line
		(start 35.76955 -41.38295)
		(end 36.6268 -42.2402)
		(stroke
			(width 0.508)
			(type default)
		)
		(layer "In6.Cu")
	)
	(gr_line
		(start 35.76955 -41.025826)
		(end 35.76955 -41.38295)
		(stroke
			(width 0.508)
			(type default)
		)
		(layer "In6.Cu")
	)
	(gr_line
		(start 35.769804 -44.819316)
		(end 35.770566 -53.835554)
		(stroke
			(width 0.508)
			(type default)
		)
		(layer "In6.Cu")
	)
	(gr_line
		(start 35.770058 -48.37176)
		(end 35.150298 -47.752)
		(stroke
			(width 0.508)
			(type default)
		)
		(layer "In6.Cu")
	)
	(gr_line
		(start 36.449 -54.483)
		(end 35.770566 -53.835554)
		(stroke
			(width 0.508)
			(type default)
		)
		(layer "In6.Cu")
	)
	(gr_line
		(start 36.449 -54.483)
		(end 38.354 -54.483)
		(stroke
			(width 0.508)
			(type default)
		)
		(layer "In6.Cu")
	)
	(gr_line
		(start 36.6268 -43.96232)
		(end 35.769804 -44.819316)
		(stroke
			(width 0.508)
			(type default)
		)
		(layer "In6.Cu")
	)
	(gr_line
		(start 36.6268 -42.2402)
		(end 36.6268 -43.96232)
		(stroke
			(width 0.508)
			(type default)
		)
		(layer "In6.Cu")
	)
	(gr_line
		(start 37.730684 -30.330394)
		(end 35.768788 -32.29229)
		(stroke
			(width 0.508)
			(type default)
		)
		(layer "In6.Cu")
	)
	(gr_line
		(start 38.354 -54.483)
		(end 38.47846 -54.453536)
		(stroke
			(width 0.508)
			(type default)
		)
		(layer "In6.Cu")
	)
	(gr_line
		(start 38.47846 -54.453536)
		(end 39.111682 -53.820314)
		(stroke
			(width 0.508)
			(type default)
		)
		(layer "In6.Cu")
	)
	(gr_line
		(start 39.111682 -53.820314)
		(end 39.111682 -51.369468)
		(stroke
			(width 0.508)
			(type default)
		)
		(layer "In6.Cu")
	)
	(gr_line
		(start 39.111682 -51.369468)
		(end 39.411656 -51.069494)
		(stroke
			(width 0.508)
			(type default)
		)
		(layer "In6.Cu")
	)
	(gr_line
		(start 39.411656 -51.069494)
		(end 43.217084 -51.069494)
		(stroke
			(width 0.508)
			(type default)
		)
		(layer "In6.Cu")
	)
	(gr_line
		(start 40.490648 -61.526166)
		(end 29.824934 -61.526166)
		(stroke
			(width 0.508)
			(type default)
		)
		(layer "In6.Cu")
	)
	(gr_line
		(start 41.8338 -64.4398)
		(end 41.84396 -62.879478)
		(stroke
			(width 0.508)
			(type default)
		)
		(layer "In6.Cu")
	)
	(gr_line
		(start 41.84396 -62.879478)
		(end 40.490648 -61.526166)
		(stroke
			(width 0.508)
			(type default)
		)
		(layer "In6.Cu")
	)
	(gr_line
		(start 41.91 -74.676)
		(end 48.641 -74.676)
		(stroke
			(width 0.508)
			(type default)
		)
		(layer "In6.Cu")
	)
	(gr_line
		(start 42.2402 -70.9422)
		(end 42.2402 -64.8462)
		(stroke
			(width 0.508)
			(type default)
		)
		(layer "In6.Cu")
	)
	(gr_line
		(start 42.2402 -64.8462)
		(end 41.855136 -64.453516)
		(stroke
			(width 0.508)
			(type default)
		)
		(layer "In6.Cu")
	)
	(gr_line
		(start 42.2402 -64.8462)
		(end 54.71414 -64.858138)
		(stroke
			(width 0.508)
			(type default)
		)
		(layer "In6.Cu")
	)
	(gr_line
		(start 43.217084 -51.069494)
		(end 43.691302 -51.543712)
		(stroke
			(width 0.508)
			(type default)
		)
		(layer "In6.Cu")
	)
	(gr_line
		(start 43.561 -72.263)
		(end 42.2402 -70.9422)
		(stroke
			(width 0.508)
			(type default)
		)
		(layer "In6.Cu")
	)
	(gr_line
		(start 43.584876 -120.400064)
		(end 35.124898 -120.400064)
		(stroke
			(width 2.032)
			(type default)
		)
		(layer "In6.Cu")
	)
	(gr_line
		(start 43.691302 -52.61229)
		(end 44.210986 -53.131974)
		(stroke
			(width 0.508)
			(type default)
		)
		(layer "In6.Cu")
	)
	(gr_line
		(start 43.691302 -51.543712)
		(end 43.691302 -52.61229)
		(stroke
			(width 0.508)
			(type default)
		)
		(layer "In6.Cu")
	)
	(gr_line
		(start 44.210986 -53.131974)
		(end 54.052216 -53.131974)
		(stroke
			(width 0.508)
			(type default)
		)
		(layer "In6.Cu")
	)
	(gr_line
		(start 44.334938 -119.650002)
		(end 43.584876 -120.400064)
		(stroke
			(width 2.032)
			(type default)
		)
		(layer "In6.Cu")
	)
	(gr_line
		(start 44.334938 -114.324892)
		(end 44.334938 -119.650002)
		(stroke
			(width 2.032)
			(type default)
		)
		(layer "In6.Cu")
	)
	(gr_line
		(start 46.185074 -119.650002)
		(end 46.185074 -114.324892)
		(stroke
			(width 2.032)
			(type default)
		)
		(layer "In6.Cu")
	)
	(gr_arc
		(start 46.185074 -114.324892)
		(mid 45.260006 -113.399824)
		(end 44.334938 -114.324892)
		(stroke
			(width 2.032)
			(type default)
		)
		(layer "In6.Cu")
	)
	(gr_line
		(start 46.934882 -120.400064)
		(end 46.185074 -119.650002)
		(stroke
			(width 2.032)
			(type default)
		)
		(layer "In6.Cu")
	)
	(gr_line
		(start 48.641 -74.676)
		(end 49.784 -75.819)
		(stroke
			(width 0.508)
			(type default)
		)
		(layer "In6.Cu")
	)
	(gr_line
		(start 49.784 -77.978)
		(end 52.959 -81.153)
		(stroke
			(width 0.508)
			(type default)
		)
		(layer "In6.Cu")
	)
	(gr_line
		(start 49.784 -75.819)
		(end 49.784 -77.978)
		(stroke
			(width 0.508)
			(type default)
		)
		(layer "In6.Cu")
	)
	(gr_line
		(start 50.165 -72.263)
		(end 43.561 -72.263)
		(stroke
			(width 0.508)
			(type default)
		)
		(layer "In6.Cu")
	)
	(gr_line
		(start 51.943 -76.581)
		(end 51.943 -74.041)
		(stroke
			(width 0.508)
			(type default)
		)
		(layer "In6.Cu")
	)
	(gr_line
		(start 51.943 -74.041)
		(end 50.165 -72.263)
		(stroke
			(width 0.508)
			(type default)
		)
		(layer "In6.Cu")
	)
	(gr_line
		(start 52.959 -81.153)
		(end 59.182 -81.153)
		(stroke
			(width 0.508)
			(type default)
		)
		(layer "In6.Cu")
	)
	(gr_line
		(start 53.721 -78.359)
		(end 51.943 -76.581)
		(stroke
			(width 0.508)
			(type default)
		)
		(layer "In6.Cu")
	)
	(gr_line
		(start 54.052216 -53.131974)
		(end 54.779418 -52.404772)
		(stroke
			(width 0.508)
			(type default)
		)
		(layer "In6.Cu")
	)
	(gr_line
		(start 54.557676 -64.930274)
		(end 54.943756 -65.316354)
		(stroke
			(width 0.508)
			(type default)
		)
		(layer "In6.Cu")
	)
	(gr_line
		(start 54.68366 -65.012316)
		(end 55.06974 -65.398396)
		(stroke
			(width 0.508)
			(type default)
		)
		(layer "In6.Cu")
	)
	(gr_line
		(start 54.71414 -64.858138)
		(end 68.085462 -64.858138)
		(stroke
			(width 0.508)
			(type default)
		)
		(layer "In6.Cu")
	)
	(gr_line
		(start 54.779418 -52.404772)
		(end 54.779418 -46.938946)
		(stroke
			(width 0.508)
			(type default)
		)
		(layer "In6.Cu")
	)
	(gr_line
		(start 54.779418 -46.938946)
		(end 55.136288 -46.582076)
		(stroke
			(width 0.508)
			(type default)
		)
		(layer "In6.Cu")
	)
	(gr_line
		(start 54.943756 -65.316354)
		(end 55.404004 -64.856106)
		(stroke
			(width 0.508)
			(type default)
		)
		(layer "In6.Cu")
	)
	(gr_line
		(start 55.06974 -65.398396)
		(end 55.529988 -64.938148)
		(stroke
			(width 0.508)
			(type default)
		)
		(layer "In6.Cu")
	)
	(gr_line
		(start 55.089298 -73.426066)
		(end 55.569612 -73.90638)
		(stroke
			(width 0.508)
			(type default)
		)
		(layer "In6.Cu")
	)
	(gr_line
		(start 55.089298 -65.75298)
		(end 55.089298 -73.426066)
		(stroke
			(width 0.508)
			(type default)
		)
		(layer "In6.Cu")
	)
	(gr_line
		(start 55.089298 -65.75298)
		(end 55.089298 -64.94399)
		(stroke
			(width 0.508)
			(type default)
		)
		(layer "In6.Cu")
	)
	(gr_line
		(start 55.089298 -64.94399)
		(end 55.09768 -64.935608)
		(stroke
			(width 0.508)
			(type default)
		)
		(layer "In6.Cu")
	)
	(gr_line
		(start 55.136288 -46.582076)
		(end 60.382404 -46.582076)
		(stroke
			(width 0.508)
			(type default)
		)
		(layer "In6.Cu")
	)
	(gr_line
		(start 55.569612 -73.90638)
		(end 64.824356 -73.90638)
		(stroke
			(width 0.508)
			(type default)
		)
		(layer "In6.Cu")
	)
	(gr_line
		(start 56.642 -78.359)
		(end 53.721 -78.359)
		(stroke
			(width 0.508)
			(type default)
		)
		(layer "In6.Cu")
	)
	(gr_line
		(start 57.531 -77.47)
		(end 56.642 -78.359)
		(stroke
			(width 0.508)
			(type default)
		)
		(layer "In6.Cu")
	)
	(gr_line
		(start 57.771284 -30.330394)
		(end 37.730684 -30.330394)
		(stroke
			(width 0.508)
			(type default)
		)
		(layer "In6.Cu")
	)
	(gr_line
		(start 59.182 -81.153)
		(end 60.833 -79.502)
		(stroke
			(width 0.508)
			(type default)
		)
		(layer "In6.Cu")
	)
	(gr_line
		(start 59.829446 -32.388556)
		(end 57.771284 -30.330394)
		(stroke
			(width 0.508)
			(type default)
		)
		(layer "In6.Cu")
	)
	(gr_line
		(start 60.747148 -54.143148)
		(end 60.747148 -46.94682)
		(stroke
			(width 0.508)
			(type default)
		)
		(layer "In6.Cu")
	)
	(gr_line
		(start 60.747148 -46.94682)
		(end 60.382404 -46.582076)
		(stroke
			(width 0.508)
			(type default)
		)
		(layer "In6.Cu")
	)
	(gr_line
		(start 60.833 -79.502)
		(end 68.961 -79.502)
		(stroke
			(width 0.508)
			(type default)
		)
		(layer "In6.Cu")
	)
	(gr_line
		(start 61.3156 -54.7116)
		(end 60.747148 -54.143148)
		(stroke
			(width 0.508)
			(type default)
		)
		(layer "In6.Cu")
	)
	(gr_line
		(start 63.627 -77.47)
		(end 57.531 -77.47)
		(stroke
			(width 0.508)
			(type default)
		)
		(layer "In6.Cu")
	)
	(gr_line
		(start 63.784988 -120.400064)
		(end 46.934882 -120.400064)
		(stroke
			(width 2.032)
			(type default)
		)
		(layer "In6.Cu")
	)
	(gr_line
		(start 64.135 -76.962)
		(end 63.627 -77.47)
		(stroke
			(width 0.508)
			(type default)
		)
		(layer "In6.Cu")
	)
	(gr_line
		(start 64.53505 -119.650002)
		(end 63.784988 -120.400064)
		(stroke
			(width 2.032)
			(type default)
		)
		(layer "In6.Cu")
	)
	(gr_line
		(start 64.53505 -114.525044)
		(end 64.53505 -119.650002)
		(stroke
			(width 2.032)
			(type default)
		)
		(layer "In6.Cu")
	)
	(gr_line
		(start 64.824356 -73.90638)
		(end 65.61963 -73.111106)
		(stroke
			(width 0.508)
			(type default)
		)
		(layer "In6.Cu")
	)
	(gr_line
		(start 65.61963 -73.111106)
		(end 65.61963 -68.71335)
		(stroke
			(width 0.508)
			(type default)
		)
		(layer "In6.Cu")
	)
	(gr_line
		(start 65.61963 -68.71335)
		(end 66.090546 -68.242434)
		(stroke
			(width 0.508)
			(type default)
		)
		(layer "In6.Cu")
	)
	(gr_line
		(start 66.090546 -68.242434)
		(end 69.5452 -68.242434)
		(stroke
			(width 0.508)
			(type default)
		)
		(layer "In6.Cu")
	)
	(gr_line
		(start 66.784982 -119.650002)
		(end 66.784982 -114.525044)
		(stroke
			(width 2.032)
			(type default)
		)
		(layer "In6.Cu")
	)
	(gr_arc
		(start 66.784982 -114.525044)
		(mid 65.660016 -113.400078)
		(end 64.53505 -114.525044)
		(stroke
			(width 2.032)
			(type default)
		)
		(layer "In6.Cu")
	)
	(gr_line
		(start 67.535044 -120.400064)
		(end 66.784982 -119.650002)
		(stroke
			(width 2.032)
			(type default)
		)
		(layer "In6.Cu")
	)
	(gr_line
		(start 68.085462 -64.858138)
		(end 68.9864 -63.9572)
		(stroke
			(width 0.508)
			(type default)
		)
		(layer "In6.Cu")
	)
	(gr_line
		(start 68.961 -79.502)
		(end 69.977 -80.518)
		(stroke
			(width 0.508)
			(type default)
		)
		(layer "In6.Cu")
	)
	(gr_line
		(start 68.9864 -63.9572)
		(end 68.9864 -58.1152)
		(stroke
			(width 0.508)
			(type default)
		)
		(layer "In6.Cu")
	)
	(gr_line
		(start 68.9864 -58.1152)
		(end 70.0024 -57.0992)
		(stroke
			(width 0.508)
			(type default)
		)
		(layer "In6.Cu")
	)
	(gr_line
		(start 69.5452 -68.242434)
		(end 89.902538 -68.242434)
		(stroke
			(width 0.508)
			(type default)
		)
		(layer "In6.Cu")
	)
	(gr_line
		(start 69.977 -80.518)
		(end 77.851 -80.518)
		(stroke
			(width 0.508)
			(type default)
		)
		(layer "In6.Cu")
	)
	(gr_line
		(start 70.0024 -57.0992)
		(end 79.1464 -57.0992)
		(stroke
			(width 0.508)
			(type default)
		)
		(layer "In6.Cu")
	)
	(gr_line
		(start 71.882 -76.962)
		(end 64.135 -76.962)
		(stroke
			(width 0.508)
			(type default)
		)
		(layer "In6.Cu")
	)
	(gr_line
		(start 72.136 -77.216)
		(end 71.882 -76.962)
		(stroke
			(width 0.508)
			(type default)
		)
		(layer "In6.Cu")
	)
	(gr_line
		(start 72.87768 -32.388556)
		(end 59.829446 -32.388556)
		(stroke
			(width 0.508)
			(type default)
		)
		(layer "In6.Cu")
	)
	(gr_line
		(start 74.676 -54.7116)
		(end 61.3156 -54.7116)
		(stroke
			(width 0.508)
			(type default)
		)
		(layer "In6.Cu")
	)
	(gr_line
		(start 75.0316 -54.356)
		(end 74.676 -54.7116)
		(stroke
			(width 0.508)
			(type default)
		)
		(layer "In6.Cu")
	)
	(gr_line
		(start 75.705462 -35.216338)
		(end 72.87768 -32.388556)
		(stroke
			(width 0.508)
			(type default)
		)
		(layer "In6.Cu")
	)
	(gr_line
		(start 75.989942 -120.400064)
		(end 67.535044 -120.400064)
		(stroke
			(width 2.032)
			(type default)
		)
		(layer "In6.Cu")
	)
	(gr_line
		(start 76.740004 -119.650002)
		(end 75.989942 -120.400064)
		(stroke
			(width 2.032)
			(type default)
		)
		(layer "In6.Cu")
	)
	(gr_line
		(start 76.740004 -114.800126)
		(end 76.740004 -119.650002)
		(stroke
			(width 2.032)
			(type default)
		)
		(layer "In6.Cu")
	)
	(gr_arc
		(start 77.239876 -114.3)
		(mid 76.886398 -114.446573)
		(end 76.740004 -114.800126)
		(stroke
			(width 2.032)
			(type default)
		)
		(layer "In6.Cu")
	)
	(gr_line
		(start 77.597 -77.216)
		(end 72.136 -77.216)
		(stroke
			(width 0.508)
			(type default)
		)
		(layer "In6.Cu")
	)
	(gr_line
		(start 77.851 -80.518)
		(end 78.486 -79.883)
		(stroke
			(width 0.508)
			(type default)
		)
		(layer "In6.Cu")
	)
	(gr_line
		(start 78.486 -79.883)
		(end 78.486 -78.105)
		(stroke
			(width 0.508)
			(type default)
		)
		(layer "In6.Cu")
	)
	(gr_line
		(start 78.486 -78.105)
		(end 77.597 -77.216)
		(stroke
			(width 0.508)
			(type default)
		)
		(layer "In6.Cu")
	)
	(gr_line
		(start 78.74 -114.3)
		(end 77.239876 -114.3)
		(stroke
			(width 2.032)
			(type default)
		)
		(layer "In6.Cu")
	)
	(gr_line
		(start 79.0448 -54.356)
		(end 75.0316 -54.356)
		(stroke
			(width 0.508)
			(type default)
		)
		(layer "In6.Cu")
	)
	(gr_line
		(start 79.1464 -57.0992)
		(end 79.6544 -56.5912)
		(stroke
			(width 0.508)
			(type default)
		)
		(layer "In6.Cu")
	)
	(gr_line
		(start 79.240126 -119.650002)
		(end 79.240126 -114.800126)
		(stroke
			(width 2.032)
			(type default)
		)
		(layer "In6.Cu")
	)
	(gr_arc
		(start 79.240126 -114.800126)
		(mid 79.093642 -114.446484)
		(end 78.74 -114.3)
		(stroke
			(width 2.032)
			(type default)
		)
		(layer "In6.Cu")
	)
	(gr_line
		(start 79.6544 -56.5912)
		(end 79.6544 -54.9656)
		(stroke
			(width 0.508)
			(type default)
		)
		(layer "In6.Cu")
	)
	(gr_line
		(start 79.6544 -54.9656)
		(end 79.0448 -54.356)
		(stroke
			(width 0.508)
			(type default)
		)
		(layer "In6.Cu")
	)
	(gr_line
		(start 79.989934 -120.400064)
		(end 79.240126 -119.650002)
		(stroke
			(width 2.032)
			(type default)
		)
		(layer "In6.Cu")
	)
	(gr_line
		(start 84.268056 -120.400064)
		(end 79.989934 -120.400064)
		(stroke
			(width 2.032)
			(type default)
		)
		(layer "In6.Cu")
	)
	(gr_line
		(start 85.000084 -119.132096)
		(end 84.268056 -120.400064)
		(stroke
			(width 2.032)
			(type default)
		)
		(layer "In6.Cu")
	)
	(gr_line
		(start 85.000084 -114.800126)
		(end 85.000084 -119.132096)
		(stroke
			(width 2.032)
			(type default)
		)
		(layer "In6.Cu")
	)
	(gr_arc
		(start 85.499956 -114.3)
		(mid 85.146478 -114.446573)
		(end 85.000084 -114.800126)
		(stroke
			(width 2.032)
			(type default)
		)
		(layer "In6.Cu")
	)
	(gr_arc
		(start 87.250016 -84.499958)
		(mid 87.39632 -84.853675)
		(end 87.749888 -85.000084)
		(stroke
			(width 2.032)
			(type default)
		)
		(layer "In6.Cu")
	)
	(gr_line
		(start 87.250016 -82.00009)
		(end 87.250016 -84.499958)
		(stroke
			(width 2.032)
			(type default)
		)
		(layer "In6.Cu")
	)
	(gr_line
		(start 87.749888 -85.000084)
		(end 89.749884 -85.000084)
		(stroke
			(width 2.032)
			(type default)
		)
		(layer "In6.Cu")
	)
	(gr_arc
		(start 87.749888 -81.499964)
		(mid 87.39641 -81.646537)
		(end 87.250016 -82.00009)
		(stroke
			(width 2.032)
			(type default)
		)
		(layer "In6.Cu")
	)
	(gr_line
		(start 88.000078 -114.3)
		(end 85.499956 -114.3)
		(stroke
			(width 2.032)
			(type default)
		)
		(layer "In6.Cu")
	)
	(gr_arc
		(start 88.000078 -114.3)
		(mid 89.414304 -113.714223)
		(end 90.000074 -112.300004)
		(stroke
			(width 2.032)
			(type default)
		)
		(layer "In6.Cu")
	)
	(gr_line
		(start 88.640666 -35.165538)
		(end 89.21242 -35.737292)
		(stroke
			(width 0.508)
			(type default)
		)
		(layer "In6.Cu")
	)
	(gr_line
		(start 88.696038 -68.24091)
		(end 89.267792 -68.812664)
		(stroke
			(width 0.508)
			(type default)
		)
		(layer "In6.Cu")
	)
	(gr_line
		(start 89.154508 -34.651696)
		(end 88.640666 -35.165538)
		(stroke
			(width 0.508)
			(type default)
		)
		(layer "In6.Cu")
	)
	(gr_line
		(start 89.20988 -67.727068)
		(end 88.696038 -68.24091)
		(stroke
			(width 0.508)
			(type default)
		)
		(layer "In6.Cu")
	)
	(gr_line
		(start 89.570052 -35.216338)
		(end 75.705462 -35.216338)
		(stroke
			(width 0.508)
			(type default)
		)
		(layer "In6.Cu")
	)
	(gr_line
		(start 89.586308 -35.232594)
		(end 89.570052 -35.216338)
		(stroke
			(width 0.508)
			(type default)
		)
		(layer "In6.Cu")
	)
	(gr_line
		(start 89.749884 -81.499964)
		(end 87.749888 -81.499964)
		(stroke
			(width 2.032)
			(type default)
		)
		(layer "In6.Cu")
	)
	(gr_arc
		(start 89.749884 -81.499964)
		(mid 89.926765 -81.426838)
		(end 90.000074 -81.250028)
		(stroke
			(width 2.032)
			(type default)
		)
		(layer "In6.Cu")
	)
	(gr_line
		(start 89.902538 -68.242434)
		(end 90.000074 -68.144898)
		(stroke
			(width 0.508)
			(type default)
		)
		(layer "In6.Cu")
	)
	(gr_arc
		(start 90.000074 -85.25002)
		(mid 89.926848 -85.073114)
		(end 89.749884 -85.000084)
		(stroke
			(width 2.032)
			(type default)
		)
		(layer "In6.Cu")
	)
	(gr_line
		(start 90.000074 -85.25002)
		(end 90.000074 -112.300004)
		(stroke
			(width 2.032)
			(type default)
		)
		(layer "In6.Cu")
	)
	(gr_arc
		(start 90.000074 -1.999996)
		(mid 89.414286 -0.585796)
		(end 88.000078 0)
		(stroke
			(width 2.032)
			(type default)
		)
		(layer "In6.Cu")
	)
	(gr_line
		(start 90.000074 -1.999996)
		(end 90.000074 -81.250028)
		(stroke
			(width 2.032)
			(type default)
		)
		(layer "In6.Cu")
	)
	(gr_poly
		(pts
			(xy 22.70379 -79.435198) (xy 22.70379 -75.78979) (xy 22.32533 -75.41133) (xy 19.096228 -75.41133)
			(xy 18.927064 -75.580494) (xy 18.927064 -78.896464) (xy 19.54403 -79.51343) (xy 22.625558 -79.51343)
		)
		(stroke
			(width 0)
			(type solid)
		)
		(fill yes)
		(layer "In7.Cu")
		(net "GND")
	)
	(gr_poly
		(pts
			(xy 80.255364 -118.737634) (xy 80.255364 -115.252754) (xy 80.174338 -115.171728) (xy 79.865474 -115.171728)
			(xy 79.748126 -115.289076) (xy 79.748126 -118.718584) (xy 79.85379 -118.824248) (xy 80.16875 -118.824248)
		)
		(stroke
			(width 0)
			(type solid)
		)
		(fill yes)
		(layer "In7.Cu")
		(net "GND")
	)
	(gr_poly
		(pts
			(xy 37.46627 -57.13349) (xy 37.46627 -55.034434)
			(arc
				(start 37.252656 -54.82082)
				(mid 37.204853 -54.757137)
				(end 37.17671 -54.682644)
			)
			(xy 37.16782 -54.64302) (xy 35.979608 -54.64302) (xy 35.829748 -54.79288) (xy 35.829748 -56.714898)
			(xy 35.82924 -56.72836) (xy 35.82924 -56.96331) (xy 36.104068 -57.238138) (xy 37.361622 -57.238138)
		)
		(stroke
			(width 0)
			(type solid)
		)
		(fill yes)
		(layer "In7.Cu")
		(net "GND")
	)
	(gr_poly
		(pts
			(xy 58.743088 -28.44165)
			(arc
				(start 58.707782 -28.43022)
				(mid 58.442896 -28.067)
				(end 58.707782 -27.70378)
			)
			(xy 58.743088 -27.69235) (xy 58.743088 -26.7589) (xy 55.359808 -26.7589) (xy 55.359808 -29.405326)
			(xy 58.743088 -29.405326)
		)
		(stroke
			(width 0)
			(type solid)
		)
		(fill yes)
		(layer "In7.Cu")
		(net "GND")
	)
	(gr_poly
		(pts
			(xy 76.221844 -117.139466) (xy 76.221844 -113.814098) (xy 76.859892 -113.17605) (xy 83.762342 -113.17605)
			(xy 84.430616 -112.507776)
			(arc
				(start 84.430616 -110.06836)
				(mid 84.427244 -110.00096)
				(end 84.426044 -109.933486)
			)
			(arc
				(start 84.426044 -109.933486)
				(mid 84.427245 -109.866012)
				(end 84.430616 -109.798612)
			)
			(xy 84.430616 -108.609384) (xy 85.68817 -107.35183) (xy 85.68817 -103.115364) (xy 85.536024 -102.963218)
			(xy 80.399382 -102.963218) (xy 79.7687 -103.5939) (xy 79.7687 -109.309662) (xy 78.227174 -110.851188)
			(xy 75.244706 -110.851188) (xy 74.866246 -111.229648) (xy 74.866246 -117.131846) (xy 74.977498 -117.243098)
			(xy 76.118212 -117.243098)
		)
		(stroke
			(width 0)
			(type solid)
		)
		(fill yes)
		(layer "In7.Cu")
		(net "P12V_AUX")
	)
	(gr_poly
		(pts
			(xy 10.257028 -118.783354)
			(arc
				(start 10.257028 -114.799872)
				(mid 10.552301 -114.087273)
				(end 11.2649 -113.792)
			)
			(xy 11.677904 -113.792) (xy 11.769344 -113.70056) (xy 11.769344 -113.376456) (xy 11.677396 -113.284508)
			(arc
				(start 11.2649 -113.284508)
				(mid 10.193376 -113.728348)
				(end 9.749536 -114.799872)
			)
			(xy 9.749536 -118.76532) (xy 9.862312 -118.878096) (xy 10.162286 -118.878096)
		)
		(stroke
			(width 0)
			(type solid)
		)
		(fill yes)
		(layer "In7.Cu")
		(net "GND")
	)
	(gr_poly
		(pts
			(xy 41.7322 -59.5122) (xy 41.7322 -58.684922) (xy 41.731652 -58.669799) (xy 41.722803 -58.640877)
			(xy 41.705875 -58.615812) (xy 41.682351 -58.596801) (xy 41.654292 -58.585511) (xy 41.624156 -58.582929)
			(xy 41.609264 -58.585608) (xy 41.589442 -58.589629) (xy 41.549224 -58.593953) (xy 41.529 -58.594244)
			(xy 41.501746 -58.593758) (xy 41.447793 -58.586001) (xy 41.395494 -58.570644) (xy 41.345912 -58.548001)
			(xy 41.300057 -58.518532) (xy 41.258863 -58.482837) (xy 41.223168 -58.441643) (xy 41.193699 -58.395788)
			(xy 41.171056 -58.346206) (xy 41.155699 -58.293907) (xy 41.147942 -58.239954) (xy 41.147942 -58.185446)
			(xy 41.155699 -58.131493) (xy 41.171056 -58.079194) (xy 41.193699 -58.029612) (xy 41.223168 -57.983757)
			(xy 41.258863 -57.942563) (xy 41.300057 -57.906868) (xy 41.345912 -57.877399) (xy 41.395494 -57.854756)
			(xy 41.447793 -57.839399) (xy 41.501746 -57.831642) (xy 41.529 -57.831228) (xy 41.549224 -57.831523)
			(xy 41.58944 -57.835853) (xy 41.609264 -57.839864) (xy 41.624163 -57.8425) (xy 41.654292 -57.839919)
			(xy 41.682347 -57.828634) (xy 41.705872 -57.809634) (xy 41.722808 -57.784581) (xy 41.731671 -57.75567)
			(xy 41.7322 -57.74055) (xy 41.7322 -55.3974) (xy 41.5544 -55.2196) (xy 40.894 -55.2196) (xy 40.861488 -55.252112)
			(xy 40.861488 -55.43169) (xy 40.860779 -55.461966) (xy 40.84888 -55.521336) (xy 40.837866 -55.549546)
			(xy 40.567102 -56.203088) (xy 40.555417 -56.229504) (xy 40.816782 -56.229504) (xy 40.820853 -56.173882)
			(xy 40.832979 -56.119445) (xy 40.852902 -56.067354) (xy 40.880198 -56.018719) (xy 40.914284 -55.974576)
			(xy 40.954433 -55.935867) (xy 40.999791 -55.903416) (xy 41.049391 -55.877915) (xy 41.102175 -55.859908)
			(xy 41.157018 -55.849778) (xy 41.212752 -55.847741) (xy 41.268189 -55.853841) (xy 41.322146 -55.867947)
			(xy 41.373475 -55.889759) (xy 41.421081 -55.918813) (xy 41.463949 -55.954488) (xy 41.501166 -55.996025)
			(xy 41.531939 -56.042538) (xy 41.555611 -56.093035) (xy 41.571679 -56.146442) (xy 41.579799 -56.201618)
			(xy 41.580308 -56.229504) (xy 41.579799 -56.25739) (xy 41.571679 -56.312566) (xy 41.555611 -56.365973)
			(xy 41.531939 -56.41647) (xy 41.501166 -56.462983) (xy 41.463949 -56.50452) (xy 41.421081 -56.540195)
			(xy 41.373475 -56.569249) (xy 41.322146 -56.591061) (xy 41.268189 -56.605167) (xy 41.212752 -56.611267)
			(xy 41.157018 -56.60923) (xy 41.102175 -56.5991) (xy 41.049391 -56.581093) (xy 40.999791 -56.555592)
			(xy 40.954433 -56.523141) (xy 40.914284 -56.484432) (xy 40.880198 -56.440289) (xy 40.852902 -56.391654)
			(xy 40.832979 -56.339563) (xy 40.820853 -56.285126) (xy 40.816782 -56.229504) (xy 40.555417 -56.229504)
			(xy 40.554877 -56.230724) (xy 40.52136 -56.280995) (xy 40.500554 -56.30291) (xy 40.346376 -56.456834)
			(xy 40.346376 -58.743596) (xy 40.651938 -59.048904) (xy 40.668706 -59.066346) (xy 40.69714 -59.105488)
			(xy 40.719103 -59.148596) (xy 40.734053 -59.194608) (xy 40.741623 -59.242392) (xy 40.742108 -59.266582)
			(xy 40.742108 -59.7916) (xy 41.4528 -59.7916)
		)
		(stroke
			(width 0)
			(type solid)
		)
		(fill yes)
		(layer "In7.Cu")
		(net "P3V3_AUX")
	)
	(gr_poly
		(pts
			(xy 76.507848 -69.904102) (xy 76.513581 -69.876961) (xy 76.531846 -69.824583) (xy 76.557504 -69.775403)
			(xy 76.590014 -69.730456) (xy 76.628689 -69.690692) (xy 76.672716 -69.656947) (xy 76.721165 -69.629933)
			(xy 76.773015 -69.61022) (xy 76.827173 -69.598224) (xy 76.882498 -69.594197) (xy 76.937823 -69.598224)
			(xy 76.991981 -69.61022) (xy 77.043831 -69.629933) (xy 77.09228 -69.656947) (xy 77.136307 -69.690692)
			(xy 77.174982 -69.730456) (xy 77.207492 -69.775403) (xy 77.23315 -69.824583) (xy 77.251415 -69.876961)
			(xy 77.257148 -69.904102) (xy 77.265022 -69.94525) (xy 77.523848 -69.94525) (xy 77.949552 -69.519292)
			(xy 77.949552 -67.361308) (xy 76.158344 -65.569846) (xy 68.593462 -65.569846) (xy 67.5132 -66.650108)
			(xy 67.5132 -67.777614) (xy 67.513753 -67.792733) (xy 67.522607 -67.821646) (xy 67.539537 -67.846701)
			(xy 67.563058 -67.865704) (xy 67.591112 -67.87699) (xy 67.62124 -67.879571) (xy 67.636136 -67.876928)
			(xy 67.655958 -67.872906) (xy 67.696176 -67.868583) (xy 67.7164 -67.868292) (xy 67.743651 -67.868778)
			(xy 67.797599 -67.876534) (xy 67.849894 -67.891889) (xy 67.899471 -67.914531) (xy 67.945321 -67.943997)
			(xy 67.986512 -67.979688) (xy 68.022203 -68.020879) (xy 68.051669 -68.066729) (xy 68.074311 -68.116306)
			(xy 68.089666 -68.168601) (xy 68.097422 -68.222549) (xy 68.097422 -68.277051) (xy 68.089666 -68.330999)
			(xy 68.074311 -68.383294) (xy 68.051669 -68.432871) (xy 68.022203 -68.478721) (xy 67.986512 -68.519912)
			(xy 67.946772 -68.554346) (xy 71.217788 -68.554346) (xy 71.221859 -68.498724) (xy 71.233985 -68.444287)
			(xy 71.253908 -68.392196) (xy 71.281204 -68.343561) (xy 71.31529 -68.299418) (xy 71.355439 -68.260709)
			(xy 71.400797 -68.228258) (xy 71.450397 -68.202757) (xy 71.503181 -68.18475) (xy 71.558024 -68.17462)
			(xy 71.613758 -68.172583) (xy 71.669195 -68.178683) (xy 71.723152 -68.192789) (xy 71.774481 -68.214601)
			(xy 71.822087 -68.243655) (xy 71.864955 -68.27933) (xy 71.902172 -68.320867) (xy 71.932945 -68.36738)
			(xy 71.956617 -68.417877) (xy 71.972685 -68.471284) (xy 71.980805 -68.52646) (xy 71.981314 -68.554346)
			(xy 72.239376 -68.554346) (xy 72.243447 -68.498724) (xy 72.255573 -68.444287) (xy 72.275496 -68.392196)
			(xy 72.302792 -68.343561) (xy 72.336878 -68.299418) (xy 72.377027 -68.260709) (xy 72.422385 -68.228258)
			(xy 72.471985 -68.202757) (xy 72.524769 -68.18475) (xy 72.579612 -68.17462) (xy 72.635346 -68.172583)
			(xy 72.690783 -68.178683) (xy 72.74474 -68.192789) (xy 72.796069 -68.214601) (xy 72.843675 -68.243655)
			(xy 72.886543 -68.27933) (xy 72.92376 -68.320867) (xy 72.954533 -68.36738) (xy 72.978205 -68.417877)
			(xy 72.994273 -68.471284) (xy 73.002393 -68.52646) (xy 73.002902 -68.554346) (xy 73.002393 -68.582232)
			(xy 72.994273 -68.637408) (xy 72.978205 -68.690815) (xy 72.954533 -68.741312) (xy 72.92376 -68.787825)
			(xy 72.886543 -68.829362) (xy 72.843675 -68.865037) (xy 72.796069 -68.894091) (xy 72.74474 -68.915903)
			(xy 72.690783 -68.930009) (xy 72.635346 -68.936109) (xy 72.579612 -68.934072) (xy 72.524769 -68.923942)
			(xy 72.471985 -68.905935) (xy 72.422385 -68.880434) (xy 72.377027 -68.847983) (xy 72.336878 -68.809274)
			(xy 72.302792 -68.765131) (xy 72.275496 -68.716496) (xy 72.255573 -68.664405) (xy 72.243447 -68.609968)
			(xy 72.239376 -68.554346) (xy 71.981314 -68.554346) (xy 71.980805 -68.582232) (xy 71.972685 -68.637408)
			(xy 71.956617 -68.690815) (xy 71.932945 -68.741312) (xy 71.902172 -68.787825) (xy 71.864955 -68.829362)
			(xy 71.822087 -68.865037) (xy 71.774481 -68.894091) (xy 71.723152 -68.915903) (xy 71.669195 -68.930009)
			(xy 71.613758 -68.936109) (xy 71.558024 -68.934072) (xy 71.503181 -68.923942) (xy 71.450397 -68.905935)
			(xy 71.400797 -68.880434) (xy 71.355439 -68.847983) (xy 71.31529 -68.809274) (xy 71.281204 -68.765131)
			(xy 71.253908 -68.716496) (xy 71.233985 -68.664405) (xy 71.221859 -68.609968) (xy 71.217788 -68.554346)
			(xy 67.946772 -68.554346) (xy 67.945321 -68.555603) (xy 67.899471 -68.585069) (xy 67.849894 -68.607711)
			(xy 67.797599 -68.623066) (xy 67.743651 -68.630822) (xy 67.7164 -68.631308) (xy 67.696176 -68.631013)
			(xy 67.65596 -68.626683) (xy 67.636136 -68.622672) (xy 67.621239 -68.620035) (xy 67.591113 -68.622616)
			(xy 67.563061 -68.633901) (xy 67.539541 -68.652903) (xy 67.522613 -68.677957) (xy 67.513759 -68.706868)
			(xy 67.5132 -68.721986) (xy 67.5132 -68.853812) (xy 68.604638 -69.94525) (xy 76.499974 -69.94525)
		)
		(stroke
			(width 0)
			(type solid)
		)
		(fill yes)
		(layer "In7.Cu")
		(net "P1V8_AUX")
	)
	(gr_poly
		(pts
			(xy 22.225 -37.338) (xy 22.225 -34.490152) (xy 22.221444 -34.481008) (xy 22.210851 -34.452795) (xy 22.195948 -34.394402)
			(xy 22.188414 -34.33461) (xy 22.187916 -34.304478) (xy 22.187916 -33.437322) (xy 22.188391 -33.407188)
			(xy 22.195917 -33.347392) (xy 22.210831 -33.288999) (xy 22.221444 -33.260792) (xy 22.225 -33.251648)
			(xy 22.225 -33.147) (xy 23.273766 -32.098234) (xy 23.273766 -30.7594) (xy 23.0124 -30.498034) (xy 23.0124 -30.167072)
			(xy 23.011892 -30.1498) (xy 23.011892 -29.5148) (xy 23.0124 -29.497528) (xy 23.0124 -29.2608) (xy 23.368 -28.9052)
			(xy 23.749 -28.9052) (xy 23.9522 -28.702) (xy 23.9522 -21.463) (xy 23.534624 -21.463) (xy 23.522093 -21.483836)
			(xy 23.492542 -21.522445) (xy 23.458317 -21.556979) (xy 23.439374 -21.57222) (xy 23.427577 -21.58212)
			(xy 23.410075 -21.607441) (xy 23.400911 -21.636827) (xy 23.400916 -21.667609) (xy 23.410091 -21.696992)
			(xy 23.427603 -21.722307) (xy 23.439374 -21.73224) (xy 23.460153 -21.748994) (xy 23.497277 -21.787348)
			(xy 23.528691 -21.830502) (xy 23.553784 -21.877614) (xy 23.572065 -21.927763) (xy 23.583178 -21.979971)
			(xy 23.586904 -22.033218) (xy 23.583172 -22.086465) (xy 23.572055 -22.138672) (xy 23.553769 -22.18882)
			(xy 23.528672 -22.235929) (xy 23.497253 -22.27908) (xy 23.460126 -22.31743) (xy 23.439374 -22.33422)
			(xy 23.427577 -22.34412) (xy 23.410075 -22.369441) (xy 23.400911 -22.398827) (xy 23.400916 -22.429609)
			(xy 23.410091 -22.458992) (xy 23.427603 -22.484307) (xy 23.439374 -22.49424) (xy 23.460153 -22.510994)
			(xy 23.497277 -22.549348) (xy 23.528691 -22.592502) (xy 23.553784 -22.639614) (xy 23.572065 -22.689763)
			(xy 23.583178 -22.741971) (xy 23.586904 -22.795218) (xy 23.583172 -22.848465) (xy 23.572055 -22.900672)
			(xy 23.553769 -22.95082) (xy 23.528672 -22.997929) (xy 23.497253 -23.04108) (xy 23.460126 -23.07943)
			(xy 23.439374 -23.09622) (xy 23.427577 -23.10612) (xy 23.410075 -23.131441) (xy 23.400911 -23.160827)
			(xy 23.400916 -23.191609) (xy 23.410091 -23.220992) (xy 23.427603 -23.246307) (xy 23.439374 -23.25624)
			(xy 23.461861 -23.274429) (xy 23.501604 -23.316445) (xy 23.534548 -23.363978) (xy 23.55994 -23.415941)
			(xy 23.577197 -23.47114) (xy 23.585923 -23.528313) (xy 23.58644 -23.55723) (xy 23.585954 -23.584481)
			(xy 23.578198 -23.638429) (xy 23.562843 -23.690724) (xy 23.540201 -23.740301) (xy 23.510735 -23.786151)
			(xy 23.475044 -23.827342) (xy 23.433853 -23.863033) (xy 23.388003 -23.892499) (xy 23.338426 -23.915141)
			(xy 23.286131 -23.930496) (xy 23.232183 -23.938252) (xy 23.177681 -23.938252) (xy 23.123733 -23.930496)
			(xy 23.071438 -23.915141) (xy 23.021861 -23.892499) (xy 22.976011 -23.863033) (xy 22.93482 -23.827342)
			(xy 22.899129 -23.786151) (xy 22.869663 -23.740301) (xy 22.847021 -23.690724) (xy 22.831666 -23.638429)
			(xy 22.82391 -23.584481) (xy 22.823424 -23.55723) (xy 22.823956 -23.528313) (xy 22.832679 -23.471139)
			(xy 22.849931 -23.415938) (xy 22.875316 -23.363971) (xy 22.908252 -23.316431) (xy 22.947985 -23.274406)
			(xy 22.97049 -23.25624) (xy 22.9823 -23.246342) (xy 22.999825 -23.221016) (xy 23.009008 -23.191618)
			(xy 23.009014 -23.160819) (xy 22.999842 -23.131417) (xy 22.982325 -23.106085) (xy 22.97049 -23.09622)
			(xy 22.949703 -23.079468) (xy 22.912566 -23.041115) (xy 22.881138 -22.99796) (xy 22.856033 -22.950844)
			(xy 22.837742 -22.900689) (xy 22.826621 -22.848474) (xy 22.822888 -22.795218) (xy 22.826616 -22.741962)
			(xy 22.837731 -22.689746) (xy 22.856018 -22.639589) (xy 22.881118 -22.592472) (xy 22.912542 -22.549313)
			(xy 22.949676 -22.510957) (xy 22.97049 -22.49424) (xy 22.9823 -22.484342) (xy 22.999825 -22.459016)
			(xy 23.009008 -22.429618) (xy 23.009014 -22.398819) (xy 22.999842 -22.369417) (xy 22.982325 -22.344085)
			(xy 22.97049 -22.33422) (xy 22.949703 -22.317468) (xy 22.912566 -22.279115) (xy 22.881138 -22.23596)
			(xy 22.856033 -22.188844) (xy 22.837742 -22.138689) (xy 22.826621 -22.086474) (xy 22.822888 -22.033218)
			(xy 22.826616 -21.979962) (xy 22.837731 -21.927746) (xy 22.856018 -21.877589) (xy 22.881118 -21.830472)
			(xy 22.912542 -21.787313) (xy 22.949676 -21.748957) (xy 22.97049 -21.73224) (xy 22.9823 -21.722342)
			(xy 22.999825 -21.697016) (xy 23.009008 -21.667618) (xy 23.009014 -21.636819) (xy 22.999842 -21.607417)
			(xy 22.982325 -21.582085) (xy 22.97049 -21.57222) (xy 22.951564 -21.55696) (xy 22.91735 -21.522421)
			(xy 22.887792 -21.483821) (xy 22.87524 -21.463) (xy 19.31797 -21.463) (xy 19.305441 -21.483837) (xy 19.275892 -21.522449)
			(xy 19.241669 -21.556986) (xy 19.22272 -21.57222) (xy 19.210919 -21.582117) (xy 19.193409 -21.607438)
			(xy 19.18424 -21.636826) (xy 19.184245 -21.667611) (xy 19.193425 -21.696996) (xy 19.210944 -21.72231)
			(xy 19.22272 -21.73224) (xy 19.243502 -21.748993) (xy 19.28063 -21.787345) (xy 19.312049 -21.830498)
			(xy 19.337145 -21.87761) (xy 19.355429 -21.92776) (xy 19.366543 -21.979969) (xy 19.37027 -22.033218)
			(xy 19.366538 -22.086467) (xy 19.355419 -22.138676) (xy 19.33713 -22.188824) (xy 19.312029 -22.235933)
			(xy 19.280606 -22.279084) (xy 19.243474 -22.317432) (xy 19.22272 -22.33422) (xy 19.210919 -22.344117)
			(xy 19.193409 -22.369438) (xy 19.18424 -22.398826) (xy 19.184245 -22.429611) (xy 19.193425 -22.458996)
			(xy 19.210944 -22.48431) (xy 19.22272 -22.49424) (xy 19.243502 -22.510993) (xy 19.28063 -22.549345)
			(xy 19.312049 -22.592498) (xy 19.337145 -22.63961) (xy 19.355429 -22.68976) (xy 19.366543 -22.741969)
			(xy 19.37027 -22.795218) (xy 19.366538 -22.848467) (xy 19.355419 -22.900676) (xy 19.33713 -22.950824)
			(xy 19.312029 -22.997933) (xy 19.280606 -23.041084) (xy 19.243474 -23.079432) (xy 19.22272 -23.09622)
			(xy 19.210919 -23.106117) (xy 19.193409 -23.131438) (xy 19.18424 -23.160826) (xy 19.184245 -23.191611)
			(xy 19.193425 -23.220996) (xy 19.210944 -23.24631) (xy 19.22272 -23.25624) (xy 19.245204 -23.274431)
			(xy 19.284943 -23.316448) (xy 19.317884 -23.363982) (xy 19.343272 -23.415944) (xy 19.360526 -23.471143)
			(xy 19.369251 -23.528314) (xy 19.369786 -23.55723) (xy 19.3693 -23.584481) (xy 19.361544 -23.638429)
			(xy 19.346189 -23.690724) (xy 19.323547 -23.740301) (xy 19.294081 -23.786151) (xy 19.25839 -23.827342)
			(xy 19.217199 -23.863033) (xy 19.171349 -23.892499) (xy 19.121772 -23.915141) (xy 19.069477 -23.930496)
			(xy 19.015529 -23.938252) (xy 18.961027 -23.938252) (xy 18.907079 -23.930496) (xy 18.854784 -23.915141)
			(xy 18.805207 -23.892499) (xy 18.759357 -23.863033) (xy 18.718166 -23.827342) (xy 18.682475 -23.786151)
			(xy 18.653009 -23.740301) (xy 18.630367 -23.690724) (xy 18.615012 -23.638429) (xy 18.607256 -23.584481)
			(xy 18.60677 -23.55723) (xy 18.607302 -23.528313) (xy 18.616026 -23.471141) (xy 18.633279 -23.41594)
			(xy 18.658666 -23.363976) (xy 18.691605 -23.316439) (xy 18.731341 -23.274418) (xy 18.753836 -23.25624)
			(xy 18.76565 -23.246345) (xy 18.783186 -23.22102) (xy 18.792374 -23.19162) (xy 18.792379 -23.160817)
			(xy 18.783202 -23.131413) (xy 18.765676 -23.106082) (xy 18.753836 -23.09622) (xy 18.733052 -23.079466)
			(xy 18.69592 -23.041111) (xy 18.664496 -22.997955) (xy 18.639395 -22.95084) (xy 18.621106 -22.900686)
			(xy 18.609987 -22.848472) (xy 18.606255 -22.795218) (xy 18.609982 -22.741964) (xy 18.621096 -22.68975)
			(xy 18.63938 -22.639594) (xy 18.664476 -22.592476) (xy 18.695896 -22.549317) (xy 18.733025 -22.510959)
			(xy 18.753836 -22.49424) (xy 18.765557 -22.484444) (xy 18.783005 -22.459388) (xy 18.792269 -22.430294)
			(xy 18.792519 -22.399762) (xy 18.783734 -22.37052) (xy 18.766698 -22.345181) (xy 18.755106 -22.335236)
			(xy 18.732437 -22.317053) (xy 18.692349 -22.274984) (xy 18.659107 -22.22732) (xy 18.633482 -22.175164)
			(xy 18.616064 -22.119725) (xy 18.607259 -22.062285) (xy 18.60677 -22.03323) (xy 18.606823 -22.023242)
			(xy 18.607842 -22.003293) (xy 18.608802 -21.993352) (xy 18.60931 -21.988526) (xy 18.613419 -21.958577)
			(xy 18.629878 -21.900413) (xy 18.655311 -21.845575) (xy 18.689082 -21.795441) (xy 18.730344 -21.751265)
			(xy 18.753836 -21.73224) (xy 18.76565 -21.722345) (xy 18.783186 -21.69702) (xy 18.792374 -21.66762)
			(xy 18.792379 -21.636817) (xy 18.783202 -21.607413) (xy 18.765676 -21.582082) (xy 18.753836 -21.57222)
			(xy 18.734909 -21.556962) (xy 18.700691 -21.522424) (xy 18.67113 -21.483826) (xy 18.658586 -21.463)
			(xy 17.789144 -21.463) (xy 16.47444 -22.777704) (xy 16.47444 -27.822906) (xy 16.63319 -28.285948)
			(xy 16.638778 -28.29306) (xy 16.65462 -28.313636) (xy 16.679888 -28.358997) (xy 16.697184 -28.407956)
			(xy 16.706018 -28.459123) (xy 16.706596 -28.485084) (xy 16.706596 -28.499816) (xy 17.306802 -30.2514)
			(xy 21.639782 -30.2514) (xy 21.643853 -30.195778) (xy 21.655979 -30.141341) (xy 21.675902 -30.08925)
			(xy 21.703198 -30.040615) (xy 21.737284 -29.996472) (xy 21.777433 -29.957763) (xy 21.822791 -29.925312)
			(xy 21.872391 -29.899811) (xy 21.925175 -29.881804) (xy 21.980018 -29.871674) (xy 22.035752 -29.869637)
			(xy 22.091189 -29.875737) (xy 22.145146 -29.889843) (xy 22.196475 -29.911655) (xy 22.244081 -29.940709)
			(xy 22.286949 -29.976384) (xy 22.324166 -30.017921) (xy 22.354939 -30.064434) (xy 22.378611 -30.114931)
			(xy 22.394679 -30.168338) (xy 22.402799 -30.223514) (xy 22.403308 -30.2514) (xy 22.402799 -30.279286)
			(xy 22.394679 -30.334462) (xy 22.378611 -30.387869) (xy 22.354939 -30.438366) (xy 22.324166 -30.484879)
			(xy 22.286949 -30.526416) (xy 22.244081 -30.562091) (xy 22.196475 -30.591145) (xy 22.145146 -30.612957)
			(xy 22.091189 -30.627063) (xy 22.035752 -30.633163) (xy 21.980018 -30.631126) (xy 21.925175 -30.620996)
			(xy 21.872391 -30.602989) (xy 21.822791 -30.577488) (xy 21.777433 -30.545037) (xy 21.737284 -30.506328)
			(xy 21.703198 -30.462185) (xy 21.675902 -30.41355) (xy 21.655979 -30.361459) (xy 21.643853 -30.307022)
			(xy 21.639782 -30.2514) (xy 17.306802 -30.2514) (xy 17.431004 -30.613858) (xy 17.431004 -32.520128)
			(xy 17.431512 -32.5374) (xy 17.431004 -32.554672) (xy 17.431004 -35.426396) (xy 17.34185 -35.51555)
			(xy 17.341088 -35.516312) (xy 17.33931 -35.51809) (xy 17.333468 -35.52444) (xy 17.173448 -35.684206)
			(xy 17.098264 -35.75939) (xy 17.098264 -39.069264) (xy 17.907 -39.878) (xy 19.685 -39.878)
		)
		(stroke
			(width 0)
			(type solid)
		)
		(fill yes)
		(layer "In7.Cu")
		(net "GND")
	)
	(gr_poly
		(pts
			(xy 74.0664 -59.858656) (xy 74.0664 -59.3598) (xy 73.998836 -59.292236) (xy 73.998836 -56.934354)
			(xy 69.285866 -52.221384) (xy 68.496942 -52.221384) (xy 68.481987 -52.221906) (xy 68.453359 -52.230561)
			(xy 68.428467 -52.247142) (xy 68.409449 -52.270226) (xy 68.397937 -52.29783) (xy 68.394918 -52.327586)
			(xy 68.400652 -52.356939) (xy 68.414647 -52.383371) (xy 68.424806 -52.394358) (xy 68.443913 -52.414491)
			(xy 68.476283 -52.459576) (xy 68.501274 -52.509134) (xy 68.51828 -52.561967) (xy 68.526891 -52.616797)
			(xy 68.527422 -52.644548) (xy 68.526869 -52.672529) (xy 68.518109 -52.727801) (xy 68.50081 -52.781023)
			(xy 68.4754 -52.830883) (xy 68.442503 -52.876156) (xy 68.40293 -52.915725) (xy 68.357654 -52.948617)
			(xy 68.307791 -52.974023) (xy 68.254568 -52.991317) (xy 68.199295 -53.000072) (xy 68.171314 -53.000656)
			(xy 68.144858 -53.000174) (xy 68.092528 -52.99235) (xy 68.041931 -52.976873) (xy 67.99418 -52.954082)
			(xy 67.950324 -52.924479) (xy 67.930522 -52.90693) (xy 67.922954 -52.900552) (xy 67.904443 -52.8936)
			(xy 67.884678 -52.894166) (xy 67.866596 -52.902164) (xy 67.859402 -52.908962) (xy 67.841347 -52.927127)
			(xy 67.801217 -52.958953) (xy 67.757195 -52.98513) (xy 67.710069 -53.00519) (xy 67.660685 -53.018772)
			(xy 67.609929 -53.025632) (xy 67.58432 -53.026056) (xy 66.69532 -53.026056) (xy 66.667833 -53.025587)
			(xy 66.613424 -53.017727) (xy 66.560703 -53.002152) (xy 66.510757 -52.979183) (xy 66.464618 -52.949295)
			(xy 66.443606 -52.931568) (xy 66.43268 -52.922561) (xy 66.407114 -52.910412) (xy 66.379193 -52.905768)
			(xy 66.351071 -52.908985) (xy 66.324921 -52.919817) (xy 66.313558 -52.928266) (xy 66.291493 -52.945009)
			(xy 66.242943 -52.971659) (xy 66.19063 -52.989846) (xy 66.136018 -52.999063) (xy 66.108326 -52.99964)
			(xy 66.082333 -52.999159) (xy 66.030986 -52.99103) (xy 65.981543 -52.974968) (xy 65.935222 -52.95137)
			(xy 65.893163 -52.920815) (xy 65.856402 -52.884057) (xy 65.825844 -52.842) (xy 65.802242 -52.795681)
			(xy 65.786176 -52.746239) (xy 65.778043 -52.694893) (xy 65.778043 -52.642907) (xy 65.786176 -52.591561)
			(xy 65.802242 -52.542119) (xy 65.825844 -52.4958) (xy 65.856402 -52.453743) (xy 65.893163 -52.416985)
			(xy 65.935222 -52.38643) (xy 65.981543 -52.362832) (xy 66.030986 -52.34677) (xy 66.082333 -52.338641)
			(xy 66.108326 -52.338224) (xy 66.1326 -52.338654) (xy 66.180626 -52.345758) (xy 66.227096 -52.35981)
			(xy 66.271012 -52.380508) (xy 66.29146 -52.393596) (xy 66.3035 -52.401038) (xy 66.330462 -52.409617)
			(xy 66.358743 -52.410457) (xy 66.386166 -52.403493) (xy 66.41062 -52.389261) (xy 66.420746 -52.379372)
			(xy 66.438918 -52.361158) (xy 66.479316 -52.329297) (xy 66.501264 -52.315872) (xy 66.475356 -52.221384)
			(xy 65.647316 -52.221384) (xy 65.633523 -52.22183) (xy 65.60694 -52.229199) (xy 65.583308 -52.243428)
			(xy 65.564359 -52.263475) (xy 65.551482 -52.28787) (xy 65.54562 -52.314825) (xy 65.547203 -52.342365)
			(xy 65.556116 -52.368471) (xy 65.563496 -52.380134) (xy 65.577077 -52.400849) (xy 65.598551 -52.445484)
			(xy 65.613131 -52.492822) (xy 65.62049 -52.541804) (xy 65.6209 -52.56657) (xy 65.62039 -52.592557)
			(xy 65.61226 -52.643892) (xy 65.596199 -52.693322) (xy 65.572603 -52.739632) (xy 65.542053 -52.78168)
			(xy 65.505302 -52.818431) (xy 65.463254 -52.848981) (xy 65.416944 -52.872577) (xy 65.367514 -52.888638)
			(xy 65.316179 -52.896768) (xy 65.264205 -52.896768) (xy 65.21287 -52.888638) (xy 65.16344 -52.872577)
			(xy 65.11713 -52.848981) (xy 65.075082 -52.818431) (xy 65.038331 -52.78168) (xy 65.007781 -52.739632)
			(xy 64.984185 -52.693322) (xy 64.968124 -52.643892) (xy 64.959994 -52.592557) (xy 64.959484 -52.56657)
			(xy 64.959905 -52.541804) (xy 64.967256 -52.492821) (xy 64.981834 -52.445484) (xy 65.003312 -52.400852)
			(xy 65.016888 -52.380134) (xy 65.024259 -52.368486) (xy 65.033098 -52.342388) (xy 65.034633 -52.314877)
			(xy 65.028752 -52.287958) (xy 65.015884 -52.263594) (xy 64.996968 -52.243559) (xy 64.973381 -52.229316)
			(xy 64.946844 -52.221901) (xy 64.933068 -52.221384) (xy 64.847216 -52.221384) (xy 64.833423 -52.22183)
			(xy 64.80684 -52.229199) (xy 64.783208 -52.243428) (xy 64.764259 -52.263475) (xy 64.751382 -52.28787)
			(xy 64.74552 -52.314825) (xy 64.747103 -52.342365) (xy 64.756016 -52.368471) (xy 64.763396 -52.380134)
			(xy 64.776977 -52.400849) (xy 64.798451 -52.445484) (xy 64.813031 -52.492822) (xy 64.82039 -52.541804)
			(xy 64.8208 -52.56657) (xy 64.82029 -52.592557) (xy 64.81216 -52.643892) (xy 64.796099 -52.693322)
			(xy 64.772503 -52.739632) (xy 64.741953 -52.78168) (xy 64.705202 -52.818431) (xy 64.663154 -52.848981)
			(xy 64.616844 -52.872577) (xy 64.567414 -52.888638) (xy 64.516079 -52.896768) (xy 64.464105 -52.896768)
			(xy 64.41277 -52.888638) (xy 64.36334 -52.872577) (xy 64.31703 -52.848981) (xy 64.274982 -52.818431)
			(xy 64.238231 -52.78168) (xy 64.207681 -52.739632) (xy 64.184085 -52.693322) (xy 64.168024 -52.643892)
			(xy 64.159894 -52.592557) (xy 64.159384 -52.56657) (xy 64.159805 -52.541804) (xy 64.167156 -52.492821)
			(xy 64.181734 -52.445484) (xy 64.203212 -52.400852) (xy 64.216788 -52.380134) (xy 64.224159 -52.368486)
			(xy 64.232998 -52.342388) (xy 64.234533 -52.314877) (xy 64.228652 -52.287958) (xy 64.215784 -52.263594)
			(xy 64.196868 -52.243559) (xy 64.173281 -52.229316) (xy 64.146744 -52.221901) (xy 64.132968 -52.221384)
			(xy 64.04737 -52.221384) (xy 64.033582 -52.221835) (xy 64.00701 -52.229211) (xy 63.98339 -52.243443)
			(xy 63.964451 -52.263487) (xy 63.95158 -52.287875) (xy 63.94572 -52.314822) (xy 63.947301 -52.342353)
			(xy 63.956207 -52.368452) (xy 63.96355 -52.380134) (xy 63.977129 -52.40085) (xy 63.9986 -52.445485)
			(xy 64.013177 -52.492823) (xy 64.020535 -52.541804) (xy 64.020954 -52.56657) (xy 64.020444 -52.592557)
			(xy 64.012314 -52.643892) (xy 63.996253 -52.693322) (xy 63.972657 -52.739632) (xy 63.942107 -52.78168)
			(xy 63.905356 -52.818431) (xy 63.863308 -52.848981) (xy 63.816998 -52.872577) (xy 63.767568 -52.888638)
			(xy 63.716233 -52.896768) (xy 63.664259 -52.896768) (xy 63.612924 -52.888638) (xy 63.563494 -52.872577)
			(xy 63.517184 -52.848981) (xy 63.475136 -52.818431) (xy 63.438385 -52.78168) (xy 63.407835 -52.739632)
			(xy 63.384239 -52.693322) (xy 63.368178 -52.643892) (xy 63.360048 -52.592557) (xy 63.359538 -52.56657)
			(xy 63.359959 -52.541804) (xy 63.367309 -52.492821) (xy 63.381885 -52.445482) (xy 63.403361 -52.400849)
			(xy 63.416942 -52.380134) (xy 63.424316 -52.368488) (xy 63.433158 -52.342393) (xy 63.434695 -52.314884)
			(xy 63.428814 -52.287966) (xy 63.415945 -52.263604) (xy 63.397026 -52.243574) (xy 63.373436 -52.229338)
			(xy 63.346898 -52.221933) (xy 63.333122 -52.221384) (xy 63.24727 -52.221384) (xy 63.233482 -52.221835)
			(xy 63.20691 -52.229211) (xy 63.18329 -52.243443) (xy 63.164351 -52.263487) (xy 63.15148 -52.287875)
			(xy 63.14562 -52.314822) (xy 63.147201 -52.342353) (xy 63.156107 -52.368452) (xy 63.16345 -52.380134)
			(xy 63.177029 -52.40085) (xy 63.1985 -52.445485) (xy 63.213077 -52.492823) (xy 63.220435 -52.541804)
			(xy 63.220854 -52.56657) (xy 63.220344 -52.592557) (xy 63.212214 -52.643892) (xy 63.196153 -52.693322)
			(xy 63.172557 -52.739632) (xy 63.142007 -52.78168) (xy 63.105256 -52.818431) (xy 63.063208 -52.848981)
			(xy 63.016898 -52.872577) (xy 62.967468 -52.888638) (xy 62.916133 -52.896768) (xy 62.864159 -52.896768)
			(xy 62.812824 -52.888638) (xy 62.763394 -52.872577) (xy 62.717084 -52.848981) (xy 62.675036 -52.818431)
			(xy 62.638285 -52.78168) (xy 62.607735 -52.739632) (xy 62.584139 -52.693322) (xy 62.568078 -52.643892)
			(xy 62.559948 -52.592557) (xy 62.559438 -52.56657) (xy 62.559859 -52.541804) (xy 62.567209 -52.492821)
			(xy 62.581785 -52.445482) (xy 62.603261 -52.400849) (xy 62.616842 -52.380134) (xy 62.624216 -52.368488)
			(xy 62.633058 -52.342393) (xy 62.634595 -52.314884) (xy 62.628714 -52.287966) (xy 62.615845 -52.263604)
			(xy 62.596926 -52.243574) (xy 62.573336 -52.229338) (xy 62.546798 -52.221933) (xy 62.533022 -52.221384)
			(xy 61.638942 -52.221384) (xy 60.898786 -51.481228) (xy 59.584336 -51.481228) (xy 59.450224 -51.61534)
			(xy 59.450224 -51.85029) (xy 60.836048 -53.236114) (xy 60.845962 -53.245425) (xy 60.869573 -53.258908)
			(xy 60.895903 -53.265688) (xy 60.923088 -53.265287) (xy 60.949207 -53.257732) (xy 60.972409 -53.243558)
			(xy 60.991053 -53.223769) (xy 60.997846 -53.211984) (xy 61.010231 -53.18953) (xy 61.040868 -53.14841)
			(xy 61.077491 -53.112519) (xy 61.119222 -53.082721) (xy 61.165057 -53.05973) (xy 61.213894 -53.044099)
			(xy 61.264561 -53.036204) (xy 61.2902 -53.035708) (xy 61.316189 -53.036191) (xy 61.367526 -53.044322)
			(xy 61.41696 -53.060385) (xy 61.463272 -53.083983) (xy 61.505322 -53.114535) (xy 61.542075 -53.15129)
			(xy 61.572625 -53.193342) (xy 61.596221 -53.239655) (xy 61.612281 -53.289089) (xy 61.62041 -53.340427)
			(xy 61.620908 -53.366416) (xy 61.620405 -53.392403) (xy 62.559948 -53.392403) (xy 62.559948 -53.340429)
			(xy 62.568078 -53.289094) (xy 62.584139 -53.239664) (xy 62.607735 -53.193354) (xy 62.638285 -53.151306)
			(xy 62.675036 -53.114555) (xy 62.717084 -53.084005) (xy 62.763394 -53.060409) (xy 62.812824 -53.044348)
			(xy 62.864159 -53.036218) (xy 62.916133 -53.036218) (xy 62.967468 -53.044348) (xy 63.016898 -53.060409)
			(xy 63.063208 -53.084005) (xy 63.105256 -53.114555) (xy 63.142007 -53.151306) (xy 63.172557 -53.193354)
			(xy 63.196153 -53.239664) (xy 63.212214 -53.289094) (xy 63.220344 -53.340429) (xy 63.220854 -53.366416)
			(xy 63.220344 -53.392403) (xy 63.360048 -53.392403) (xy 63.360048 -53.340429) (xy 63.368178 -53.289094)
			(xy 63.384239 -53.239664) (xy 63.407835 -53.193354) (xy 63.438385 -53.151306) (xy 63.475136 -53.114555)
			(xy 63.517184 -53.084005) (xy 63.563494 -53.060409) (xy 63.612924 -53.044348) (xy 63.664259 -53.036218)
			(xy 63.716233 -53.036218) (xy 63.767568 -53.044348) (xy 63.816998 -53.060409) (xy 63.863308 -53.084005)
			(xy 63.905356 -53.114555) (xy 63.942107 -53.151306) (xy 63.972657 -53.193354) (xy 63.996253 -53.239664)
			(xy 64.012314 -53.289094) (xy 64.020444 -53.340429) (xy 64.020954 -53.366416) (xy 64.020444 -53.392403)
			(xy 64.012314 -53.443738) (xy 63.996253 -53.493168) (xy 63.972657 -53.539478) (xy 63.942107 -53.581526)
			(xy 63.905356 -53.618277) (xy 63.863308 -53.648827) (xy 63.816998 -53.672423) (xy 63.767568 -53.688484)
			(xy 63.716233 -53.696614) (xy 63.664259 -53.696614) (xy 63.612924 -53.688484) (xy 63.563494 -53.672423)
			(xy 63.517184 -53.648827) (xy 63.475136 -53.618277) (xy 63.438385 -53.581526) (xy 63.407835 -53.539478)
			(xy 63.384239 -53.493168) (xy 63.368178 -53.443738) (xy 63.360048 -53.392403) (xy 63.220344 -53.392403)
			(xy 63.212214 -53.443738) (xy 63.196153 -53.493168) (xy 63.172557 -53.539478) (xy 63.142007 -53.581526)
			(xy 63.105256 -53.618277) (xy 63.063208 -53.648827) (xy 63.016898 -53.672423) (xy 62.967468 -53.688484)
			(xy 62.916133 -53.696614) (xy 62.864159 -53.696614) (xy 62.812824 -53.688484) (xy 62.763394 -53.672423)
			(xy 62.717084 -53.648827) (xy 62.675036 -53.618277) (xy 62.638285 -53.581526) (xy 62.607735 -53.539478)
			(xy 62.584139 -53.493168) (xy 62.568078 -53.443738) (xy 62.559948 -53.392403) (xy 61.620405 -53.392403)
			(xy 61.620399 -53.392707) (xy 61.612074 -53.444626) (xy 61.595635 -53.494573) (xy 61.571497 -53.541288)
			(xy 61.54027 -53.583593) (xy 61.50274 -53.620422) (xy 61.459853 -53.650846) (xy 61.412691 -53.674098)
			(xy 61.387736 -53.682392) (xy 61.375798 -53.686202) (xy 61.33084 -53.730906) (xy 61.416692 -53.816758)
			(xy 68.99148 -53.816758) (xy 69.026024 -53.851048) (xy 69.037962 -53.851048) (xy 72.812148 -57.625488)
			(xy 72.812148 -59.396884) (xy 72.923908 -59.50839) (xy 72.923908 -59.980322) (xy 72.9996 -60.056268)
			(xy 73.868788 -60.056268)
		)
		(stroke
			(width 0)
			(type solid)
		)
		(fill yes)
		(layer "In7.Cu")
		(net "P1V0_STBY_DP_VCC10A")
	)
	(gr_poly
		(pts
			(xy 72.6694 -59.9186) (xy 72.6694 -59.6138) (xy 72.557894 -59.502294) (xy 72.557894 -57.730898) (xy 68.932552 -54.105556)
			(xy 68.771516 -54.105556) (xy 68.756953 -54.105981) (xy 68.728989 -54.114114) (xy 68.704458 -54.129811)
			(xy 68.685355 -54.151794) (xy 68.673235 -54.178275) (xy 68.669082 -54.2071) (xy 68.673235 -54.235925)
			(xy 68.685355 -54.262406) (xy 68.694554 -54.273704) (xy 68.710867 -54.293188) (xy 68.73834 -54.335936)
			(xy 68.75945 -54.382159) (xy 68.773765 -54.430916) (xy 68.780995 -54.481214) (xy 68.781422 -54.506622)
			(xy 68.780871 -54.534604) (xy 68.772114 -54.58988) (xy 68.754817 -54.643105) (xy 68.729408 -54.692969)
			(xy 68.696512 -54.738245) (xy 68.656939 -54.777817) (xy 68.611662 -54.810713) (xy 68.561797 -54.836121)
			(xy 68.508572 -54.853416) (xy 68.453296 -54.862172) (xy 68.425314 -54.86273) (xy 68.398858 -54.862248)
			(xy 68.346529 -54.854424) (xy 68.295933 -54.838945) (xy 68.248182 -54.816153) (xy 68.204328 -54.786549)
			(xy 68.184522 -54.769004) (xy 68.176953 -54.762629) (xy 68.158442 -54.75568) (xy 68.138679 -54.756245)
			(xy 68.120596 -54.76424) (xy 68.113402 -54.771036) (xy 68.095358 -54.789225) (xy 68.055243 -54.821098)
			(xy 68.011227 -54.847321) (xy 67.964099 -54.867423) (xy 67.914707 -54.881043) (xy 67.863937 -54.887936)
			(xy 67.83832 -54.888384) (xy 66.94932 -54.888384) (xy 66.919617 -54.887803) (xy 66.860932 -54.878564)
			(xy 66.80439 -54.860337) (xy 66.751357 -54.833563) (xy 66.703118 -54.79889) (xy 66.681604 -54.778402)
			(xy 66.674221 -54.77182) (xy 66.655924 -54.764355) (xy 66.636164 -54.764355) (xy 66.617867 -54.77182)
			(xy 66.610484 -54.778402) (xy 66.590418 -54.797163) (xy 66.545589 -54.828909) (xy 66.496419 -54.853398)
			(xy 66.444073 -54.870049) (xy 66.389792 -54.878469) (xy 66.362326 -54.878986) (xy 66.33434 -54.878467)
			(xy 66.279057 -54.869715) (xy 66.225823 -54.852421) (xy 66.175951 -54.827012) (xy 66.130668 -54.794113)
			(xy 66.09109 -54.754535) (xy 66.05819 -54.709253) (xy 66.032781 -54.659381) (xy 66.015486 -54.606147)
			(xy 66.006733 -54.550864) (xy 66.006218 -54.522878) (xy 66.006722 -54.495757) (xy 66.014941 -54.442143)
			(xy 66.031201 -54.390396) (xy 66.055125 -54.341716) (xy 66.08616 -54.29723) (xy 66.104516 -54.27726)
			(xy 66.114379 -54.266157) (xy 66.127801 -54.239681) (xy 66.133047 -54.210464) (xy 66.129676 -54.180971)
			(xy 66.117972 -54.153692) (xy 66.098923 -54.130927) (xy 66.074134 -54.114596) (xy 66.045698 -54.106078)
			(xy 66.030856 -54.105556) (xy 65.720468 -54.105556) (xy 65.705442 -54.106084) (xy 65.676686 -54.114812)
			(xy 65.651716 -54.131532) (xy 65.632694 -54.154796) (xy 65.621267 -54.18259) (xy 65.619376 -54.197504)
			(xy 65.616286 -54.224481) (xy 65.602435 -54.27698) (xy 65.580195 -54.326512) (xy 65.550164 -54.371746)
			(xy 65.513147 -54.411467) (xy 65.47014 -54.444609) (xy 65.422297 -54.470281) (xy 65.370903 -54.487794)
			(xy 65.31734 -54.496677) (xy 65.290192 -54.497224) (xy 65.264205 -54.496714) (xy 65.21287 -54.488582)
			(xy 65.16344 -54.472521) (xy 65.11713 -54.448925) (xy 65.075082 -54.418375) (xy 65.03833 -54.381624)
			(xy 65.007779 -54.339577) (xy 64.984182 -54.293268) (xy 64.968119 -54.243837) (xy 64.959987 -54.192503)
			(xy 64.959484 -54.166516) (xy 64.959484 -54.157626) (xy 64.959738 -54.157118) (xy 64.959738 -54.105556)
			(xy 64.820546 -54.105556) (xy 64.820546 -54.157118) (xy 64.8208 -54.157626) (xy 64.8208 -54.166516)
			(xy 64.82029 -54.192503) (xy 64.81216 -54.243838) (xy 64.796099 -54.293268) (xy 64.772503 -54.339578)
			(xy 64.741953 -54.381626) (xy 64.705202 -54.418377) (xy 64.663154 -54.448927) (xy 64.616844 -54.472523)
			(xy 64.567414 -54.488584) (xy 64.516079 -54.496714) (xy 64.464105 -54.496714) (xy 64.41277 -54.488584)
			(xy 64.36334 -54.472523) (xy 64.31703 -54.448927) (xy 64.274982 -54.418377) (xy 64.238231 -54.381626)
			(xy 64.207681 -54.339578) (xy 64.184085 -54.293268) (xy 64.168024 -54.243838) (xy 64.159894 -54.192503)
			(xy 64.159384 -54.166516) (xy 64.159384 -54.157626) (xy 64.159638 -54.157118) (xy 64.159638 -54.105556)
			(xy 64.0207 -54.105556) (xy 64.0207 -54.157118) (xy 64.020954 -54.157626) (xy 64.020954 -54.166516)
			(xy 64.020444 -54.192503) (xy 64.012314 -54.243838) (xy 63.996253 -54.293268) (xy 63.972657 -54.339578)
			(xy 63.942107 -54.381626) (xy 63.905356 -54.418377) (xy 63.863308 -54.448927) (xy 63.816998 -54.472523)
			(xy 63.767568 -54.488584) (xy 63.716233 -54.496714) (xy 63.664259 -54.496714) (xy 63.612924 -54.488584)
			(xy 63.563494 -54.472523) (xy 63.517184 -54.448927) (xy 63.475136 -54.418377) (xy 63.438385 -54.381626)
			(xy 63.407835 -54.339578) (xy 63.384239 -54.293268) (xy 63.368178 -54.243838) (xy 63.360048 -54.192503)
			(xy 63.359538 -54.166516) (xy 63.359538 -54.157626) (xy 63.359792 -54.157118) (xy 63.359792 -54.105556)
			(xy 63.2206 -54.105556) (xy 63.2206 -54.157118) (xy 63.220854 -54.157626) (xy 63.220854 -54.166516)
			(xy 63.220343 -54.192504) (xy 63.212211 -54.243839) (xy 63.196149 -54.29327) (xy 63.172553 -54.339581)
			(xy 63.142004 -54.381631) (xy 63.105254 -54.418384) (xy 63.063207 -54.448938) (xy 63.016898 -54.472538)
			(xy 62.967468 -54.488604) (xy 62.916134 -54.496741) (xy 62.890146 -54.497224) (xy 62.862995 -54.496679)
			(xy 62.809421 -54.487813) (xy 62.758016 -54.470312) (xy 62.710161 -54.444645) (xy 62.667145 -54.411504)
			(xy 62.630122 -54.371779) (xy 62.600088 -54.326538) (xy 62.577851 -54.276997) (xy 62.564008 -54.224489)
			(xy 62.560962 -54.197504) (xy 62.558997 -54.182608) (xy 62.547567 -54.154838) (xy 62.528558 -54.131589)
			(xy 62.503613 -54.114868) (xy 62.474885 -54.10612) (xy 62.45987 -54.105556) (xy 61.720476 -54.105556)
			(xy 61.705449 -54.106083) (xy 61.676692 -54.114809) (xy 61.651719 -54.131529) (xy 61.632696 -54.154794)
			(xy 61.621268 -54.182589) (xy 61.619384 -54.197504) (xy 61.616294 -54.224481) (xy 61.602444 -54.276981)
			(xy 61.580204 -54.326513) (xy 61.550173 -54.371748) (xy 61.513156 -54.41147) (xy 61.470149 -54.444613)
			(xy 61.422306 -54.470286) (xy 61.370912 -54.4878) (xy 61.317348 -54.496685) (xy 61.2902 -54.497224)
			(xy 61.264212 -54.496714) (xy 61.212877 -54.488584) (xy 61.163445 -54.472523) (xy 61.117135 -54.448928)
			(xy 61.075085 -54.418378) (xy 61.038332 -54.381627) (xy 61.007781 -54.339579) (xy 60.984183 -54.293269)
			(xy 60.96812 -54.243839) (xy 60.959987 -54.192504) (xy 60.959492 -54.166516) (xy 60.959911 -54.142365)
			(xy 60.966943 -54.094579) (xy 60.980859 -54.048326) (xy 61.001364 -54.004593) (xy 61.028018 -53.964312)
			(xy 61.04382 -53.946044) (xy 61.053745 -53.934177) (xy 61.066565 -53.90604) (xy 61.070367 -53.875355)
			(xy 61.064801 -53.84494) (xy 61.050377 -53.81759) (xy 61.039756 -53.806344) (xy 60.348368 -53.114956)
			(xy 60.348368 -53.108352) (xy 60.053728 -52.813712) (xy 60.042343 -52.803159) (xy 60.0148 -52.788872)
			(xy 59.984241 -52.783497) (xy 59.953476 -52.787528) (xy 59.925334 -52.800595) (xy 59.91352 -52.810664)
			(xy 59.895122 -52.826873) (xy 59.854442 -52.854242) (xy 59.810166 -52.875307) (xy 59.763266 -52.889604)
			(xy 59.71477 -52.89682) (xy 59.690254 -52.897278) (xy 59.66427 -52.896765) (xy 59.612943 -52.888629)
			(xy 59.56352 -52.872563) (xy 59.517219 -52.848964) (xy 59.47518 -52.818413) (xy 59.438437 -52.781662)
			(xy 59.407896 -52.739616) (xy 59.384308 -52.693309) (xy 59.368254 -52.643883) (xy 59.360129 -52.592554)
			(xy 59.359546 -52.56657) (xy 59.359991 -52.542055) (xy 59.367225 -52.493561) (xy 59.38153 -52.446664)
			(xy 59.402593 -52.402389) (xy 59.429954 -52.361704) (xy 59.44616 -52.343304) (xy 59.456236 -52.331486)
			(xy 59.469355 -52.303353) (xy 59.473407 -52.272577) (xy 59.468018 -52.242007) (xy 59.453686 -52.214472)
			(xy 59.443112 -52.203096) (xy 59.180222 -51.940206) (xy 59.180222 -51.626008) (xy 59.056778 -51.502564)
			(xy 58.760106 -51.502564) (xy 58.670952 -51.591972) (xy 58.642758 -51.620166) (xy 58.642758 -52.959508)
			(xy 58.643179 -52.973435) (xy 58.650692 -53.000256) (xy 58.665183 -53.024043) (xy 58.68557 -53.043021)
			(xy 58.710332 -53.055775) (xy 58.737622 -53.061351) (xy 58.765402 -53.059335) (xy 58.778648 -53.055012)
			(xy 58.805639 -53.046002) (xy 58.861705 -53.036302) (xy 58.890154 -53.035708) (xy 58.916144 -53.036188)
			(xy 58.967486 -53.044313) (xy 59.016924 -53.06037) (xy 59.063242 -53.083964) (xy 59.105297 -53.114514)
			(xy 59.142056 -53.151268) (xy 59.172612 -53.193319) (xy 59.196212 -53.239633) (xy 59.212276 -53.289069)
			(xy 59.220409 -53.34041) (xy 59.220409 -53.39239) (xy 59.220407 -53.392403) (xy 59.360056 -53.392403)
			(xy 59.360056 -53.340429) (xy 59.368186 -53.289094) (xy 59.384247 -53.239664) (xy 59.407843 -53.193354)
			(xy 59.438393 -53.151306) (xy 59.475144 -53.114555) (xy 59.517192 -53.084005) (xy 59.563502 -53.060409)
			(xy 59.612932 -53.044348) (xy 59.664267 -53.036218) (xy 59.716241 -53.036218) (xy 59.767576 -53.044348)
			(xy 59.817006 -53.060409) (xy 59.863316 -53.084005) (xy 59.905364 -53.114555) (xy 59.942115 -53.151306)
			(xy 59.972665 -53.193354) (xy 59.996261 -53.239664) (xy 60.012322 -53.289094) (xy 60.020452 -53.340429)
			(xy 60.020962 -53.366416) (xy 60.020452 -53.392403) (xy 60.012322 -53.443738) (xy 59.996261 -53.493168)
			(xy 59.972665 -53.539478) (xy 59.942115 -53.581526) (xy 59.905364 -53.618277) (xy 59.863316 -53.648827)
			(xy 59.817006 -53.672423) (xy 59.767576 -53.688484) (xy 59.716241 -53.696614) (xy 59.664267 -53.696614)
			(xy 59.612932 -53.688484) (xy 59.563502 -53.672423) (xy 59.517192 -53.648827) (xy 59.475144 -53.618277)
			(xy 59.438393 -53.581526) (xy 59.407843 -53.539478) (xy 59.384247 -53.493168) (xy 59.368186 -53.443738)
			(xy 59.360056 -53.392403) (xy 59.220407 -53.392403) (xy 59.212276 -53.443731) (xy 59.196212 -53.493167)
			(xy 59.172612 -53.539481) (xy 59.142056 -53.581532) (xy 59.105297 -53.618286) (xy 59.063242 -53.648836)
			(xy 59.016924 -53.67243) (xy 58.967486 -53.688487) (xy 58.916144 -53.696612) (xy 58.890154 -53.697124)
			(xy 58.861702 -53.696557) (xy 58.805634 -53.686852) (xy 58.778648 -53.67782) (xy 58.765404 -53.673536)
			(xy 58.737648 -53.671576) (xy 58.710392 -53.67718) (xy 58.68566 -53.689931) (xy 58.665287 -53.708884)
			(xy 58.650785 -53.732632) (xy 58.643229 -53.759412) (xy 58.642758 -53.773324) (xy 58.642758 -54.162452)
			(xy 60.050934 -55.570628) (xy 60.223654 -55.570628) (xy 60.239354 -55.550107) (xy 60.276054 -55.513742)
			(xy 60.317964 -55.483527) (xy 60.364063 -55.460198) (xy 60.41323 -55.444322) (xy 60.464267 -55.436286)
			(xy 60.515933 -55.436286) (xy 60.56697 -55.444322) (xy 60.616137 -55.460198) (xy 60.662236 -55.483527)
			(xy 60.704146 -55.513742) (xy 60.740846 -55.550107) (xy 60.756546 -55.570628) (xy 63.4238 -55.570628)
			(xy 63.4395 -55.550107) (xy 63.4762 -55.513742) (xy 63.51811 -55.483527) (xy 63.564209 -55.460198)
			(xy 63.613376 -55.444322) (xy 63.664413 -55.436286) (xy 63.716079 -55.436286) (xy 63.767116 -55.444322)
			(xy 63.816283 -55.460198) (xy 63.862382 -55.483527) (xy 63.904292 -55.513742) (xy 63.940992 -55.550107)
			(xy 63.956692 -55.570628) (xy 64.223646 -55.570628) (xy 64.239346 -55.550107) (xy 64.276046 -55.513742)
			(xy 64.317956 -55.483527) (xy 64.364055 -55.460198) (xy 64.413222 -55.444322) (xy 64.464259 -55.436286)
			(xy 64.515925 -55.436286) (xy 64.566962 -55.444322) (xy 64.616129 -55.460198) (xy 64.662228 -55.483527)
			(xy 64.704138 -55.513742) (xy 64.740838 -55.550107) (xy 64.756538 -55.570628) (xy 65.023746 -55.570628)
			(xy 65.039446 -55.550107) (xy 65.076146 -55.513742) (xy 65.118056 -55.483527) (xy 65.164155 -55.460198)
			(xy 65.213322 -55.444322) (xy 65.264359 -55.436286) (xy 65.316025 -55.436286) (xy 65.367062 -55.444322)
			(xy 65.416229 -55.460198) (xy 65.462328 -55.483527) (xy 65.504238 -55.513742) (xy 65.540938 -55.550107)
			(xy 65.556638 -55.570628) (xy 68.360544 -55.570628) (xy 68.362068 -55.572152) (xy 68.557902 -55.572152)
			(xy 68.976494 -55.990744) (xy 68.976494 -55.995824) (xy 70.84822 -57.867296) (xy 70.84822 -59.90082)
			(xy 70.983094 -60.035694) (xy 72.552306 -60.035694)
		)
		(stroke
			(width 0)
			(type solid)
		)
		(fill yes)
		(layer "In7.Cu")
		(net "P1V0_STBY_PE_VCC10A")
	)
	(gr_poly
		(pts
			(xy 84.492084 -118.78056)
			(arc
				(start 84.492084 -114.799872)
				(mid 84.787357 -114.087273)
				(end 85.499956 -113.792)
			)
			(arc
				(start 88.000078 -113.792)
				(mid 89.055078 -113.355004)
				(end 89.492074 -112.300004)
			)
			(xy 89.492074 -85.508084)
			(arc
				(start 87.749888 -85.508084)
				(mid 87.037379 -85.212795)
				(end 86.742016 -84.500212)
			)
			(arc
				(start 86.742016 -81.999836)
				(mid 87.037289 -81.287237)
				(end 87.749888 -80.991964)
			)
			(xy 89.492074 -80.991964)
			(arc
				(start 89.492074 -1.999996)
				(mid 89.055078 -0.944996)
				(end 88.000078 -0.508)
			)
			(arc
				(start 1.999996 -0.508)
				(mid 0.944996 -0.944996)
				(end 0.508 -1.999996)
			)
			(xy 0.508 -80.991964)
			(arc
				(start 2.249932 -80.991964)
				(mid 2.962785 -81.287237)
				(end 3.258058 -82.00009)
			)
			(arc
				(start 3.258058 -84.499958)
				(mid 2.962785 -85.212811)
				(end 2.249932 -85.508084)
			)
			(xy 0.508 -85.508084)
			(arc
				(start 0.508 -112.300004)
				(mid 0.944996 -113.355004)
				(end 1.999996 -113.792)
			)
			(arc
				(start 4.500118 -113.792)
				(mid 5.212717 -114.087273)
				(end 5.50799 -114.799872)
			)
			(xy 5.50799 -118.71071) (xy 5.621528 -118.824248) (xy 5.936488 -118.824248) (xy 6.015228 -118.745508)
			(arc
				(start 6.015228 -114.799872)
				(mid 5.571478 -113.728438)
				(end 4.500118 -113.284508)
			)
			(arc
				(start 1.999996 -113.284508)
				(mid 1.303847 -112.996153)
				(end 1.015492 -112.300004)
			)
			(xy 1.015492 -86.015576)
			(arc
				(start 2.249932 -86.015576)
				(mid 2.814747 -85.906299)
				(end 3.29819 -85.594444)
			)
			(arc
				(start 3.344164 -85.54847)
				(mid 3.511059 -85.340136)
				(end 3.638804 -85.105748)
			)
			(arc
				(start 3.660394 -85.053932)
				(mid 3.735515 -84.798565)
				(end 3.764788 -84.533994)
			)
			(arc
				(start 3.764788 -81.9658)
				(mid 3.309352 -80.916273)
				(end 2.249932 -80.484472)
			)
			(xy 1.015492 -80.484472) (xy 1.015492 -77.949044) (xy 1.014984 -77.93482) (xy 1.014984 -9.319768)
			(xy 1.015492 -9.305544)
			(arc
				(start 1.015492 -1.999996)
				(mid 1.303847 -1.303847)
				(end 1.999996 -1.015492)
			)
			(xy 63.728092 -1.015492) (xy 76.606908 -1.015492)
			(arc
				(start 88.000078 -1.015492)
				(mid 88.696317 -1.303831)
				(end 88.984836 -1.999996)
			)
			(xy 88.984836 -80.484472) (xy 88.366092 -80.484472) (xy 88.351868 -80.48498)
			(arc
				(start 87.716106 -80.48498)
				(mid 87.166362 -80.601449)
				(end 86.696804 -80.910176)
			)
			(arc
				(start 86.660228 -80.946752)
				(mid 86.345023 -81.431911)
				(end 86.234524 -81.999836)
			)
			(arc
				(start 86.234524 -84.500212)
				(mid 86.678348 -85.571826)
				(end 87.749888 -86.015576)
			)
			(xy 88.984836 -86.015576)
			(arc
				(start 88.984836 -112.300004)
				(mid 88.696571 -112.996064)
				(end 88.000586 -113.284508)
			)
			(arc
				(start 85.499956 -113.284508)
				(mid 84.428432 -113.728348)
				(end 83.984592 -114.799872)
			)
			(xy 83.984592 -118.768114) (xy 84.094574 -118.878096) (xy 84.394548 -118.878096)
		)
		(stroke
			(width 0)
			(type solid)
		)
		(fill yes)
		(layer "In7.Cu")
		(net "GND")
	)
	(gr_poly
		(pts
			(xy 56.575452 -69.724016) (xy 56.575452 -69.287136) (xy 56.057546 -68.170298) (xy 56.011826 -68.191126)
			(xy 55.987009 -68.201816) (xy 55.935117 -68.216879) (xy 55.881618 -68.224465) (xy 55.8546 -68.224908)
			(xy 55.827349 -68.224422) (xy 55.773401 -68.216666) (xy 55.721106 -68.201311) (xy 55.671529 -68.178669)
			(xy 55.625679 -68.149203) (xy 55.584488 -68.113512) (xy 55.548797 -68.072321) (xy 55.519331 -68.026471)
			(xy 55.496689 -67.976894) (xy 55.481334 -67.924599) (xy 55.473578 -67.870651) (xy 55.473092 -67.8434)
			(xy 55.473533 -67.817371) (xy 55.480608 -67.765796) (xy 55.494627 -67.715661) (xy 55.51533 -67.667896)
			(xy 55.542331 -67.623389) (xy 55.575132 -67.582963) (xy 55.613121 -67.547371) (xy 55.634128 -67.531996)
			(xy 55.646476 -67.522617) (xy 55.665285 -67.497984) (xy 55.675845 -67.468845) (xy 55.677183 -67.437881)
			(xy 55.669178 -67.40794) (xy 55.661306 -67.394582) (xy 55.644796 -67.368674) (xy 55.636645 -67.356644)
			(xy 55.614835 -67.337457) (xy 55.588498 -67.325201) (xy 55.559774 -67.320872) (xy 55.530995 -67.324821)
			(xy 55.504499 -67.336727) (xy 55.493158 -67.345814) (xy 55.472315 -67.363027) (xy 55.426695 -67.392022)
			(xy 55.377442 -67.414295) (xy 55.32554 -67.4294) (xy 55.272027 -67.437036) (xy 55.245 -67.437508)
			(xy 55.217749 -67.437022) (xy 55.163801 -67.429266) (xy 55.111506 -67.413911) (xy 55.061929 -67.391269)
			(xy 55.016079 -67.361803) (xy 54.974888 -67.326112) (xy 54.939197 -67.284921) (xy 54.909731 -67.239071)
			(xy 54.887089 -67.189494) (xy 54.871734 -67.137199) (xy 54.863978 -67.083251) (xy 54.863492 -67.056)
			(xy 54.863966 -67.028582) (xy 54.871811 -66.974311) (xy 54.887338 -66.921721) (xy 54.91023 -66.871892)
			(xy 54.940015 -66.825851) (xy 54.97608 -66.784545) (xy 55.017683 -66.748823) (xy 55.063968 -66.71942)
			(xy 55.08879 -66.707766) (xy 55.101877 -66.701402) (xy 55.12401 -66.682524) (xy 55.139927 -66.658175)
			(xy 55.14834 -66.630328) (xy 55.148565 -66.601239) (xy 55.140585 -66.573264) (xy 55.13324 -66.5607)
			(xy 52.893214 -63.02502) (xy 52.884787 -63.012678) (xy 52.862197 -62.993135) (xy 52.834918 -62.980964)
			(xy 52.805285 -62.977208) (xy 52.775832 -62.982189) (xy 52.749081 -62.995478) (xy 52.72732 -63.015941)
			(xy 52.712412 -63.041825) (xy 52.708556 -63.056262) (xy 52.701548 -63.083827) (xy 52.680482 -63.136657)
			(xy 52.651814 -63.185778) (xy 52.616176 -63.230104) (xy 52.574359 -63.268653) (xy 52.527286 -63.300574)
			(xy 52.476 -63.32516) (xy 52.421634 -63.341867) (xy 52.365391 -63.350325) (xy 52.336954 -63.350902)
			(xy 52.309705 -63.350413) (xy 52.255763 -63.342651) (xy 52.203475 -63.327293) (xy 52.153904 -63.304649)
			(xy 52.10806 -63.275182) (xy 52.066876 -63.239491) (xy 52.03119 -63.198303) (xy 52.001729 -63.152455)
			(xy 51.979091 -63.102882) (xy 51.963739 -63.050592) (xy 51.955984 -62.996649) (xy 51.955984 -62.942151)
			(xy 51.963739 -62.888208) (xy 51.979091 -62.835918) (xy 52.001729 -62.786345) (xy 52.03119 -62.740497)
			(xy 52.066876 -62.699309) (xy 52.10806 -62.663618) (xy 52.153904 -62.634151) (xy 52.203475 -62.611507)
			(xy 52.255763 -62.596149) (xy 52.309705 -62.588387) (xy 52.336954 -62.587886) (xy 52.357178 -62.588178)
			(xy 52.397395 -62.592504) (xy 52.417218 -62.596522) (xy 52.43192 -62.599138) (xy 52.461667 -62.596688)
			(xy 52.489436 -62.585744) (xy 52.512856 -62.567241) (xy 52.529928 -62.542758) (xy 52.539194 -62.514385)
			(xy 52.539863 -62.484544) (xy 52.531878 -62.455785) (xy 52.524406 -62.442852) (xy 52.202842 -61.935106)
			(xy 51.108356 -60.27166) (xy 51.108356 -59.775344) (xy 50.85461 -59.521598) (xy 49.306988 -59.521598)
			(xy 49.19345 -59.635136) (xy 49.19345 -61.048646) (xy 49.61204 -61.048646) (xy 49.616111 -60.993024)
			(xy 49.628237 -60.938587) (xy 49.64816 -60.886496) (xy 49.675456 -60.837861) (xy 49.709542 -60.793718)
			(xy 49.749691 -60.755009) (xy 49.795049 -60.722558) (xy 49.844649 -60.697057) (xy 49.897433 -60.67905)
			(xy 49.952276 -60.66892) (xy 50.00801 -60.666883) (xy 50.063447 -60.672983) (xy 50.117404 -60.687089)
			(xy 50.168733 -60.708901) (xy 50.216339 -60.737955) (xy 50.259207 -60.77363) (xy 50.296424 -60.815167)
			(xy 50.327197 -60.86168) (xy 50.350869 -60.912177) (xy 50.366937 -60.965584) (xy 50.375057 -61.02076)
			(xy 50.375566 -61.048646) (xy 50.375057 -61.076532) (xy 50.366937 -61.131708) (xy 50.350869 -61.185115)
			(xy 50.327197 -61.235612) (xy 50.296424 -61.282125) (xy 50.259207 -61.323662) (xy 50.216339 -61.359337)
			(xy 50.168733 -61.388391) (xy 50.117404 -61.410203) (xy 50.063447 -61.424309) (xy 50.00801 -61.430409)
			(xy 49.952276 -61.428372) (xy 49.897433 -61.418242) (xy 49.844649 -61.400235) (xy 49.795049 -61.374734)
			(xy 49.749691 -61.342283) (xy 49.709542 -61.303574) (xy 49.675456 -61.259431) (xy 49.64816 -61.210796)
			(xy 49.628237 -61.158705) (xy 49.616111 -61.104268) (xy 49.61204 -61.048646) (xy 49.19345 -61.048646)
			(xy 49.19345 -62.002924) (xy 50.024284 -62.833758) (xy 50.034742 -62.843548) (xy 50.059805 -62.857395)
			(xy 50.08773 -62.863729) (xy 50.116314 -62.862049) (xy 50.143305 -62.852489) (xy 50.166574 -62.835802)
			(xy 50.184286 -62.813303) (xy 50.190146 -62.80023) (xy 50.201269 -62.774257) (xy 50.230053 -62.725639)
			(xy 50.265691 -62.681796) (xy 50.307404 -62.643687) (xy 50.354279 -62.612144) (xy 50.405293 -62.587858)
			(xy 50.459331 -62.571359) (xy 50.51521 -62.563008) (xy 50.54346 -62.562486) (xy 50.570715 -62.562947)
			(xy 50.62467 -62.570699) (xy 50.676973 -62.586051) (xy 50.726559 -62.608692) (xy 50.772418 -62.638158)
			(xy 50.813615 -62.673852) (xy 50.849314 -62.715046) (xy 50.878786 -62.760901) (xy 50.901432 -62.810483)
			(xy 50.916791 -62.862785) (xy 50.92455 -62.916739) (xy 50.924968 -62.943994) (xy 50.924463 -62.972248)
			(xy 50.916139 -63.02814) (xy 50.899655 -63.08219) (xy 50.875375 -63.133216) (xy 50.843829 -63.180099)
			(xy 50.805709 -63.221813) (xy 50.76185 -63.257443) (xy 50.713212 -63.28621) (xy 50.687224 -63.297308)
			(xy 50.674167 -63.30317) (xy 50.651727 -63.320915) (xy 50.635085 -63.344186) (xy 50.625548 -63.371158)
			(xy 50.623862 -63.399717) (xy 50.630159 -63.427624) (xy 50.643947 -63.452691) (xy 50.653696 -63.46317)
			(xy 51.57597 -64.385444) (xy 51.57597 -65.6082) (xy 51.815492 -65.6082) (xy 51.815998 -65.580926)
			(xy 51.823741 -65.526932) (xy 51.839099 -65.474592) (xy 51.861757 -65.424974) (xy 51.891253 -65.37909)
			(xy 51.926986 -65.337877) (xy 51.968227 -65.302176) (xy 52.014133 -65.272715) (xy 52.038758 -65.260982)
			(xy 52.052582 -65.25413) (xy 52.075616 -65.233626) (xy 52.091477 -65.207179) (xy 52.098716 -65.177203)
			(xy 52.096674 -65.146432) (xy 52.085537 -65.117675) (xy 52.07635 -65.10528) (xy 52.060733 -65.08493)
			(xy 52.034453 -65.040879) (xy 52.014304 -64.993707) (xy 52.000649 -64.944263) (xy 51.993733 -64.893437)
			(xy 51.993292 -64.86779) (xy 51.993778 -64.840539) (xy 52.001534 -64.786591) (xy 52.016889 -64.734296)
			(xy 52.039531 -64.684719) (xy 52.068997 -64.638869) (xy 52.104688 -64.597678) (xy 52.145879 -64.561987)
			(xy 52.191729 -64.532521) (xy 52.241306 -64.509879) (xy 52.293601 -64.494524) (xy 52.347549 -64.486768)
			(xy 52.402051 -64.486768) (xy 52.455999 -64.494524) (xy 52.508294 -64.509879) (xy 52.557871 -64.532521)
			(xy 52.603721 -64.561987) (xy 52.644912 -64.597678) (xy 52.680603 -64.638869) (xy 52.710069 -64.684719)
			(xy 52.732711 -64.734296) (xy 52.748066 -64.786591) (xy 52.755822 -64.840539) (xy 52.756308 -64.86779)
			(xy 52.755794 -64.895063) (xy 52.748052 -64.949057) (xy 52.732696 -65.001397) (xy 52.710039 -65.051015)
			(xy 52.680543 -65.096899) (xy 52.644812 -65.138112) (xy 52.603572 -65.173813) (xy 52.557666 -65.203275)
			(xy 52.533042 -65.215008) (xy 52.519225 -65.221873) (xy 52.496192 -65.242374) (xy 52.480331 -65.268818)
			(xy 52.47309 -65.298792) (xy 52.47513 -65.32956) (xy 52.486265 -65.358315) (xy 52.49545 -65.37071)
			(xy 52.511108 -65.391029) (xy 52.537381 -65.435089) (xy 52.557522 -65.482269) (xy 52.571168 -65.531719)
			(xy 52.578073 -65.582551) (xy 52.578508 -65.6082) (xy 52.578022 -65.635451) (xy 52.570266 -65.689399)
			(xy 52.554911 -65.741694) (xy 52.532269 -65.791271) (xy 52.502803 -65.837121) (xy 52.467112 -65.878312)
			(xy 52.425921 -65.914003) (xy 52.380071 -65.943469) (xy 52.330494 -65.966111) (xy 52.278199 -65.981466)
			(xy 52.224251 -65.989222) (xy 52.169749 -65.989222) (xy 52.115801 -65.981466) (xy 52.063506 -65.966111)
			(xy 52.013929 -65.943469) (xy 51.968079 -65.914003) (xy 51.926888 -65.878312) (xy 51.891197 -65.837121)
			(xy 51.861731 -65.791271) (xy 51.839089 -65.741694) (xy 51.823734 -65.689399) (xy 51.815978 -65.635451)
			(xy 51.815492 -65.6082) (xy 51.57597 -65.6082) (xy 51.57597 -66.416428) (xy 53.982618 -66.416428)
			(xy 53.986689 -66.360806) (xy 53.998815 -66.306369) (xy 54.018738 -66.254278) (xy 54.046034 -66.205643)
			(xy 54.08012 -66.1615) (xy 54.120269 -66.122791) (xy 54.165627 -66.09034) (xy 54.215227 -66.064839)
			(xy 54.268011 -66.046832) (xy 54.322854 -66.036702) (xy 54.378588 -66.034665) (xy 54.434025 -66.040765)
			(xy 54.487982 -66.054871) (xy 54.539311 -66.076683) (xy 54.586917 -66.105737) (xy 54.629785 -66.141412)
			(xy 54.667002 -66.182949) (xy 54.697775 -66.229462) (xy 54.721447 -66.279959) (xy 54.737515 -66.333366)
			(xy 54.745635 -66.388542) (xy 54.746144 -66.416428) (xy 54.745635 -66.444314) (xy 54.737515 -66.49949)
			(xy 54.721447 -66.552897) (xy 54.697775 -66.603394) (xy 54.667002 -66.649907) (xy 54.629785 -66.691444)
			(xy 54.586917 -66.727119) (xy 54.539311 -66.756173) (xy 54.487982 -66.777985) (xy 54.434025 -66.792091)
			(xy 54.378588 -66.798191) (xy 54.322854 -66.796154) (xy 54.268011 -66.786024) (xy 54.215227 -66.768017)
			(xy 54.165627 -66.742516) (xy 54.120269 -66.710065) (xy 54.08012 -66.671356) (xy 54.046034 -66.627213)
			(xy 54.018738 -66.578578) (xy 53.998815 -66.526487) (xy 53.986689 -66.47205) (xy 53.982618 -66.416428)
			(xy 51.57597 -66.416428) (xy 51.57597 -66.896996) (xy 52.015644 -67.33667) (xy 52.051458 -67.306444)
			(xy 52.072241 -67.289362) (xy 52.117705 -67.2606) (xy 52.166762 -67.238517) (xy 52.218436 -67.223552)
			(xy 52.271701 -67.216001) (xy 52.2986 -67.215512) (xy 52.325852 -67.215975) (xy 52.379802 -67.223732)
			(xy 52.432099 -67.239089) (xy 52.481678 -67.261731) (xy 52.527529 -67.2912) (xy 52.56872 -67.326894)
			(xy 52.604412 -67.368087) (xy 52.633878 -67.41394) (xy 52.656518 -67.46352) (xy 52.671872 -67.515817)
			(xy 52.679626 -67.569768) (xy 52.680108 -67.59702) (xy 52.679645 -67.62392) (xy 52.672082 -67.677185)
			(xy 52.657109 -67.728858) (xy 52.635023 -67.777915) (xy 52.606263 -67.823382) (xy 52.589176 -67.844162)
			(xy 52.55895 -67.879976) (xy 52.573174 -67.8942) (xy 53.279292 -67.8942) (xy 53.283363 -67.838578)
			(xy 53.295489 -67.784141) (xy 53.315412 -67.73205) (xy 53.342708 -67.683415) (xy 53.376794 -67.639272)
			(xy 53.416943 -67.600563) (xy 53.462301 -67.568112) (xy 53.511901 -67.542611) (xy 53.564685 -67.524604)
			(xy 53.619528 -67.514474) (xy 53.675262 -67.512437) (xy 53.730699 -67.518537) (xy 53.784656 -67.532643)
			(xy 53.835985 -67.554455) (xy 53.883591 -67.583509) (xy 53.926459 -67.619184) (xy 53.963676 -67.660721)
			(xy 53.994449 -67.707234) (xy 54.018121 -67.757731) (xy 54.034189 -67.811138) (xy 54.042309 -67.866314)
			(xy 54.042818 -67.8942) (xy 54.042309 -67.922086) (xy 54.034189 -67.977262) (xy 54.018121 -68.030669)
			(xy 53.994449 -68.081166) (xy 53.963676 -68.127679) (xy 53.926459 -68.169216) (xy 53.883591 -68.204891)
			(xy 53.835985 -68.233945) (xy 53.784656 -68.255757) (xy 53.730699 -68.269863) (xy 53.675262 -68.275963)
			(xy 53.619528 -68.273926) (xy 53.564685 -68.263796) (xy 53.511901 -68.245789) (xy 53.462301 -68.220288)
			(xy 53.416943 -68.187837) (xy 53.376794 -68.149128) (xy 53.342708 -68.104985) (xy 53.315412 -68.05635)
			(xy 53.295489 -68.004259) (xy 53.283363 -67.949822) (xy 53.279292 -67.8942) (xy 52.573174 -67.8942)
			(xy 53.85816 -69.179186) (xy 53.894228 -69.143118) (xy 53.894482 -69.142864) (xy 53.912498 -69.124999)
			(xy 53.952434 -69.093706) (xy 53.996165 -69.067983) (xy 54.042921 -69.048283) (xy 54.091875 -69.034956)
			(xy 54.142164 -69.028234) (xy 54.167532 -69.027802) (xy 54.194781 -69.02829) (xy 54.248725 -69.036051)
			(xy 54.301015 -69.051409) (xy 54.350588 -69.074052) (xy 54.396434 -69.103519) (xy 54.437619 -69.139211)
			(xy 54.473306 -69.1804) (xy 54.502768 -69.226249) (xy 54.525406 -69.275824) (xy 54.540758 -69.328116)
			(xy 54.548513 -69.38206) (xy 54.54904 -69.40931) (xy 54.548623 -69.434678) (xy 54.541897 -69.484968)
			(xy 54.528565 -69.533922) (xy 54.508863 -69.580677) (xy 54.483138 -69.624408) (xy 54.451843 -69.664344)
			(xy 54.433978 -69.68236) (xy 54.433724 -69.682614) (xy 54.397656 -69.718682) (xy 54.508654 -69.82968)
			(xy 56.469788 -69.82968)
		)
		(stroke
			(width 0)
			(type solid)
		)
		(fill yes)
		(layer "In7.Cu")
		(net "ADCVREFEXT0")
	)
	(gr_poly
		(pts
			(xy 70.72376 -91.00312) (xy 70.72376 -90.14206) (xy 69.88556 -89.30386) (xy 69.88556 -87.91702) (xy 68.54444 -86.5759)
			(xy 68.54444 -82.58048) (xy 67.21094 -81.24698) (xy 67.21094 -80.700372) (xy 67.210359 -80.684683)
			(xy 67.200837 -80.654783) (xy 67.182698 -80.629178) (xy 67.157651 -80.610277) (xy 67.128052 -80.59986)
			(xy 67.112388 -80.598772) (xy 67.085662 -80.59755) (xy 67.032924 -80.588553) (xy 66.981959 -80.572277)
			(xy 66.933767 -80.549044) (xy 66.889293 -80.519307) (xy 66.849407 -80.48365) (xy 66.814892 -80.442772)
			(xy 66.786425 -80.397474) (xy 66.764564 -80.348644) (xy 66.749737 -80.297239) (xy 66.742234 -80.244268)
			(xy 66.741802 -80.217518) (xy 66.74225 -80.190799) (xy 66.749706 -80.137885) (xy 66.764476 -80.086529)
			(xy 66.78627 -80.037738) (xy 66.814661 -79.992467) (xy 66.849094 -79.951602) (xy 66.888893 -79.915943)
			(xy 66.933281 -79.886189) (xy 66.981387 -79.862922) (xy 67.03227 -79.846598) (xy 67.084934 -79.837537)
			(xy 67.111626 -79.836264) (xy 67.127324 -79.835213) (xy 67.156983 -79.82477) (xy 67.182067 -79.805807)
			(xy 67.200201 -79.780118) (xy 67.209671 -79.750134) (xy 67.210178 -79.73441) (xy 67.1703 -68.34124)
			(xy 67.072002 -68.242942) (xy 67.064628 -68.236285) (xy 67.046292 -68.228692) (xy 67.026446 -68.228625)
			(xy 67.00806 -68.236094) (xy 67.000628 -68.242688) (xy 66.979093 -68.263031) (xy 66.930905 -68.297483)
			(xy 66.877971 -68.324074) (xy 66.821564 -68.342165) (xy 66.763039 -68.351323) (xy 66.73342 -68.351908)
			(xy 66.706166 -68.351446) (xy 66.652213 -68.343691) (xy 66.599913 -68.328337) (xy 66.55033 -68.305696)
			(xy 66.504475 -68.276228) (xy 66.46328 -68.240535) (xy 66.427584 -68.199341) (xy 66.398114 -68.153487)
			(xy 66.37547 -68.103906) (xy 66.360113 -68.051606) (xy 66.352355 -67.997654) (xy 66.351912 -67.9704)
			(xy 66.352472 -67.94078) (xy 66.361629 -67.882251) (xy 66.379724 -67.825842) (xy 66.406321 -67.772908)
			(xy 66.440781 -67.724721) (xy 66.461132 -67.703192) (xy 66.467744 -67.69577) (xy 66.47522 -67.677373)
			(xy 66.475159 -67.657516) (xy 66.467569 -67.639166) (xy 66.460878 -67.631818) (xy 66.125598 -67.296538)
			(xy 66.101903 -67.311844) (xy 66.050956 -67.336059) (xy 65.996997 -67.352502) (xy 65.941204 -67.360814)
			(xy 65.913 -67.361308) (xy 65.885749 -67.360822) (xy 65.831801 -67.353066) (xy 65.779506 -67.337711)
			(xy 65.729929 -67.315069) (xy 65.684079 -67.285603) (xy 65.642888 -67.249912) (xy 65.607197 -67.208721)
			(xy 65.577731 -67.162871) (xy 65.555089 -67.113294) (xy 65.539734 -67.060999) (xy 65.531978 -67.007051)
			(xy 65.531492 -66.9798) (xy 65.532001 -66.951596) (xy 65.54031 -66.895805) (xy 65.556749 -66.841846)
			(xy 65.580957 -66.790897) (xy 65.596262 -66.767202) (xy 65.3542 -66.52514) (xy 65.14084 -66.52514)
			(xy 64.8716 -66.79438) (xy 64.8716 -68.14312) (xy 65.31356 -68.58508) (xy 65.31356 -68.622164) (xy 65.43548 -68.74383)
			(xy 65.43548 -69.816726) (xy 65.31356 -69.938392) (xy 65.31356 -70.659498) (xy 65.358518 -70.664832)
			(xy 65.386061 -70.668514) (xy 65.439753 -70.682824) (xy 65.490802 -70.704771) (xy 65.538126 -70.733892)
			(xy 65.580725 -70.769572) (xy 65.617697 -70.811054) (xy 65.648259 -70.85746) (xy 65.671765 -70.90781)
			(xy 65.687718 -70.961038) (xy 65.69578 -71.016017) (xy 65.69578 -71.071583) (xy 65.687718 -71.126562)
			(xy 65.671765 -71.17979) (xy 65.648259 -71.23014) (xy 65.617697 -71.276546) (xy 65.598754 -71.2978)
			(xy 66.191382 -71.2978) (xy 66.195453 -71.242178) (xy 66.207579 -71.187741) (xy 66.227502 -71.13565)
			(xy 66.254798 -71.087015) (xy 66.288884 -71.042872) (xy 66.329033 -71.004163) (xy 66.374391 -70.971712)
			(xy 66.423991 -70.946211) (xy 66.476775 -70.928204) (xy 66.531618 -70.918074) (xy 66.587352 -70.916037)
			(xy 66.642789 -70.922137) (xy 66.696746 -70.936243) (xy 66.748075 -70.958055) (xy 66.795681 -70.987109)
			(xy 66.838549 -71.022784) (xy 66.875766 -71.064321) (xy 66.906539 -71.110834) (xy 66.930211 -71.161331)
			(xy 66.946279 -71.214738) (xy 66.954399 -71.269914) (xy 66.954908 -71.2978) (xy 66.954399 -71.325686)
			(xy 66.946279 -71.380862) (xy 66.930211 -71.434269) (xy 66.906539 -71.484766) (xy 66.875766 -71.531279)
			(xy 66.838549 -71.572816) (xy 66.795681 -71.608491) (xy 66.748075 -71.637545) (xy 66.696746 -71.659357)
			(xy 66.642789 -71.673463) (xy 66.587352 -71.679563) (xy 66.531618 -71.677526) (xy 66.476775 -71.667396)
			(xy 66.423991 -71.649389) (xy 66.374391 -71.623888) (xy 66.329033 -71.591437) (xy 66.288884 -71.552728)
			(xy 66.254798 -71.508585) (xy 66.227502 -71.45995) (xy 66.207579 -71.407859) (xy 66.195453 -71.353422)
			(xy 66.191382 -71.2978) (xy 65.598754 -71.2978) (xy 65.580725 -71.318028) (xy 65.538126 -71.353708)
			(xy 65.490802 -71.382829) (xy 65.439753 -71.404776) (xy 65.386061 -71.419086) (xy 65.358518 -71.422768)
			(xy 65.31356 -71.428102) (xy 65.31356 -71.89597) (xy 65.314091 -71.911379) (xy 65.323272 -71.940799)
			(xy 65.340807 -71.966142) (xy 65.365102 -71.985104) (xy 65.393945 -71.995959) (xy 65.424714 -71.99772)
			(xy 65.439798 -71.994522) (xy 65.462477 -71.989202) (xy 65.508708 -71.983475) (xy 65.532 -71.983092)
			(xy 65.559251 -71.983578) (xy 65.613199 -71.991334) (xy 65.665494 -72.006689) (xy 65.715071 -72.029331)
			(xy 65.760921 -72.058797) (xy 65.802112 -72.094488) (xy 65.837803 -72.135679) (xy 65.867269 -72.181529)
			(xy 65.889911 -72.231106) (xy 65.905266 -72.283401) (xy 65.913022 -72.337349) (xy 65.913022 -72.391851)
			(xy 65.905266 -72.445799) (xy 65.889911 -72.498094) (xy 65.867269 -72.547671) (xy 65.837803 -72.593521)
			(xy 65.802112 -72.634712) (xy 65.760921 -72.670403) (xy 65.715071 -72.699869) (xy 65.665494 -72.722511)
			(xy 65.613199 -72.737866) (xy 65.559251 -72.745622) (xy 65.532 -72.746108) (xy 65.508708 -72.74573)
			(xy 65.462476 -72.740003) (xy 65.439798 -72.734678) (xy 65.42472 -72.731467) (xy 65.393959 -72.733253)
			(xy 65.365126 -72.74412) (xy 65.340837 -72.763081) (xy 65.323298 -72.788415) (xy 65.314101 -72.817824)
			(xy 65.31356 -72.83323) (xy 65.31356 -73.77176) (xy 66.038982 -73.77176) (xy 66.043053 -73.716138)
			(xy 66.055179 -73.661701) (xy 66.075102 -73.60961) (xy 66.102398 -73.560975) (xy 66.136484 -73.516832)
			(xy 66.176633 -73.478123) (xy 66.221991 -73.445672) (xy 66.271591 -73.420171) (xy 66.324375 -73.402164)
			(xy 66.379218 -73.392034) (xy 66.434952 -73.389997) (xy 66.490389 -73.396097) (xy 66.544346 -73.410203)
			(xy 66.595675 -73.432015) (xy 66.643281 -73.461069) (xy 66.686149 -73.496744) (xy 66.723366 -73.538281)
			(xy 66.754139 -73.584794) (xy 66.777811 -73.635291) (xy 66.793879 -73.688698) (xy 66.801999 -73.743874)
			(xy 66.802508 -73.77176) (xy 66.801999 -73.799646) (xy 66.793879 -73.854822) (xy 66.777811 -73.908229)
			(xy 66.754139 -73.958726) (xy 66.723366 -74.005239) (xy 66.686149 -74.046776) (xy 66.643281 -74.082451)
			(xy 66.595675 -74.111505) (xy 66.544346 -74.133317) (xy 66.490389 -74.147423) (xy 66.434952 -74.153523)
			(xy 66.379218 -74.151486) (xy 66.324375 -74.141356) (xy 66.271591 -74.123349) (xy 66.221991 -74.097848)
			(xy 66.176633 -74.065397) (xy 66.136484 -74.026688) (xy 66.102398 -73.982545) (xy 66.075102 -73.93391)
			(xy 66.055179 -73.881819) (xy 66.043053 -73.827382) (xy 66.038982 -73.77176) (xy 65.31356 -73.77176)
			(xy 65.31356 -74.488548) (xy 65.313961 -74.50216) (xy 65.321094 -74.528431) (xy 65.334922 -74.55188)
			(xy 65.354457 -74.570837) (xy 65.378311 -74.583954) (xy 65.404784 -74.590295) (xy 65.431992 -74.58941)
			(xy 65.445132 -74.58583) (xy 65.472516 -74.577883) (xy 65.528891 -74.569338) (xy 65.5574 -74.568812)
			(xy 65.58465 -74.569298) (xy 65.638595 -74.577054) (xy 65.690887 -74.592409) (xy 65.740461 -74.615049)
			(xy 65.786309 -74.644513) (xy 65.827497 -74.680203) (xy 65.863187 -74.721391) (xy 65.892651 -74.767239)
			(xy 65.915291 -74.816813) (xy 65.930646 -74.869105) (xy 65.938402 -74.92305) (xy 65.938402 -74.97755)
			(xy 65.930646 -75.031495) (xy 65.915291 -75.083787) (xy 65.892651 -75.133361) (xy 65.863187 -75.179209)
			(xy 65.827497 -75.220397) (xy 65.786309 -75.256087) (xy 65.740461 -75.285551) (xy 65.690887 -75.308191)
			(xy 65.638595 -75.323546) (xy 65.58465 -75.331302) (xy 65.5574 -75.331828) (xy 65.528894 -75.331259)
			(xy 65.472525 -75.322715) (xy 65.445132 -75.31481) (xy 65.432002 -75.311216) (xy 65.404802 -75.310354)
			(xy 65.378342 -75.31671) (xy 65.354501 -75.329831) (xy 65.334974 -75.348785) (xy 65.321149 -75.372225)
			(xy 65.314009 -75.398485) (xy 65.31356 -75.412092) (xy 65.31356 -78.798928) (xy 65.314088 -78.813881)
			(xy 65.322744 -78.842509) (xy 65.339309 -78.86741) (xy 65.362366 -78.886457) (xy 65.389946 -78.898023)
			(xy 65.419692 -78.90112) (xy 65.434464 -78.89875) (xy 65.452323 -78.895524) (xy 65.488453 -78.892093)
			(xy 65.5066 -78.891892) (xy 65.533851 -78.892378) (xy 65.587799 -78.900134) (xy 65.640094 -78.915489)
			(xy 65.689671 -78.938131) (xy 65.735521 -78.967597) (xy 65.776712 -79.003288) (xy 65.812403 -79.044479)
			(xy 65.841869 -79.090329) (xy 65.864511 -79.139906) (xy 65.879866 -79.192201) (xy 65.887622 -79.246149)
			(xy 65.888108 -79.2734) (xy 65.887656 -79.299946) (xy 65.880305 -79.352526) (xy 65.86573 -79.403578)
			(xy 65.844214 -79.452114) (xy 65.816172 -79.497196) (xy 65.782147 -79.537952) (xy 65.742798 -79.573593)
			(xy 65.698884 -79.603431) (xy 65.675256 -79.615538) (xy 65.667636 -79.619348) (xy 65.506092 -79.780892)
			(xy 65.314068 -79.97317) (xy 65.314068 -82.254344) (xy 65.685876 -82.6262) (xy 66.402202 -82.6262)
			(xy 66.406273 -82.570578) (xy 66.418399 -82.516141) (xy 66.438322 -82.46405) (xy 66.465618 -82.415415)
			(xy 66.499704 -82.371272) (xy 66.539853 -82.332563) (xy 66.585211 -82.300112) (xy 66.634811 -82.274611)
			(xy 66.687595 -82.256604) (xy 66.742438 -82.246474) (xy 66.798172 -82.244437) (xy 66.853609 -82.250537)
			(xy 66.907566 -82.264643) (xy 66.958895 -82.286455) (xy 67.006501 -82.315509) (xy 67.049369 -82.351184)
			(xy 67.086586 -82.392721) (xy 67.117359 -82.439234) (xy 67.141031 -82.489731) (xy 67.157099 -82.543138)
			(xy 67.165219 -82.598314) (xy 67.165728 -82.6262) (xy 67.165219 -82.654086) (xy 67.157099 -82.709262)
			(xy 67.141031 -82.762669) (xy 67.117359 -82.813166) (xy 67.086586 -82.859679) (xy 67.049369 -82.901216)
			(xy 67.006501 -82.936891) (xy 66.958895 -82.965945) (xy 66.907566 -82.987757) (xy 66.853609 -83.001863)
			(xy 66.798172 -83.007963) (xy 66.742438 -83.005926) (xy 66.687595 -82.995796) (xy 66.634811 -82.977789)
			(xy 66.585211 -82.952288) (xy 66.539853 -82.919837) (xy 66.499704 -82.881128) (xy 66.465618 -82.836985)
			(xy 66.438322 -82.78835) (xy 66.418399 -82.736259) (xy 66.406273 -82.681822) (xy 66.402202 -82.6262)
			(xy 65.685876 -82.6262) (xy 67.300856 -84.241386) (xy 67.323208 -84.266024) (xy 67.333114 -84.277962)
			(xy 67.349624 -84.298573) (xy 67.377043 -84.343705) (xy 67.397543 -84.392371) (xy 67.410681 -84.443519)
			(xy 67.413886 -84.469732) (xy 67.415156 -84.481924) (xy 67.417188 -84.519008) (xy 67.417188 -85.049106)
			(xy 67.415156 -85.08619) (xy 67.413886 -85.098382) (xy 67.410737 -85.124175) (xy 67.397958 -85.17454)
			(xy 67.378049 -85.222536) (xy 67.351428 -85.26716) (xy 67.3354 -85.287612) (xy 67.32651 -85.298534)
			(xy 67.301872 -85.325712) (xy 67.059048 -85.56879) (xy 67.059048 -88.03005) (xy 68.477382 -88.03005)
			(xy 68.481453 -87.974428) (xy 68.493579 -87.919991) (xy 68.513502 -87.8679) (xy 68.540798 -87.819265)
			(xy 68.574884 -87.775122) (xy 68.615033 -87.736413) (xy 68.660391 -87.703962) (xy 68.709991 -87.678461)
			(xy 68.762775 -87.660454) (xy 68.817618 -87.650324) (xy 68.873352 -87.648287) (xy 68.928789 -87.654387)
			(xy 68.982746 -87.668493) (xy 69.034075 -87.690305) (xy 69.081681 -87.719359) (xy 69.124549 -87.755034)
			(xy 69.161766 -87.796571) (xy 69.192539 -87.843084) (xy 69.216211 -87.893581) (xy 69.232279 -87.946988)
			(xy 69.240399 -88.002164) (xy 69.240908 -88.03005) (xy 69.240399 -88.057936) (xy 69.232279 -88.113112)
			(xy 69.216211 -88.166519) (xy 69.192539 -88.217016) (xy 69.161766 -88.263529) (xy 69.124549 -88.305066)
			(xy 69.081681 -88.340741) (xy 69.034075 -88.369795) (xy 68.982746 -88.391607) (xy 68.928789 -88.405713)
			(xy 68.873352 -88.411813) (xy 68.817618 -88.409776) (xy 68.762775 -88.399646) (xy 68.709991 -88.381639)
			(xy 68.660391 -88.356138) (xy 68.615033 -88.323687) (xy 68.574884 -88.284978) (xy 68.540798 -88.240835)
			(xy 68.513502 -88.1922) (xy 68.493579 -88.140109) (xy 68.481453 -88.085672) (xy 68.477382 -88.03005)
			(xy 67.059048 -88.03005) (xy 67.059048 -89.230708) (xy 67.437508 -89.609168) (xy 67.464432 -89.603326)
			(xy 67.484136 -89.599394) (xy 67.524097 -89.595198) (xy 67.544188 -89.594944) (xy 67.571441 -89.595429)
			(xy 67.625393 -89.603184) (xy 67.677692 -89.618537) (xy 67.727273 -89.641177) (xy 67.773129 -89.670642)
			(xy 67.814324 -89.706333) (xy 67.850022 -89.747523) (xy 67.879494 -89.793374) (xy 67.902142 -89.842952)
			(xy 67.917503 -89.895249) (xy 67.925267 -89.949199) (xy 67.925696 -89.976452) (xy 67.92545 -89.996543)
			(xy 67.921246 -90.036504) (xy 67.917314 -90.056208) (xy 67.911472 -90.083132) (xy 68.858892 -91.030552)
			(xy 69.3039 -91.030552) (xy 69.340984 -91.032584) (xy 69.353176 -91.033854) (xy 69.379386 -91.037071)
			(xy 69.430531 -91.050214) (xy 69.479195 -91.070713) (xy 69.524329 -91.098125) (xy 69.544946 -91.114626)
			(xy 69.556884 -91.124532) (xy 69.581522 -91.146884) (xy 69.869558 -91.43492) (xy 70.29196 -91.43492)
		)
		(stroke
			(width 0)
			(type solid)
		)
		(fill yes)
		(layer "In7.Cu")
		(net "PGPPA_BMC_AUX_L")
	)
	(gr_poly
		(pts
			(xy 24.9174 -97.79) (xy 24.9174 -97.2312) (xy 24.777192 -97.090992) (xy 24.748236 -97.099628) (xy 24.725386 -97.105937)
			(xy 24.678466 -97.112692) (xy 24.654764 -97.11309) (xy 24.631226 -97.112675) (xy 24.584628 -97.105988)
			(xy 24.539455 -97.092741) (xy 24.517858 -97.083372) (xy 24.507698 -97.0788) (xy 24.384 -97.0788)
			(xy 24.27351 -96.96831) (xy 24.262874 -96.958335) (xy 24.237288 -96.944373) (xy 24.208803 -96.938198)
			(xy 24.179732 -96.940309) (xy 24.152438 -96.950537) (xy 24.129138 -96.96805) (xy 24.120094 -96.979486)
			(xy 24.104395 -96.999838) (xy 24.067759 -97.035885) (xy 24.025982 -97.065824) (xy 23.980073 -97.088932)
			(xy 23.93114 -97.104653) (xy 23.880362 -97.112606) (xy 23.854664 -97.11309) (xy 23.828679 -97.112578)
			(xy 23.77735 -97.104443) (xy 23.727926 -97.088378) (xy 23.681622 -97.06478) (xy 23.639581 -97.034229)
			(xy 23.602835 -96.997478) (xy 23.572292 -96.955432) (xy 23.548701 -96.909125) (xy 23.532645 -96.859697)
			(xy 23.524518 -96.808367) (xy 23.523956 -96.782382) (xy 23.524446 -96.756685) (xy 23.532405 -96.705911)
			(xy 23.54813 -96.656982) (xy 23.57124 -96.611077) (xy 23.601178 -96.569304) (xy 23.637224 -96.532669)
			(xy 23.65756 -96.516952) (xy 23.668964 -96.507871) (xy 23.686473 -96.484578) (xy 23.696702 -96.457293)
			(xy 23.698821 -96.42823) (xy 23.692658 -96.39975) (xy 23.678713 -96.374163) (xy 23.668736 -96.363536)
			(xy 23.47341 -96.16821) (xy 23.462774 -96.158235) (xy 23.437188 -96.144273) (xy 23.408703 -96.138098)
			(xy 23.379632 -96.140209) (xy 23.352338 -96.150437) (xy 23.329038 -96.16795) (xy 23.319994 -96.179386)
			(xy 23.304295 -96.199738) (xy 23.267659 -96.235785) (xy 23.225882 -96.265724) (xy 23.179973 -96.288832)
			(xy 23.13104 -96.304553) (xy 23.080262 -96.312506) (xy 23.054564 -96.31299) (xy 23.028579 -96.312478)
			(xy 22.97725 -96.304343) (xy 22.927826 -96.288278) (xy 22.881522 -96.26468) (xy 22.839481 -96.234129)
			(xy 22.802735 -96.197378) (xy 22.772192 -96.155332) (xy 22.748601 -96.109025) (xy 22.732545 -96.059597)
			(xy 22.724418 -96.008267) (xy 22.723856 -95.982282) (xy 22.724346 -95.956585) (xy 22.732305 -95.905811)
			(xy 22.74803 -95.856882) (xy 22.77114 -95.810977) (xy 22.801078 -95.769204) (xy 22.837124 -95.732569)
			(xy 22.85746 -95.716852) (xy 22.868864 -95.707771) (xy 22.886373 -95.684478) (xy 22.896602 -95.657193)
			(xy 22.898721 -95.62813) (xy 22.892558 -95.59965) (xy 22.878613 -95.574063) (xy 22.868636 -95.563436)
			(xy 22.733 -95.4278) (xy 22.733 -95.259652) (xy 22.73173 -95.254064) (xy 22.728045 -95.236322) (xy 22.724097 -95.200301)
			(xy 22.723856 -95.182182) (xy 22.724364 -95.16364) (xy 22.725634 -95.141034) (xy 22.4536 -94.869)
			(xy 21.8948 -94.869) (xy 21.336 -95.4278) (xy 21.336 -95.6818) (xy 21.009531 -96.008269) (xy 21.92452 -96.008269)
			(xy 21.92452 -95.956295) (xy 21.93265 -95.90496) (xy 21.948711 -95.85553) (xy 21.972307 -95.80922)
			(xy 22.002857 -95.767172) (xy 22.039608 -95.730421) (xy 22.081656 -95.699871) (xy 22.127966 -95.676275)
			(xy 22.177396 -95.660214) (xy 22.228731 -95.652084) (xy 22.280705 -95.652084) (xy 22.33204 -95.660214)
			(xy 22.38147 -95.676275) (xy 22.42778 -95.699871) (xy 22.469828 -95.730421) (xy 22.506579 -95.767172)
			(xy 22.537129 -95.80922) (xy 22.560725 -95.85553) (xy 22.576786 -95.90496) (xy 22.584916 -95.956295)
			(xy 22.585426 -95.982282) (xy 22.584916 -96.008269) (xy 22.576786 -96.059604) (xy 22.560725 -96.109034)
			(xy 22.537129 -96.155344) (xy 22.506579 -96.197392) (xy 22.469828 -96.234143) (xy 22.42778 -96.264693)
			(xy 22.38147 -96.288289) (xy 22.33204 -96.30435) (xy 22.280705 -96.31248) (xy 22.228731 -96.31248)
			(xy 22.177396 -96.30435) (xy 22.127966 -96.288289) (xy 22.081656 -96.264693) (xy 22.039608 -96.234143)
			(xy 22.002857 -96.197392) (xy 21.972307 -96.155344) (xy 21.948711 -96.109034) (xy 21.93265 -96.059604)
			(xy 21.92452 -96.008269) (xy 21.009531 -96.008269) (xy 20.992338 -96.025462) (xy 20.989544 -96.040956)
			(xy 20.984528 -96.066055) (xy 20.967788 -96.114422) (xy 20.943798 -96.159634) (xy 20.913131 -96.200611)
			(xy 20.876519 -96.236376) (xy 20.834835 -96.266076) (xy 20.789074 -96.289) (xy 20.740328 -96.304603)
			(xy 20.689761 -96.312512) (xy 20.66417 -96.31299) (xy 20.636933 -96.312434) (xy 20.583196 -96.303506)
			(xy 20.531646 -96.285898) (xy 20.483677 -96.260084) (xy 20.440584 -96.226762) (xy 20.40353 -96.186832)
			(xy 20.388072 -96.1644) (xy 20.140422 -96.1644) (xy 20.126187 -96.185129) (xy 20.092465 -96.22243)
			(xy 20.053485 -96.254196) (xy 20.010146 -96.279696) (xy 19.963447 -96.298341) (xy 19.914463 -96.309704)
			(xy 19.864324 -96.31352) (xy 19.814185 -96.309704) (xy 19.765201 -96.298341) (xy 19.718502 -96.279696)
			(xy 19.675163 -96.254196) (xy 19.636183 -96.22243) (xy 19.602461 -96.185129) (xy 19.588226 -96.1644)
			(xy 19.340322 -96.1644) (xy 19.324861 -96.18683) (xy 19.287818 -96.226769) (xy 19.244727 -96.260094)
			(xy 19.196756 -96.285902) (xy 19.145202 -96.303496) (xy 19.091461 -96.312399) (xy 19.064224 -96.31299)
			(xy 19.039606 -96.312538) (xy 18.990915 -96.305237) (xy 18.943845 -96.290794) (xy 18.899439 -96.269526)
			(xy 18.878804 -96.256094) (xy 18.867143 -96.248763) (xy 18.841041 -96.240002) (xy 18.813547 -96.238534)
			(xy 18.78666 -96.244466) (xy 18.762336 -96.257366) (xy 18.742342 -96.276296) (xy 18.728133 -96.299879)
			(xy 18.720742 -96.326402) (xy 18.720308 -96.340168) (xy 18.720308 -96.418146) (xy 18.720735 -96.431746)
			(xy 18.727912 -96.457983) (xy 18.741769 -96.481389) (xy 18.761322 -96.500298) (xy 18.785178 -96.513366)
			(xy 18.811639 -96.519662) (xy 18.838824 -96.518738) (xy 18.864797 -96.51066) (xy 18.876518 -96.503744)
			(xy 18.89655 -96.49142) (xy 18.939361 -96.471948) (xy 18.984501 -96.458742) (xy 19.031056 -96.45207)
			(xy 19.054572 -96.451674) (xy 19.080564 -96.452155) (xy 19.131909 -96.460283) (xy 19.18135 -96.476344)
			(xy 19.227669 -96.499941) (xy 19.269727 -96.530495) (xy 19.306487 -96.567252) (xy 19.337044 -96.609307)
			(xy 19.360645 -96.655624) (xy 19.37671 -96.705064) (xy 19.384843 -96.756408) (xy 19.384843 -96.808369)
			(xy 19.534126 -96.808369) (xy 19.534126 -96.756395) (xy 19.542256 -96.70506) (xy 19.558317 -96.65563)
			(xy 19.581913 -96.60932) (xy 19.612463 -96.567272) (xy 19.649214 -96.530521) (xy 19.691262 -96.499971)
			(xy 19.737572 -96.476375) (xy 19.787002 -96.460314) (xy 19.838337 -96.452184) (xy 19.890311 -96.452184)
			(xy 19.941646 -96.460314) (xy 19.991076 -96.476375) (xy 20.037386 -96.499971) (xy 20.079434 -96.530521)
			(xy 20.116185 -96.567272) (xy 20.146735 -96.60932) (xy 20.170331 -96.65563) (xy 20.186392 -96.70506)
			(xy 20.194522 -96.756395) (xy 20.195032 -96.782382) (xy 20.194522 -96.808369) (xy 20.333972 -96.808369)
			(xy 20.333972 -96.756395) (xy 20.342102 -96.70506) (xy 20.358163 -96.65563) (xy 20.381759 -96.60932)
			(xy 20.412309 -96.567272) (xy 20.44906 -96.530521) (xy 20.491108 -96.499971) (xy 20.537418 -96.476375)
			(xy 20.586848 -96.460314) (xy 20.638183 -96.452184) (xy 20.690157 -96.452184) (xy 20.741492 -96.460314)
			(xy 20.790922 -96.476375) (xy 20.837232 -96.499971) (xy 20.87928 -96.530521) (xy 20.916031 -96.567272)
			(xy 20.946581 -96.60932) (xy 20.970177 -96.65563) (xy 20.986238 -96.70506) (xy 20.994368 -96.756395)
			(xy 20.994878 -96.782382) (xy 20.994368 -96.808369) (xy 22.724366 -96.808369) (xy 22.724366 -96.756395)
			(xy 22.732496 -96.70506) (xy 22.748557 -96.65563) (xy 22.772153 -96.60932) (xy 22.802703 -96.567272)
			(xy 22.839454 -96.530521) (xy 22.881502 -96.499971) (xy 22.927812 -96.476375) (xy 22.977242 -96.460314)
			(xy 23.028577 -96.452184) (xy 23.080551 -96.452184) (xy 23.131886 -96.460314) (xy 23.181316 -96.476375)
			(xy 23.227626 -96.499971) (xy 23.269674 -96.530521) (xy 23.306425 -96.567272) (xy 23.336975 -96.60932)
			(xy 23.360571 -96.65563) (xy 23.376632 -96.70506) (xy 23.384762 -96.756395) (xy 23.385272 -96.782382)
			(xy 23.384762 -96.808369) (xy 23.376632 -96.859704) (xy 23.360571 -96.909134) (xy 23.336975 -96.955444)
			(xy 23.306425 -96.997492) (xy 23.269674 -97.034243) (xy 23.227626 -97.064793) (xy 23.181316 -97.088389)
			(xy 23.131886 -97.10445) (xy 23.080551 -97.11258) (xy 23.028577 -97.11258) (xy 22.977242 -97.10445)
			(xy 22.927812 -97.088389) (xy 22.881502 -97.064793) (xy 22.839454 -97.034243) (xy 22.802703 -96.997492)
			(xy 22.772153 -96.955444) (xy 22.748557 -96.909134) (xy 22.732496 -96.859704) (xy 22.724366 -96.808369)
			(xy 20.994368 -96.808369) (xy 20.986238 -96.859704) (xy 20.970177 -96.909134) (xy 20.946581 -96.955444)
			(xy 20.916031 -96.997492) (xy 20.87928 -97.034243) (xy 20.837232 -97.064793) (xy 20.790922 -97.088389)
			(xy 20.741492 -97.10445) (xy 20.690157 -97.11258) (xy 20.638183 -97.11258) (xy 20.586848 -97.10445)
			(xy 20.537418 -97.088389) (xy 20.491108 -97.064793) (xy 20.44906 -97.034243) (xy 20.412309 -96.997492)
			(xy 20.381759 -96.955444) (xy 20.358163 -96.909134) (xy 20.342102 -96.859704) (xy 20.333972 -96.808369)
			(xy 20.194522 -96.808369) (xy 20.186392 -96.859704) (xy 20.170331 -96.909134) (xy 20.146735 -96.955444)
			(xy 20.116185 -96.997492) (xy 20.079434 -97.034243) (xy 20.037386 -97.064793) (xy 19.991076 -97.088389)
			(xy 19.941646 -97.10445) (xy 19.890311 -97.11258) (xy 19.838337 -97.11258) (xy 19.787002 -97.10445)
			(xy 19.737572 -97.088389) (xy 19.691262 -97.064793) (xy 19.649214 -97.034243) (xy 19.612463 -96.997492)
			(xy 19.581913 -96.955444) (xy 19.558317 -96.909134) (xy 19.542256 -96.859704) (xy 19.534126 -96.808369)
			(xy 19.384843 -96.808369) (xy 19.384843 -96.808392) (xy 19.37671 -96.859736) (xy 19.360645 -96.909176)
			(xy 19.337044 -96.955493) (xy 19.306487 -96.997548) (xy 19.269727 -97.034305) (xy 19.227669 -97.064859)
			(xy 19.18135 -97.088456) (xy 19.131909 -97.104517) (xy 19.080564 -97.112645) (xy 19.054572 -97.11309)
			(xy 19.027517 -97.112555) (xy 18.974127 -97.103755) (xy 18.922883 -97.086377) (xy 18.875153 -97.060887)
			(xy 18.832211 -97.027963) (xy 18.795204 -96.988486) (xy 18.779744 -96.966278) (xy 18.770972 -96.954095)
			(xy 18.747786 -96.935048) (xy 18.720068 -96.923555) (xy 18.690207 -96.920606) (xy 18.660776 -96.926455)
			(xy 18.634312 -96.940598) (xy 18.62328 -96.950784) (xy 18.034508 -97.53981) (xy 18.034508 -97.608215)
			(xy 20.333972 -97.608215) (xy 20.333972 -97.556241) (xy 20.342102 -97.504906) (xy 20.358163 -97.455476)
			(xy 20.381759 -97.409166) (xy 20.412309 -97.367118) (xy 20.44906 -97.330367) (xy 20.491108 -97.299817)
			(xy 20.537418 -97.276221) (xy 20.586848 -97.26016) (xy 20.638183 -97.25203) (xy 20.690157 -97.25203)
			(xy 20.741492 -97.26016) (xy 20.790922 -97.276221) (xy 20.837232 -97.299817) (xy 20.87928 -97.330367)
			(xy 20.916031 -97.367118) (xy 20.946581 -97.409166) (xy 20.970177 -97.455476) (xy 20.986238 -97.504906)
			(xy 20.994368 -97.556241) (xy 20.994878 -97.582228) (xy 20.994368 -97.608215) (xy 21.92452 -97.608215)
			(xy 21.92452 -97.556241) (xy 21.93265 -97.504906) (xy 21.948711 -97.455476) (xy 21.972307 -97.409166)
			(xy 22.002857 -97.367118) (xy 22.039608 -97.330367) (xy 22.081656 -97.299817) (xy 22.127966 -97.276221)
			(xy 22.177396 -97.26016) (xy 22.228731 -97.25203) (xy 22.280705 -97.25203) (xy 22.33204 -97.26016)
			(xy 22.38147 -97.276221) (xy 22.42778 -97.299817) (xy 22.469828 -97.330367) (xy 22.506579 -97.367118)
			(xy 22.537129 -97.409166) (xy 22.560725 -97.455476) (xy 22.576786 -97.504906) (xy 22.584916 -97.556241)
			(xy 22.585426 -97.582228) (xy 22.584916 -97.608215) (xy 22.724366 -97.608215) (xy 22.724366 -97.556241)
			(xy 22.732496 -97.504906) (xy 22.748557 -97.455476) (xy 22.772153 -97.409166) (xy 22.802703 -97.367118)
			(xy 22.839454 -97.330367) (xy 22.881502 -97.299817) (xy 22.927812 -97.276221) (xy 22.977242 -97.26016)
			(xy 23.028577 -97.25203) (xy 23.080551 -97.25203) (xy 23.131886 -97.26016) (xy 23.181316 -97.276221)
			(xy 23.227626 -97.299817) (xy 23.269674 -97.330367) (xy 23.306425 -97.367118) (xy 23.336975 -97.409166)
			(xy 23.360571 -97.455476) (xy 23.376632 -97.504906) (xy 23.384762 -97.556241) (xy 23.385272 -97.582228)
			(xy 23.384762 -97.608215) (xy 23.524466 -97.608215) (xy 23.524466 -97.556241) (xy 23.532596 -97.504906)
			(xy 23.548657 -97.455476) (xy 23.572253 -97.409166) (xy 23.602803 -97.367118) (xy 23.639554 -97.330367)
			(xy 23.681602 -97.299817) (xy 23.727912 -97.276221) (xy 23.777342 -97.26016) (xy 23.828677 -97.25203)
			(xy 23.880651 -97.25203) (xy 23.931986 -97.26016) (xy 23.981416 -97.276221) (xy 24.027726 -97.299817)
			(xy 24.069774 -97.330367) (xy 24.106525 -97.367118) (xy 24.137075 -97.409166) (xy 24.160671 -97.455476)
			(xy 24.176732 -97.504906) (xy 24.184862 -97.556241) (xy 24.185372 -97.582228) (xy 24.184862 -97.608215)
			(xy 24.176732 -97.65955) (xy 24.160671 -97.70898) (xy 24.137075 -97.75529) (xy 24.106525 -97.797338)
			(xy 24.069774 -97.834089) (xy 24.027726 -97.864639) (xy 23.981416 -97.888235) (xy 23.931986 -97.904296)
			(xy 23.880651 -97.912426) (xy 23.828677 -97.912426) (xy 23.777342 -97.904296) (xy 23.727912 -97.888235)
			(xy 23.681602 -97.864639) (xy 23.639554 -97.834089) (xy 23.602803 -97.797338) (xy 23.572253 -97.75529)
			(xy 23.548657 -97.70898) (xy 23.532596 -97.65955) (xy 23.524466 -97.608215) (xy 23.384762 -97.608215)
			(xy 23.376632 -97.65955) (xy 23.360571 -97.70898) (xy 23.336975 -97.75529) (xy 23.306425 -97.797338)
			(xy 23.269674 -97.834089) (xy 23.227626 -97.864639) (xy 23.181316 -97.888235) (xy 23.131886 -97.904296)
			(xy 23.080551 -97.912426) (xy 23.028577 -97.912426) (xy 22.977242 -97.904296) (xy 22.927812 -97.888235)
			(xy 22.881502 -97.864639) (xy 22.839454 -97.834089) (xy 22.802703 -97.797338) (xy 22.772153 -97.75529)
			(xy 22.748557 -97.70898) (xy 22.732496 -97.65955) (xy 22.724366 -97.608215) (xy 22.584916 -97.608215)
			(xy 22.576786 -97.65955) (xy 22.560725 -97.70898) (xy 22.537129 -97.75529) (xy 22.506579 -97.797338)
			(xy 22.469828 -97.834089) (xy 22.42778 -97.864639) (xy 22.38147 -97.888235) (xy 22.33204 -97.904296)
			(xy 22.280705 -97.912426) (xy 22.228731 -97.912426) (xy 22.177396 -97.904296) (xy 22.127966 -97.888235)
			(xy 22.081656 -97.864639) (xy 22.039608 -97.834089) (xy 22.002857 -97.797338) (xy 21.972307 -97.75529)
			(xy 21.948711 -97.70898) (xy 21.93265 -97.65955) (xy 21.92452 -97.608215) (xy 20.994368 -97.608215)
			(xy 20.986238 -97.65955) (xy 20.970177 -97.70898) (xy 20.946581 -97.75529) (xy 20.916031 -97.797338)
			(xy 20.87928 -97.834089) (xy 20.837232 -97.864639) (xy 20.790922 -97.888235) (xy 20.741492 -97.904296)
			(xy 20.690157 -97.912426) (xy 20.638183 -97.912426) (xy 20.586848 -97.904296) (xy 20.537418 -97.888235)
			(xy 20.491108 -97.864639) (xy 20.44906 -97.834089) (xy 20.412309 -97.797338) (xy 20.381759 -97.75529)
			(xy 20.358163 -97.70898) (xy 20.342102 -97.65955) (xy 20.333972 -97.608215) (xy 18.034508 -97.608215)
			(xy 18.034508 -97.73539) (xy 18.19021 -97.891092) (xy 18.49501 -97.891092) (xy 18.622264 -98.0186)
			(xy 24.6888 -98.0186)
		)
		(stroke
			(width 0)
			(type solid)
		)
		(fill yes)
		(layer "In7.Cu")
		(net "VCCIO2")
	)
	(gr_poly
		(pts
			(xy 87.845392 -77.791564) (xy 87.845392 -57.31256) (xy 87.7316 -57.198514) (xy 80.46466 -57.198514)
			(xy 80.069944 -57.59323) (xy 80.069944 -60.634118) (xy 80.37068 -60.634118) (xy 80.37108 -60.607894)
			(xy 80.378287 -60.555942) (xy 80.392539 -60.505467) (xy 80.413569 -60.457419) (xy 80.440979 -60.412703)
			(xy 80.474255 -60.372161) (xy 80.512768 -60.336558) (xy 80.555794 -60.306564) (xy 80.57896 -60.294266)
			(xy 80.591225 -60.287503) (xy 80.611793 -60.268512) (xy 80.626431 -60.244647) (xy 80.634036 -60.217705)
			(xy 80.634038 -60.189709) (xy 80.626436 -60.162765) (xy 80.611802 -60.138899) (xy 80.591236 -60.119905)
			(xy 80.57896 -60.113164) (xy 80.555775 -60.100899) (xy 80.512738 -60.070913) (xy 80.474218 -60.035311)
			(xy 80.440941 -59.994765) (xy 80.413536 -59.950041) (xy 80.392519 -59.901983) (xy 80.378288 -59.851498)
			(xy 80.37111 -59.799539) (xy 80.37068 -59.773312) (xy 80.371166 -59.746061) (xy 80.378922 -59.692113)
			(xy 80.394277 -59.639818) (xy 80.416919 -59.590241) (xy 80.446385 -59.544391) (xy 80.482076 -59.5032)
			(xy 80.523267 -59.467509) (xy 80.569117 -59.438043) (xy 80.618694 -59.415401) (xy 80.670989 -59.400046)
			(xy 80.724937 -59.39229) (xy 80.779439 -59.39229) (xy 80.833387 -59.400046) (xy 80.885682 -59.415401)
			(xy 80.935259 -59.438043) (xy 80.981109 -59.467509) (xy 81.0223 -59.5032) (xy 81.057991 -59.544391)
			(xy 81.087457 -59.590241) (xy 81.110099 -59.639818) (xy 81.125454 -59.692113) (xy 81.13321 -59.746061)
			(xy 81.133696 -59.773312) (xy 81.133251 -59.799535) (xy 81.126054 -59.851485) (xy 81.111809 -59.90196)
			(xy 81.090787 -59.950008) (xy 81.063382 -59.994725) (xy 81.030112 -60.035267) (xy 80.991603 -60.070871)
			(xy 80.948581 -60.100866) (xy 80.925416 -60.113164) (xy 80.913166 -60.119914) (xy 80.892677 -60.138943)
			(xy 80.878104 -60.162807) (xy 80.870537 -60.189726) (xy 80.870538 -60.217688) (xy 80.87811 -60.244605)
			(xy 80.892686 -60.268468) (xy 80.913177 -60.287494) (xy 80.925416 -60.294266) (xy 80.948567 -60.306593)
			(xy 80.991603 -60.33657) (xy 81.030124 -60.372163) (xy 81.063404 -60.412699) (xy 81.090814 -60.457414)
			(xy 81.111836 -60.505464) (xy 81.126075 -60.555941) (xy 81.133261 -60.607894) (xy 81.133595 -60.628022)
			(xy 82.504534 -60.628022) (xy 82.504962 -60.601799) (xy 82.512167 -60.54985) (xy 82.526417 -60.499377)
			(xy 82.547444 -60.45133) (xy 82.57485 -60.406614) (xy 82.608121 -60.366072) (xy 82.646629 -60.330467)
			(xy 82.68965 -60.30047) (xy 82.712814 -60.28817) (xy 82.725079 -60.281404) (xy 82.745657 -60.262417)
			(xy 82.760301 -60.238553) (xy 82.767911 -60.211608) (xy 82.767913 -60.183609) (xy 82.760308 -60.156663)
			(xy 82.745668 -60.132796) (xy 82.725093 -60.113806) (xy 82.712814 -60.107068) (xy 82.68962 -60.09482)
			(xy 82.646585 -60.064829) (xy 82.608067 -60.029224) (xy 82.574792 -59.988676) (xy 82.547388 -59.943949)
			(xy 82.526373 -59.89589) (xy 82.512142 -59.845403) (xy 82.504965 -59.793443) (xy 82.504534 -59.767216)
			(xy 82.50502 -59.739965) (xy 82.512776 -59.686017) (xy 82.528131 -59.633722) (xy 82.550773 -59.584145)
			(xy 82.580239 -59.538295) (xy 82.61593 -59.497104) (xy 82.657121 -59.461413) (xy 82.702971 -59.431947)
			(xy 82.752548 -59.409305) (xy 82.804843 -59.39395) (xy 82.858791 -59.386194) (xy 82.913293 -59.386194)
			(xy 82.967241 -59.39395) (xy 83.019536 -59.409305) (xy 83.069113 -59.431947) (xy 83.114963 -59.461413)
			(xy 83.156154 -59.497104) (xy 83.191845 -59.538295) (xy 83.221311 -59.584145) (xy 83.243953 -59.633722)
			(xy 83.259308 -59.686017) (xy 83.267064 -59.739965) (xy 83.26755 -59.767216) (xy 83.267079 -59.793438)
			(xy 83.259882 -59.845385) (xy 83.24564 -59.895858) (xy 83.22462 -59.943905) (xy 83.197219 -59.988621)
			(xy 83.163953 -60.029164) (xy 83.125449 -60.06477) (xy 83.082432 -60.094768) (xy 83.05927 -60.107068)
			(xy 83.047011 -60.113808) (xy 83.026511 -60.132834) (xy 83.01193 -60.156701) (xy 83.004358 -60.183625)
			(xy 83.00436 -60.211593) (xy 83.011937 -60.238515) (xy 83.026522 -60.262379) (xy 83.047025 -60.281402)
			(xy 83.05927 -60.28817) (xy 83.082435 -60.300471) (xy 83.125469 -60.330454) (xy 83.163988 -60.366052)
			(xy 83.197265 -60.406592) (xy 83.224673 -60.45131) (xy 83.245694 -60.499363) (xy 83.259931 -60.549843)
			(xy 83.267115 -60.601797) (xy 83.267449 -60.621926) (xy 84.638388 -60.621926) (xy 84.63879 -60.595702)
			(xy 84.645996 -60.54375) (xy 84.660248 -60.493275) (xy 84.681277 -60.445227) (xy 84.708687 -60.40051)
			(xy 84.741963 -60.359969) (xy 84.780476 -60.324366) (xy 84.823502 -60.294371) (xy 84.846668 -60.282074)
			(xy 84.858925 -60.275299) (xy 84.879491 -60.256309) (xy 84.894127 -60.232447) (xy 84.901733 -60.205507)
			(xy 84.901735 -60.177514) (xy 84.894136 -60.150572) (xy 84.879505 -60.126708) (xy 84.858942 -60.107713)
			(xy 84.846668 -60.100972) (xy 84.823488 -60.088698) (xy 84.780451 -60.058713) (xy 84.741931 -60.023113)
			(xy 84.708653 -59.982569) (xy 84.681247 -59.937846) (xy 84.66023 -59.889789) (xy 84.645997 -59.839305)
			(xy 84.638819 -59.787346) (xy 84.638388 -59.76112) (xy 84.638874 -59.733868) (xy 84.646628 -59.679918)
			(xy 84.661981 -59.627621) (xy 84.684621 -59.578041) (xy 84.714087 -59.532188) (xy 84.749778 -59.490995)
			(xy 84.790969 -59.455301) (xy 84.83682 -59.425833) (xy 84.886398 -59.40319) (xy 84.938694 -59.387833)
			(xy 84.992644 -59.380076) (xy 85.019896 -59.379612) (xy 85.047125 -59.38008) (xy 85.10103 -59.387823)
			(xy 85.153286 -59.403153) (xy 85.20283 -59.425758) (xy 85.248657 -59.455179) (xy 85.289835 -59.490817)
			(xy 85.325526 -59.531948) (xy 85.355006 -59.577737) (xy 85.377675 -59.627253) (xy 85.393072 -59.679489)
			(xy 85.400885 -59.733384) (xy 85.401404 -59.760612) (xy 85.401897 -59.775375) (xy 85.410315 -59.803675)
			(xy 85.426476 -59.828386) (xy 85.449028 -59.847443) (xy 85.476088 -59.859255) (xy 85.505395 -59.862835)
			(xy 85.534503 -59.857885) (xy 85.547962 -59.851798) (xy 85.57433 -59.839393) (xy 85.629893 -59.821844)
			(xy 85.687483 -59.812975) (xy 85.716618 -59.812428) (xy 85.743871 -59.812843) (xy 85.797822 -59.820602)
			(xy 85.850119 -59.835961) (xy 85.899699 -59.858605) (xy 85.945551 -59.888074) (xy 85.986743 -59.923769)
			(xy 86.022436 -59.964963) (xy 86.051904 -60.010817) (xy 86.074546 -60.060398) (xy 86.089901 -60.112696)
			(xy 86.097658 -60.166647) (xy 86.097658 -60.221153) (xy 86.089901 -60.275104) (xy 86.074546 -60.327402)
			(xy 86.051904 -60.376983) (xy 86.022436 -60.422837) (xy 85.986743 -60.464031) (xy 85.945551 -60.499726)
			(xy 85.899699 -60.529195) (xy 85.850119 -60.551839) (xy 85.797822 -60.567198) (xy 85.743871 -60.574957)
			(xy 85.716618 -60.575444) (xy 85.687487 -60.574862) (xy 85.629906 -60.565971) (xy 85.574338 -60.548454)
			(xy 85.547962 -60.536074) (xy 85.534604 -60.529994) (xy 85.505684 -60.525054) (xy 85.47655 -60.528527)
			(xy 85.449602 -60.540128) (xy 85.427056 -60.558902) (xy 85.410767 -60.583305) (xy 85.402076 -60.611328)
			(xy 85.401404 -60.62599) (xy 85.400649 -60.653051) (xy 85.392423 -60.706558) (xy 85.376716 -60.758364)
			(xy 85.353844 -60.80743) (xy 85.324267 -60.852771) (xy 85.288577 -60.893475) (xy 85.247492 -60.928726)
			(xy 85.201836 -60.957816) (xy 85.152527 -60.98016) (xy 85.100555 -60.99531) (xy 85.046964 -61.002962)
			(xy 85.019896 -61.003434) (xy 84.992646 -61.002926) (xy 84.9387 -60.99517) (xy 84.886408 -60.979815)
			(xy 84.836832 -60.957176) (xy 84.790983 -60.927711) (xy 84.749793 -60.892022) (xy 84.714102 -60.850835)
			(xy 84.684635 -60.804987) (xy 84.661992 -60.755413) (xy 84.646635 -60.703121) (xy 84.638876 -60.649176)
			(xy 84.638388 -60.621926) (xy 83.267449 -60.621926) (xy 83.26755 -60.628022) (xy 83.267064 -60.655273)
			(xy 83.259308 -60.709221) (xy 83.243953 -60.761516) (xy 83.221311 -60.811093) (xy 83.191845 -60.856943)
			(xy 83.156154 -60.898134) (xy 83.114963 -60.933825) (xy 83.069113 -60.963291) (xy 83.019536 -60.985933)
			(xy 82.967241 -61.001288) (xy 82.913293 -61.009044) (xy 82.858791 -61.009044) (xy 82.804843 -61.001288)
			(xy 82.752548 -60.985933) (xy 82.702971 -60.963291) (xy 82.657121 -60.933825) (xy 82.61593 -60.898134)
			(xy 82.580239 -60.856943) (xy 82.550773 -60.811093) (xy 82.528131 -60.761516) (xy 82.512776 -60.709221)
			(xy 82.50502 -60.655273) (xy 82.504534 -60.628022) (xy 81.133595 -60.628022) (xy 81.133696 -60.634118)
			(xy 81.13321 -60.661369) (xy 81.125454 -60.715317) (xy 81.110099 -60.767612) (xy 81.087457 -60.817189)
			(xy 81.057991 -60.863039) (xy 81.0223 -60.90423) (xy 80.981109 -60.939921) (xy 80.935259 -60.969387)
			(xy 80.885682 -60.992029) (xy 80.833387 -61.007384) (xy 80.779439 -61.01514) (xy 80.724937 -61.01514)
			(xy 80.670989 -61.007384) (xy 80.618694 -60.992029) (xy 80.569117 -60.969387) (xy 80.523267 -60.939921)
			(xy 80.482076 -60.90423) (xy 80.446385 -60.863039) (xy 80.416919 -60.817189) (xy 80.394277 -60.767612)
			(xy 80.378922 -60.715317) (xy 80.371166 -60.661369) (xy 80.37068 -60.634118) (xy 80.069944 -60.634118)
			(xy 80.069944 -61.772546) (xy 79.591662 -62.250828) (xy 79.591662 -70.858888) (xy 82.71713 -70.858888)
			(xy 82.721201 -70.803266) (xy 82.733327 -70.748829) (xy 82.75325 -70.696738) (xy 82.780546 -70.648103)
			(xy 82.814632 -70.60396) (xy 82.854781 -70.565251) (xy 82.900139 -70.5328) (xy 82.949739 -70.507299)
			(xy 83.002523 -70.489292) (xy 83.057366 -70.479162) (xy 83.1131 -70.477125) (xy 83.168537 -70.483225)
			(xy 83.222494 -70.497331) (xy 83.273823 -70.519143) (xy 83.321429 -70.548197) (xy 83.364297 -70.583872)
			(xy 83.401514 -70.625409) (xy 83.432287 -70.671922) (xy 83.455959 -70.722419) (xy 83.472027 -70.775826)
			(xy 83.480147 -70.831002) (xy 83.480656 -70.858888) (xy 86.13343 -70.858888) (xy 86.137501 -70.803266)
			(xy 86.149627 -70.748829) (xy 86.16955 -70.696738) (xy 86.196846 -70.648103) (xy 86.230932 -70.60396)
			(xy 86.271081 -70.565251) (xy 86.316439 -70.5328) (xy 86.366039 -70.507299) (xy 86.418823 -70.489292)
			(xy 86.473666 -70.479162) (xy 86.5294 -70.477125) (xy 86.584837 -70.483225) (xy 86.638794 -70.497331)
			(xy 86.690123 -70.519143) (xy 86.737729 -70.548197) (xy 86.780597 -70.583872) (xy 86.817814 -70.625409)
			(xy 86.848587 -70.671922) (xy 86.872259 -70.722419) (xy 86.888327 -70.775826) (xy 86.896447 -70.831002)
			(xy 86.896956 -70.858888) (xy 86.896447 -70.886774) (xy 86.888327 -70.94195) (xy 86.872259 -70.995357)
			(xy 86.848587 -71.045854) (xy 86.817814 -71.092367) (xy 86.780597 -71.133904) (xy 86.737729 -71.169579)
			(xy 86.690123 -71.198633) (xy 86.638794 -71.220445) (xy 86.584837 -71.234551) (xy 86.5294 -71.240651)
			(xy 86.473666 -71.238614) (xy 86.418823 -71.228484) (xy 86.366039 -71.210477) (xy 86.316439 -71.184976)
			(xy 86.271081 -71.152525) (xy 86.230932 -71.113816) (xy 86.196846 -71.069673) (xy 86.16955 -71.021038)
			(xy 86.149627 -70.968947) (xy 86.137501 -70.91451) (xy 86.13343 -70.858888) (xy 83.480656 -70.858888)
			(xy 83.480147 -70.886774) (xy 83.472027 -70.94195) (xy 83.455959 -70.995357) (xy 83.432287 -71.045854)
			(xy 83.401514 -71.092367) (xy 83.364297 -71.133904) (xy 83.321429 -71.169579) (xy 83.273823 -71.198633)
			(xy 83.222494 -71.220445) (xy 83.168537 -71.234551) (xy 83.1131 -71.240651) (xy 83.057366 -71.238614)
			(xy 83.002523 -71.228484) (xy 82.949739 -71.210477) (xy 82.900139 -71.184976) (xy 82.854781 -71.152525)
			(xy 82.814632 -71.113816) (xy 82.780546 -71.069673) (xy 82.75325 -71.021038) (xy 82.733327 -70.968947)
			(xy 82.721201 -70.91451) (xy 82.71713 -70.858888) (xy 79.591662 -70.858888) (xy 79.591662 -71.390256)
			(xy 79.609823 -71.409743) (xy 79.64112 -71.452847) (xy 79.666117 -71.499885) (xy 79.684328 -71.549942)
			(xy 79.695399 -71.602047) (xy 79.699115 -71.655184) (xy 79.695403 -71.708322) (xy 79.684337 -71.760427)
			(xy 79.66613 -71.810486) (xy 79.641136 -71.857526) (xy 79.609843 -71.900632) (xy 79.591662 -71.9201)
			(xy 79.591662 -71.933308) (xy 85.079076 -71.933308) (xy 85.083147 -71.877686) (xy 85.095273 -71.823249)
			(xy 85.115196 -71.771158) (xy 85.142492 -71.722523) (xy 85.176578 -71.67838) (xy 85.216727 -71.639671)
			(xy 85.262085 -71.60722) (xy 85.311685 -71.581719) (xy 85.364469 -71.563712) (xy 85.419312 -71.553582)
			(xy 85.475046 -71.551545) (xy 85.530483 -71.557645) (xy 85.58444 -71.571751) (xy 85.635769 -71.593563)
			(xy 85.683375 -71.622617) (xy 85.726243 -71.658292) (xy 85.76346 -71.699829) (xy 85.794233 -71.746342)
			(xy 85.817905 -71.796839) (xy 85.833973 -71.850246) (xy 85.842093 -71.905422) (xy 85.842602 -71.933308)
			(xy 85.842093 -71.961194) (xy 85.833973 -72.01637) (xy 85.817905 -72.069777) (xy 85.794233 -72.120274)
			(xy 85.76346 -72.166787) (xy 85.726243 -72.208324) (xy 85.683375 -72.243999) (xy 85.635769 -72.273053)
			(xy 85.58444 -72.294865) (xy 85.530483 -72.308971) (xy 85.475046 -72.315071) (xy 85.419312 -72.313034)
			(xy 85.364469 -72.302904) (xy 85.311685 -72.284897) (xy 85.262085 -72.259396) (xy 85.216727 -72.226945)
			(xy 85.176578 -72.188236) (xy 85.142492 -72.144093) (xy 85.115196 -72.095458) (xy 85.095273 -72.043367)
			(xy 85.083147 -71.98893) (xy 85.079076 -71.933308) (xy 79.591662 -71.933308) (xy 79.591662 -73.04786)
			(xy 79.60744 -73.071795) (xy 79.632406 -73.1234) (xy 79.649369 -73.17816) (xy 79.657946 -73.234842)
			(xy 79.657946 -73.292168) (xy 79.649367 -73.34885) (xy 79.632403 -73.403609) (xy 79.607435 -73.455213)
			(xy 79.591662 -73.479152) (xy 79.591662 -74.19848) (xy 79.611622 -74.218226) (xy 79.646112 -74.26253)
			(xy 79.673742 -74.311407) (xy 79.693914 -74.363804) (xy 79.706196 -74.418591) (xy 79.706447 -74.422)
			(xy 85.901782 -74.422) (xy 85.905853 -74.366378) (xy 85.917979 -74.311941) (xy 85.937902 -74.25985)
			(xy 85.965198 -74.211215) (xy 85.999284 -74.167072) (xy 86.039433 -74.128363) (xy 86.084791 -74.095912)
			(xy 86.134391 -74.070411) (xy 86.187175 -74.052404) (xy 86.242018 -74.042274) (xy 86.297752 -74.040237)
			(xy 86.353189 -74.046337) (xy 86.407146 -74.060443) (xy 86.458475 -74.082255) (xy 86.506081 -74.111309)
			(xy 86.548949 -74.146984) (xy 86.586166 -74.188521) (xy 86.616939 -74.235034) (xy 86.640611 -74.285531)
			(xy 86.656679 -74.338938) (xy 86.664799 -74.394114) (xy 86.665308 -74.422) (xy 86.664799 -74.449886)
			(xy 86.656679 -74.505062) (xy 86.640611 -74.558469) (xy 86.616939 -74.608966) (xy 86.586166 -74.655479)
			(xy 86.548949 -74.697016) (xy 86.506081 -74.732691) (xy 86.458475 -74.761745) (xy 86.407146 -74.783557)
			(xy 86.353189 -74.797663) (xy 86.297752 -74.803763) (xy 86.242018 -74.801726) (xy 86.187175 -74.791596)
			(xy 86.134391 -74.773589) (xy 86.084791 -74.748088) (xy 86.039433 -74.715637) (xy 85.999284 -74.676928)
			(xy 85.965198 -74.632785) (xy 85.937902 -74.58415) (xy 85.917979 -74.532059) (xy 85.905853 -74.477622)
			(xy 85.901782 -74.422) (xy 79.706447 -74.422) (xy 79.710321 -74.474585) (xy 79.7062 -74.530579) (xy 79.693923 -74.585367)
			(xy 79.673755 -74.637765) (xy 79.646129 -74.686645) (xy 79.611643 -74.730951) (xy 79.591662 -74.750676)
			(xy 79.591662 -78.78064) (xy 79.94523 -79.134208) (xy 86.503002 -79.134208)
		)
		(stroke
			(width 0)
			(type solid)
		)
		(fill yes)
		(layer "In7.Cu")
		(net "GND")
	)
	(gr_poly
		(pts
			(xy 61.809122 -48.401732) (xy 61.823182 -48.380022) (xy 61.85696 -48.340854) (xy 61.89642 -48.307418)
			(xy 61.940602 -48.280528) (xy 61.988429 -48.260839) (xy 62.038737 -48.24883) (xy 62.0903 -48.244795)
			(xy 62.141863 -48.24883) (xy 62.192171 -48.260839) (xy 62.239998 -48.280528) (xy 62.28418 -48.307418)
			(xy 62.32364 -48.340854) (xy 62.357418 -48.380022) (xy 62.371478 -48.401732) (xy 62.608968 -48.401732)
			(xy 62.623028 -48.380022) (xy 62.656806 -48.340854) (xy 62.696266 -48.307418) (xy 62.740448 -48.280528)
			(xy 62.788275 -48.260839) (xy 62.838583 -48.24883) (xy 62.890146 -48.244795) (xy 62.941709 -48.24883)
			(xy 62.992017 -48.260839) (xy 63.039844 -48.280528) (xy 63.084026 -48.307418) (xy 63.123486 -48.340854)
			(xy 63.157264 -48.380022) (xy 63.171324 -48.401732) (xy 63.409068 -48.401732) (xy 63.422093 -48.381552)
			(xy 63.453047 -48.344829) (xy 63.488983 -48.312963) (xy 63.529146 -48.286624) (xy 63.572693 -48.266364)
			(xy 63.61871 -48.252609) (xy 63.666232 -48.245647) (xy 63.690246 -48.245268) (xy 63.716612 -48.245778)
			(xy 63.768677 -48.254142) (xy 63.818753 -48.270666) (xy 63.86557 -48.294931) (xy 63.907941 -48.326322)
			(xy 63.92672 -48.344836) (xy 66.504058 -45.767498) (xy 66.510632 -45.760386) (xy 66.518339 -45.742637)
			(xy 66.518903 -45.723294) (xy 66.512244 -45.705126) (xy 66.50609 -45.697648) (xy 66.489109 -45.677945)
			(xy 66.460447 -45.634543) (xy 66.438399 -45.587435) (xy 66.423431 -45.537623) (xy 66.415863 -45.486164)
			(xy 66.415412 -45.460158) (xy 66.415849 -45.43469) (xy 66.423111 -45.384274) (xy 66.43748 -45.335406)
			(xy 66.458664 -45.289084) (xy 66.486231 -45.246251) (xy 66.519618 -45.207783) (xy 66.558144 -45.174462)
			(xy 66.601024 -45.146969) (xy 66.647383 -45.125865) (xy 66.671698 -45.118274) (xy 66.686485 -45.113376)
			(xy 66.712356 -45.096053) (xy 66.7318 -45.071737) (xy 66.743009 -45.04269) (xy 66.744939 -45.011616)
			(xy 66.741802 -44.996354) (xy 66.73664 -44.973849) (xy 66.731164 -44.928001) (xy 66.73088 -44.904914)
			(xy 66.731365 -44.877657) (xy 66.739118 -44.823696) (xy 66.75447 -44.771388) (xy 66.777108 -44.721795)
			(xy 66.80657 -44.675928) (xy 66.842258 -44.634718) (xy 66.883447 -44.599006) (xy 66.929297 -44.569516)
			(xy 66.978876 -44.546849) (xy 67.031175 -44.531467) (xy 67.085131 -44.523681) (xy 67.112388 -44.523152)
			(xy 67.74815 -44.523152) (xy 69.920104 -42.351452) (xy 69.920104 -41.76522) (xy 69.762116 -41.607232)
			(xy 69.733414 -41.615614) (xy 69.707732 -41.622449) (xy 69.655086 -41.629712) (xy 69.628512 -41.630092)
			(xy 67.401948 -41.630092) (xy 67.26682 -41.765474) (xy 67.247378 -41.78423) (xy 67.204156 -41.816634)
			(xy 67.156798 -41.842624) (xy 67.131692 -41.852596) (xy 67.121532 -41.856406) (xy 65.550542 -43.427396)
			(xy 65.54026 -43.438426) (xy 65.526068 -43.465013) (xy 65.520251 -43.494585) (xy 65.523316 -43.524567)
			(xy 65.534996 -43.55235) (xy 65.544192 -43.564302) (xy 65.562122 -43.58679) (xy 65.590743 -43.636669)
			(xy 65.610319 -43.690743) (xy 65.620262 -43.747384) (xy 65.6209 -43.776138) (xy 65.620407 -43.801885)
			(xy 65.612422 -43.852756) (xy 65.59665 -43.901775) (xy 65.573474 -43.947759) (xy 65.543452 -43.989595)
			(xy 65.50731 -44.026275) (xy 65.46592 -44.05691) (xy 65.420284 -44.080763) (xy 65.371503 -44.097256)
			(xy 65.320755 -44.10599) (xy 65.295018 -44.106846) (xy 65.281857 -44.107493) (xy 65.256516 -44.114684)
			(xy 65.233862 -44.128124) (xy 65.215404 -44.146916) (xy 65.202374 -44.169809) (xy 65.19564 -44.195275)
			(xy 65.195196 -44.208446) (xy 65.195196 -44.721272) (xy 65.194748 -44.745465) (xy 65.187182 -44.793256)
			(xy 65.172231 -44.839275) (xy 65.150264 -44.882387) (xy 65.121822 -44.921532) (xy 65.105026 -44.93895)
			(xy 64.866774 -45.177202) (xy 64.84928 -45.194018) (xy 64.809982 -45.22248) (xy 64.788542 -45.233844)
			(xy 64.798705 -45.256165) (xy 64.813062 -45.30306) (xy 64.820329 -45.351562) (xy 64.8208 -45.376084)
			(xy 64.82029 -45.402071) (xy 64.81216 -45.453406) (xy 64.796099 -45.502836) (xy 64.772503 -45.549146)
			(xy 64.741953 -45.591194) (xy 64.705202 -45.627945) (xy 64.663154 -45.658495) (xy 64.616844 -45.682091)
			(xy 64.567414 -45.698152) (xy 64.516079 -45.706282) (xy 64.464105 -45.706282) (xy 64.41277 -45.698152)
			(xy 64.36334 -45.682091) (xy 64.31703 -45.658495) (xy 64.274982 -45.627945) (xy 64.238231 -45.591194)
			(xy 64.207681 -45.549146) (xy 64.184085 -45.502836) (xy 64.168024 -45.453406) (xy 64.159894 -45.402071)
			(xy 64.159384 -45.376084) (xy 64.159463 -45.365833) (xy 64.160734 -45.345372) (xy 64.161924 -45.33519)
			(xy 64.162432 -45.332142) (xy 64.162432 -45.27804) (xy 64.017906 -45.27804) (xy 64.017906 -45.332142)
			(xy 64.018414 -45.33519) (xy 64.019604 -45.345372) (xy 64.020875 -45.365833) (xy 64.020954 -45.376084)
			(xy 64.020446 -45.402073) (xy 64.012317 -45.453412) (xy 63.996258 -45.502848) (xy 63.972664 -45.549163)
			(xy 63.942115 -45.591217) (xy 63.905364 -45.627975) (xy 63.863316 -45.658532) (xy 63.817005 -45.682135)
			(xy 63.767573 -45.698203) (xy 63.716235 -45.706341) (xy 63.690246 -45.706792) (xy 63.662138 -45.706213)
			(xy 63.606724 -45.696758) (xy 63.58001 -45.687996) (xy 63.567845 -45.714854) (xy 63.534849 -45.763709)
			(xy 63.514478 -45.785024) (xy 63.507737 -45.792395) (xy 63.500008 -45.810792) (xy 63.499877 -45.830747)
			(xy 63.507364 -45.849244) (xy 63.521338 -45.863488) (xy 63.539688 -45.871329) (xy 63.559641 -45.871581)
			(xy 63.569088 -45.868336) (xy 63.598221 -45.857593) (xy 63.659204 -45.845951) (xy 63.690246 -45.845222)
			(xy 63.716229 -45.845735) (xy 63.767556 -45.853871) (xy 63.816977 -45.869936) (xy 63.863278 -45.893534)
			(xy 63.905317 -45.924084) (xy 63.942059 -45.960834) (xy 63.972601 -46.002879) (xy 63.99619 -46.049184)
			(xy 64.012244 -46.098609) (xy 64.02037 -46.149937) (xy 64.020367 -46.201904) (xy 64.012235 -46.253231)
			(xy 63.996174 -46.302654) (xy 63.972579 -46.348956) (xy 63.942032 -46.390997) (xy 63.905285 -46.427743)
			(xy 63.863242 -46.458288) (xy 63.816939 -46.48188) (xy 63.767515 -46.497939) (xy 63.716188 -46.506068)
			(xy 63.664221 -46.506069) (xy 63.612894 -46.497941) (xy 63.563469 -46.481883) (xy 63.517166 -46.458293)
			(xy 63.475122 -46.427749) (xy 63.438374 -46.391005) (xy 63.407826 -46.348964) (xy 63.38423 -46.302663)
			(xy 63.368167 -46.25324) (xy 63.360034 -46.201914) (xy 63.359538 -46.17593) (xy 63.360262 -46.144887)
			(xy 63.371891 -46.083899) (xy 63.382652 -46.054772) (xy 63.394844 -46.023784) (xy 63.335154 -45.964348)
			(xy 63.289688 -46.010068) (xy 63.270564 -46.028347) (xy 63.22727 -46.058742) (xy 63.203582 -46.07052)
			(xy 63.211637 -46.096125) (xy 63.22031 -46.149093) (xy 63.220854 -46.17593) (xy 63.220342 -46.201917)
			(xy 63.212208 -46.253251) (xy 63.196145 -46.30268) (xy 63.172548 -46.348989) (xy 63.141999 -46.391037)
			(xy 63.105249 -46.427789) (xy 63.063202 -46.45834) (xy 63.016895 -46.481939) (xy 62.967466 -46.498005)
			(xy 62.916133 -46.506141) (xy 62.890146 -46.506638) (xy 62.866744 -46.506219) (xy 62.820411 -46.499587)
			(xy 62.775479 -46.486477) (xy 62.754002 -46.477174) (xy 62.743181 -46.49628) (xy 62.716915 -46.531467)
			(xy 62.701678 -46.547278) (xy 62.455806 -46.79315) (xy 62.441427 -46.807042) (xy 62.4097 -46.831371)
			(xy 62.39256 -46.841664) (xy 62.401546 -46.862913) (xy 62.414216 -46.907273) (xy 62.420611 -46.952963)
			(xy 62.421008 -46.97603) (xy 62.420498 -47.002017) (xy 62.559948 -47.002017) (xy 62.559948 -46.950043)
			(xy 62.568078 -46.898708) (xy 62.584139 -46.849278) (xy 62.607735 -46.802968) (xy 62.638285 -46.76092)
			(xy 62.675036 -46.724169) (xy 62.717084 -46.693619) (xy 62.763394 -46.670023) (xy 62.812824 -46.653962)
			(xy 62.864159 -46.645832) (xy 62.916133 -46.645832) (xy 62.967468 -46.653962) (xy 63.016898 -46.670023)
			(xy 63.063208 -46.693619) (xy 63.105256 -46.724169) (xy 63.142007 -46.76092) (xy 63.172557 -46.802968)
			(xy 63.196153 -46.849278) (xy 63.212214 -46.898708) (xy 63.220344 -46.950043) (xy 63.220854 -46.97603)
			(xy 63.220344 -47.002017) (xy 63.360048 -47.002017) (xy 63.360048 -46.950043) (xy 63.368178 -46.898708)
			(xy 63.384239 -46.849278) (xy 63.407835 -46.802968) (xy 63.438385 -46.76092) (xy 63.475136 -46.724169)
			(xy 63.517184 -46.693619) (xy 63.563494 -46.670023) (xy 63.612924 -46.653962) (xy 63.664259 -46.645832)
			(xy 63.716233 -46.645832) (xy 63.767568 -46.653962) (xy 63.816998 -46.670023) (xy 63.863308 -46.693619)
			(xy 63.905356 -46.724169) (xy 63.942107 -46.76092) (xy 63.972657 -46.802968) (xy 63.996253 -46.849278)
			(xy 64.012314 -46.898708) (xy 64.020444 -46.950043) (xy 64.020954 -46.97603) (xy 64.020444 -47.002017)
			(xy 64.159894 -47.002017) (xy 64.159894 -46.950043) (xy 64.168024 -46.898708) (xy 64.184085 -46.849278)
			(xy 64.207681 -46.802968) (xy 64.238231 -46.76092) (xy 64.274982 -46.724169) (xy 64.31703 -46.693619)
			(xy 64.36334 -46.670023) (xy 64.41277 -46.653962) (xy 64.464105 -46.645832) (xy 64.516079 -46.645832)
			(xy 64.567414 -46.653962) (xy 64.616844 -46.670023) (xy 64.663154 -46.693619) (xy 64.705202 -46.724169)
			(xy 64.741953 -46.76092) (xy 64.772503 -46.802968) (xy 64.796099 -46.849278) (xy 64.81216 -46.898708)
			(xy 64.82029 -46.950043) (xy 64.8208 -46.97603) (xy 64.82029 -47.002017) (xy 64.81216 -47.053352)
			(xy 64.796099 -47.102782) (xy 64.772503 -47.149092) (xy 64.741953 -47.19114) (xy 64.705202 -47.227891)
			(xy 64.663154 -47.258441) (xy 64.616844 -47.282037) (xy 64.567414 -47.298098) (xy 64.516079 -47.306228)
			(xy 64.464105 -47.306228) (xy 64.41277 -47.298098) (xy 64.36334 -47.282037) (xy 64.31703 -47.258441)
			(xy 64.274982 -47.227891) (xy 64.238231 -47.19114) (xy 64.207681 -47.149092) (xy 64.184085 -47.102782)
			(xy 64.168024 -47.053352) (xy 64.159894 -47.002017) (xy 64.020444 -47.002017) (xy 64.012314 -47.053352)
			(xy 63.996253 -47.102782) (xy 63.972657 -47.149092) (xy 63.942107 -47.19114) (xy 63.905356 -47.227891)
			(xy 63.863308 -47.258441) (xy 63.816998 -47.282037) (xy 63.767568 -47.298098) (xy 63.716233 -47.306228)
			(xy 63.664259 -47.306228) (xy 63.612924 -47.298098) (xy 63.563494 -47.282037) (xy 63.517184 -47.258441)
			(xy 63.475136 -47.227891) (xy 63.438385 -47.19114) (xy 63.407835 -47.149092) (xy 63.384239 -47.102782)
			(xy 63.368178 -47.053352) (xy 63.360048 -47.002017) (xy 63.220344 -47.002017) (xy 63.212214 -47.053352)
			(xy 63.196153 -47.102782) (xy 63.172557 -47.149092) (xy 63.142007 -47.19114) (xy 63.105256 -47.227891)
			(xy 63.063208 -47.258441) (xy 63.016898 -47.282037) (xy 62.967468 -47.298098) (xy 62.916133 -47.306228)
			(xy 62.864159 -47.306228) (xy 62.812824 -47.298098) (xy 62.763394 -47.282037) (xy 62.717084 -47.258441)
			(xy 62.675036 -47.227891) (xy 62.638285 -47.19114) (xy 62.607735 -47.149092) (xy 62.584139 -47.102782)
			(xy 62.568078 -47.053352) (xy 62.559948 -47.002017) (xy 62.420498 -47.002017) (xy 62.412368 -47.053352)
			(xy 62.396307 -47.102782) (xy 62.372711 -47.149092) (xy 62.342161 -47.19114) (xy 62.30541 -47.227891)
			(xy 62.263362 -47.258441) (xy 62.217052 -47.282037) (xy 62.167622 -47.298098) (xy 62.116287 -47.306228)
			(xy 62.064313 -47.306228) (xy 62.012978 -47.298098) (xy 61.963548 -47.282037) (xy 61.917238 -47.258441)
			(xy 61.87519 -47.227891) (xy 61.838439 -47.19114) (xy 61.807889 -47.149092) (xy 61.784293 -47.102782)
			(xy 61.768232 -47.053352) (xy 61.760102 -47.002017) (xy 61.759592 -46.97603) (xy 61.76137 -46.940724)
			(xy 61.761878 -46.938184) (xy 61.761878 -46.88459) (xy 61.618622 -46.88459) (xy 61.618622 -46.938184)
			(xy 61.61913 -46.940724) (xy 61.620908 -46.97603) (xy 61.620396 -47.002016) (xy 61.612262 -47.053346)
			(xy 61.596198 -47.102773) (xy 61.572601 -47.149078) (xy 61.542051 -47.191122) (xy 61.5053 -47.22787)
			(xy 61.463253 -47.258417) (xy 61.416945 -47.28201) (xy 61.367517 -47.298069) (xy 61.316186 -47.306199)
			(xy 61.2902 -47.306738) (xy 61.264353 -47.306231) (xy 61.213292 -47.298171) (xy 61.164108 -47.282262)
			(xy 61.117998 -47.258893) (xy 61.076087 -47.228632) (xy 61.039396 -47.192218) (xy 61.008819 -47.150537)
			(xy 60.985102 -47.104606) (xy 60.968821 -47.055543) (xy 60.964064 -47.030132) (xy 60.96127 -47.01413)
			(xy 60.913772 -46.966632) (xy 60.80633 -47.074074) (xy 60.80633 -47.783242) (xy 60.808616 -47.785528)
			(xy 60.808616 -47.802117) (xy 61.760102 -47.802117) (xy 61.760102 -47.750143) (xy 61.768232 -47.698808)
			(xy 61.784293 -47.649378) (xy 61.807889 -47.603068) (xy 61.838439 -47.56102) (xy 61.87519 -47.524269)
			(xy 61.917238 -47.493719) (xy 61.963548 -47.470123) (xy 62.012978 -47.454062) (xy 62.064313 -47.445932)
			(xy 62.116287 -47.445932) (xy 62.167622 -47.454062) (xy 62.217052 -47.470123) (xy 62.263362 -47.493719)
			(xy 62.30541 -47.524269) (xy 62.342161 -47.56102) (xy 62.372711 -47.603068) (xy 62.396307 -47.649378)
			(xy 62.412368 -47.698808) (xy 62.420498 -47.750143) (xy 62.421008 -47.77613) (xy 62.420498 -47.802117)
			(xy 62.559948 -47.802117) (xy 62.559948 -47.750143) (xy 62.568078 -47.698808) (xy 62.584139 -47.649378)
			(xy 62.607735 -47.603068) (xy 62.638285 -47.56102) (xy 62.675036 -47.524269) (xy 62.717084 -47.493719)
			(xy 62.763394 -47.470123) (xy 62.812824 -47.454062) (xy 62.864159 -47.445932) (xy 62.916133 -47.445932)
			(xy 62.967468 -47.454062) (xy 63.016898 -47.470123) (xy 63.063208 -47.493719) (xy 63.105256 -47.524269)
			(xy 63.142007 -47.56102) (xy 63.172557 -47.603068) (xy 63.196153 -47.649378) (xy 63.212214 -47.698808)
			(xy 63.220344 -47.750143) (xy 63.220854 -47.77613) (xy 63.220344 -47.802117) (xy 63.360048 -47.802117)
			(xy 63.360048 -47.750143) (xy 63.368178 -47.698808) (xy 63.384239 -47.649378) (xy 63.407835 -47.603068)
			(xy 63.438385 -47.56102) (xy 63.475136 -47.524269) (xy 63.517184 -47.493719) (xy 63.563494 -47.470123)
			(xy 63.612924 -47.454062) (xy 63.664259 -47.445932) (xy 63.716233 -47.445932) (xy 63.767568 -47.454062)
			(xy 63.816998 -47.470123) (xy 63.863308 -47.493719) (xy 63.905356 -47.524269) (xy 63.942107 -47.56102)
			(xy 63.972657 -47.603068) (xy 63.996253 -47.649378) (xy 64.012314 -47.698808) (xy 64.020444 -47.750143)
			(xy 64.020954 -47.77613) (xy 64.020444 -47.802117) (xy 64.012314 -47.853452) (xy 63.996253 -47.902882)
			(xy 63.972657 -47.949192) (xy 63.942107 -47.99124) (xy 63.905356 -48.027991) (xy 63.863308 -48.058541)
			(xy 63.816998 -48.082137) (xy 63.767568 -48.098198) (xy 63.716233 -48.106328) (xy 63.664259 -48.106328)
			(xy 63.612924 -48.098198) (xy 63.563494 -48.082137) (xy 63.517184 -48.058541) (xy 63.475136 -48.027991)
			(xy 63.438385 -47.99124) (xy 63.407835 -47.949192) (xy 63.384239 -47.902882) (xy 63.368178 -47.853452)
			(xy 63.360048 -47.802117) (xy 63.220344 -47.802117) (xy 63.212214 -47.853452) (xy 63.196153 -47.902882)
			(xy 63.172557 -47.949192) (xy 63.142007 -47.99124) (xy 63.105256 -48.027991) (xy 63.063208 -48.058541)
			(xy 63.016898 -48.082137) (xy 62.967468 -48.098198) (xy 62.916133 -48.106328) (xy 62.864159 -48.106328)
			(xy 62.812824 -48.098198) (xy 62.763394 -48.082137) (xy 62.717084 -48.058541) (xy 62.675036 -48.027991)
			(xy 62.638285 -47.99124) (xy 62.607735 -47.949192) (xy 62.584139 -47.902882) (xy 62.568078 -47.853452)
			(xy 62.559948 -47.802117) (xy 62.420498 -47.802117) (xy 62.412368 -47.853452) (xy 62.396307 -47.902882)
			(xy 62.372711 -47.949192) (xy 62.342161 -47.99124) (xy 62.30541 -48.027991) (xy 62.263362 -48.058541)
			(xy 62.217052 -48.082137) (xy 62.167622 -48.098198) (xy 62.116287 -48.106328) (xy 62.064313 -48.106328)
			(xy 62.012978 -48.098198) (xy 61.963548 -48.082137) (xy 61.917238 -48.058541) (xy 61.87519 -48.027991)
			(xy 61.838439 -47.99124) (xy 61.807889 -47.949192) (xy 61.784293 -47.902882) (xy 61.768232 -47.853452)
			(xy 61.760102 -47.802117) (xy 60.808616 -47.802117) (xy 60.808616 -48.08982) (xy 61.058552 -48.339756)
			(xy 61.077231 -48.322142) (xy 61.119018 -48.292316) (xy 61.164909 -48.269302) (xy 61.213805 -48.253651)
			(xy 61.26453 -48.245738) (xy 61.2902 -48.245268) (xy 61.314213 -48.245697) (xy 61.361734 -48.252641)
			(xy 61.407752 -48.266384) (xy 61.451299 -48.286635) (xy 61.491461 -48.312971) (xy 61.527392 -48.344837)
			(xy 61.558338 -48.381563) (xy 61.571378 -48.401732)
		)
		(stroke
			(width 0)
			(type solid)
		)
		(fill yes)
		(layer "In7.Cu")
		(net "P1V2_STBY_MVDD_CK")
	)
	(gr_poly
		(pts
			(xy 49.7586 -54.02072) (xy 49.7586 -52.047648) (xy 49.356772 -51.64582) (xy 49.356772 -50.162968)
			(xy 49.271428 -50.077624) (xy 48.93183 -50.077624) (xy 48.916118 -50.078215) (xy 48.886182 -50.087774)
			(xy 48.860559 -50.105967) (xy 48.841667 -50.131079) (xy 48.831288 -50.160741) (xy 48.83023 -50.17643)
			(xy 48.828987 -50.201887) (xy 48.819646 -50.251991) (xy 48.802731 -50.300069) (xy 48.778641 -50.344983)
			(xy 48.747946 -50.38567) (xy 48.711375 -50.421168) (xy 48.669791 -50.450637) (xy 48.624179 -50.473378)
			(xy 48.575619 -50.488854) (xy 48.525259 -50.496698) (xy 48.499776 -50.497232) (xy 48.473789 -50.496721)
			(xy 48.422456 -50.488587) (xy 48.373027 -50.472524) (xy 48.32672 -50.448928) (xy 48.284673 -50.418378)
			(xy 48.247922 -50.381627) (xy 48.217372 -50.33958) (xy 48.193776 -50.293273) (xy 48.177713 -50.243844)
			(xy 48.169579 -50.192511) (xy 48.169068 -50.166524) (xy 48.170592 -50.133504) (xy 48.170846 -50.130964)
			(xy 48.170846 -50.077624) (xy 48.028606 -50.077624) (xy 48.028606 -50.130964) (xy 48.02886 -50.133504)
			(xy 48.030384 -50.166524) (xy 48.029874 -50.192511) (xy 48.021744 -50.243846) (xy 48.005683 -50.293276)
			(xy 47.982087 -50.339586) (xy 47.951537 -50.381634) (xy 47.914786 -50.418385) (xy 47.872738 -50.448935)
			(xy 47.826428 -50.472531) (xy 47.776998 -50.488592) (xy 47.725663 -50.496722) (xy 47.673689 -50.496722)
			(xy 47.622354 -50.488592) (xy 47.572924 -50.472531) (xy 47.526614 -50.448935) (xy 47.484566 -50.418385)
			(xy 47.447815 -50.381634) (xy 47.417265 -50.339586) (xy 47.393669 -50.293276) (xy 47.377608 -50.243846)
			(xy 47.369478 -50.192511) (xy 47.368968 -50.166524) (xy 47.370492 -50.133504) (xy 47.370746 -50.130964)
			(xy 47.370746 -50.077624) (xy 47.22876 -50.077624) (xy 47.22876 -50.130964) (xy 47.229014 -50.133504)
			(xy 47.230538 -50.166524) (xy 47.230028 -50.192511) (xy 47.221898 -50.243846) (xy 47.205837 -50.293276)
			(xy 47.182241 -50.339586) (xy 47.151691 -50.381634) (xy 47.11494 -50.418385) (xy 47.072892 -50.448935)
			(xy 47.026582 -50.472531) (xy 46.977152 -50.488592) (xy 46.925817 -50.496722) (xy 46.873843 -50.496722)
			(xy 46.822508 -50.488592) (xy 46.773078 -50.472531) (xy 46.726768 -50.448935) (xy 46.68472 -50.418385)
			(xy 46.647969 -50.381634) (xy 46.617419 -50.339586) (xy 46.593823 -50.293276) (xy 46.577762 -50.243846)
			(xy 46.569632 -50.192511) (xy 46.569122 -50.166524) (xy 46.570646 -50.133504) (xy 46.5709 -50.130964)
			(xy 46.5709 -50.077624) (xy 46.42866 -50.077624) (xy 46.42866 -50.130964) (xy 46.428914 -50.133504)
			(xy 46.430438 -50.166524) (xy 46.429927 -50.192511) (xy 46.421793 -50.243844) (xy 46.405731 -50.293273)
			(xy 46.382134 -50.339582) (xy 46.351584 -50.381629) (xy 46.314834 -50.41838) (xy 46.272787 -50.448931)
			(xy 46.226479 -50.472528) (xy 46.17705 -50.488592) (xy 46.125717 -50.496726) (xy 46.09973 -50.497232)
			(xy 46.073322 -50.496717) (xy 46.021177 -50.48832) (xy 45.971032 -50.471735) (xy 45.924163 -50.447384)
			(xy 45.881765 -50.415889) (xy 45.844917 -50.378049) (xy 45.814557 -50.33483) (xy 45.80255 -50.311304)
			(xy 45.79606 -50.299068) (xy 45.777678 -50.278365) (xy 45.754411 -50.263359) (xy 45.727969 -50.255154)
			(xy 45.700294 -50.254351) (xy 45.673421 -50.261012) (xy 45.649324 -50.274645) (xy 45.639228 -50.284126)
			(xy 45.578268 -50.345086) (xy 45.565115 -50.364832) (xy 45.534054 -50.400693) (xy 45.498187 -50.431748)
			(xy 45.478446 -50.444908) (xy 45.417486 -50.505868) (xy 45.408037 -50.515981) (xy 45.394448 -50.540079)
			(xy 45.387815 -50.566937) (xy 45.388624 -50.59459) (xy 45.396816 -50.621015) (xy 45.411791 -50.644277)
			(xy 45.432453 -50.662674) (xy 45.444664 -50.66919) (xy 45.468185 -50.681206) (xy 45.511402 -50.711567)
			(xy 45.54924 -50.748415) (xy 45.580736 -50.790812) (xy 45.60509 -50.837677) (xy 45.621679 -50.88782)
			(xy 45.630084 -50.939962) (xy 45.630592 -50.96637) (xy 45.630111 -50.992357) (xy 45.769532 -50.992357)
			(xy 45.769532 -50.940383) (xy 45.777662 -50.889048) (xy 45.793723 -50.839618) (xy 45.817319 -50.793308)
			(xy 45.847869 -50.75126) (xy 45.88462 -50.714509) (xy 45.926668 -50.683959) (xy 45.972978 -50.660363)
			(xy 46.022408 -50.644302) (xy 46.073743 -50.636172) (xy 46.125717 -50.636172) (xy 46.177052 -50.644302)
			(xy 46.226482 -50.660363) (xy 46.272792 -50.683959) (xy 46.31484 -50.714509) (xy 46.351591 -50.75126)
			(xy 46.382141 -50.793308) (xy 46.405737 -50.839618) (xy 46.421798 -50.889048) (xy 46.429928 -50.940383)
			(xy 46.430438 -50.96637) (xy 46.429928 -50.992357) (xy 46.569632 -50.992357) (xy 46.569632 -50.940383)
			(xy 46.577762 -50.889048) (xy 46.593823 -50.839618) (xy 46.617419 -50.793308) (xy 46.647969 -50.75126)
			(xy 46.68472 -50.714509) (xy 46.726768 -50.683959) (xy 46.773078 -50.660363) (xy 46.822508 -50.644302)
			(xy 46.873843 -50.636172) (xy 46.925817 -50.636172) (xy 46.977152 -50.644302) (xy 47.026582 -50.660363)
			(xy 47.072892 -50.683959) (xy 47.11494 -50.714509) (xy 47.151691 -50.75126) (xy 47.182241 -50.793308)
			(xy 47.205837 -50.839618) (xy 47.221898 -50.889048) (xy 47.230028 -50.940383) (xy 47.230538 -50.96637)
			(xy 47.230028 -50.992357) (xy 47.369478 -50.992357) (xy 47.369478 -50.940383) (xy 47.377608 -50.889048)
			(xy 47.393669 -50.839618) (xy 47.417265 -50.793308) (xy 47.447815 -50.75126) (xy 47.484566 -50.714509)
			(xy 47.526614 -50.683959) (xy 47.572924 -50.660363) (xy 47.622354 -50.644302) (xy 47.673689 -50.636172)
			(xy 47.725663 -50.636172) (xy 47.776998 -50.644302) (xy 47.826428 -50.660363) (xy 47.872738 -50.683959)
			(xy 47.914786 -50.714509) (xy 47.951537 -50.75126) (xy 47.982087 -50.793308) (xy 48.005683 -50.839618)
			(xy 48.021744 -50.889048) (xy 48.029874 -50.940383) (xy 48.030384 -50.96637) (xy 48.029874 -50.992357)
			(xy 48.169578 -50.992357) (xy 48.169578 -50.940383) (xy 48.177708 -50.889048) (xy 48.193769 -50.839618)
			(xy 48.217365 -50.793308) (xy 48.247915 -50.75126) (xy 48.284666 -50.714509) (xy 48.326714 -50.683959)
			(xy 48.373024 -50.660363) (xy 48.422454 -50.644302) (xy 48.473789 -50.636172) (xy 48.525763 -50.636172)
			(xy 48.577098 -50.644302) (xy 48.626528 -50.660363) (xy 48.672838 -50.683959) (xy 48.714886 -50.714509)
			(xy 48.751637 -50.75126) (xy 48.782187 -50.793308) (xy 48.805783 -50.839618) (xy 48.821844 -50.889048)
			(xy 48.829974 -50.940383) (xy 48.830484 -50.96637) (xy 48.829974 -50.992357) (xy 48.821844 -51.043692)
			(xy 48.805783 -51.093122) (xy 48.782187 -51.139432) (xy 48.751637 -51.18148) (xy 48.714886 -51.218231)
			(xy 48.672838 -51.248781) (xy 48.626528 -51.272377) (xy 48.577098 -51.288438) (xy 48.525763 -51.296568)
			(xy 48.473789 -51.296568) (xy 48.422454 -51.288438) (xy 48.373024 -51.272377) (xy 48.326714 -51.248781)
			(xy 48.284666 -51.218231) (xy 48.247915 -51.18148) (xy 48.217365 -51.139432) (xy 48.193769 -51.093122)
			(xy 48.177708 -51.043692) (xy 48.169578 -50.992357) (xy 48.029874 -50.992357) (xy 48.021744 -51.043692)
			(xy 48.005683 -51.093122) (xy 47.982087 -51.139432) (xy 47.951537 -51.18148) (xy 47.914786 -51.218231)
			(xy 47.872738 -51.248781) (xy 47.826428 -51.272377) (xy 47.776998 -51.288438) (xy 47.725663 -51.296568)
			(xy 47.673689 -51.296568) (xy 47.622354 -51.288438) (xy 47.572924 -51.272377) (xy 47.526614 -51.248781)
			(xy 47.484566 -51.218231) (xy 47.447815 -51.18148) (xy 47.417265 -51.139432) (xy 47.393669 -51.093122)
			(xy 47.377608 -51.043692) (xy 47.369478 -50.992357) (xy 47.230028 -50.992357) (xy 47.221898 -51.043692)
			(xy 47.205837 -51.093122) (xy 47.182241 -51.139432) (xy 47.151691 -51.18148) (xy 47.11494 -51.218231)
			(xy 47.072892 -51.248781) (xy 47.026582 -51.272377) (xy 46.977152 -51.288438) (xy 46.925817 -51.296568)
			(xy 46.873843 -51.296568) (xy 46.822508 -51.288438) (xy 46.773078 -51.272377) (xy 46.726768 -51.248781)
			(xy 46.68472 -51.218231) (xy 46.647969 -51.18148) (xy 46.617419 -51.139432) (xy 46.593823 -51.093122)
			(xy 46.577762 -51.043692) (xy 46.569632 -50.992357) (xy 46.429928 -50.992357) (xy 46.421798 -51.043692)
			(xy 46.405737 -51.093122) (xy 46.382141 -51.139432) (xy 46.351591 -51.18148) (xy 46.31484 -51.218231)
			(xy 46.272792 -51.248781) (xy 46.226482 -51.272377) (xy 46.177052 -51.288438) (xy 46.125717 -51.296568)
			(xy 46.073743 -51.296568) (xy 46.022408 -51.288438) (xy 45.972978 -51.272377) (xy 45.926668 -51.248781)
			(xy 45.88462 -51.218231) (xy 45.847869 -51.18148) (xy 45.817319 -51.139432) (xy 45.793723 -51.093122)
			(xy 45.777662 -51.043692) (xy 45.769532 -50.992357) (xy 45.630111 -50.992357) (xy 45.630111 -50.99236)
			(xy 45.621983 -51.043702) (xy 45.605924 -51.093139) (xy 45.582327 -51.139455) (xy 45.551775 -51.18151)
			(xy 45.51502 -51.218266) (xy 45.472967 -51.24882) (xy 45.426652 -51.272418) (xy 45.377215 -51.28848)
			(xy 45.325874 -51.29661) (xy 45.299884 -51.297078) (xy 45.272788 -51.296534) (xy 45.21932 -51.287698)
			(xy 45.168009 -51.270264) (xy 45.120225 -51.2447) (xy 45.077247 -51.211688) (xy 45.040226 -51.172112)
			(xy 45.01015 -51.127031) (xy 44.987826 -51.077651) (xy 44.973849 -51.025292) (xy 44.9707 -50.998374)
			(xy 44.966382 -50.9524) (xy 44.833286 -50.9524) (xy 44.828968 -50.998374) (xy 44.825807 -51.025293)
			(xy 44.811842 -51.07766) (xy 44.789526 -51.127049) (xy 44.759455 -51.172138) (xy 44.722435 -51.211721)
			(xy 44.679457 -51.244738) (xy 44.63167 -51.270306) (xy 44.580354 -51.287741) (xy 44.526882 -51.296575)
			(xy 44.499784 -51.297078) (xy 44.474387 -51.296613) (xy 44.424191 -51.288846) (xy 44.375772 -51.273497)
			(xy 44.330268 -51.250926) (xy 44.28875 -51.221664) (xy 44.252193 -51.186399) (xy 44.221457 -51.145961)
			(xy 44.208954 -51.12385) (xy 44.202128 -51.1122) (xy 44.183452 -51.092711) (xy 44.160322 -51.078797)
			(xy 44.134355 -51.071427) (xy 44.107364 -51.071118) (xy 44.081235 -51.07789) (xy 44.057793 -51.091272)
			(xy 44.047918 -51.100482) (xy 43.53306 -51.61534) (xy 43.53306 -51.792457) (xy 44.169586 -51.792457)
			(xy 44.169586 -51.740483) (xy 44.177716 -51.689148) (xy 44.193777 -51.639718) (xy 44.217373 -51.593408)
			(xy 44.247923 -51.55136) (xy 44.284674 -51.514609) (xy 44.326722 -51.484059) (xy 44.373032 -51.460463)
			(xy 44.422462 -51.444402) (xy 44.473797 -51.436272) (xy 44.525771 -51.436272) (xy 44.577106 -51.444402)
			(xy 44.626536 -51.460463) (xy 44.672846 -51.484059) (xy 44.714894 -51.514609) (xy 44.751645 -51.55136)
			(xy 44.782195 -51.593408) (xy 44.805791 -51.639718) (xy 44.821852 -51.689148) (xy 44.829982 -51.740483)
			(xy 44.830492 -51.76647) (xy 44.829982 -51.792457) (xy 44.969686 -51.792457) (xy 44.969686 -51.740483)
			(xy 44.977816 -51.689148) (xy 44.993877 -51.639718) (xy 45.017473 -51.593408) (xy 45.048023 -51.55136)
			(xy 45.084774 -51.514609) (xy 45.126822 -51.484059) (xy 45.173132 -51.460463) (xy 45.222562 -51.444402)
			(xy 45.273897 -51.436272) (xy 45.325871 -51.436272) (xy 45.377206 -51.444402) (xy 45.426636 -51.460463)
			(xy 45.472946 -51.484059) (xy 45.514994 -51.514609) (xy 45.551745 -51.55136) (xy 45.582295 -51.593408)
			(xy 45.605891 -51.639718) (xy 45.621952 -51.689148) (xy 45.630082 -51.740483) (xy 45.630592 -51.76647)
			(xy 45.630082 -51.792457) (xy 45.621952 -51.843792) (xy 45.605891 -51.893222) (xy 45.582295 -51.939532)
			(xy 45.551745 -51.98158) (xy 45.514994 -52.018331) (xy 45.472946 -52.048881) (xy 45.426636 -52.072477)
			(xy 45.377206 -52.088538) (xy 45.325871 -52.096668) (xy 45.273897 -52.096668) (xy 45.222562 -52.088538)
			(xy 45.173132 -52.072477) (xy 45.126822 -52.048881) (xy 45.084774 -52.018331) (xy 45.048023 -51.98158)
			(xy 45.017473 -51.939532) (xy 44.993877 -51.893222) (xy 44.977816 -51.843792) (xy 44.969686 -51.792457)
			(xy 44.829982 -51.792457) (xy 44.821852 -51.843792) (xy 44.805791 -51.893222) (xy 44.782195 -51.939532)
			(xy 44.751645 -51.98158) (xy 44.714894 -52.018331) (xy 44.672846 -52.048881) (xy 44.626536 -52.072477)
			(xy 44.577106 -52.088538) (xy 44.525771 -52.096668) (xy 44.473797 -52.096668) (xy 44.422462 -52.088538)
			(xy 44.373032 -52.072477) (xy 44.326722 -52.048881) (xy 44.284674 -52.018331) (xy 44.247923 -51.98158)
			(xy 44.217373 -51.939532) (xy 44.193777 -51.893222) (xy 44.177716 -51.843792) (xy 44.169586 -51.792457)
			(xy 43.53306 -51.792457) (xy 43.53306 -52.592557) (xy 44.169586 -52.592557) (xy 44.169586 -52.540583)
			(xy 44.177716 -52.489248) (xy 44.193777 -52.439818) (xy 44.217373 -52.393508) (xy 44.247923 -52.35146)
			(xy 44.284674 -52.314709) (xy 44.326722 -52.284159) (xy 44.373032 -52.260563) (xy 44.422462 -52.244502)
			(xy 44.473797 -52.236372) (xy 44.525771 -52.236372) (xy 44.577106 -52.244502) (xy 44.626536 -52.260563)
			(xy 44.672846 -52.284159) (xy 44.714894 -52.314709) (xy 44.751645 -52.35146) (xy 44.782195 -52.393508)
			(xy 44.805791 -52.439818) (xy 44.821852 -52.489248) (xy 44.829982 -52.540583) (xy 44.830492 -52.56657)
			(xy 44.829982 -52.592557) (xy 44.821852 -52.643892) (xy 44.805791 -52.693322) (xy 44.782195 -52.739632)
			(xy 44.751645 -52.78168) (xy 44.714894 -52.818431) (xy 44.672846 -52.848981) (xy 44.626536 -52.872577)
			(xy 44.577106 -52.888638) (xy 44.525771 -52.896768) (xy 44.473797 -52.896768) (xy 44.422462 -52.888638)
			(xy 44.373032 -52.872577) (xy 44.326722 -52.848981) (xy 44.284674 -52.818431) (xy 44.247923 -52.78168)
			(xy 44.217373 -52.739632) (xy 44.193777 -52.693322) (xy 44.177716 -52.643892) (xy 44.169586 -52.592557)
			(xy 43.53306 -52.592557) (xy 43.53306 -53.10886) (xy 43.7388 -53.3146) (xy 44.170854 -53.3146) (xy 44.181268 -53.277516)
			(xy 44.188991 -53.251788) (xy 44.211601 -53.203063) (xy 44.241787 -53.158632) (xy 44.278758 -53.119664)
			(xy 44.32154 -53.087184) (xy 44.36901 -53.062045) (xy 44.419918 -53.044908) (xy 44.472926 -53.036225)
			(xy 44.499784 -53.035708) (xy 44.524213 -53.036127) (xy 44.572545 -53.043264) (xy 44.59605 -53.049932)
			(xy 44.62526 -53.058822) (xy 44.99229 -52.691792) (xy 44.9834 -52.662836) (xy 44.976725 -52.639332)
			(xy 44.96958 -52.591) (xy 44.969176 -52.56657) (xy 44.969688 -52.540584) (xy 44.977822 -52.489252)
			(xy 44.993885 -52.439825) (xy 45.017483 -52.393518) (xy 45.048033 -52.351473) (xy 45.084783 -52.314723)
			(xy 45.12683 -52.284175) (xy 45.173137 -52.26058) (xy 45.222566 -52.244519) (xy 45.273898 -52.236387)
			(xy 45.299884 -52.235862) (xy 45.324313 -52.236281) (xy 45.372645 -52.24342) (xy 45.39615 -52.250086)
			(xy 45.425106 -52.258976) (xy 45.792136 -51.891946) (xy 45.783246 -51.862736) (xy 45.77657 -51.839233)
			(xy 45.769425 -51.7909) (xy 45.769022 -51.76647) (xy 45.769534 -51.740485) (xy 45.777668 -51.689156)
			(xy 45.793732 -51.639732) (xy 45.81733 -51.593428) (xy 45.847881 -51.551387) (xy 45.884632 -51.514642)
			(xy 45.92668 -51.484099) (xy 45.972987 -51.460509) (xy 46.022415 -51.444454) (xy 46.073745 -51.436329)
			(xy 46.09973 -51.435762) (xy 46.124487 -51.436219) (xy 46.173449 -51.443588) (xy 46.220766 -51.458171)
			(xy 46.265381 -51.479643) (xy 46.306297 -51.507525) (xy 46.342602 -51.541193) (xy 46.373483 -51.579896)
			(xy 46.386242 -51.601116) (xy 46.613318 -51.601116) (xy 46.627123 -51.578303) (xy 46.660861 -51.537016)
			(xy 46.700783 -51.501672) (xy 46.745856 -51.473187) (xy 46.794912 -51.452297) (xy 46.846684 -51.439543)
			(xy 46.89983 -51.435254) (xy 46.952976 -51.439543) (xy 47.004748 -51.452297) (xy 47.053804 -51.473187)
			(xy 47.098877 -51.501672) (xy 47.138799 -51.537016) (xy 47.172537 -51.578303) (xy 47.186342 -51.601116)
			(xy 47.465488 -51.601116) (xy 47.467774 -51.603402) (xy 47.655988 -51.603402) (xy 48.058324 -52.005484)
			(xy 48.08982 -52.005484) (xy 48.103602 -52.005063) (xy 48.130178 -51.997754) (xy 48.153825 -51.983595)
			(xy 48.172815 -51.963618) (xy 48.185761 -51.939286) (xy 48.191717 -51.912375) (xy 48.190247 -51.884852)
			(xy 48.18634 -51.871626) (xy 48.178296 -51.846084) (xy 48.169615 -51.793243) (xy 48.169068 -51.76647)
			(xy 48.169578 -51.740483) (xy 48.177708 -51.689148) (xy 48.193769 -51.639718) (xy 48.217365 -51.593408)
			(xy 48.247915 -51.55136) (xy 48.284666 -51.514609) (xy 48.326714 -51.484059) (xy 48.373024 -51.460463)
			(xy 48.422454 -51.444402) (xy 48.473789 -51.436272) (xy 48.525763 -51.436272) (xy 48.577098 -51.444402)
			(xy 48.626528 -51.460463) (xy 48.672838 -51.484059) (xy 48.714886 -51.514609) (xy 48.751637 -51.55136)
			(xy 48.782187 -51.593408) (xy 48.805783 -51.639718) (xy 48.821844 -51.689148) (xy 48.829974 -51.740483)
			(xy 48.830484 -51.76647) (xy 48.830105 -51.7898) (xy 48.823585 -51.836001) (xy 48.810627 -51.880825)
			(xy 48.79149 -51.923379) (xy 48.766554 -51.962816) (xy 48.751744 -51.980846) (xy 48.742296 -51.992737)
			(xy 48.730206 -52.020579) (xy 48.726852 -52.050747) (xy 48.732531 -52.080565) (xy 48.746739 -52.107389)
			(xy 48.757078 -52.118514) (xy 48.964088 -52.32527) (xy 48.964088 -53.62067) (xy 48.69307 -53.891688)
			(xy 48.394112 -53.891688) (xy 48.26 -54.0258) (xy 48.26 -54.281578) (xy 48.318166 -54.339744) (xy 49.439576 -54.339744)
		)
		(stroke
			(width 0)
			(type solid)
		)
		(fill yes)
		(layer "In7.Cu")
		(net "P3V3_STBY_DACAV33")
	)
	(gr_poly
		(pts
			(xy 62.21984 -75.908662) (xy 62.236355 -75.8854) (xy 62.275169 -75.843592) (xy 62.319778 -75.808033)
			(xy 62.369187 -75.779518) (xy 62.422294 -75.758682) (xy 62.477912 -75.745992) (xy 62.5348 -75.74173)
			(xy 62.591688 -75.745992) (xy 62.647306 -75.758682) (xy 62.700413 -75.779518) (xy 62.749822 -75.808033)
			(xy 62.794431 -75.843592) (xy 62.833245 -75.8854) (xy 62.84976 -75.908662) (xy 63.07455 -75.908662)
			(xy 63.400432 -75.58278) (xy 63.400432 -74.567288) (xy 62.528704 -73.69556) (xy 62.528704 -72.227948)
			(xy 61.527944 -71.227188) (xy 61.506455 -71.247387) (xy 61.458409 -71.281586) (xy 61.405674 -71.307984)
			(xy 61.349504 -71.325954) (xy 61.291239 -71.335067) (xy 61.261752 -71.335646) (xy 61.234502 -71.335157)
			(xy 61.180557 -71.327395) (xy 61.128266 -71.312036) (xy 61.078693 -71.289393) (xy 61.032846 -71.259926)
			(xy 60.991658 -71.224235) (xy 60.955968 -71.183046) (xy 60.926502 -71.137199) (xy 60.90386 -71.087624)
			(xy 60.888503 -71.035333) (xy 60.880742 -70.981388) (xy 60.880244 -70.954138) (xy 60.880648 -70.92908)
			(xy 60.887218 -70.879397) (xy 60.900224 -70.830998) (xy 60.919444 -70.784714) (xy 60.944547 -70.741338)
			(xy 60.959492 -70.72122) (xy 60.98667 -70.685914) (xy 59.456066 -69.15531) (xy 59.446001 -69.145868)
			(xy 59.422003 -69.132265) (xy 59.395239 -69.12558) (xy 59.367663 -69.126303) (xy 59.341286 -69.134379)
			(xy 59.318032 -69.14922) (xy 59.299599 -69.169743) (xy 59.287331 -69.19445) (xy 59.282123 -69.22154)
			(xy 59.282838 -69.23532) (xy 59.284108 -69.2658) (xy 59.283622 -69.293051) (xy 59.275866 -69.346999)
			(xy 59.260511 -69.399294) (xy 59.237869 -69.448871) (xy 59.208403 -69.494721) (xy 59.172712 -69.535912)
			(xy 59.131521 -69.571603) (xy 59.085671 -69.601069) (xy 59.036094 -69.623711) (xy 58.983799 -69.639066)
			(xy 58.929851 -69.646822) (xy 58.875349 -69.646822) (xy 58.821401 -69.639066) (xy 58.769106 -69.623711)
			(xy 58.719529 -69.601069) (xy 58.673679 -69.571603) (xy 58.632488 -69.535912) (xy 58.596797 -69.494721)
			(xy 58.567331 -69.448871) (xy 58.544689 -69.399294) (xy 58.529334 -69.346999) (xy 58.521578 -69.293051)
			(xy 58.521092 -69.2658) (xy 58.521595 -69.237986) (xy 58.529672 -69.182948) (xy 58.545654 -69.129665)
			(xy 58.569203 -69.079268) (xy 58.59982 -69.032824) (xy 58.636855 -68.991317) (xy 58.679525 -68.955627)
			(xy 58.726924 -68.926511) (xy 58.778048 -68.904585) (xy 58.80481 -68.896992) (xy 58.819342 -68.892593)
			(xy 58.845127 -68.876594) (xy 58.86507 -68.853723) (xy 58.877411 -68.826) (xy 58.881059 -68.795875)
			(xy 58.875692 -68.766008) (xy 58.861784 -68.739038) (xy 58.851546 -68.727828) (xy 58.831401 -68.706448)
			(xy 58.797262 -68.658645) (xy 58.770851 -68.606176) (xy 58.752794 -68.550278) (xy 58.743517 -68.492274)
			(xy 58.742834 -68.462906) (xy 58.742834 -68.442078) (xy 58.599832 -68.299076) (xy 58.571384 -68.30695)
			(xy 58.546478 -68.313379) (xy 58.495503 -68.320266) (xy 58.469784 -68.320666) (xy 58.442533 -68.320202)
			(xy 58.388586 -68.312442) (xy 58.336293 -68.297085) (xy 58.286717 -68.274441) (xy 58.240869 -68.244972)
			(xy 58.199682 -68.209277) (xy 58.163994 -68.168085) (xy 58.134532 -68.122232) (xy 58.111895 -68.072653)
			(xy 58.096545 -68.020357) (xy 58.088794 -67.966409) (xy 58.088276 -67.939158) (xy 58.088849 -67.909322)
			(xy 58.098135 -67.850377) (xy 58.116489 -67.793599) (xy 58.143463 -67.740372) (xy 58.178399 -67.691997)
			(xy 58.19902 -67.670426) (xy 58.208585 -67.660176) (xy 58.22219 -67.635676) (xy 58.22861 -67.608398)
			(xy 58.227361 -67.580401) (xy 58.218537 -67.553803) (xy 58.202805 -67.530611) (xy 58.181352 -67.51258)
			(xy 58.168794 -67.506342) (xy 58.144081 -67.494631) (xy 58.097998 -67.465186) (xy 58.056587 -67.42947)
			(xy 58.020693 -67.388211) (xy 57.991052 -67.342255) (xy 57.96827 -67.29254) (xy 57.952812 -67.240084)
			(xy 57.944995 -67.185959) (xy 57.944512 -67.158616) (xy 57.944982 -67.131666) (xy 57.952578 -67.078305)
			(xy 57.967608 -67.026543) (xy 57.989772 -66.977412) (xy 58.01863 -66.931888) (xy 58.053606 -66.890878)
			(xy 58.094005 -66.855198) (xy 58.139023 -66.825558) (xy 58.187764 -66.802547) (xy 58.239257 -66.786625)
			(xy 58.29248 -66.778107) (xy 58.319416 -66.777108) (xy 58.329289 -66.776448) (xy 58.347438 -66.76861)
			(xy 58.361278 -66.754493) (xy 58.368754 -66.736192) (xy 58.3692 -66.726308) (xy 58.3692 -65.328038)
			(xy 58.330338 -65.31864) (xy 58.30642 -65.312455) (xy 58.260301 -65.294745) (xy 58.23839 -65.283334)
			(xy 58.225437 -65.276915) (xy 58.197185 -65.270857) (xy 58.168366 -65.272949) (xy 58.141285 -65.283024)
			(xy 58.118107 -65.300277) (xy 58.100684 -65.323328) (xy 58.095134 -65.336674) (xy 58.084438 -65.363476)
			(xy 58.056138 -65.413764) (xy 58.020588 -65.459217) (xy 57.978597 -65.498797) (xy 57.931124 -65.531602)
			(xy 57.879252 -65.556881) (xy 57.824163 -65.57406) (xy 57.767116 -65.582746) (xy 57.738264 -65.583308)
			(xy 57.711014 -65.58282) (xy 57.657071 -65.575059) (xy 57.60478 -65.559701) (xy 57.555207 -65.537058)
			(xy 57.509362 -65.50759) (xy 57.468176 -65.471899) (xy 57.432488 -65.43071) (xy 57.403025 -65.384861)
			(xy 57.380387 -65.335286) (xy 57.365033 -65.282994) (xy 57.357278 -65.22905) (xy 57.357278 -65.17455)
			(xy 57.365033 -65.120606) (xy 57.380387 -65.068314) (xy 57.403025 -65.018739) (xy 57.432488 -64.97289)
			(xy 57.468176 -64.931701) (xy 57.509362 -64.89601) (xy 57.555207 -64.866542) (xy 57.60478 -64.843899)
			(xy 57.657071 -64.828541) (xy 57.711014 -64.82078) (xy 57.738264 -64.820292) (xy 57.769828 -64.82094)
			(xy 57.832096 -64.831324) (xy 57.891806 -64.851814) (xy 57.919874 -64.866266) (xy 57.932824 -64.872675)
			(xy 57.961065 -64.878716) (xy 57.989869 -64.876612) (xy 58.016933 -64.866532) (xy 58.040094 -64.849279)
			(xy 58.057501 -64.826235) (xy 58.06313 -64.812926) (xy 58.072742 -64.788747) (xy 58.097579 -64.743026)
			(xy 58.128393 -64.701099) (xy 58.146188 -64.682116) (xy 58.155088 -64.672354) (xy 58.168015 -64.649326)
			(xy 58.174601 -64.623753) (xy 58.174405 -64.597346) (xy 58.16744 -64.571873) (xy 58.154174 -64.54904)
			(xy 58.145172 -64.539368) (xy 53.641498 -60.035694) (xy 53.630055 -60.025043) (xy 53.602324 -60.010647)
			(xy 53.571538 -60.005311) (xy 53.54058 -60.009535) (xy 53.512349 -60.022923) (xy 53.500528 -60.033154)
			(xy 53.482083 -60.049687) (xy 53.441171 -60.07761) (xy 53.396553 -60.099121) (xy 53.349227 -60.113739)
			(xy 53.30025 -60.121137) (xy 53.275484 -60.121546) (xy 53.249497 -60.121035) (xy 53.198162 -60.112903)
			(xy 53.148731 -60.096841) (xy 53.102421 -60.073245) (xy 53.060372 -60.042696) (xy 53.023619 -60.005945)
			(xy 52.993067 -59.963898) (xy 52.969467 -59.917589) (xy 52.953402 -59.86816) (xy 52.945266 -59.816825)
			(xy 52.944776 -59.790838) (xy 52.945457 -59.761269) (xy 52.956011 -59.703079) (xy 52.976718 -59.647684)
			(xy 52.991258 -59.621928) (xy 52.998626 -59.608486) (xy 53.005747 -59.578684) (xy 53.003715 -59.548111)
			(xy 52.992712 -59.519514) (xy 52.973728 -59.495463) (xy 52.948468 -59.47812) (xy 52.919202 -59.469044)
			(xy 52.903882 -59.468512) (xy 51.672744 -59.468512) (xy 51.43881 -59.702446) (xy 51.43881 -60.038742)
			(xy 52.629455 -62.0014) (xy 54.253892 -62.0014) (xy 54.254378 -61.974149) (xy 54.262134 -61.920201)
			(xy 54.277489 -61.867906) (xy 54.300131 -61.818329) (xy 54.329597 -61.772479) (xy 54.365288 -61.731288)
			(xy 54.406479 -61.695597) (xy 54.452329 -61.666131) (xy 54.501906 -61.643489) (xy 54.554201 -61.628134)
			(xy 54.608149 -61.620378) (xy 54.662651 -61.620378) (xy 54.716599 -61.628134) (xy 54.768894 -61.643489)
			(xy 54.818471 -61.666131) (xy 54.864321 -61.695597) (xy 54.905512 -61.731288) (xy 54.941203 -61.772479)
			(xy 54.970669 -61.818329) (xy 54.993311 -61.867906) (xy 55.008666 -61.920201) (xy 55.016422 -61.974149)
			(xy 55.016908 -62.0014) (xy 55.016346 -62.031668) (xy 55.006774 -62.091443) (xy 54.987885 -62.148957)
			(xy 54.960152 -62.202768) (xy 54.924273 -62.251526) (xy 54.903116 -62.27318) (xy 54.893848 -62.282914)
			(xy 54.880324 -62.306131) (xy 54.873321 -62.332071) (xy 54.873322 -62.35894) (xy 54.880329 -62.384879)
			(xy 54.893855 -62.408095) (xy 54.912967 -62.426981) (xy 54.924452 -62.433962) (xy 54.949267 -62.448628)
			(xy 54.994647 -62.484163) (xy 55.034162 -62.526122) (xy 55.066912 -62.573551) (xy 55.092151 -62.625369)
			(xy 55.109304 -62.680395) (xy 55.11798 -62.737375) (xy 55.118508 -62.766194) (xy 55.118022 -62.793445)
			(xy 55.110266 -62.847393) (xy 55.094911 -62.899688) (xy 55.072269 -62.949265) (xy 55.042803 -62.995115)
			(xy 55.007112 -63.036306) (xy 54.965921 -63.071997) (xy 54.920071 -63.101463) (xy 54.870494 -63.124105)
			(xy 54.818199 -63.13946) (xy 54.764251 -63.147216) (xy 54.709749 -63.147216) (xy 54.655801 -63.13946)
			(xy 54.603506 -63.124105) (xy 54.553929 -63.101463) (xy 54.508079 -63.071997) (xy 54.466888 -63.036306)
			(xy 54.431197 -62.995115) (xy 54.401731 -62.949265) (xy 54.379089 -62.899688) (xy 54.363734 -62.847393)
			(xy 54.355978 -62.793445) (xy 54.355492 -62.766194) (xy 54.35605 -62.735926) (xy 54.365623 -62.676151)
			(xy 54.384514 -62.618636) (xy 54.412246 -62.564826) (xy 54.448127 -62.516068) (xy 54.469284 -62.494414)
			(xy 54.478558 -62.484686) (xy 54.492082 -62.461467) (xy 54.499085 -62.435526) (xy 54.499082 -62.408656)
			(xy 54.492075 -62.382716) (xy 54.478547 -62.3595) (xy 54.459434 -62.340613) (xy 54.447948 -62.333632)
			(xy 54.423131 -62.31897) (xy 54.37775 -62.283435) (xy 54.338235 -62.241475) (xy 54.305485 -62.194045)
			(xy 54.280247 -62.142227) (xy 54.263095 -62.0872) (xy 54.25442 -62.030219) (xy 54.253892 -62.0014)
			(xy 52.629455 -62.0014) (xy 54.048614 -64.34074) (xy 54.358032 -64.34074) (xy 54.358518 -64.313489)
			(xy 54.366274 -64.259541) (xy 54.381629 -64.207246) (xy 54.404271 -64.157669) (xy 54.433737 -64.111819)
			(xy 54.469428 -64.070628) (xy 54.510619 -64.034937) (xy 54.556469 -64.005471) (xy 54.606046 -63.982829)
			(xy 54.658341 -63.967474) (xy 54.712289 -63.959718) (xy 54.766791 -63.959718) (xy 54.820739 -63.967474)
			(xy 54.873034 -63.982829) (xy 54.922611 -64.005471) (xy 54.968461 -64.034937) (xy 55.009652 -64.070628)
			(xy 55.045343 -64.111819) (xy 55.074809 -64.157669) (xy 55.097451 -64.207246) (xy 55.112806 -64.259541)
			(xy 55.120562 -64.313489) (xy 55.121048 -64.34074) (xy 55.120751 -64.362201) (xy 55.115913 -64.404848)
			(xy 55.111396 -64.42583) (xy 55.10861 -64.440801) (xy 55.110891 -64.471148) (xy 55.12201 -64.499476)
			(xy 55.140978 -64.523274) (xy 55.166114 -64.540428) (xy 55.180484 -64.545464) (xy 55.206055 -64.553872)
			(xy 55.254706 -64.576908) (xy 55.299633 -64.606557) (xy 55.339944 -64.642229) (xy 55.374838 -64.683217)
			(xy 55.397606 -64.7192) (xy 56.463182 -64.7192) (xy 56.467253 -64.663578) (xy 56.479379 -64.609141)
			(xy 56.499302 -64.55705) (xy 56.526598 -64.508415) (xy 56.560684 -64.464272) (xy 56.600833 -64.425563)
			(xy 56.646191 -64.393112) (xy 56.695791 -64.367611) (xy 56.748575 -64.349604) (xy 56.803418 -64.339474)
			(xy 56.859152 -64.337437) (xy 56.914589 -64.343537) (xy 56.968546 -64.357643) (xy 57.019875 -64.379455)
			(xy 57.067481 -64.408509) (xy 57.110349 -64.444184) (xy 57.147566 -64.485721) (xy 57.178339 -64.532234)
			(xy 57.202011 -64.582731) (xy 57.218079 -64.636138) (xy 57.226199 -64.691314) (xy 57.226708 -64.7192)
			(xy 57.226199 -64.747086) (xy 57.218079 -64.802262) (xy 57.202011 -64.855669) (xy 57.178339 -64.906166)
			(xy 57.147566 -64.952679) (xy 57.110349 -64.994216) (xy 57.067481 -65.029891) (xy 57.019875 -65.058945)
			(xy 56.968546 -65.080757) (xy 56.914589 -65.094863) (xy 56.859152 -65.100963) (xy 56.803418 -65.098926)
			(xy 56.748575 -65.088796) (xy 56.695791 -65.070789) (xy 56.646191 -65.045288) (xy 56.600833 -65.012837)
			(xy 56.560684 -64.974128) (xy 56.526598 -64.929985) (xy 56.499302 -64.88135) (xy 56.479379 -64.829259)
			(xy 56.467253 -64.774822) (xy 56.463182 -64.7192) (xy 55.397606 -64.7192) (xy 55.40362 -64.728704)
			(xy 55.425719 -64.777787) (xy 55.440696 -64.82949) (xy 55.448252 -64.882786) (xy 55.448708 -64.9097)
			(xy 55.448222 -64.936951) (xy 55.440466 -64.990899) (xy 55.425111 -65.043194) (xy 55.402469 -65.092771)
			(xy 55.373003 -65.138621) (xy 55.337312 -65.179812) (xy 55.296121 -65.215503) (xy 55.250271 -65.244969)
			(xy 55.200694 -65.267611) (xy 55.148399 -65.282966) (xy 55.094451 -65.290722) (xy 55.039949 -65.290722)
			(xy 54.986001 -65.282966) (xy 54.933706 -65.267611) (xy 54.884129 -65.244969) (xy 54.838279 -65.215503)
			(xy 54.797088 -65.179812) (xy 54.761397 -65.138621) (xy 54.731931 -65.092771) (xy 54.709289 -65.043194)
			(xy 54.693934 -64.990899) (xy 54.686178 -64.936951) (xy 54.685692 -64.9097) (xy 54.685998 -64.88824)
			(xy 54.69083 -64.845592) (xy 54.695344 -64.82461) (xy 54.698163 -64.809645) (xy 54.695867 -64.779297)
			(xy 54.684739 -64.750969) (xy 54.665765 -64.727172) (xy 54.640626 -64.710014) (xy 54.626256 -64.704976)
			(xy 54.600685 -64.696569) (xy 54.552038 -64.673529) (xy 54.507113 -64.643878) (xy 54.466804 -64.608204)
			(xy 54.431912 -64.567217) (xy 54.40313 -64.521731) (xy 54.38103 -64.472649) (xy 54.366051 -64.420948)
			(xy 54.35849 -64.367654) (xy 54.358032 -64.34074) (xy 54.048614 -64.34074) (xy 54.516274 -65.11163)
			(xy 55.372774 -66.463672) (xy 56.217564 -66.463672) (xy 56.221635 -66.40805) (xy 56.233761 -66.353613)
			(xy 56.253684 -66.301522) (xy 56.28098 -66.252887) (xy 56.315066 -66.208744) (xy 56.355215 -66.170035)
			(xy 56.400573 -66.137584) (xy 56.450173 -66.112083) (xy 56.502957 -66.094076) (xy 56.5578 -66.083946)
			(xy 56.613534 -66.081909) (xy 56.668971 -66.088009) (xy 56.722928 -66.102115) (xy 56.774257 -66.123927)
			(xy 56.821863 -66.152981) (xy 56.864731 -66.188656) (xy 56.901948 -66.230193) (xy 56.932721 -66.276706)
			(xy 56.956393 -66.327203) (xy 56.972461 -66.38061) (xy 56.980581 -66.435786) (xy 56.98109 -66.463672)
			(xy 56.980581 -66.491558) (xy 56.972461 -66.546734) (xy 56.956393 -66.600141) (xy 56.932721 -66.650638)
			(xy 56.901948 -66.697151) (xy 56.864731 -66.738688) (xy 56.821863 -66.774363) (xy 56.774257 -66.803417)
			(xy 56.722928 -66.825229) (xy 56.668971 -66.839335) (xy 56.613534 -66.845435) (xy 56.5578 -66.843398)
			(xy 56.502957 -66.833268) (xy 56.450173 -66.815261) (xy 56.400573 -66.78976) (xy 56.355215 -66.757309)
			(xy 56.315066 -66.7186) (xy 56.28098 -66.674457) (xy 56.253684 -66.625822) (xy 56.233761 -66.573731)
			(xy 56.221635 -66.519294) (xy 56.217564 -66.463672) (xy 55.372774 -66.463672) (xy 56.021224 -67.487292)
			(xy 56.028844 -67.503548) (xy 56.042814 -67.511676) (xy 56.067572 -67.526306) (xy 56.112777 -67.561851)
			(xy 56.152129 -67.603782) (xy 56.18332 -67.64909) (xy 57.124852 -67.64909) (xy 57.128923 -67.593468)
			(xy 57.141049 -67.539031) (xy 57.160972 -67.48694) (xy 57.188268 -67.438305) (xy 57.222354 -67.394162)
			(xy 57.262503 -67.355453) (xy 57.307861 -67.323002) (xy 57.357461 -67.297501) (xy 57.410245 -67.279494)
			(xy 57.465088 -67.269364) (xy 57.520822 -67.267327) (xy 57.576259 -67.273427) (xy 57.630216 -67.287533)
			(xy 57.681545 -67.309345) (xy 57.729151 -67.338399) (xy 57.772019 -67.374074) (xy 57.809236 -67.415611)
			(xy 57.840009 -67.462124) (xy 57.863681 -67.512621) (xy 57.879749 -67.566028) (xy 57.887869 -67.621204)
			(xy 57.888378 -67.64909) (xy 57.887869 -67.676976) (xy 57.879749 -67.732152) (xy 57.863681 -67.785559)
			(xy 57.840009 -67.836056) (xy 57.809236 -67.882569) (xy 57.772019 -67.924106) (xy 57.729151 -67.959781)
			(xy 57.681545 -67.988835) (xy 57.630216 -68.010647) (xy 57.576259 -68.024753) (xy 57.520822 -68.030853)
			(xy 57.465088 -68.028816) (xy 57.410245 -68.018686) (xy 57.357461 -68.000679) (xy 57.307861 -67.975178)
			(xy 57.262503 -67.942727) (xy 57.222354 -67.904018) (xy 57.188268 -67.859875) (xy 57.160972 -67.81124)
			(xy 57.141049 -67.759149) (xy 57.128923 -67.704712) (xy 57.124852 -67.64909) (xy 56.18332 -67.64909)
			(xy 56.184737 -67.651149) (xy 56.209859 -67.702877) (xy 56.226925 -67.757792) (xy 56.235548 -67.814647)
			(xy 56.236108 -67.8434) (xy 56.236024 -67.855625) (xy 56.234501 -67.880028) (xy 56.23306 -67.892168)
			(xy 56.230774 -67.909948) (xy 56.912002 -69.020436) (xy 56.912002 -69.56933) (xy 57.333642 -69.99097)
			(xy 57.34478 -70.001313) (xy 57.371626 -70.015528) (xy 57.401464 -70.021225) (xy 57.431659 -70.017901)
			(xy 57.459543 -70.005848) (xy 57.482653 -69.986132) (xy 57.498947 -69.960494) (xy 57.503568 -69.946012)
			(xy 57.509555 -69.925199) (xy 57.525591 -69.884968) (xy 57.535572 -69.865748) (xy 57.541656 -69.853448)
			(xy 57.547715 -69.826696) (xy 57.546441 -69.799296) (xy 57.537926 -69.773221) (xy 57.522784 -69.75035)
			(xy 57.502104 -69.732329) (xy 57.477377 -69.720456) (xy 57.463944 -69.717666) (xy 57.437829 -69.712539)
			(xy 57.387243 -69.696002) (xy 57.339448 -69.672593) (xy 57.295372 -69.642766) (xy 57.255871 -69.607101)
			(xy 57.221713 -69.56629) (xy 57.19356 -69.521126) (xy 57.171959 -69.472487) (xy 57.157331 -69.421317)
			(xy 57.14996 -69.36861) (xy 57.149492 -69.342) (xy 57.149991 -69.313908) (xy 57.158226 -69.258332)
			(xy 57.17452 -69.204563) (xy 57.198519 -69.153763) (xy 57.229706 -69.10703) (xy 57.267406 -69.065373)
			(xy 57.310805 -69.029693) (xy 57.334658 -69.014848) (xy 57.347298 -69.006625) (xy 57.367483 -68.984244)
			(xy 57.380255 -68.956946) (xy 57.384501 -68.927108) (xy 57.379851 -68.897331) (xy 57.373774 -68.88353)
			(xy 57.361682 -68.857435) (xy 57.344598 -68.802518) (xy 57.335936 -68.745662) (xy 57.33542 -68.716906)
			(xy 57.335906 -68.689655) (xy 57.343662 -68.635707) (xy 57.359017 -68.583412) (xy 57.381659 -68.533835)
			(xy 57.411125 -68.487985) (xy 57.446816 -68.446794) (xy 57.488007 -68.411103) (xy 57.533857 -68.381637)
			(xy 57.583434 -68.358995) (xy 57.635729 -68.34364) (xy 57.689677 -68.335884) (xy 57.744179 -68.335884)
			(xy 57.798127 -68.34364) (xy 57.850422 -68.358995) (xy 57.899999 -68.381637) (xy 57.945849 -68.411103)
			(xy 57.98704 -68.446794) (xy 58.022731 -68.487985) (xy 58.052197 -68.533835) (xy 58.074839 -68.583412)
			(xy 58.090194 -68.635707) (xy 58.09795 -68.689655) (xy 58.098436 -68.716906) (xy 58.097937 -68.744997)
			(xy 58.089699 -68.800571) (xy 58.073403 -68.854337) (xy 58.049401 -68.905132) (xy 58.018211 -68.95186)
			(xy 57.980507 -68.993511) (xy 57.937104 -69.029183) (xy 57.91327 -69.044058) (xy 57.900628 -69.052279)
			(xy 57.880439 -69.074659) (xy 57.867664 -69.101958) (xy 57.863419 -69.131798) (xy 57.868072 -69.161577)
			(xy 57.874154 -69.175376) (xy 57.886245 -69.201472) (xy 57.903326 -69.256388) (xy 57.911987 -69.313244)
			(xy 57.912508 -69.342) (xy 57.911871 -69.373373) (xy 57.901598 -69.435273) (xy 57.88133 -69.494656)
			(xy 57.867042 -69.522594) (xy 57.860964 -69.534891) (xy 57.854915 -69.561635) (xy 57.856196 -69.589025)
			(xy 57.864714 -69.615088) (xy 57.879857 -69.637948) (xy 57.900533 -69.655957) (xy 57.925254 -69.66782)
			(xy 57.93867 -69.670676) (xy 57.964786 -69.675804) (xy 58.015374 -69.692341) (xy 58.063171 -69.71575)
			(xy 58.10725 -69.745576) (xy 58.146755 -69.781241) (xy 58.180918 -69.822051) (xy 58.209076 -69.867214)
			(xy 58.230682 -69.915853) (xy 58.245317 -69.967023) (xy 58.252696 -70.019731) (xy 58.253122 -70.046342)
			(xy 58.252633 -70.074008) (xy 58.244646 -70.12876) (xy 58.228832 -70.181783) (xy 58.205523 -70.231965)
			(xy 58.175207 -70.278252) (xy 58.138522 -70.319673) (xy 58.096236 -70.355359) (xy 58.049238 -70.38456)
			(xy 57.998514 -70.406664) (xy 57.971944 -70.414388) (xy 57.957448 -70.418956) (xy 57.931819 -70.435263)
			(xy 57.912114 -70.45838) (xy 57.900071 -70.486268) (xy 57.896756 -70.516463) (xy 57.902459 -70.546299)
			(xy 57.916678 -70.573142) (xy 57.926986 -70.584314) (xy 58.04027 -70.697598) (xy 58.638694 -70.697598)
			(xy 60.02909 -72.087994) (xy 60.02909 -73.08977) (xy 60.669678 -73.730104) (xy 60.686449 -73.747544)
			(xy 60.714889 -73.786685) (xy 60.736856 -73.829792) (xy 60.751809 -73.875805) (xy 60.75938 -73.923591)
			(xy 60.759848 -73.947782) (xy 60.759848 -74.563224) (xy 62.105032 -75.908662)
		)
		(stroke
			(width 0)
			(type solid)
		)
		(fill yes)
		(layer "In7.Cu")
		(net "ADCVREFEXT1")
	)
	(gr_poly
		(pts
			(xy 22.5044 -92.2782) (xy 22.5044 -91.7702) (xy 22.4282 -91.694) (xy 22.4282 -91.618054) (xy 22.427711 -91.603325)
			(xy 22.419306 -91.575092) (xy 22.403181 -91.55044) (xy 22.380683 -91.531426) (xy 22.353688 -91.519636)
			(xy 22.324449 -91.516055) (xy 22.309836 -91.517978) (xy 22.296159 -91.520138) (xy 22.268564 -91.522431)
			(xy 22.254718 -91.52255) (xy 22.228725 -91.522068) (xy 22.177377 -91.513938) (xy 22.127934 -91.497875)
			(xy 22.081612 -91.474276) (xy 22.039553 -91.44372) (xy 22.002792 -91.406961) (xy 21.972234 -91.364903)
			(xy 21.948632 -91.318583) (xy 21.932566 -91.26914) (xy 21.924433 -91.217793) (xy 21.924433 -91.165807)
			(xy 21.932566 -91.11446) (xy 21.948632 -91.065017) (xy 21.972234 -91.018697) (xy 22.002792 -90.976639)
			(xy 22.039553 -90.93988) (xy 22.081612 -90.909324) (xy 22.127934 -90.885725) (xy 22.177377 -90.869662)
			(xy 22.228725 -90.861532) (xy 22.254718 -90.861134) (xy 22.268563 -90.861269) (xy 22.296158 -90.863558)
			(xy 22.309836 -90.865706) (xy 22.324435 -90.867634) (xy 22.353643 -90.863987) (xy 22.380602 -90.852171)
			(xy 22.403078 -90.833164) (xy 22.419208 -90.808543) (xy 22.427657 -90.780346) (xy 22.4282 -90.76563)
			(xy 22.4282 -90.70213) (xy 22.369018 -90.70213) (xy 22.361144 -90.704924) (xy 22.335303 -90.71311)
			(xy 22.28182 -90.721919) (xy 22.254718 -90.72245) (xy 22.228725 -90.721968) (xy 22.177377 -90.713838)
			(xy 22.127934 -90.697775) (xy 22.081612 -90.674176) (xy 22.039553 -90.64362) (xy 22.002792 -90.606861)
			(xy 21.972234 -90.564803) (xy 21.948632 -90.518483) (xy 21.932566 -90.46904) (xy 21.924433 -90.417693)
			(xy 21.924433 -90.365707) (xy 21.932566 -90.31436) (xy 21.948632 -90.264917) (xy 21.972234 -90.218597)
			(xy 22.002792 -90.176539) (xy 22.039553 -90.13978) (xy 22.081612 -90.109224) (xy 22.127934 -90.085625)
			(xy 22.177377 -90.069562) (xy 22.228725 -90.061432) (xy 22.254718 -90.061034) (xy 22.279291 -90.061485)
			(xy 22.327896 -90.068759) (xy 22.37489 -90.083146) (xy 22.419237 -90.104327) (xy 22.459962 -90.131838)
			(xy 22.496169 -90.165072) (xy 22.527059 -90.203297) (xy 22.551953 -90.245672) (xy 22.56155 -90.268298)
			(xy 22.567364 -90.281426) (xy 22.585062 -90.304018) (xy 22.608341 -90.320802) (xy 22.635368 -90.330454)
			(xy 22.664013 -90.332215) (xy 22.692019 -90.325945) (xy 22.717178 -90.312138) (xy 22.727666 -90.302334)
			(xy 22.739604 -90.290396) (xy 22.743414 -90.279728) (xy 22.752454 -90.256055) (xy 22.776694 -90.211558)
			(xy 22.807438 -90.171278) (xy 22.843966 -90.136159) (xy 22.885423 -90.107023) (xy 22.930838 -90.084551)
			(xy 22.979151 -90.069269) (xy 23.029228 -90.061535) (xy 23.054564 -90.061034) (xy 23.078608 -90.061464)
			(xy 23.126189 -90.068426) (xy 23.172258 -90.082209) (xy 23.215845 -90.102522) (xy 23.256029 -90.128935)
			(xy 23.274274 -90.1446) (xy 23.634954 -90.1446) (xy 23.655263 -90.127232) (xy 23.700387 -90.098611)
			(xy 23.749527 -90.077619) (xy 23.801402 -90.064801) (xy 23.854664 -90.060491) (xy 23.907926 -90.064801)
			(xy 23.959801 -90.077619) (xy 24.008941 -90.098611) (xy 24.054065 -90.127232) (xy 24.074374 -90.1446)
			(xy 24.435054 -90.1446) (xy 24.45331 -90.128948) (xy 24.493494 -90.102537) (xy 24.537078 -90.082222)
			(xy 24.583144 -90.068429) (xy 24.630721 -90.061449) (xy 24.654764 -90.061034) (xy 24.684376 -90.061694)
			(xy 24.742654 -90.072233) (xy 24.79813 -90.092963) (xy 24.823928 -90.107516) (xy 24.857964 -90.127836)
			(xy 25.1206 -89.8652) (xy 25.1206 -87.8586) (xy 24.8666 -87.6046) (xy 20.988528 -87.6046) (xy 20.973945 -87.60507)
			(xy 20.945969 -87.61331) (xy 20.921464 -87.629125) (xy 20.902433 -87.651224) (xy 20.890427 -87.677804)
			(xy 20.886429 -87.706693) (xy 20.890763 -87.735534) (xy 20.903076 -87.761972) (xy 20.912328 -87.773256)
			(xy 20.927809 -87.791474) (xy 20.953911 -87.831525) (xy 20.97398 -87.874914) (xy 20.987598 -87.920739)
			(xy 20.994483 -87.968047) (xy 20.994878 -87.99195) (xy 20.994368 -88.017937) (xy 20.986238 -88.069272)
			(xy 20.970177 -88.118702) (xy 20.946581 -88.165012) (xy 20.916031 -88.20706) (xy 20.87928 -88.243811)
			(xy 20.837232 -88.274361) (xy 20.790922 -88.297957) (xy 20.741492 -88.314018) (xy 20.690157 -88.322148)
			(xy 20.638183 -88.322148) (xy 20.586848 -88.314018) (xy 20.537418 -88.297957) (xy 20.491108 -88.274361)
			(xy 20.44906 -88.243811) (xy 20.412309 -88.20706) (xy 20.381759 -88.165012) (xy 20.358163 -88.118702)
			(xy 20.342102 -88.069272) (xy 20.333972 -88.017937) (xy 20.333462 -87.99195) (xy 20.333879 -87.968047)
			(xy 20.340751 -87.920737) (xy 20.354358 -87.874908) (xy 20.374418 -87.831514) (xy 20.400514 -87.791458)
			(xy 20.416012 -87.773256) (xy 20.425279 -87.761995) (xy 20.437553 -87.735554) (xy 20.44186 -87.706722)
			(xy 20.437848 -87.677847) (xy 20.425844 -87.651282) (xy 20.406827 -87.629188) (xy 20.382343 -87.613364)
			(xy 20.354387 -87.6051) (xy 20.339812 -87.6046) (xy 19.388582 -87.6046) (xy 19.373994 -87.605063)
			(xy 19.346003 -87.613294) (xy 19.321484 -87.629108) (xy 19.302441 -87.651212) (xy 19.290428 -87.6778)
			(xy 19.286429 -87.706701) (xy 19.290768 -87.735552) (xy 19.303093 -87.761997) (xy 19.312382 -87.773256)
			(xy 19.327864 -87.791473) (xy 19.35397 -87.831523) (xy 19.374042 -87.874912) (xy 19.387662 -87.920738)
			(xy 19.394548 -87.968047) (xy 19.394932 -87.99195) (xy 19.394422 -88.017937) (xy 19.386292 -88.069272)
			(xy 19.370231 -88.118702) (xy 19.346635 -88.165012) (xy 19.316085 -88.20706) (xy 19.279334 -88.243811)
			(xy 19.237286 -88.274361) (xy 19.190976 -88.297957) (xy 19.141546 -88.314018) (xy 19.090211 -88.322148)
			(xy 19.038237 -88.322148) (xy 18.986902 -88.314018) (xy 18.937472 -88.297957) (xy 18.891162 -88.274361)
			(xy 18.849114 -88.243811) (xy 18.812363 -88.20706) (xy 18.781813 -88.165012) (xy 18.758217 -88.118702)
			(xy 18.742156 -88.069272) (xy 18.734026 -88.017937) (xy 18.733516 -87.99195) (xy 18.733933 -87.968046)
			(xy 18.740804 -87.920736) (xy 18.75441 -87.874906) (xy 18.774468 -87.83151) (xy 18.80056 -87.791452)
			(xy 18.816066 -87.773256) (xy 18.825336 -87.761998) (xy 18.837615 -87.735559) (xy 18.841925 -87.706728)
			(xy 18.837914 -87.677854) (xy 18.825908 -87.65129) (xy 18.806887 -87.629199) (xy 18.7824 -87.613383)
			(xy 18.754441 -87.605128) (xy 18.739866 -87.6046) (xy 17.9324 -87.6046) (xy 17.7546 -87.7824) (xy 17.7546 -87.8332)
			(xy 17.759934 -87.843868) (xy 17.770966 -87.866979) (xy 17.786566 -87.915753) (xy 17.794479 -87.966346)
			(xy 17.794986 -87.99195) (xy 17.794506 -88.017556) (xy 17.786602 -88.068154) (xy 17.770976 -88.116924)
			(xy 17.759934 -88.140032) (xy 17.7546 -88.1507) (xy 17.7546 -88.633046) (xy 17.759934 -88.643714)
			(xy 17.770969 -88.666824) (xy 17.786577 -88.715598) (xy 17.794499 -88.766191) (xy 17.794986 -88.791796)
			(xy 17.794511 -88.817403) (xy 17.794452 -88.817783) (xy 17.933926 -88.817783) (xy 17.933926 -88.765809)
			(xy 17.942056 -88.714474) (xy 17.958117 -88.665044) (xy 17.981713 -88.618734) (xy 18.012263 -88.576686)
			(xy 18.049014 -88.539935) (xy 18.091062 -88.509385) (xy 18.137372 -88.485789) (xy 18.186802 -88.469728)
			(xy 18.238137 -88.461598) (xy 18.290111 -88.461598) (xy 18.341446 -88.469728) (xy 18.390876 -88.485789)
			(xy 18.437186 -88.509385) (xy 18.479234 -88.539935) (xy 18.515985 -88.576686) (xy 18.546535 -88.618734)
			(xy 18.570131 -88.665044) (xy 18.586192 -88.714474) (xy 18.594322 -88.765809) (xy 18.594832 -88.791796)
			(xy 18.594322 -88.817783) (xy 18.734026 -88.817783) (xy 18.734026 -88.765809) (xy 18.742156 -88.714474)
			(xy 18.758217 -88.665044) (xy 18.781813 -88.618734) (xy 18.812363 -88.576686) (xy 18.849114 -88.539935)
			(xy 18.891162 -88.509385) (xy 18.937472 -88.485789) (xy 18.986902 -88.469728) (xy 19.038237 -88.461598)
			(xy 19.090211 -88.461598) (xy 19.141546 -88.469728) (xy 19.190976 -88.485789) (xy 19.237286 -88.509385)
			(xy 19.279334 -88.539935) (xy 19.316085 -88.576686) (xy 19.346635 -88.618734) (xy 19.370231 -88.665044)
			(xy 19.386292 -88.714474) (xy 19.394422 -88.765809) (xy 19.394932 -88.791796) (xy 19.394422 -88.817783)
			(xy 19.534126 -88.817783) (xy 19.534126 -88.765809) (xy 19.542256 -88.714474) (xy 19.558317 -88.665044)
			(xy 19.581913 -88.618734) (xy 19.612463 -88.576686) (xy 19.649214 -88.539935) (xy 19.691262 -88.509385)
			(xy 19.737572 -88.485789) (xy 19.787002 -88.469728) (xy 19.838337 -88.461598) (xy 19.890311 -88.461598)
			(xy 19.941646 -88.469728) (xy 19.991076 -88.485789) (xy 20.037386 -88.509385) (xy 20.079434 -88.539935)
			(xy 20.116185 -88.576686) (xy 20.146735 -88.618734) (xy 20.170331 -88.665044) (xy 20.186392 -88.714474)
			(xy 20.194522 -88.765809) (xy 20.195032 -88.791796) (xy 20.194522 -88.817783) (xy 20.333972 -88.817783)
			(xy 20.333972 -88.765809) (xy 20.342102 -88.714474) (xy 20.358163 -88.665044) (xy 20.381759 -88.618734)
			(xy 20.412309 -88.576686) (xy 20.44906 -88.539935) (xy 20.491108 -88.509385) (xy 20.537418 -88.485789)
			(xy 20.586848 -88.469728) (xy 20.638183 -88.461598) (xy 20.690157 -88.461598) (xy 20.741492 -88.469728)
			(xy 20.790922 -88.485789) (xy 20.837232 -88.509385) (xy 20.87928 -88.539935) (xy 20.916031 -88.576686)
			(xy 20.946581 -88.618734) (xy 20.970177 -88.665044) (xy 20.986238 -88.714474) (xy 20.994368 -88.765809)
			(xy 20.994878 -88.791796) (xy 20.994368 -88.817783) (xy 21.92452 -88.817783) (xy 21.92452 -88.765809)
			(xy 21.93265 -88.714474) (xy 21.948711 -88.665044) (xy 21.972307 -88.618734) (xy 22.002857 -88.576686)
			(xy 22.039608 -88.539935) (xy 22.081656 -88.509385) (xy 22.127966 -88.485789) (xy 22.177396 -88.469728)
			(xy 22.228731 -88.461598) (xy 22.280705 -88.461598) (xy 22.33204 -88.469728) (xy 22.38147 -88.485789)
			(xy 22.42778 -88.509385) (xy 22.469828 -88.539935) (xy 22.506579 -88.576686) (xy 22.537129 -88.618734)
			(xy 22.560725 -88.665044) (xy 22.576786 -88.714474) (xy 22.584916 -88.765809) (xy 22.585426 -88.791796)
			(xy 22.584916 -88.817783) (xy 22.724366 -88.817783) (xy 22.724366 -88.765809) (xy 22.732496 -88.714474)
			(xy 22.748557 -88.665044) (xy 22.772153 -88.618734) (xy 22.802703 -88.576686) (xy 22.839454 -88.539935)
			(xy 22.881502 -88.509385) (xy 22.927812 -88.485789) (xy 22.977242 -88.469728) (xy 23.028577 -88.461598)
			(xy 23.080551 -88.461598) (xy 23.131886 -88.469728) (xy 23.181316 -88.485789) (xy 23.227626 -88.509385)
			(xy 23.269674 -88.539935) (xy 23.306425 -88.576686) (xy 23.336975 -88.618734) (xy 23.360571 -88.665044)
			(xy 23.376632 -88.714474) (xy 23.384762 -88.765809) (xy 23.385272 -88.791796) (xy 23.384762 -88.817783)
			(xy 23.524466 -88.817783) (xy 23.524466 -88.765809) (xy 23.532596 -88.714474) (xy 23.548657 -88.665044)
			(xy 23.572253 -88.618734) (xy 23.602803 -88.576686) (xy 23.639554 -88.539935) (xy 23.681602 -88.509385)
			(xy 23.727912 -88.485789) (xy 23.777342 -88.469728) (xy 23.828677 -88.461598) (xy 23.880651 -88.461598)
			(xy 23.931986 -88.469728) (xy 23.981416 -88.485789) (xy 24.027726 -88.509385) (xy 24.069774 -88.539935)
			(xy 24.106525 -88.576686) (xy 24.137075 -88.618734) (xy 24.160671 -88.665044) (xy 24.176732 -88.714474)
			(xy 24.184862 -88.765809) (xy 24.185372 -88.791796) (xy 24.184862 -88.817783) (xy 24.324566 -88.817783)
			(xy 24.324566 -88.765809) (xy 24.332696 -88.714474) (xy 24.348757 -88.665044) (xy 24.372353 -88.618734)
			(xy 24.402903 -88.576686) (xy 24.439654 -88.539935) (xy 24.481702 -88.509385) (xy 24.528012 -88.485789)
			(xy 24.577442 -88.469728) (xy 24.628777 -88.461598) (xy 24.680751 -88.461598) (xy 24.732086 -88.469728)
			(xy 24.781516 -88.485789) (xy 24.827826 -88.509385) (xy 24.869874 -88.539935) (xy 24.906625 -88.576686)
			(xy 24.937175 -88.618734) (xy 24.960771 -88.665044) (xy 24.976832 -88.714474) (xy 24.984962 -88.765809)
			(xy 24.985472 -88.791796) (xy 24.984962 -88.817783) (xy 24.976832 -88.869118) (xy 24.960771 -88.918548)
			(xy 24.937175 -88.964858) (xy 24.906625 -89.006906) (xy 24.869874 -89.043657) (xy 24.827826 -89.074207)
			(xy 24.781516 -89.097803) (xy 24.732086 -89.113864) (xy 24.680751 -89.121994) (xy 24.628777 -89.121994)
			(xy 24.577442 -89.113864) (xy 24.528012 -89.097803) (xy 24.481702 -89.074207) (xy 24.439654 -89.043657)
			(xy 24.402903 -89.006906) (xy 24.372353 -88.964858) (xy 24.348757 -88.918548) (xy 24.332696 -88.869118)
			(xy 24.324566 -88.817783) (xy 24.184862 -88.817783) (xy 24.176732 -88.869118) (xy 24.160671 -88.918548)
			(xy 24.137075 -88.964858) (xy 24.106525 -89.006906) (xy 24.069774 -89.043657) (xy 24.027726 -89.074207)
			(xy 23.981416 -89.097803) (xy 23.931986 -89.113864) (xy 23.880651 -89.121994) (xy 23.828677 -89.121994)
			(xy 23.777342 -89.113864) (xy 23.727912 -89.097803) (xy 23.681602 -89.074207) (xy 23.639554 -89.043657)
			(xy 23.602803 -89.006906) (xy 23.572253 -88.964858) (xy 23.548657 -88.918548) (xy 23.532596 -88.869118)
			(xy 23.524466 -88.817783) (xy 23.384762 -88.817783) (xy 23.376632 -88.869118) (xy 23.360571 -88.918548)
			(xy 23.336975 -88.964858) (xy 23.306425 -89.006906) (xy 23.269674 -89.043657) (xy 23.227626 -89.074207)
			(xy 23.181316 -89.097803) (xy 23.131886 -89.113864) (xy 23.080551 -89.121994) (xy 23.028577 -89.121994)
			(xy 22.977242 -89.113864) (xy 22.927812 -89.097803) (xy 22.881502 -89.074207) (xy 22.839454 -89.043657)
			(xy 22.802703 -89.006906) (xy 22.772153 -88.964858) (xy 22.748557 -88.918548) (xy 22.732496 -88.869118)
			(xy 22.724366 -88.817783) (xy 22.584916 -88.817783) (xy 22.576786 -88.869118) (xy 22.560725 -88.918548)
			(xy 22.537129 -88.964858) (xy 22.506579 -89.006906) (xy 22.469828 -89.043657) (xy 22.42778 -89.074207)
			(xy 22.38147 -89.097803) (xy 22.33204 -89.113864) (xy 22.280705 -89.121994) (xy 22.228731 -89.121994)
			(xy 22.177396 -89.113864) (xy 22.127966 -89.097803) (xy 22.081656 -89.074207) (xy 22.039608 -89.043657)
			(xy 22.002857 -89.006906) (xy 21.972307 -88.964858) (xy 21.948711 -88.918548) (xy 21.93265 -88.869118)
			(xy 21.92452 -88.817783) (xy 20.994368 -88.817783) (xy 20.986238 -88.869118) (xy 20.970177 -88.918548)
			(xy 20.946581 -88.964858) (xy 20.916031 -89.006906) (xy 20.87928 -89.043657) (xy 20.837232 -89.074207)
			(xy 20.790922 -89.097803) (xy 20.741492 -89.113864) (xy 20.690157 -89.121994) (xy 20.638183 -89.121994)
			(xy 20.586848 -89.113864) (xy 20.537418 -89.097803) (xy 20.491108 -89.074207) (xy 20.44906 -89.043657)
			(xy 20.412309 -89.006906) (xy 20.381759 -88.964858) (xy 20.358163 -88.918548) (xy 20.342102 -88.869118)
			(xy 20.333972 -88.817783) (xy 20.194522 -88.817783) (xy 20.186392 -88.869118) (xy 20.170331 -88.918548)
			(xy 20.146735 -88.964858) (xy 20.116185 -89.006906) (xy 20.079434 -89.043657) (xy 20.037386 -89.074207)
			(xy 19.991076 -89.097803) (xy 19.941646 -89.113864) (xy 19.890311 -89.121994) (xy 19.838337 -89.121994)
			(xy 19.787002 -89.113864) (xy 19.737572 -89.097803) (xy 19.691262 -89.074207) (xy 19.649214 -89.043657)
			(xy 19.612463 -89.006906) (xy 19.581913 -88.964858) (xy 19.558317 -88.918548) (xy 19.542256 -88.869118)
			(xy 19.534126 -88.817783) (xy 19.394422 -88.817783) (xy 19.386292 -88.869118) (xy 19.370231 -88.918548)
			(xy 19.346635 -88.964858) (xy 19.316085 -89.006906) (xy 19.279334 -89.043657) (xy 19.237286 -89.074207)
			(xy 19.190976 -89.097803) (xy 19.141546 -89.113864) (xy 19.090211 -89.121994) (xy 19.038237 -89.121994)
			(xy 18.986902 -89.113864) (xy 18.937472 -89.097803) (xy 18.891162 -89.074207) (xy 18.849114 -89.043657)
			(xy 18.812363 -89.006906) (xy 18.781813 -88.964858) (xy 18.758217 -88.918548) (xy 18.742156 -88.869118)
			(xy 18.734026 -88.817783) (xy 18.594322 -88.817783) (xy 18.586192 -88.869118) (xy 18.570131 -88.918548)
			(xy 18.546535 -88.964858) (xy 18.515985 -89.006906) (xy 18.479234 -89.043657) (xy 18.437186 -89.074207)
			(xy 18.390876 -89.097803) (xy 18.341446 -89.113864) (xy 18.290111 -89.121994) (xy 18.238137 -89.121994)
			(xy 18.186802 -89.113864) (xy 18.137372 -89.097803) (xy 18.091062 -89.074207) (xy 18.049014 -89.043657)
			(xy 18.012263 -89.006906) (xy 17.981713 -88.964858) (xy 17.958117 -88.918548) (xy 17.942056 -88.869118)
			(xy 17.933926 -88.817783) (xy 17.794452 -88.817783) (xy 17.786614 -88.868004) (xy 17.770995 -88.916778)
			(xy 17.759934 -88.939878) (xy 17.7546 -88.950546) (xy 17.7546 -89.433146) (xy 17.759934 -89.443814)
			(xy 17.770003 -89.464852) (xy 17.784786 -89.509089) (xy 17.789398 -89.531952) (xy 17.792446 -89.547446)
			(xy 18.0848 -89.8398) (xy 18.657316 -89.8398) (xy 18.671228 -89.839311) (xy 18.698013 -89.831773)
			(xy 18.721772 -89.817289) (xy 18.740742 -89.796931) (xy 18.753516 -89.772211) (xy 18.759147 -89.744962)
			(xy 18.757218 -89.717203) (xy 18.753074 -89.70391) (xy 18.743949 -89.67681) (xy 18.734108 -89.620485)
			(xy 18.733516 -89.591896) (xy 18.734026 -89.565909) (xy 18.742156 -89.514574) (xy 18.758217 -89.465144)
			(xy 18.781813 -89.418834) (xy 18.812363 -89.376786) (xy 18.849114 -89.340035) (xy 18.891162 -89.309485)
			(xy 18.937472 -89.285889) (xy 18.986902 -89.269828) (xy 19.038237 -89.261698) (xy 19.090211 -89.261698)
			(xy 19.141546 -89.269828) (xy 19.190976 -89.285889) (xy 19.237286 -89.309485) (xy 19.279334 -89.340035)
			(xy 19.316085 -89.376786) (xy 19.346635 -89.418834) (xy 19.370231 -89.465144) (xy 19.386292 -89.514574)
			(xy 19.394422 -89.565909) (xy 19.394932 -89.591896) (xy 19.394383 -89.617883) (xy 21.92452 -89.617883)
			(xy 21.92452 -89.565909) (xy 21.93265 -89.514574) (xy 21.948711 -89.465144) (xy 21.972307 -89.418834)
			(xy 22.002857 -89.376786) (xy 22.039608 -89.340035) (xy 22.081656 -89.309485) (xy 22.127966 -89.285889)
			(xy 22.177396 -89.269828) (xy 22.228731 -89.261698) (xy 22.280705 -89.261698) (xy 22.33204 -89.269828)
			(xy 22.38147 -89.285889) (xy 22.42778 -89.309485) (xy 22.469828 -89.340035) (xy 22.506579 -89.376786)
			(xy 22.537129 -89.418834) (xy 22.560725 -89.465144) (xy 22.576786 -89.514574) (xy 22.584916 -89.565909)
			(xy 22.585426 -89.591896) (xy 22.584916 -89.617883) (xy 22.724366 -89.617883) (xy 22.724366 -89.565909)
			(xy 22.732496 -89.514574) (xy 22.748557 -89.465144) (xy 22.772153 -89.418834) (xy 22.802703 -89.376786)
			(xy 22.839454 -89.340035) (xy 22.881502 -89.309485) (xy 22.927812 -89.285889) (xy 22.977242 -89.269828)
			(xy 23.028577 -89.261698) (xy 23.080551 -89.261698) (xy 23.131886 -89.269828) (xy 23.181316 -89.285889)
			(xy 23.227626 -89.309485) (xy 23.269674 -89.340035) (xy 23.306425 -89.376786) (xy 23.336975 -89.418834)
			(xy 23.360571 -89.465144) (xy 23.376632 -89.514574) (xy 23.384762 -89.565909) (xy 23.385272 -89.591896)
			(xy 23.384762 -89.617883) (xy 23.524466 -89.617883) (xy 23.524466 -89.565909) (xy 23.532596 -89.514574)
			(xy 23.548657 -89.465144) (xy 23.572253 -89.418834) (xy 23.602803 -89.376786) (xy 23.639554 -89.340035)
			(xy 23.681602 -89.309485) (xy 23.727912 -89.285889) (xy 23.777342 -89.269828) (xy 23.828677 -89.261698)
			(xy 23.880651 -89.261698) (xy 23.931986 -89.269828) (xy 23.981416 -89.285889) (xy 24.027726 -89.309485)
			(xy 24.069774 -89.340035) (xy 24.106525 -89.376786) (xy 24.137075 -89.418834) (xy 24.160671 -89.465144)
			(xy 24.176732 -89.514574) (xy 24.184862 -89.565909) (xy 24.185372 -89.591896) (xy 24.184862 -89.617883)
			(xy 24.176732 -89.669218) (xy 24.160671 -89.718648) (xy 24.137075 -89.764958) (xy 24.106525 -89.807006)
			(xy 24.069774 -89.843757) (xy 24.027726 -89.874307) (xy 23.981416 -89.897903) (xy 23.931986 -89.913964)
			(xy 23.880651 -89.922094) (xy 23.828677 -89.922094) (xy 23.777342 -89.913964) (xy 23.727912 -89.897903)
			(xy 23.681602 -89.874307) (xy 23.639554 -89.843757) (xy 23.602803 -89.807006) (xy 23.572253 -89.764958)
			(xy 23.548657 -89.718648) (xy 23.532596 -89.669218) (xy 23.524466 -89.617883) (xy 23.384762 -89.617883)
			(xy 23.376632 -89.669218) (xy 23.360571 -89.718648) (xy 23.336975 -89.764958) (xy 23.306425 -89.807006)
			(xy 23.269674 -89.843757) (xy 23.227626 -89.874307) (xy 23.181316 -89.897903) (xy 23.131886 -89.913964)
			(xy 23.080551 -89.922094) (xy 23.028577 -89.922094) (xy 22.977242 -89.913964) (xy 22.927812 -89.897903)
			(xy 22.881502 -89.874307) (xy 22.839454 -89.843757) (xy 22.802703 -89.807006) (xy 22.772153 -89.764958)
			(xy 22.748557 -89.718648) (xy 22.732496 -89.669218) (xy 22.724366 -89.617883) (xy 22.584916 -89.617883)
			(xy 22.576786 -89.669218) (xy 22.560725 -89.718648) (xy 22.537129 -89.764958) (xy 22.506579 -89.807006)
			(xy 22.469828 -89.843757) (xy 22.42778 -89.874307) (xy 22.38147 -89.897903) (xy 22.33204 -89.913964)
			(xy 22.280705 -89.922094) (xy 22.228731 -89.922094) (xy 22.177396 -89.913964) (xy 22.127966 -89.897903)
			(xy 22.081656 -89.874307) (xy 22.039608 -89.843757) (xy 22.002857 -89.807006) (xy 21.972307 -89.764958)
			(xy 21.948711 -89.718648) (xy 21.93265 -89.669218) (xy 21.92452 -89.617883) (xy 19.394383 -89.617883)
			(xy 19.394328 -89.620484) (xy 19.384497 -89.67681) (xy 19.375374 -89.70391) (xy 19.371078 -89.717172)
			(xy 19.369114 -89.744971) (xy 19.374739 -89.772265) (xy 19.387534 -89.797022) (xy 19.406546 -89.817397)
			(xy 19.430358 -89.831874) (xy 19.457198 -89.839373) (xy 19.471132 -89.8398) (xy 20.4978 -89.8398)
			(xy 20.724114 -90.066114) (xy 20.738338 -90.069416) (xy 20.763987 -90.075849) (xy 20.812976 -90.095752)
			(xy 20.858173 -90.123196) (xy 20.898427 -90.157483) (xy 20.932712 -90.197739) (xy 20.960155 -90.242937)
			(xy 20.980056 -90.291926) (xy 20.986496 -90.317574) (xy 20.989798 -90.331798) (xy 21.082 -90.424)
			(xy 21.082 -91.3384) (xy 22.1234 -92.3798) (xy 22.4028 -92.3798)
		)
		(stroke
			(width 0)
			(type solid)
		)
		(fill yes)
		(layer "In7.Cu")
		(net "VCCIO0")
	)
	(gr_poly
		(pts
			(xy 45.429424 -65.09893) (xy 45.397166 -65.063116) (xy 45.378848 -65.042005) (xy 45.347947 -64.995431)
			(xy 45.324171 -64.944848) (xy 45.308026 -64.891339) (xy 45.29986 -64.836046) (xy 45.299376 -64.8081)
			(xy 45.299862 -64.780848) (xy 45.307618 -64.7269) (xy 45.322973 -64.674604) (xy 45.345614 -64.625026)
			(xy 45.37508 -64.579174) (xy 45.410771 -64.537983) (xy 45.451961 -64.50229) (xy 45.497812 -64.472822)
			(xy 45.547389 -64.450179) (xy 45.599684 -64.434822) (xy 45.653632 -64.427063) (xy 45.680884 -64.426592)
			(xy 45.708943 -64.427088) (xy 45.764454 -64.435309) (xy 45.818162 -64.451574) (xy 45.868907 -64.475534)
			(xy 45.915593 -64.506671) (xy 45.957213 -64.544313) (xy 45.992869 -64.587647) (xy 46.021789 -64.635737)
			(xy 46.043351 -64.687546) (xy 46.050708 -64.714628) (xy 46.05438 -64.727551) (xy 46.067502 -64.750983)
			(xy 46.086288 -64.770175) (xy 46.109435 -64.783795) (xy 46.135336 -64.790895) (xy 46.162192 -64.790984)
			(xy 46.18814 -64.784056) (xy 46.211377 -64.770591) (xy 46.221142 -64.761364) (xy 46.281594 -64.700912)
			(xy 46.281594 -64.694816) (xy 46.555914 -64.420496) (xy 46.555914 -55.323486) (xy 47.470314 -54.409086)
			(xy 47.441866 -54.373526) (xy 47.424795 -54.351347) (xy 47.397581 -54.302445) (xy 47.378989 -54.24966)
			(xy 47.369549 -54.194498) (xy 47.368968 -54.166516) (xy 47.369476 -54.140527) (xy 47.377605 -54.089189)
			(xy 47.393664 -54.039755) (xy 47.417259 -53.993442) (xy 47.447808 -53.951389) (xy 47.484559 -53.914634)
			(xy 47.526608 -53.88408) (xy 47.572918 -53.860479) (xy 47.622351 -53.844414) (xy 47.673687 -53.836279)
			(xy 47.699676 -53.835808) (xy 47.727658 -53.836394) (xy 47.782823 -53.845822) (xy 47.83561 -53.864411)
			(xy 47.884509 -53.891631) (xy 47.906686 -53.908706) (xy 47.942246 -53.937154) (xy 48.24222 -53.63718)
			(xy 48.58766 -53.63718) (xy 48.70958 -53.51526) (xy 48.70958 -52.43068) (xy 48.538892 -52.259992)
			(xy 47.930562 -52.259992) (xy 47.605442 -51.934872) (xy 47.184564 -51.934872) (xy 47.170673 -51.957315)
			(xy 47.13691 -51.99788) (xy 47.097136 -52.032572) (xy 47.05236 -52.060511) (xy 47.003717 -52.080989)
			(xy 46.95244 -52.093488) (xy 46.89983 -52.097689) (xy 46.84722 -52.093488) (xy 46.795943 -52.080989)
			(xy 46.7473 -52.060511) (xy 46.702524 -52.032572) (xy 46.66275 -51.99788) (xy 46.628987 -51.957315)
			(xy 46.615096 -51.934872) (xy 46.384464 -51.934872) (xy 46.371592 -51.955723) (xy 46.340668 -51.993732)
			(xy 46.304478 -52.026768) (xy 46.263814 -52.054108) (xy 46.219564 -52.075154) (xy 46.172694 -52.089448)
			(xy 46.12423 -52.096676) (xy 46.09973 -52.097178) (xy 46.074565 -52.096683) (xy 46.024822 -52.089024)
			(xy 46.00067 -52.081938) (xy 45.971206 -52.072794) (xy 45.606208 -52.437792) (xy 45.615352 -52.467256)
			(xy 45.622471 -52.491465) (xy 45.630117 -52.54134) (xy 45.630592 -52.56657) (xy 45.630111 -52.592557)
			(xy 45.769532 -52.592557) (xy 45.769532 -52.540583) (xy 45.777662 -52.489248) (xy 45.793723 -52.439818)
			(xy 45.817319 -52.393508) (xy 45.847869 -52.35146) (xy 45.88462 -52.314709) (xy 45.926668 -52.284159)
			(xy 45.972978 -52.260563) (xy 46.022408 -52.244502) (xy 46.073743 -52.236372) (xy 46.125717 -52.236372)
			(xy 46.177052 -52.244502) (xy 46.226482 -52.260563) (xy 46.272792 -52.284159) (xy 46.31484 -52.314709)
			(xy 46.351591 -52.35146) (xy 46.382141 -52.393508) (xy 46.405737 -52.439818) (xy 46.421798 -52.489248)
			(xy 46.429928 -52.540583) (xy 46.430438 -52.56657) (xy 46.429928 -52.592557) (xy 46.569632 -52.592557)
			(xy 46.569632 -52.540583) (xy 46.577762 -52.489248) (xy 46.593823 -52.439818) (xy 46.617419 -52.393508)
			(xy 46.647969 -52.35146) (xy 46.68472 -52.314709) (xy 46.726768 -52.284159) (xy 46.773078 -52.260563)
			(xy 46.822508 -52.244502) (xy 46.873843 -52.236372) (xy 46.925817 -52.236372) (xy 46.977152 -52.244502)
			(xy 47.026582 -52.260563) (xy 47.072892 -52.284159) (xy 47.11494 -52.314709) (xy 47.151691 -52.35146)
			(xy 47.182241 -52.393508) (xy 47.205837 -52.439818) (xy 47.221898 -52.489248) (xy 47.230028 -52.540583)
			(xy 47.230538 -52.56657) (xy 47.230028 -52.592557) (xy 47.221898 -52.643892) (xy 47.205837 -52.693322)
			(xy 47.182241 -52.739632) (xy 47.151691 -52.78168) (xy 47.11494 -52.818431) (xy 47.072892 -52.848981)
			(xy 47.026582 -52.872577) (xy 46.977152 -52.888638) (xy 46.925817 -52.896768) (xy 46.873843 -52.896768)
			(xy 46.822508 -52.888638) (xy 46.773078 -52.872577) (xy 46.726768 -52.848981) (xy 46.68472 -52.818431)
			(xy 46.647969 -52.78168) (xy 46.617419 -52.739632) (xy 46.593823 -52.693322) (xy 46.577762 -52.643892)
			(xy 46.569632 -52.592557) (xy 46.429928 -52.592557) (xy 46.421798 -52.643892) (xy 46.405737 -52.693322)
			(xy 46.382141 -52.739632) (xy 46.351591 -52.78168) (xy 46.31484 -52.818431) (xy 46.272792 -52.848981)
			(xy 46.226482 -52.872577) (xy 46.177052 -52.888638) (xy 46.125717 -52.896768) (xy 46.073743 -52.896768)
			(xy 46.022408 -52.888638) (xy 45.972978 -52.872577) (xy 45.926668 -52.848981) (xy 45.88462 -52.818431)
			(xy 45.847869 -52.78168) (xy 45.817319 -52.739632) (xy 45.793723 -52.693322) (xy 45.777662 -52.643892)
			(xy 45.769532 -52.592557) (xy 45.630111 -52.592557) (xy 45.630111 -52.59256) (xy 45.621983 -52.643902)
			(xy 45.605924 -52.693339) (xy 45.582327 -52.739655) (xy 45.551775 -52.78171) (xy 45.51502 -52.818466)
			(xy 45.472967 -52.84902) (xy 45.426652 -52.872618) (xy 45.377215 -52.88868) (xy 45.325874 -52.89681)
			(xy 45.299884 -52.897278) (xy 45.274656 -52.896798) (xy 45.224783 -52.88914) (xy 45.20057 -52.882038)
			(xy 45.171106 -52.872894) (xy 44.806108 -53.237892) (xy 44.815252 -53.267356) (xy 44.822359 -53.291502)
			(xy 44.830007 -53.34125) (xy 44.830492 -53.366416) (xy 44.829949 -53.392403) (xy 44.969686 -53.392403)
			(xy 44.969686 -53.340429) (xy 44.977816 -53.289094) (xy 44.993877 -53.239664) (xy 45.017473 -53.193354)
			(xy 45.048023 -53.151306) (xy 45.084774 -53.114555) (xy 45.126822 -53.084005) (xy 45.173132 -53.060409)
			(xy 45.222562 -53.044348) (xy 45.273897 -53.036218) (xy 45.325871 -53.036218) (xy 45.377206 -53.044348)
			(xy 45.426636 -53.060409) (xy 45.472946 -53.084005) (xy 45.514994 -53.114555) (xy 45.551745 -53.151306)
			(xy 45.582295 -53.193354) (xy 45.605891 -53.239664) (xy 45.621952 -53.289094) (xy 45.630082 -53.340429)
			(xy 45.630592 -53.366416) (xy 45.630082 -53.392403) (xy 46.569632 -53.392403) (xy 46.569632 -53.340429)
			(xy 46.577762 -53.289094) (xy 46.593823 -53.239664) (xy 46.617419 -53.193354) (xy 46.647969 -53.151306)
			(xy 46.68472 -53.114555) (xy 46.726768 -53.084005) (xy 46.773078 -53.060409) (xy 46.822508 -53.044348)
			(xy 46.873843 -53.036218) (xy 46.925817 -53.036218) (xy 46.977152 -53.044348) (xy 47.026582 -53.060409)
			(xy 47.072892 -53.084005) (xy 47.11494 -53.114555) (xy 47.151691 -53.151306) (xy 47.182241 -53.193354)
			(xy 47.205837 -53.239664) (xy 47.221898 -53.289094) (xy 47.230028 -53.340429) (xy 47.230538 -53.366416)
			(xy 47.230028 -53.392403) (xy 47.369478 -53.392403) (xy 47.369478 -53.340429) (xy 47.377608 -53.289094)
			(xy 47.393669 -53.239664) (xy 47.417265 -53.193354) (xy 47.447815 -53.151306) (xy 47.484566 -53.114555)
			(xy 47.526614 -53.084005) (xy 47.572924 -53.060409) (xy 47.622354 -53.044348) (xy 47.673689 -53.036218)
			(xy 47.725663 -53.036218) (xy 47.776998 -53.044348) (xy 47.826428 -53.060409) (xy 47.872738 -53.084005)
			(xy 47.914786 -53.114555) (xy 47.951537 -53.151306) (xy 47.982087 -53.193354) (xy 48.005683 -53.239664)
			(xy 48.021744 -53.289094) (xy 48.029874 -53.340429) (xy 48.030384 -53.366416) (xy 48.029874 -53.392403)
			(xy 48.021744 -53.443738) (xy 48.005683 -53.493168) (xy 47.982087 -53.539478) (xy 47.951537 -53.581526)
			(xy 47.914786 -53.618277) (xy 47.872738 -53.648827) (xy 47.826428 -53.672423) (xy 47.776998 -53.688484)
			(xy 47.725663 -53.696614) (xy 47.673689 -53.696614) (xy 47.622354 -53.688484) (xy 47.572924 -53.672423)
			(xy 47.526614 -53.648827) (xy 47.484566 -53.618277) (xy 47.447815 -53.581526) (xy 47.417265 -53.539478)
			(xy 47.393669 -53.493168) (xy 47.377608 -53.443738) (xy 47.369478 -53.392403) (xy 47.230028 -53.392403)
			(xy 47.221898 -53.443738) (xy 47.205837 -53.493168) (xy 47.182241 -53.539478) (xy 47.151691 -53.581526)
			(xy 47.11494 -53.618277) (xy 47.072892 -53.648827) (xy 47.026582 -53.672423) (xy 46.977152 -53.688484)
			(xy 46.925817 -53.696614) (xy 46.873843 -53.696614) (xy 46.822508 -53.688484) (xy 46.773078 -53.672423)
			(xy 46.726768 -53.648827) (xy 46.68472 -53.618277) (xy 46.647969 -53.581526) (xy 46.617419 -53.539478)
			(xy 46.593823 -53.493168) (xy 46.577762 -53.443738) (xy 46.569632 -53.392403) (xy 45.630082 -53.392403)
			(xy 45.621952 -53.443738) (xy 45.605891 -53.493168) (xy 45.582295 -53.539478) (xy 45.551745 -53.581526)
			(xy 45.514994 -53.618277) (xy 45.472946 -53.648827) (xy 45.426636 -53.672423) (xy 45.377206 -53.688484)
			(xy 45.325871 -53.696614) (xy 45.273897 -53.696614) (xy 45.222562 -53.688484) (xy 45.173132 -53.672423)
			(xy 45.126822 -53.648827) (xy 45.084774 -53.618277) (xy 45.048023 -53.581526) (xy 45.017473 -53.539478)
			(xy 44.993877 -53.493168) (xy 44.977816 -53.443738) (xy 44.969686 -53.392403) (xy 44.829949 -53.392403)
			(xy 44.829878 -53.395814) (xy 44.819531 -53.45369) (xy 44.809918 -53.481478) (xy 44.806616 -53.490114)
			(xy 44.806616 -54.042818) (xy 44.809918 -54.051454) (xy 44.819523 -54.079244) (xy 44.82987 -54.137119)
			(xy 44.830492 -54.166516) (xy 44.829949 -54.192503) (xy 44.969686 -54.192503) (xy 44.969686 -54.140529)
			(xy 44.977816 -54.089194) (xy 44.993877 -54.039764) (xy 45.017473 -53.993454) (xy 45.048023 -53.951406)
			(xy 45.084774 -53.914655) (xy 45.126822 -53.884105) (xy 45.173132 -53.860509) (xy 45.222562 -53.844448)
			(xy 45.273897 -53.836318) (xy 45.325871 -53.836318) (xy 45.377206 -53.844448) (xy 45.426636 -53.860509)
			(xy 45.472946 -53.884105) (xy 45.514994 -53.914655) (xy 45.551745 -53.951406) (xy 45.582295 -53.993454)
			(xy 45.605891 -54.039764) (xy 45.621952 -54.089194) (xy 45.630082 -54.140529) (xy 45.630592 -54.166516)
			(xy 45.630082 -54.192503) (xy 46.569632 -54.192503) (xy 46.569632 -54.140529) (xy 46.577762 -54.089194)
			(xy 46.593823 -54.039764) (xy 46.617419 -53.993454) (xy 46.647969 -53.951406) (xy 46.68472 -53.914655)
			(xy 46.726768 -53.884105) (xy 46.773078 -53.860509) (xy 46.822508 -53.844448) (xy 46.873843 -53.836318)
			(xy 46.925817 -53.836318) (xy 46.977152 -53.844448) (xy 47.026582 -53.860509) (xy 47.072892 -53.884105)
			(xy 47.11494 -53.914655) (xy 47.151691 -53.951406) (xy 47.182241 -53.993454) (xy 47.205837 -54.039764)
			(xy 47.221898 -54.089194) (xy 47.230028 -54.140529) (xy 47.230538 -54.166516) (xy 47.230028 -54.192503)
			(xy 47.221898 -54.243838) (xy 47.205837 -54.293268) (xy 47.182241 -54.339578) (xy 47.151691 -54.381626)
			(xy 47.11494 -54.418377) (xy 47.072892 -54.448927) (xy 47.026582 -54.472523) (xy 46.977152 -54.488584)
			(xy 46.925817 -54.496714) (xy 46.873843 -54.496714) (xy 46.822508 -54.488584) (xy 46.773078 -54.472523)
			(xy 46.726768 -54.448927) (xy 46.68472 -54.418377) (xy 46.647969 -54.381626) (xy 46.617419 -54.339578)
			(xy 46.593823 -54.293268) (xy 46.577762 -54.243838) (xy 46.569632 -54.192503) (xy 45.630082 -54.192503)
			(xy 45.621952 -54.243838) (xy 45.605891 -54.293268) (xy 45.582295 -54.339578) (xy 45.551745 -54.381626)
			(xy 45.514994 -54.418377) (xy 45.472946 -54.448927) (xy 45.426636 -54.472523) (xy 45.377206 -54.488584)
			(xy 45.325871 -54.496714) (xy 45.273897 -54.496714) (xy 45.222562 -54.488584) (xy 45.173132 -54.472523)
			(xy 45.126822 -54.448927) (xy 45.084774 -54.418377) (xy 45.048023 -54.381626) (xy 45.017473 -54.339578)
			(xy 44.993877 -54.293268) (xy 44.977816 -54.243838) (xy 44.969686 -54.192503) (xy 44.829949 -54.192503)
			(xy 44.829878 -54.195914) (xy 44.819531 -54.25379) (xy 44.809918 -54.281578) (xy 44.806616 -54.290214)
			(xy 44.806616 -54.727094) (xy 44.972478 -54.892702) (xy 44.989249 -54.910142) (xy 45.017689 -54.949283)
			(xy 45.039635 -54.992349) (xy 45.769532 -54.992349) (xy 45.769532 -54.940375) (xy 45.777662 -54.88904)
			(xy 45.793723 -54.83961) (xy 45.817319 -54.7933) (xy 45.847869 -54.751252) (xy 45.88462 -54.714501)
			(xy 45.926668 -54.683951) (xy 45.972978 -54.660355) (xy 46.022408 -54.644294) (xy 46.073743 -54.636164)
			(xy 46.125717 -54.636164) (xy 46.177052 -54.644294) (xy 46.226482 -54.660355) (xy 46.272792 -54.683951)
			(xy 46.31484 -54.714501) (xy 46.351591 -54.751252) (xy 46.382141 -54.7933) (xy 46.405737 -54.83961)
			(xy 46.421798 -54.88904) (xy 46.429928 -54.940375) (xy 46.430438 -54.966362) (xy 46.429928 -54.992349)
			(xy 46.421798 -55.043684) (xy 46.405737 -55.093114) (xy 46.382141 -55.139424) (xy 46.351591 -55.181472)
			(xy 46.31484 -55.218223) (xy 46.272792 -55.248773) (xy 46.226482 -55.272369) (xy 46.177052 -55.28843)
			(xy 46.125717 -55.29656) (xy 46.073743 -55.29656) (xy 46.022408 -55.28843) (xy 45.972978 -55.272369)
			(xy 45.926668 -55.248773) (xy 45.88462 -55.218223) (xy 45.847869 -55.181472) (xy 45.817319 -55.139424)
			(xy 45.793723 -55.093114) (xy 45.777662 -55.043684) (xy 45.769532 -54.992349) (xy 45.039635 -54.992349)
			(xy 45.039656 -54.99239) (xy 45.05461 -55.038403) (xy 45.062181 -55.086189) (xy 45.062648 -55.11038)
			(xy 45.062648 -55.792449) (xy 45.769532 -55.792449) (xy 45.769532 -55.740475) (xy 45.777662 -55.68914)
			(xy 45.793723 -55.63971) (xy 45.817319 -55.5934) (xy 45.847869 -55.551352) (xy 45.88462 -55.514601)
			(xy 45.926668 -55.484051) (xy 45.972978 -55.460455) (xy 46.022408 -55.444394) (xy 46.073743 -55.436264)
			(xy 46.125717 -55.436264) (xy 46.177052 -55.444394) (xy 46.226482 -55.460455) (xy 46.272792 -55.484051)
			(xy 46.31484 -55.514601) (xy 46.351591 -55.551352) (xy 46.382141 -55.5934) (xy 46.405737 -55.63971)
			(xy 46.421798 -55.68914) (xy 46.429928 -55.740475) (xy 46.430438 -55.766462) (xy 46.429928 -55.792449)
			(xy 46.421798 -55.843784) (xy 46.405737 -55.893214) (xy 46.382141 -55.939524) (xy 46.351591 -55.981572)
			(xy 46.31484 -56.018323) (xy 46.272792 -56.048873) (xy 46.226482 -56.072469) (xy 46.177052 -56.08853)
			(xy 46.125717 -56.09666) (xy 46.073743 -56.09666) (xy 46.022408 -56.08853) (xy 45.972978 -56.072469)
			(xy 45.926668 -56.048873) (xy 45.88462 -56.018323) (xy 45.847869 -55.981572) (xy 45.817319 -55.939524)
			(xy 45.793723 -55.893214) (xy 45.777662 -55.843784) (xy 45.769532 -55.792449) (xy 45.062648 -55.792449)
			(xy 45.062648 -55.8546) (xy 45.062174 -55.878791) (xy 45.054605 -55.926577) (xy 45.039654 -55.97259)
			(xy 45.017689 -56.015699) (xy 44.989251 -56.05484) (xy 44.972478 -56.072278) (xy 44.910248 -56.134508)
			(xy 44.910248 -56.592549) (xy 45.769532 -56.592549) (xy 45.769532 -56.540575) (xy 45.777662 -56.48924)
			(xy 45.793723 -56.43981) (xy 45.817319 -56.3935) (xy 45.847869 -56.351452) (xy 45.88462 -56.314701)
			(xy 45.926668 -56.284151) (xy 45.972978 -56.260555) (xy 46.022408 -56.244494) (xy 46.073743 -56.236364)
			(xy 46.125717 -56.236364) (xy 46.177052 -56.244494) (xy 46.226482 -56.260555) (xy 46.272792 -56.284151)
			(xy 46.31484 -56.314701) (xy 46.351591 -56.351452) (xy 46.382141 -56.3935) (xy 46.405737 -56.43981)
			(xy 46.421798 -56.48924) (xy 46.429928 -56.540575) (xy 46.430438 -56.566562) (xy 46.429928 -56.592549)
			(xy 46.421798 -56.643884) (xy 46.405737 -56.693314) (xy 46.382141 -56.739624) (xy 46.351591 -56.781672)
			(xy 46.31484 -56.818423) (xy 46.272792 -56.848973) (xy 46.226482 -56.872569) (xy 46.177052 -56.88863)
			(xy 46.125717 -56.89676) (xy 46.073743 -56.89676) (xy 46.022408 -56.88863) (xy 45.972978 -56.872569)
			(xy 45.926668 -56.848973) (xy 45.88462 -56.818423) (xy 45.847869 -56.781672) (xy 45.817319 -56.739624)
			(xy 45.793723 -56.693314) (xy 45.777662 -56.643884) (xy 45.769532 -56.592549) (xy 44.910248 -56.592549)
			(xy 44.910248 -57.044082) (xy 44.910713 -57.058714) (xy 44.918987 -57.086784) (xy 44.934888 -57.11135)
			(xy 44.957109 -57.130391) (xy 44.983821 -57.142342) (xy 45.012826 -57.146219) (xy 45.041739 -57.141703)
			(xy 45.068181 -57.129165) (xy 45.079412 -57.119774) (xy 45.09771 -57.104027) (xy 45.138012 -57.077451)
			(xy 45.181745 -57.05701) (xy 45.227984 -57.043136) (xy 45.275747 -57.036123) (xy 45.299884 -57.0357)
			(xy 45.325873 -57.036182) (xy 45.377213 -57.044311) (xy 45.426648 -57.060371) (xy 45.472962 -57.083968)
			(xy 45.515015 -57.114519) (xy 45.551771 -57.151273) (xy 45.582324 -57.193324) (xy 45.605922 -57.239637)
			(xy 45.621985 -57.289072) (xy 45.630117 -57.340411) (xy 45.630117 -57.392389) (xy 45.630116 -57.392395)
			(xy 45.769532 -57.392395) (xy 45.769532 -57.340421) (xy 45.777662 -57.289086) (xy 45.793723 -57.239656)
			(xy 45.817319 -57.193346) (xy 45.847869 -57.151298) (xy 45.88462 -57.114547) (xy 45.926668 -57.083997)
			(xy 45.972978 -57.060401) (xy 46.022408 -57.04434) (xy 46.073743 -57.03621) (xy 46.125717 -57.03621)
			(xy 46.177052 -57.04434) (xy 46.226482 -57.060401) (xy 46.272792 -57.083997) (xy 46.31484 -57.114547)
			(xy 46.351591 -57.151298) (xy 46.382141 -57.193346) (xy 46.405737 -57.239656) (xy 46.421798 -57.289086)
			(xy 46.429928 -57.340421) (xy 46.430438 -57.366408) (xy 46.429928 -57.392395) (xy 46.421798 -57.44373)
			(xy 46.405737 -57.49316) (xy 46.382141 -57.53947) (xy 46.351591 -57.581518) (xy 46.31484 -57.618269)
			(xy 46.272792 -57.648819) (xy 46.226482 -57.672415) (xy 46.177052 -57.688476) (xy 46.125717 -57.696606)
			(xy 46.073743 -57.696606) (xy 46.022408 -57.688476) (xy 45.972978 -57.672415) (xy 45.926668 -57.648819)
			(xy 45.88462 -57.618269) (xy 45.847869 -57.581518) (xy 45.817319 -57.53947) (xy 45.793723 -57.49316)
			(xy 45.777662 -57.44373) (xy 45.769532 -57.392395) (xy 45.630116 -57.392395) (xy 45.621985 -57.443728)
			(xy 45.605922 -57.493163) (xy 45.582324 -57.539476) (xy 45.551771 -57.581527) (xy 45.515015 -57.618281)
			(xy 45.472962 -57.648832) (xy 45.426648 -57.672429) (xy 45.377213 -57.688489) (xy 45.325873 -57.696618)
			(xy 45.299884 -57.697116) (xy 45.274759 -57.696648) (xy 45.225086 -57.689048) (xy 45.177134 -57.674025)
			(xy 45.132004 -57.651925) (xy 45.090734 -57.623256) (xy 45.054274 -57.588676) (xy 45.038518 -57.5691)
			(xy 45.029359 -57.558168) (xy 45.006274 -57.54144) (xy 44.979468 -57.531735) (xy 44.951024 -57.529807)
			(xy 44.923154 -57.535807) (xy 44.898024 -57.549268) (xy 44.877585 -57.569143) (xy 44.870116 -57.581292)
			(xy 44.857153 -57.603048) (xy 44.825245 -57.64237) (xy 44.806616 -57.659524) (xy 44.806616 -58.04281)
			(xy 44.809918 -58.051446) (xy 44.819524 -58.079236) (xy 44.829872 -58.137111) (xy 44.830492 -58.166508)
			(xy 44.82995 -58.192495) (xy 44.969686 -58.192495) (xy 44.969686 -58.140521) (xy 44.977816 -58.089186)
			(xy 44.993877 -58.039756) (xy 45.017473 -57.993446) (xy 45.048023 -57.951398) (xy 45.084774 -57.914647)
			(xy 45.126822 -57.884097) (xy 45.173132 -57.860501) (xy 45.222562 -57.84444) (xy 45.273897 -57.83631)
			(xy 45.325871 -57.83631) (xy 45.377206 -57.84444) (xy 45.426636 -57.860501) (xy 45.472946 -57.884097)
			(xy 45.514994 -57.914647) (xy 45.551745 -57.951398) (xy 45.582295 -57.993446) (xy 45.605891 -58.039756)
			(xy 45.621952 -58.089186) (xy 45.630082 -58.140521) (xy 45.630592 -58.166508) (xy 45.630082 -58.192495)
			(xy 45.769532 -58.192495) (xy 45.769532 -58.140521) (xy 45.777662 -58.089186) (xy 45.793723 -58.039756)
			(xy 45.817319 -57.993446) (xy 45.847869 -57.951398) (xy 45.88462 -57.914647) (xy 45.926668 -57.884097)
			(xy 45.972978 -57.860501) (xy 46.022408 -57.84444) (xy 46.073743 -57.83631) (xy 46.125717 -57.83631)
			(xy 46.177052 -57.84444) (xy 46.226482 -57.860501) (xy 46.272792 -57.884097) (xy 46.31484 -57.914647)
			(xy 46.351591 -57.951398) (xy 46.382141 -57.993446) (xy 46.405737 -58.039756) (xy 46.421798 -58.089186)
			(xy 46.429928 -58.140521) (xy 46.430438 -58.166508) (xy 46.429928 -58.192495) (xy 46.421798 -58.24383)
			(xy 46.405737 -58.29326) (xy 46.382141 -58.33957) (xy 46.351591 -58.381618) (xy 46.31484 -58.418369)
			(xy 46.272792 -58.448919) (xy 46.226482 -58.472515) (xy 46.177052 -58.488576) (xy 46.125717 -58.496706)
			(xy 46.073743 -58.496706) (xy 46.022408 -58.488576) (xy 45.972978 -58.472515) (xy 45.926668 -58.448919)
			(xy 45.88462 -58.418369) (xy 45.847869 -58.381618) (xy 45.817319 -58.33957) (xy 45.793723 -58.29326)
			(xy 45.777662 -58.24383) (xy 45.769532 -58.192495) (xy 45.630082 -58.192495) (xy 45.621952 -58.24383)
			(xy 45.605891 -58.29326) (xy 45.582295 -58.33957) (xy 45.551745 -58.381618) (xy 45.514994 -58.418369)
			(xy 45.472946 -58.448919) (xy 45.426636 -58.472515) (xy 45.377206 -58.488576) (xy 45.325871 -58.496706)
			(xy 45.273897 -58.496706) (xy 45.222562 -58.488576) (xy 45.173132 -58.472515) (xy 45.126822 -58.448919)
			(xy 45.084774 -58.418369) (xy 45.048023 -58.381618) (xy 45.017473 -58.33957) (xy 44.993877 -58.29326)
			(xy 44.977816 -58.24383) (xy 44.969686 -58.192495) (xy 44.82995 -58.192495) (xy 44.829879 -58.195906)
			(xy 44.819533 -58.253782) (xy 44.809918 -58.28157) (xy 44.806616 -58.290206) (xy 44.806616 -60.701428)
			(xy 44.825514 -60.722675) (xy 44.857447 -60.769721) (xy 44.882039 -60.820989) (xy 44.898743 -60.87534)
			(xy 44.907189 -60.93157) (xy 44.907189 -60.98843) (xy 44.898743 -61.04466) (xy 44.882039 -61.099011)
			(xy 44.857447 -61.150279) (xy 44.825514 -61.197325) (xy 44.806616 -61.218572) (xy 44.806616 -62.470538)
			(xy 44.479464 -62.79769) (xy 44.468996 -62.808871) (xy 44.454709 -62.835947) (xy 44.449095 -62.866043)
			(xy 44.452658 -62.896449) (xy 44.465079 -62.924431) (xy 44.485239 -62.94747) (xy 44.498006 -62.955932)
			(xy 44.521354 -62.97093) (xy 44.563854 -63.00661) (xy 44.600737 -63.048071) (xy 44.631225 -63.094438)
			(xy 44.654674 -63.144732) (xy 44.67059 -63.197893) (xy 44.678636 -63.252798) (xy 44.679108 -63.280544)
			(xy 44.678689 -63.306864) (xy 44.671494 -63.359009) (xy 44.65719 -63.409667) (xy 44.636051 -63.457875)
			(xy 44.608478 -63.502714) (xy 44.574997 -63.543333) (xy 44.555918 -63.561468) (xy 44.545902 -63.571279)
			(xy 44.531214 -63.595148) (xy 44.523585 -63.622116) (xy 44.523594 -63.650143) (xy 44.531238 -63.677107)
			(xy 44.545941 -63.700967) (xy 44.555918 -63.71082) (xy 44.574979 -63.72897) (xy 44.608435 -63.769601)
			(xy 44.635993 -63.814443) (xy 44.65713 -63.862645) (xy 44.671446 -63.913293) (xy 44.678669 -63.965428)
			(xy 44.679108 -63.991744) (xy 44.678619 -64.018993) (xy 44.670858 -64.072936) (xy 44.655499 -64.125226)
			(xy 44.632855 -64.174797) (xy 44.603388 -64.220642) (xy 44.567696 -64.261827) (xy 44.526507 -64.297514)
			(xy 44.480659 -64.326976) (xy 44.431084 -64.349614) (xy 44.378793 -64.364967) (xy 44.324849 -64.372722)
			(xy 44.2976 -64.373252) (xy 44.271292 -64.372817) (xy 44.219175 -64.365597) (xy 44.168545 -64.351282)
			(xy 44.120364 -64.330142) (xy 44.075546 -64.302578) (xy 44.034943 -64.269116) (xy 43.999326 -64.230389)
			(xy 43.969371 -64.187133) (xy 43.945647 -64.140171) (xy 43.928604 -64.090392) (xy 43.923204 -64.064642)
			(xy 43.920156 -64.049402) (xy 43.799506 -63.928752) (xy 43.789116 -63.919033) (xy 43.764243 -63.905249)
			(xy 43.736534 -63.898848) (xy 43.708135 -63.900327) (xy 43.681241 -63.909571) (xy 43.657934 -63.925865)
			(xy 43.64863 -63.936626) (xy 43.628564 -63.958978) (xy 43.412156 -64.175386) (xy 43.412156 -64.71031)
			(xy 43.680126 -64.978534) (xy 43.684444 -64.982852) (xy 43.693334 -64.991996) (xy 43.694096 -64.993012)
			(xy 43.97629 -65.274952) (xy 45.253402 -65.274952)
		)
		(stroke
			(width 0)
			(type solid)
		)
		(fill yes)
		(layer "In7.Cu")
		(net "P1V2_P1V0_I3C_VDDL1")
	)
	(gr_poly
		(pts
			(xy 68.473828 -57.459372) (xy 68.473828 -57.196228) (xy 68.49618 -57.173876) (xy 68.49618 -56.065928)
			(xy 68.255134 -55.824882) (xy 65.617852 -55.824882) (xy 65.607184 -55.861204) (xy 65.599083 -55.886421)
			(xy 65.575993 -55.934084) (xy 65.545607 -55.977462) (xy 65.508699 -56.015446) (xy 65.466213 -56.047066)
			(xy 65.419233 -56.071516) (xy 65.368958 -56.088172) (xy 65.316673 -56.096607) (xy 65.263711 -56.096607)
			(xy 65.211426 -56.088172) (xy 65.161151 -56.071516) (xy 65.114171 -56.047066) (xy 65.071685 -56.015446)
			(xy 65.034777 -55.977462) (xy 65.004391 -55.934084) (xy 64.981301 -55.886421) (xy 64.9732 -55.861204)
			(xy 64.962532 -55.824882) (xy 64.817752 -55.824882) (xy 64.807084 -55.861204) (xy 64.798983 -55.886421)
			(xy 64.775893 -55.934084) (xy 64.745507 -55.977462) (xy 64.708599 -56.015446) (xy 64.666113 -56.047066)
			(xy 64.619133 -56.071516) (xy 64.568858 -56.088172) (xy 64.516573 -56.096607) (xy 64.463611 -56.096607)
			(xy 64.411326 -56.088172) (xy 64.361051 -56.071516) (xy 64.314071 -56.047066) (xy 64.271585 -56.015446)
			(xy 64.234677 -55.977462) (xy 64.204291 -55.934084) (xy 64.181201 -55.886421) (xy 64.1731 -55.861204)
			(xy 64.162432 -55.824882) (xy 64.017906 -55.824882) (xy 64.007238 -55.861204) (xy 63.999137 -55.886421)
			(xy 63.976047 -55.934084) (xy 63.945661 -55.977462) (xy 63.908753 -56.015446) (xy 63.866267 -56.047066)
			(xy 63.819287 -56.071516) (xy 63.769012 -56.088172) (xy 63.716727 -56.096607) (xy 63.663765 -56.096607)
			(xy 63.61148 -56.088172) (xy 63.561205 -56.071516) (xy 63.514225 -56.047066) (xy 63.471739 -56.015446)
			(xy 63.434831 -55.977462) (xy 63.404445 -55.934084) (xy 63.381355 -55.886421) (xy 63.373254 -55.861204)
			(xy 63.362586 -55.824882) (xy 60.81776 -55.824882) (xy 60.807092 -55.861204) (xy 60.798991 -55.886421)
			(xy 60.775901 -55.934084) (xy 60.745515 -55.977462) (xy 60.708607 -56.015446) (xy 60.666121 -56.047066)
			(xy 60.619141 -56.071516) (xy 60.568866 -56.088172) (xy 60.516581 -56.096607) (xy 60.463619 -56.096607)
			(xy 60.411334 -56.088172) (xy 60.361059 -56.071516) (xy 60.314079 -56.047066) (xy 60.271593 -56.015446)
			(xy 60.234685 -55.977462) (xy 60.204299 -55.934084) (xy 60.181209 -55.886421) (xy 60.173108 -55.861204)
			(xy 60.16244 -55.824882) (xy 60.017914 -55.824882) (xy 60.007246 -55.861204) (xy 59.99914 -55.886417)
			(xy 59.976042 -55.934071) (xy 59.945651 -55.97744) (xy 59.908742 -56.015417) (xy 59.866258 -56.047033)
			(xy 59.819282 -56.071481) (xy 59.769013 -56.088138) (xy 59.716733 -56.096578) (xy 59.690254 -56.09717)
			(xy 59.66427 -56.096656) (xy 59.612944 -56.08852) (xy 59.563522 -56.072454) (xy 59.517222 -56.048856)
			(xy 59.475183 -56.018304) (xy 59.438441 -55.981553) (xy 59.4079 -55.939507) (xy 59.384313 -55.8932)
			(xy 59.36826 -55.843775) (xy 59.360137 -55.792446) (xy 59.359546 -55.766462) (xy 59.36016 -55.737782)
			(xy 59.370052 -55.68128) (xy 59.389534 -55.627329) (xy 59.403234 -55.602124) (xy 59.422538 -55.568342)
			(xy 58.359548 -54.505352) (xy 58.359548 -54.48554) (xy 58.35902 -54.474547) (xy 58.349849 -54.454565)
			(xy 58.333168 -54.440243) (xy 58.312029 -54.434201) (xy 58.290299 -54.437545) (xy 58.280808 -54.443122)
			(xy 58.260529 -54.455915) (xy 58.217059 -54.476142) (xy 58.17112 -54.489868) (xy 58.123679 -54.496804)
			(xy 58.099706 -54.497224) (xy 58.073715 -54.496741) (xy 58.022373 -54.48861) (xy 57.972936 -54.472548)
			(xy 57.926619 -54.448949) (xy 57.884565 -54.418396) (xy 57.847808 -54.38164) (xy 57.817254 -54.339586)
			(xy 57.793654 -54.29327) (xy 57.777591 -54.243832) (xy 57.769459 -54.192491) (xy 57.769459 -54.140509)
			(xy 57.777591 -54.089168) (xy 57.793654 -54.03973) (xy 57.817254 -53.993414) (xy 57.847808 -53.95136)
			(xy 57.884565 -53.914604) (xy 57.926619 -53.884051) (xy 57.972936 -53.860452) (xy 58.022373 -53.84439)
			(xy 58.073715 -53.836259) (xy 58.099706 -53.835808) (xy 58.130736 -53.836488) (xy 58.191721 -53.84799)
			(xy 58.220864 -53.858668) (xy 58.234183 -53.86339) (xy 58.262303 -53.866089) (xy 58.290085 -53.860977)
			(xy 58.315403 -53.848447) (xy 58.336318 -53.829459) (xy 58.351227 -53.805465) (xy 58.358991 -53.778304)
			(xy 58.359548 -53.76418) (xy 58.359548 -53.67909) (xy 58.358983 -53.66798) (xy 58.3496 -53.647837)
			(xy 58.332591 -53.633537) (xy 58.311136 -53.627753) (xy 58.289244 -53.631565) (xy 58.279792 -53.637434)
			(xy 58.258837 -53.651502) (xy 58.213561 -53.6738) (xy 58.165424 -53.688965) (xy 58.115542 -53.696644)
			(xy 58.090308 -53.697124) (xy 58.064317 -53.696641) (xy 58.012975 -53.688511) (xy 57.963537 -53.672448)
			(xy 57.917221 -53.64885) (xy 57.875166 -53.618296) (xy 57.838409 -53.58154) (xy 57.807854 -53.539486)
			(xy 57.784255 -53.49317) (xy 57.768191 -53.443733) (xy 57.760059 -53.392391) (xy 57.760059 -53.340409)
			(xy 57.768191 -53.289067) (xy 57.784255 -53.23963) (xy 57.807854 -53.193314) (xy 57.838409 -53.15126)
			(xy 57.875166 -53.114504) (xy 57.917221 -53.08395) (xy 57.963537 -53.060352) (xy 58.012975 -53.044289)
			(xy 58.064317 -53.036159) (xy 58.090308 -53.035708) (xy 58.112271 -53.036068) (xy 58.155811 -53.041888)
			(xy 58.198196 -53.053425) (xy 58.218578 -53.061616) (xy 58.231967 -53.066726) (xy 58.260417 -53.070072)
			(xy 58.288676 -53.065383) (xy 58.314521 -53.053029) (xy 58.335916 -53.033981) (xy 58.351179 -53.00974)
			(xy 58.359106 -52.982213) (xy 58.359548 -52.96789) (xy 58.359548 -51.684428) (xy 58.215276 -51.540156)
			(xy 57.327546 -51.540156) (xy 57.011316 -51.856386) (xy 57.011316 -55.002001) (xy 57.769508 -55.002001)
			(xy 57.769508 -54.950027) (xy 57.777638 -54.898692) (xy 57.793699 -54.849262) (xy 57.817295 -54.802952)
			(xy 57.847845 -54.760904) (xy 57.884596 -54.724153) (xy 57.926644 -54.693603) (xy 57.972954 -54.670007)
			(xy 58.022384 -54.653946) (xy 58.073719 -54.645816) (xy 58.125693 -54.645816) (xy 58.177028 -54.653946)
			(xy 58.226458 -54.670007) (xy 58.272768 -54.693603) (xy 58.314816 -54.724153) (xy 58.351567 -54.760904)
			(xy 58.382117 -54.802952) (xy 58.405713 -54.849262) (xy 58.421774 -54.898692) (xy 58.429904 -54.950027)
			(xy 58.430414 -54.976014) (xy 58.429904 -55.002001) (xy 58.421774 -55.053336) (xy 58.405713 -55.102766)
			(xy 58.382117 -55.149076) (xy 58.351567 -55.191124) (xy 58.314816 -55.227875) (xy 58.272768 -55.258425)
			(xy 58.226458 -55.282021) (xy 58.177028 -55.298082) (xy 58.125693 -55.306212) (xy 58.073719 -55.306212)
			(xy 58.022384 -55.298082) (xy 57.972954 -55.282021) (xy 57.926644 -55.258425) (xy 57.884596 -55.227875)
			(xy 57.847845 -55.191124) (xy 57.817295 -55.149076) (xy 57.793699 -55.102766) (xy 57.777638 -55.053336)
			(xy 57.769508 -55.002001) (xy 57.011316 -55.002001) (xy 57.011316 -55.445406) (xy 57.078372 -55.512462)
			(xy 57.10086 -55.494533) (xy 57.15074 -55.465911) (xy 57.204813 -55.446333) (xy 57.261454 -55.436386)
			(xy 57.290208 -55.435754) (xy 57.316196 -55.436264) (xy 57.367532 -55.444395) (xy 57.416964 -55.460457)
			(xy 57.463275 -55.484052) (xy 57.505325 -55.514602) (xy 57.542079 -55.551352) (xy 57.572632 -55.5934)
			(xy 57.596232 -55.639709) (xy 57.612298 -55.689139) (xy 57.620434 -55.740474) (xy 57.620916 -55.766462)
			(xy 57.620493 -55.790132) (xy 57.620157 -55.792449) (xy 57.76011 -55.792449) (xy 57.76011 -55.740475)
			(xy 57.76824 -55.68914) (xy 57.784301 -55.63971) (xy 57.807897 -55.5934) (xy 57.838447 -55.551352)
			(xy 57.875198 -55.514601) (xy 57.917246 -55.484051) (xy 57.963556 -55.460455) (xy 58.012986 -55.444394)
			(xy 58.064321 -55.436264) (xy 58.116295 -55.436264) (xy 58.16763 -55.444394) (xy 58.21706 -55.460455)
			(xy 58.26337 -55.484051) (xy 58.305418 -55.514601) (xy 58.342169 -55.551352) (xy 58.372719 -55.5934)
			(xy 58.396315 -55.63971) (xy 58.412376 -55.68914) (xy 58.420506 -55.740475) (xy 58.421016 -55.766462)
			(xy 58.420506 -55.792449) (xy 58.418977 -55.802101) (xy 58.569608 -55.802101) (xy 58.569608 -55.750127)
			(xy 58.577738 -55.698792) (xy 58.593799 -55.649362) (xy 58.617395 -55.603052) (xy 58.647945 -55.561004)
			(xy 58.684696 -55.524253) (xy 58.726744 -55.493703) (xy 58.773054 -55.470107) (xy 58.822484 -55.454046)
			(xy 58.873819 -55.445916) (xy 58.925793 -55.445916) (xy 58.977128 -55.454046) (xy 59.026558 -55.470107)
			(xy 59.072868 -55.493703) (xy 59.114916 -55.524253) (xy 59.151667 -55.561004) (xy 59.182217 -55.603052)
			(xy 59.205813 -55.649362) (xy 59.221874 -55.698792) (xy 59.230004 -55.750127) (xy 59.230514 -55.776114)
			(xy 59.230004 -55.802101) (xy 59.221874 -55.853436) (xy 59.205813 -55.902866) (xy 59.182217 -55.949176)
			(xy 59.151667 -55.991224) (xy 59.114916 -56.027975) (xy 59.072868 -56.058525) (xy 59.026558 -56.082121)
			(xy 58.977128 -56.098182) (xy 58.925793 -56.106312) (xy 58.873819 -56.106312) (xy 58.822484 -56.098182)
			(xy 58.773054 -56.082121) (xy 58.726744 -56.058525) (xy 58.684696 -56.027975) (xy 58.647945 -55.991224)
			(xy 58.617395 -55.949176) (xy 58.593799 -55.902866) (xy 58.577738 -55.853436) (xy 58.569608 -55.802101)
			(xy 58.418977 -55.802101) (xy 58.412376 -55.843784) (xy 58.396315 -55.893214) (xy 58.372719 -55.939524)
			(xy 58.342169 -55.981572) (xy 58.305418 -56.018323) (xy 58.26337 -56.048873) (xy 58.21706 -56.072469)
			(xy 58.16763 -56.08853) (xy 58.116295 -56.09666) (xy 58.064321 -56.09666) (xy 58.012986 -56.08853)
			(xy 57.963556 -56.072469) (xy 57.917246 -56.048873) (xy 57.875198 -56.018323) (xy 57.838447 -55.981572)
			(xy 57.807897 -55.939524) (xy 57.784301 -55.893214) (xy 57.76824 -55.843784) (xy 57.76011 -55.792449)
			(xy 57.620157 -55.792449) (xy 57.613707 -55.836985) (xy 57.600312 -55.882392) (xy 57.580582 -55.925425)
			(xy 57.568084 -55.945532) (xy 57.545986 -55.980076) (xy 57.881012 -56.315102) (xy 57.915556 -56.291734)
			(xy 57.936096 -56.278521) (xy 57.980241 -56.257628) (xy 58.026975 -56.243447) (xy 58.075286 -56.236287)
			(xy 58.099706 -56.235854) (xy 58.125694 -56.236364) (xy 58.17703 -56.244495) (xy 58.226462 -56.260556)
			(xy 58.272774 -56.284152) (xy 58.314824 -56.314701) (xy 58.351578 -56.351452) (xy 58.382132 -56.393499)
			(xy 58.405732 -56.439808) (xy 58.421797 -56.489239) (xy 58.429934 -56.540574) (xy 58.430414 -56.566562)
			(xy 58.429999 -56.590984) (xy 58.428379 -56.601947) (xy 58.569608 -56.601947) (xy 58.569608 -56.549973)
			(xy 58.577738 -56.498638) (xy 58.593799 -56.449208) (xy 58.617395 -56.402898) (xy 58.647945 -56.36085)
			(xy 58.684696 -56.324099) (xy 58.726744 -56.293549) (xy 58.773054 -56.269953) (xy 58.822484 -56.253892)
			(xy 58.873819 -56.245762) (xy 58.925793 -56.245762) (xy 58.977128 -56.253892) (xy 59.026558 -56.269953)
			(xy 59.072868 -56.293549) (xy 59.114916 -56.324099) (xy 59.151667 -56.36085) (xy 59.182217 -56.402898)
			(xy 59.205813 -56.449208) (xy 59.221874 -56.498638) (xy 59.230004 -56.549973) (xy 59.230514 -56.57596)
			(xy 59.230004 -56.601947) (xy 59.369454 -56.601947) (xy 59.369454 -56.549973) (xy 59.377584 -56.498638)
			(xy 59.393645 -56.449208) (xy 59.417241 -56.402898) (xy 59.447791 -56.36085) (xy 59.484542 -56.324099)
			(xy 59.52659 -56.293549) (xy 59.5729 -56.269953) (xy 59.62233 -56.253892) (xy 59.673665 -56.245762)
			(xy 59.725639 -56.245762) (xy 59.776974 -56.253892) (xy 59.826404 -56.269953) (xy 59.872714 -56.293549)
			(xy 59.914762 -56.324099) (xy 59.951513 -56.36085) (xy 59.982063 -56.402898) (xy 60.005659 -56.449208)
			(xy 60.02172 -56.498638) (xy 60.02985 -56.549973) (xy 60.03036 -56.57596) (xy 60.030034 -56.592549)
			(xy 60.159902 -56.592549) (xy 60.159902 -56.540575) (xy 60.168032 -56.48924) (xy 60.184093 -56.43981)
			(xy 60.207689 -56.3935) (xy 60.238239 -56.351452) (xy 60.27499 -56.314701) (xy 60.317038 -56.284151)
			(xy 60.363348 -56.260555) (xy 60.412778 -56.244494) (xy 60.464113 -56.236364) (xy 60.516087 -56.236364)
			(xy 60.567422 -56.244494) (xy 60.616852 -56.260555) (xy 60.663162 -56.284151) (xy 60.70521 -56.314701)
			(xy 60.741961 -56.351452) (xy 60.772511 -56.3935) (xy 60.796107 -56.43981) (xy 60.812168 -56.48924)
			(xy 60.820298 -56.540575) (xy 60.820808 -56.566562) (xy 60.820298 -56.592549) (xy 63.360048 -56.592549)
			(xy 63.360048 -56.540575) (xy 63.368178 -56.48924) (xy 63.384239 -56.43981) (xy 63.407835 -56.3935)
			(xy 63.438385 -56.351452) (xy 63.475136 -56.314701) (xy 63.517184 -56.284151) (xy 63.563494 -56.260555)
			(xy 63.612924 -56.244494) (xy 63.664259 -56.236364) (xy 63.716233 -56.236364) (xy 63.767568 -56.244494)
			(xy 63.816998 -56.260555) (xy 63.863308 -56.284151) (xy 63.905356 -56.314701) (xy 63.942107 -56.351452)
			(xy 63.972657 -56.3935) (xy 63.996253 -56.43981) (xy 64.012314 -56.48924) (xy 64.020444 -56.540575)
			(xy 64.020954 -56.566562) (xy 64.020444 -56.592549) (xy 64.159894 -56.592549) (xy 64.159894 -56.540575)
			(xy 64.168024 -56.48924) (xy 64.184085 -56.43981) (xy 64.207681 -56.3935) (xy 64.238231 -56.351452)
			(xy 64.274982 -56.314701) (xy 64.31703 -56.284151) (xy 64.36334 -56.260555) (xy 64.41277 -56.244494)
			(xy 64.464105 -56.236364) (xy 64.516079 -56.236364) (xy 64.567414 -56.244494) (xy 64.616844 -56.260555)
			(xy 64.663154 -56.284151) (xy 64.705202 -56.314701) (xy 64.741953 -56.351452) (xy 64.772503 -56.3935)
			(xy 64.796099 -56.43981) (xy 64.81216 -56.48924) (xy 64.82029 -56.540575) (xy 64.8208 -56.566562)
			(xy 64.82029 -56.592549) (xy 64.81216 -56.643884) (xy 64.796099 -56.693314) (xy 64.772503 -56.739624)
			(xy 64.741953 -56.781672) (xy 64.705202 -56.818423) (xy 64.663154 -56.848973) (xy 64.616844 -56.872569)
			(xy 64.567414 -56.88863) (xy 64.516079 -56.89676) (xy 64.464105 -56.89676) (xy 64.41277 -56.88863)
			(xy 64.36334 -56.872569) (xy 64.31703 -56.848973) (xy 64.274982 -56.818423) (xy 64.238231 -56.781672)
			(xy 64.207681 -56.739624) (xy 64.184085 -56.693314) (xy 64.168024 -56.643884) (xy 64.159894 -56.592549)
			(xy 64.020444 -56.592549) (xy 64.012314 -56.643884) (xy 63.996253 -56.693314) (xy 63.972657 -56.739624)
			(xy 63.942107 -56.781672) (xy 63.905356 -56.818423) (xy 63.863308 -56.848973) (xy 63.816998 -56.872569)
			(xy 63.767568 -56.88863) (xy 63.716233 -56.89676) (xy 63.664259 -56.89676) (xy 63.612924 -56.88863)
			(xy 63.563494 -56.872569) (xy 63.517184 -56.848973) (xy 63.475136 -56.818423) (xy 63.438385 -56.781672)
			(xy 63.407835 -56.739624) (xy 63.384239 -56.693314) (xy 63.368178 -56.643884) (xy 63.360048 -56.592549)
			(xy 60.820298 -56.592549) (xy 60.812168 -56.643884) (xy 60.796107 -56.693314) (xy 60.772511 -56.739624)
			(xy 60.741961 -56.781672) (xy 60.70521 -56.818423) (xy 60.663162 -56.848973) (xy 60.616852 -56.872569)
			(xy 60.567422 -56.88863) (xy 60.516087 -56.89676) (xy 60.464113 -56.89676) (xy 60.412778 -56.88863)
			(xy 60.363348 -56.872569) (xy 60.317038 -56.848973) (xy 60.27499 -56.818423) (xy 60.238239 -56.781672)
			(xy 60.207689 -56.739624) (xy 60.184093 -56.693314) (xy 60.168032 -56.643884) (xy 60.159902 -56.592549)
			(xy 60.030034 -56.592549) (xy 60.02985 -56.601947) (xy 60.02172 -56.653282) (xy 60.005659 -56.702712)
			(xy 59.982063 -56.749022) (xy 59.951513 -56.79107) (xy 59.914762 -56.827821) (xy 59.872714 -56.858371)
			(xy 59.826404 -56.881967) (xy 59.776974 -56.898028) (xy 59.725639 -56.906158) (xy 59.673665 -56.906158)
			(xy 59.62233 -56.898028) (xy 59.5729 -56.881967) (xy 59.52659 -56.858371) (xy 59.484542 -56.827821)
			(xy 59.447791 -56.79107) (xy 59.417241 -56.749022) (xy 59.393645 -56.702712) (xy 59.377584 -56.653282)
			(xy 59.369454 -56.601947) (xy 59.230004 -56.601947) (xy 59.221874 -56.653282) (xy 59.205813 -56.702712)
			(xy 59.182217 -56.749022) (xy 59.151667 -56.79107) (xy 59.114916 -56.827821) (xy 59.072868 -56.858371)
			(xy 59.026558 -56.881967) (xy 58.977128 -56.898028) (xy 58.925793 -56.906158) (xy 58.873819 -56.906158)
			(xy 58.822484 -56.898028) (xy 58.773054 -56.881967) (xy 58.726744 -56.858371) (xy 58.684696 -56.827821)
			(xy 58.647945 -56.79107) (xy 58.617395 -56.749022) (xy 58.593799 -56.702712) (xy 58.577738 -56.653282)
			(xy 58.569608 -56.601947) (xy 58.428379 -56.601947) (xy 58.422858 -56.639303) (xy 58.408682 -56.686044)
			(xy 58.387778 -56.730189) (xy 58.374534 -56.750712) (xy 58.351166 -56.785256) (xy 58.686192 -57.120282)
			(xy 58.720736 -57.098184) (xy 58.740845 -57.085691) (xy 58.783877 -57.065959) (xy 58.829284 -57.052567)
			(xy 58.876136 -57.045787) (xy 58.899806 -57.045352) (xy 58.925794 -57.045862) (xy 58.97713 -57.053993)
			(xy 59.026562 -57.070054) (xy 59.072874 -57.09365) (xy 59.114925 -57.124199) (xy 59.151679 -57.160949)
			(xy 59.182233 -57.202997) (xy 59.205833 -57.249306) (xy 59.221899 -57.298737) (xy 59.230035 -57.350072)
			(xy 59.230514 -57.37606) (xy 59.229899 -57.404816) (xy 59.219961 -57.461462) (xy 59.200378 -57.515536)
			(xy 59.17174 -57.56541) (xy 59.153806 -57.587896) (xy 59.269884 -57.703974) (xy 59.331352 -57.703974)
			(xy 59.344845 -57.703562) (xy 59.370889 -57.696502) (xy 59.394173 -57.682862) (xy 59.413067 -57.663596)
			(xy 59.426252 -57.640052) (xy 59.432804 -57.613875) (xy 59.432267 -57.586895) (xy 59.424677 -57.561)
			(xy 59.417966 -57.549288) (xy 59.406342 -57.529669) (xy 59.388011 -57.487913) (xy 59.3756 -57.444032)
			(xy 59.369344 -57.398861) (xy 59.368944 -57.37606) (xy 59.369454 -57.350073) (xy 59.377584 -57.298738)
			(xy 59.393645 -57.249308) (xy 59.417241 -57.202998) (xy 59.447791 -57.16095) (xy 59.484542 -57.124199)
			(xy 59.52659 -57.093649) (xy 59.5729 -57.070053) (xy 59.62233 -57.053992) (xy 59.673665 -57.045862)
			(xy 59.725639 -57.045862) (xy 59.776974 -57.053992) (xy 59.826404 -57.070053) (xy 59.872714 -57.093649)
			(xy 59.914762 -57.124199) (xy 59.951513 -57.16095) (xy 59.982063 -57.202998) (xy 60.005659 -57.249308)
			(xy 60.02172 -57.298738) (xy 60.02985 -57.350073) (xy 60.03036 -57.37606) (xy 60.029973 -57.398861)
			(xy 60.023699 -57.444028) (xy 60.011277 -57.487905) (xy 59.992944 -57.529658) (xy 59.981338 -57.549288)
			(xy 59.974643 -57.56101) (xy 59.967062 -57.586907) (xy 59.966528 -57.613887) (xy 59.973079 -57.640064)
			(xy 59.986258 -57.663612) (xy 60.005145 -57.682885) (xy 60.028421 -57.696538) (xy 60.05446 -57.703619)
			(xy 60.067952 -57.703974) (xy 60.137548 -57.703974) (xy 60.151204 -57.703539) (xy 60.177538 -57.696303)
			(xy 60.201007 -57.682334) (xy 60.219926 -57.662637) (xy 60.232936 -57.638624) (xy 60.239106 -57.612019)
			(xy 60.237991 -57.584731) (xy 60.229671 -57.558718) (xy 60.222638 -57.547002) (xy 60.209942 -57.52676)
			(xy 60.189884 -57.483393) (xy 60.176289 -57.437587) (xy 60.169441 -57.390299) (xy 60.169044 -57.366408)
			(xy 60.169554 -57.340421) (xy 60.177684 -57.289086) (xy 60.193745 -57.239656) (xy 60.217341 -57.193346)
			(xy 60.247891 -57.151298) (xy 60.284642 -57.114547) (xy 60.32669 -57.083997) (xy 60.373 -57.060401)
			(xy 60.42243 -57.04434) (xy 60.473765 -57.03621) (xy 60.525739 -57.03621) (xy 60.577074 -57.04434)
			(xy 60.626504 -57.060401) (xy 60.672814 -57.083997) (xy 60.714862 -57.114547) (xy 60.751613 -57.151298)
			(xy 60.782163 -57.193346) (xy 60.805759 -57.239656) (xy 60.82182 -57.289086) (xy 60.82995 -57.340421)
			(xy 60.83046 -57.366408) (xy 60.830034 -57.390295) (xy 60.823158 -57.437572) (xy 60.809563 -57.483372)
			(xy 60.789532 -57.526745) (xy 60.776866 -57.547002) (xy 60.769788 -57.558687) (xy 60.761497 -57.584706)
			(xy 60.760403 -57.611992) (xy 60.766584 -57.638592) (xy 60.779599 -57.662599) (xy 60.798514 -57.682296)
			(xy 60.821975 -57.696272) (xy 60.848302 -57.703525) (xy 60.861956 -57.703974) (xy 60.959492 -57.703974)
			(xy 60.959492 -57.366662) (xy 60.960004 -57.340668) (xy 60.968137 -57.289321) (xy 60.984198 -57.239876)
			(xy 61.007791 -57.19355) (xy 61.038336 -57.151482) (xy 61.075082 -57.114706) (xy 61.117126 -57.084128)
			(xy 61.163433 -57.060498) (xy 61.212865 -57.044398) (xy 61.264207 -57.036224) (xy 61.2902 -57.0357)
			(xy 61.316745 -57.036227) (xy 61.369154 -57.044709) (xy 61.419534 -57.061455) (xy 61.466591 -57.086035)
			(xy 61.509118 -57.117817) (xy 61.527944 -57.136538) (xy 61.546981 -57.155406) (xy 61.579306 -57.198158)
			(xy 61.604325 -57.245558) (xy 61.621383 -57.296368) (xy 61.630037 -57.349262) (xy 61.63056 -57.37606)
			(xy 61.630283 -57.394575) (xy 61.62608 -57.431365) (xy 61.622178 -57.449466) (xy 61.620908 -57.455054)
			(xy 61.620908 -57.703974) (xy 62.592204 -57.703974) (xy 62.592204 -57.48782) (xy 62.588902 -57.479438)
			(xy 62.579613 -57.452111) (xy 62.569641 -57.395265) (xy 62.56909 -57.366408) (xy 62.5696 -57.340421)
			(xy 62.57773 -57.289086) (xy 62.593791 -57.239656) (xy 62.617387 -57.193346) (xy 62.647937 -57.151298)
			(xy 62.684688 -57.114547) (xy 62.726736 -57.083997) (xy 62.773046 -57.060401) (xy 62.822476 -57.04434)
			(xy 62.873811 -57.03621) (xy 62.925785 -57.03621) (xy 62.97712 -57.04434) (xy 63.02655 -57.060401)
			(xy 63.07286 -57.083997) (xy 63.114908 -57.114547) (xy 63.151659 -57.151298) (xy 63.182209 -57.193346)
			(xy 63.205805 -57.239656) (xy 63.221866 -57.289086) (xy 63.229996 -57.340421) (xy 63.230506 -57.366408)
			(xy 63.229957 -57.392395) (xy 63.360048 -57.392395) (xy 63.360048 -57.340421) (xy 63.368178 -57.289086)
			(xy 63.384239 -57.239656) (xy 63.407835 -57.193346) (xy 63.438385 -57.151298) (xy 63.475136 -57.114547)
			(xy 63.517184 -57.083997) (xy 63.563494 -57.060401) (xy 63.612924 -57.04434) (xy 63.664259 -57.03621)
			(xy 63.716233 -57.03621) (xy 63.767568 -57.04434) (xy 63.816998 -57.060401) (xy 63.863308 -57.083997)
			(xy 63.905356 -57.114547) (xy 63.942107 -57.151298) (xy 63.972657 -57.193346) (xy 63.996253 -57.239656)
			(xy 64.012314 -57.289086) (xy 64.020444 -57.340421) (xy 64.020954 -57.366408) (xy 64.020444 -57.392395)
			(xy 64.018915 -57.402047) (xy 64.959994 -57.402047) (xy 64.959994 -57.350073) (xy 64.968124 -57.298738)
			(xy 64.984185 -57.249308) (xy 65.007781 -57.202998) (xy 65.038331 -57.16095) (xy 65.075082 -57.124199)
			(xy 65.11713 -57.093649) (xy 65.16344 -57.070053) (xy 65.21287 -57.053992) (xy 65.264205 -57.045862)
			(xy 65.316179 -57.045862) (xy 65.367514 -57.053992) (xy 65.416944 -57.070053) (xy 65.463254 -57.093649)
			(xy 65.505302 -57.124199) (xy 65.542053 -57.16095) (xy 65.572603 -57.202998) (xy 65.596199 -57.249308)
			(xy 65.61226 -57.298738) (xy 65.62039 -57.350073) (xy 65.6209 -57.37606) (xy 65.62039 -57.402047)
			(xy 65.61226 -57.453382) (xy 65.596199 -57.502812) (xy 65.572603 -57.549122) (xy 65.542053 -57.59117)
			(xy 65.505302 -57.627921) (xy 65.463254 -57.658471) (xy 65.416944 -57.682067) (xy 65.367514 -57.698128)
			(xy 65.316179 -57.706258) (xy 65.264205 -57.706258) (xy 65.21287 -57.698128) (xy 65.16344 -57.682067)
			(xy 65.11713 -57.658471) (xy 65.075082 -57.627921) (xy 65.038331 -57.59117) (xy 65.007781 -57.549122)
			(xy 64.984185 -57.502812) (xy 64.968124 -57.453382) (xy 64.959994 -57.402047) (xy 64.018915 -57.402047)
			(xy 64.012314 -57.44373) (xy 63.996253 -57.49316) (xy 63.972657 -57.53947) (xy 63.942107 -57.581518)
			(xy 63.905356 -57.618269) (xy 63.863308 -57.648819) (xy 63.816998 -57.672415) (xy 63.767568 -57.688476)
			(xy 63.716233 -57.696606) (xy 63.664259 -57.696606) (xy 63.612924 -57.688476) (xy 63.563494 -57.672415)
			(xy 63.517184 -57.648819) (xy 63.475136 -57.618269) (xy 63.438385 -57.581518) (xy 63.407835 -57.53947)
			(xy 63.384239 -57.49316) (xy 63.368178 -57.44373) (xy 63.360048 -57.392395) (xy 63.229957 -57.392395)
			(xy 63.229897 -57.39526) (xy 63.219928 -57.452096) (xy 63.210694 -57.479438) (xy 63.207392 -57.48782)
			(xy 63.207392 -57.746392) (xy 63.389002 -57.928002) (xy 63.396328 -57.93472) (xy 63.414617 -57.942458)
			(xy 63.434473 -57.942677) (xy 63.452927 -57.935344) (xy 63.460376 -57.928764) (xy 63.478984 -57.911424)
			(xy 63.520531 -57.882086) (xy 63.566079 -57.859454) (xy 63.614555 -57.84406) (xy 63.664815 -57.836267)
			(xy 63.690246 -57.8358) (xy 64.490092 -57.8358) (xy 64.515864 -57.836292) (xy 64.566786 -57.844283)
			(xy 64.615853 -57.860074) (xy 64.661878 -57.883282) (xy 64.703747 -57.913345) (xy 64.740448 -57.949538)
			(xy 64.771094 -57.990984) (xy 64.783462 -58.0136) (xy 67.9196 -58.0136)
		)
		(stroke
			(width 0)
			(type solid)
		)
		(fill yes)
		(layer "In7.Cu")
		(net "P1V0_STBY_RC_VCC10A")
	)
	(gr_poly
		(pts
			(xy 18.7452 -98.8568) (xy 18.7452 -98.5012) (xy 18.3896 -98.1456) (xy 18.0848 -98.1456) (xy 17.727676 -97.788476)
			(xy 17.691608 -97.822258) (xy 17.673087 -97.839182) (xy 17.631885 -97.867804) (xy 17.586829 -97.889867)
			(xy 17.538954 -97.904862) (xy 17.489362 -97.912446) (xy 17.464278 -97.912936) (xy 17.43829 -97.912425)
			(xy 17.386954 -97.904291) (xy 17.337522 -97.888226) (xy 17.291211 -97.864627) (xy 17.249163 -97.834075)
			(xy 17.212411 -97.797321) (xy 17.181861 -97.75527) (xy 17.158265 -97.708958) (xy 17.142204 -97.659525)
			(xy 17.134074 -97.608188) (xy 17.134074 -97.556212) (xy 17.142204 -97.504875) (xy 17.158265 -97.455442)
			(xy 17.181861 -97.40913) (xy 17.212411 -97.367079) (xy 17.249163 -97.330325) (xy 17.291211 -97.299773)
			(xy 17.337522 -97.276174) (xy 17.386954 -97.260109) (xy 17.43829 -97.251975) (xy 17.464278 -97.25152)
			(xy 17.491572 -97.252102) (xy 17.545412 -97.261107) (xy 17.597045 -97.278827) (xy 17.645068 -97.304782)
			(xy 17.68818 -97.338268) (xy 17.707102 -97.357946) (xy 17.716702 -97.367682) (xy 17.739914 -97.382111)
			(xy 17.766124 -97.389861) (xy 17.793451 -97.390378) (xy 17.819935 -97.383624) (xy 17.843676 -97.370084)
			(xy 17.85366 -97.36074) (xy 18.4658 -96.7486) (xy 18.4658 -96.402906) (xy 18.465279 -96.387582) (xy 18.456196 -96.35831)
			(xy 18.438846 -96.333046) (xy 18.414787 -96.31406) (xy 18.386181 -96.303058) (xy 18.3556 -96.301029)
			(xy 18.340578 -96.3041) (xy 18.321742 -96.308281) (xy 18.283416 -96.312735) (xy 18.264124 -96.31299)
			(xy 18.238135 -96.312509) (xy 18.186796 -96.304381) (xy 18.137361 -96.288322) (xy 18.091047 -96.264726)
			(xy 18.048995 -96.234176) (xy 18.012239 -96.197424) (xy 17.981686 -96.155373) (xy 17.958088 -96.109061)
			(xy 17.942025 -96.059627) (xy 17.933893 -96.008289) (xy 17.933893 -95.956311) (xy 17.942025 -95.904973)
			(xy 17.958088 -95.855539) (xy 17.981686 -95.809227) (xy 18.012239 -95.767176) (xy 18.048995 -95.730424)
			(xy 18.091047 -95.699874) (xy 18.137361 -95.676278) (xy 18.186796 -95.660219) (xy 18.238135 -95.652091)
			(xy 18.264124 -95.651574) (xy 18.283416 -95.651834) (xy 18.32174 -95.656296) (xy 18.340578 -95.660464)
			(xy 18.355604 -95.663519) (xy 18.386186 -95.661489) (xy 18.414794 -95.65049) (xy 18.438859 -95.631509)
			(xy 18.45622 -95.606251) (xy 18.465317 -95.576982) (xy 18.4658 -95.561658) (xy 18.4658 -95.481902)
			(xy 18.404586 -95.481902) (xy 18.394934 -95.485966) (xy 18.374194 -95.494497) (xy 18.330985 -95.506506)
			(xy 18.286547 -95.512548) (xy 18.264124 -95.51289) (xy 18.238135 -95.512409) (xy 18.186796 -95.504281)
			(xy 18.137361 -95.488222) (xy 18.091047 -95.464626) (xy 18.048995 -95.434076) (xy 18.012239 -95.397324)
			(xy 17.981686 -95.355273) (xy 17.958088 -95.308961) (xy 17.942025 -95.259527) (xy 17.933893 -95.208189)
			(xy 17.933893 -95.156211) (xy 17.942025 -95.104873) (xy 17.958088 -95.055439) (xy 17.981686 -95.009127)
			(xy 18.012239 -94.967076) (xy 18.048995 -94.930324) (xy 18.091047 -94.899774) (xy 18.137361 -94.876178)
			(xy 18.186796 -94.860119) (xy 18.238135 -94.851991) (xy 18.264124 -94.851474) (xy 18.291501 -94.852005)
			(xy 18.345507 -94.861021) (xy 18.397288 -94.878819) (xy 18.445425 -94.904911) (xy 18.488601 -94.938583)
			(xy 18.525633 -94.978914) (xy 18.540984 -95.001588) (xy 18.549692 -95.013924) (xy 18.572854 -95.033273)
			(xy 18.600655 -95.045017) (xy 18.630674 -95.048132) (xy 18.660295 -95.042346) (xy 18.686935 -95.028164)
			(xy 18.697956 -95.017844) (xy 19.05 -94.6658) (xy 19.9136 -94.6658) (xy 20.0914 -94.488) (xy 20.0914 -92.6846)
			(xy 19.9136 -92.5068) (xy 19.455638 -92.5068) (xy 19.441016 -92.507272) (xy 19.412968 -92.515545)
			(xy 19.388411 -92.531425) (xy 19.369359 -92.55361) (xy 19.357371 -92.580283) (xy 19.35343 -92.609259)
			(xy 19.357858 -92.638165) (xy 19.36369 -92.65158) (xy 19.373526 -92.673633) (xy 19.387427 -92.719876)
			(xy 19.394474 -92.767645) (xy 19.394932 -92.791788) (xy 19.394422 -92.817775) (xy 19.386292 -92.86911)
			(xy 19.370231 -92.91854) (xy 19.346635 -92.96485) (xy 19.316085 -93.006898) (xy 19.279334 -93.043649)
			(xy 19.237286 -93.074199) (xy 19.190976 -93.097795) (xy 19.141546 -93.113856) (xy 19.090211 -93.121986)
			(xy 19.038237 -93.121986) (xy 18.986902 -93.113856) (xy 18.937472 -93.097795) (xy 18.891162 -93.074199)
			(xy 18.849114 -93.043649) (xy 18.812363 -93.006898) (xy 18.781813 -92.96485) (xy 18.758217 -92.91854)
			(xy 18.742156 -92.86911) (xy 18.734026 -92.817775) (xy 18.733516 -92.791788) (xy 18.733931 -92.767641)
			(xy 18.740961 -92.719863) (xy 18.754885 -92.67362) (xy 18.764758 -92.65158) (xy 18.770539 -92.638148)
			(xy 18.774962 -92.609253) (xy 18.771022 -92.580289) (xy 18.759041 -92.553626) (xy 18.740001 -92.531447)
			(xy 18.715459 -92.515567) (xy 18.687425 -92.507287) (xy 18.67281 -92.5068) (xy 18.655538 -92.5068)
			(xy 18.640916 -92.507272) (xy 18.612868 -92.515545) (xy 18.588311 -92.531425) (xy 18.569259 -92.55361)
			(xy 18.557271 -92.580283) (xy 18.55333 -92.609259) (xy 18.557758 -92.638165) (xy 18.56359 -92.65158)
			(xy 18.573426 -92.673633) (xy 18.587327 -92.719876) (xy 18.594374 -92.767645) (xy 18.594832 -92.791788)
			(xy 18.594322 -92.817775) (xy 18.586192 -92.86911) (xy 18.570131 -92.91854) (xy 18.546535 -92.96485)
			(xy 18.515985 -93.006898) (xy 18.479234 -93.043649) (xy 18.437186 -93.074199) (xy 18.390876 -93.097795)
			(xy 18.341446 -93.113856) (xy 18.290111 -93.121986) (xy 18.238137 -93.121986) (xy 18.186802 -93.113856)
			(xy 18.137372 -93.097795) (xy 18.091062 -93.074199) (xy 18.049014 -93.043649) (xy 18.012263 -93.006898)
			(xy 17.981713 -92.96485) (xy 17.958117 -92.91854) (xy 17.942056 -92.86911) (xy 17.933926 -92.817775)
			(xy 17.933416 -92.791788) (xy 17.933952 -92.764878) (xy 17.942681 -92.711769) (xy 17.95989 -92.660773)
			(xy 17.985126 -92.613234) (xy 18.017722 -92.570407) (xy 18.056821 -92.53342) (xy 18.10139 -92.503248)
			(xy 18.150254 -92.480687) (xy 18.202126 -92.466333) (xy 18.228818 -92.462858) (xy 18.246598 -92.46108)
			(xy 18.295366 -92.412566) (xy 18.199354 -92.316554) (xy 18.185638 -92.313252) (xy 18.161969 -92.307016)
			(xy 18.116652 -92.288522) (xy 18.074556 -92.263549) (xy 18.036601 -92.232645) (xy 18.003615 -92.196484)
			(xy 17.97632 -92.155856) (xy 17.955312 -92.111648) (xy 17.941049 -92.064827) (xy 17.933843 -92.016415)
			(xy 17.933416 -91.991942) (xy 17.934012 -91.963479) (xy 17.943755 -91.907392) (xy 17.962944 -91.853798)
			(xy 17.991014 -91.804273) (xy 18.0086 -91.781884) (xy 18.0086 -91.4019) (xy 17.992913 -91.382045)
			(xy 17.967122 -91.338511) (xy 17.948257 -91.29156) (xy 17.936757 -91.242284) (xy 17.932891 -91.191833)
			(xy 17.936748 -91.14138) (xy 17.948238 -91.092102) (xy 17.967093 -91.045147) (xy 17.992876 -91.001608)
			(xy 18.0086 -90.981784) (xy 18.0086 -90.6018) (xy 17.990987 -90.579429) (xy 17.962907 -90.529903)
			(xy 17.943717 -90.476302) (xy 17.933984 -90.420208) (xy 17.933416 -90.391742) (xy 17.933496 -90.382067)
			(xy 17.934642 -90.362751) (xy 17.935702 -90.353134) (xy 17.938496 -90.328496) (xy 17.78 -90.17) (xy 17.079468 -90.17)
			(xy 17.066003 -90.170407) (xy 17.040007 -90.177439) (xy 17.016758 -90.191031) (xy 16.997878 -90.210235)
			(xy 16.984683 -90.233711) (xy 16.978094 -90.259823) (xy 16.97857 -90.286749) (xy 16.981932 -90.299794)
			(xy 16.988013 -90.322292) (xy 16.994521 -90.36844) (xy 16.994886 -90.391742) (xy 16.994376 -90.417729)
			(xy 16.986246 -90.469064) (xy 16.970185 -90.518494) (xy 16.946589 -90.564804) (xy 16.916039 -90.606852)
			(xy 16.879288 -90.643603) (xy 16.83724 -90.674153) (xy 16.79093 -90.697749) (xy 16.7415 -90.71381)
			(xy 16.690165 -90.72194) (xy 16.638191 -90.72194) (xy 16.586856 -90.71381) (xy 16.537426 -90.697749)
			(xy 16.491116 -90.674153) (xy 16.449068 -90.643603) (xy 16.412317 -90.606852) (xy 16.381767 -90.564804)
			(xy 16.358171 -90.518494) (xy 16.34211 -90.469064) (xy 16.33398 -90.417729) (xy 16.33347 -90.391742)
			(xy 16.334 -90.36537) (xy 16.342419 -90.313303) (xy 16.350234 -90.28811) (xy 16.359886 -90.258392)
			(xy 16.301974 -90.200226) (xy 16.187166 -90.315034) (xy 16.190976 -90.340688) (xy 16.192849 -90.353369)
			(xy 16.19488 -90.378924) (xy 16.19504 -90.391742) (xy 16.194621 -90.415662) (xy 16.187735 -90.463003)
			(xy 16.174098 -90.508858) (xy 16.153995 -90.552268) (xy 16.127846 -90.592328) (xy 16.096196 -90.628202)
			(xy 16.0782 -90.643964) (xy 16.0782 -91.217829) (xy 16.33398 -91.217829) (xy 16.33398 -91.165855)
			(xy 16.34211 -91.11452) (xy 16.358171 -91.06509) (xy 16.381767 -91.01878) (xy 16.412317 -90.976732)
			(xy 16.449068 -90.939981) (xy 16.491116 -90.909431) (xy 16.537426 -90.885835) (xy 16.586856 -90.869774)
			(xy 16.638191 -90.861644) (xy 16.690165 -90.861644) (xy 16.7415 -90.869774) (xy 16.79093 -90.885835)
			(xy 16.83724 -90.909431) (xy 16.879288 -90.939981) (xy 16.916039 -90.976732) (xy 16.946589 -91.01878)
			(xy 16.970185 -91.06509) (xy 16.986246 -91.11452) (xy 16.994376 -91.165855) (xy 16.994886 -91.191842)
			(xy 16.994376 -91.217829) (xy 17.13408 -91.217829) (xy 17.13408 -91.165855) (xy 17.14221 -91.11452)
			(xy 17.158271 -91.06509) (xy 17.181867 -91.01878) (xy 17.212417 -90.976732) (xy 17.249168 -90.939981)
			(xy 17.291216 -90.909431) (xy 17.337526 -90.885835) (xy 17.386956 -90.869774) (xy 17.438291 -90.861644)
			(xy 17.490265 -90.861644) (xy 17.5416 -90.869774) (xy 17.59103 -90.885835) (xy 17.63734 -90.909431)
			(xy 17.679388 -90.939981) (xy 17.716139 -90.976732) (xy 17.746689 -91.01878) (xy 17.770285 -91.06509)
			(xy 17.786346 -91.11452) (xy 17.794476 -91.165855) (xy 17.794986 -91.191842) (xy 17.794476 -91.217829)
			(xy 17.786346 -91.269164) (xy 17.770285 -91.318594) (xy 17.746689 -91.364904) (xy 17.716139 -91.406952)
			(xy 17.679388 -91.443703) (xy 17.63734 -91.474253) (xy 17.59103 -91.497849) (xy 17.5416 -91.51391)
			(xy 17.490265 -91.52204) (xy 17.438291 -91.52204) (xy 17.386956 -91.51391) (xy 17.337526 -91.497849)
			(xy 17.291216 -91.474253) (xy 17.249168 -91.443703) (xy 17.212417 -91.406952) (xy 17.181867 -91.364904)
			(xy 17.158271 -91.318594) (xy 17.14221 -91.269164) (xy 17.13408 -91.217829) (xy 16.994376 -91.217829)
			(xy 16.986246 -91.269164) (xy 16.970185 -91.318594) (xy 16.946589 -91.364904) (xy 16.916039 -91.406952)
			(xy 16.879288 -91.443703) (xy 16.83724 -91.474253) (xy 16.79093 -91.497849) (xy 16.7415 -91.51391)
			(xy 16.690165 -91.52204) (xy 16.638191 -91.52204) (xy 16.586856 -91.51391) (xy 16.537426 -91.497849)
			(xy 16.491116 -91.474253) (xy 16.449068 -91.443703) (xy 16.412317 -91.406952) (xy 16.381767 -91.364904)
			(xy 16.358171 -91.318594) (xy 16.34211 -91.269164) (xy 16.33398 -91.217829) (xy 16.0782 -91.217829)
			(xy 16.0782 -92.017929) (xy 17.13408 -92.017929) (xy 17.13408 -91.965955) (xy 17.14221 -91.91462)
			(xy 17.158271 -91.86519) (xy 17.181867 -91.81888) (xy 17.212417 -91.776832) (xy 17.249168 -91.740081)
			(xy 17.291216 -91.709531) (xy 17.337526 -91.685935) (xy 17.386956 -91.669874) (xy 17.438291 -91.661744)
			(xy 17.490265 -91.661744) (xy 17.5416 -91.669874) (xy 17.59103 -91.685935) (xy 17.63734 -91.709531)
			(xy 17.679388 -91.740081) (xy 17.716139 -91.776832) (xy 17.746689 -91.81888) (xy 17.770285 -91.86519)
			(xy 17.786346 -91.91462) (xy 17.794476 -91.965955) (xy 17.794986 -91.991942) (xy 17.794476 -92.017929)
			(xy 17.786346 -92.069264) (xy 17.770285 -92.118694) (xy 17.746689 -92.165004) (xy 17.716139 -92.207052)
			(xy 17.679388 -92.243803) (xy 17.63734 -92.274353) (xy 17.59103 -92.297949) (xy 17.5416 -92.31401)
			(xy 17.490265 -92.32214) (xy 17.438291 -92.32214) (xy 17.386956 -92.31401) (xy 17.337526 -92.297949)
			(xy 17.291216 -92.274353) (xy 17.249168 -92.243803) (xy 17.212417 -92.207052) (xy 17.181867 -92.165004)
			(xy 17.158271 -92.118694) (xy 17.14221 -92.069264) (xy 17.13408 -92.017929) (xy 16.0782 -92.017929)
			(xy 16.0782 -92.817775) (xy 17.13408 -92.817775) (xy 17.13408 -92.765801) (xy 17.14221 -92.714466)
			(xy 17.158271 -92.665036) (xy 17.181867 -92.618726) (xy 17.212417 -92.576678) (xy 17.249168 -92.539927)
			(xy 17.291216 -92.509377) (xy 17.337526 -92.485781) (xy 17.386956 -92.46972) (xy 17.438291 -92.46159)
			(xy 17.490265 -92.46159) (xy 17.5416 -92.46972) (xy 17.59103 -92.485781) (xy 17.63734 -92.509377)
			(xy 17.679388 -92.539927) (xy 17.716139 -92.576678) (xy 17.746689 -92.618726) (xy 17.770285 -92.665036)
			(xy 17.786346 -92.714466) (xy 17.794476 -92.765801) (xy 17.794986 -92.791788) (xy 17.794476 -92.817775)
			(xy 17.786346 -92.86911) (xy 17.770285 -92.91854) (xy 17.746689 -92.96485) (xy 17.716139 -93.006898)
			(xy 17.679388 -93.043649) (xy 17.63734 -93.074199) (xy 17.59103 -93.097795) (xy 17.5416 -93.113856)
			(xy 17.490265 -93.121986) (xy 17.438291 -93.121986) (xy 17.386956 -93.113856) (xy 17.337526 -93.097795)
			(xy 17.291216 -93.074199) (xy 17.249168 -93.043649) (xy 17.212417 -93.006898) (xy 17.181867 -92.96485)
			(xy 17.158271 -92.91854) (xy 17.14221 -92.86911) (xy 17.13408 -92.817775) (xy 16.0782 -92.817775)
			(xy 16.0782 -94.408323) (xy 16.33398 -94.408323) (xy 16.33398 -94.356349) (xy 16.34211 -94.305014)
			(xy 16.358171 -94.255584) (xy 16.381767 -94.209274) (xy 16.412317 -94.167226) (xy 16.449068 -94.130475)
			(xy 16.491116 -94.099925) (xy 16.537426 -94.076329) (xy 16.586856 -94.060268) (xy 16.638191 -94.052138)
			(xy 16.690165 -94.052138) (xy 16.7415 -94.060268) (xy 16.79093 -94.076329) (xy 16.83724 -94.099925)
			(xy 16.879288 -94.130475) (xy 16.916039 -94.167226) (xy 16.946589 -94.209274) (xy 16.970185 -94.255584)
			(xy 16.986246 -94.305014) (xy 16.994376 -94.356349) (xy 16.994886 -94.382336) (xy 16.994376 -94.408323)
			(xy 17.13408 -94.408323) (xy 17.13408 -94.356349) (xy 17.14221 -94.305014) (xy 17.158271 -94.255584)
			(xy 17.181867 -94.209274) (xy 17.212417 -94.167226) (xy 17.249168 -94.130475) (xy 17.291216 -94.099925)
			(xy 17.337526 -94.076329) (xy 17.386956 -94.060268) (xy 17.438291 -94.052138) (xy 17.490265 -94.052138)
			(xy 17.5416 -94.060268) (xy 17.59103 -94.076329) (xy 17.63734 -94.099925) (xy 17.679388 -94.130475)
			(xy 17.716139 -94.167226) (xy 17.746689 -94.209274) (xy 17.770285 -94.255584) (xy 17.786346 -94.305014)
			(xy 17.794476 -94.356349) (xy 17.794986 -94.382336) (xy 17.794476 -94.408323) (xy 17.933926 -94.408323)
			(xy 17.933926 -94.356349) (xy 17.942056 -94.305014) (xy 17.958117 -94.255584) (xy 17.981713 -94.209274)
			(xy 18.012263 -94.167226) (xy 18.049014 -94.130475) (xy 18.091062 -94.099925) (xy 18.137372 -94.076329)
			(xy 18.186802 -94.060268) (xy 18.238137 -94.052138) (xy 18.290111 -94.052138) (xy 18.341446 -94.060268)
			(xy 18.390876 -94.076329) (xy 18.437186 -94.099925) (xy 18.479234 -94.130475) (xy 18.515985 -94.167226)
			(xy 18.546535 -94.209274) (xy 18.570131 -94.255584) (xy 18.586192 -94.305014) (xy 18.594322 -94.356349)
			(xy 18.594832 -94.382336) (xy 18.594322 -94.408323) (xy 18.586192 -94.459658) (xy 18.570131 -94.509088)
			(xy 18.546535 -94.555398) (xy 18.515985 -94.597446) (xy 18.479234 -94.634197) (xy 18.437186 -94.664747)
			(xy 18.390876 -94.688343) (xy 18.341446 -94.704404) (xy 18.290111 -94.712534) (xy 18.238137 -94.712534)
			(xy 18.186802 -94.704404) (xy 18.137372 -94.688343) (xy 18.091062 -94.664747) (xy 18.049014 -94.634197)
			(xy 18.012263 -94.597446) (xy 17.981713 -94.555398) (xy 17.958117 -94.509088) (xy 17.942056 -94.459658)
			(xy 17.933926 -94.408323) (xy 17.794476 -94.408323) (xy 17.786346 -94.459658) (xy 17.770285 -94.509088)
			(xy 17.746689 -94.555398) (xy 17.716139 -94.597446) (xy 17.679388 -94.634197) (xy 17.63734 -94.664747)
			(xy 17.59103 -94.688343) (xy 17.5416 -94.704404) (xy 17.490265 -94.712534) (xy 17.438291 -94.712534)
			(xy 17.386956 -94.704404) (xy 17.337526 -94.688343) (xy 17.291216 -94.664747) (xy 17.249168 -94.634197)
			(xy 17.212417 -94.597446) (xy 17.181867 -94.555398) (xy 17.158271 -94.509088) (xy 17.14221 -94.459658)
			(xy 17.13408 -94.408323) (xy 16.994376 -94.408323) (xy 16.986246 -94.459658) (xy 16.970185 -94.509088)
			(xy 16.946589 -94.555398) (xy 16.916039 -94.597446) (xy 16.879288 -94.634197) (xy 16.83724 -94.664747)
			(xy 16.79093 -94.688343) (xy 16.7415 -94.704404) (xy 16.690165 -94.712534) (xy 16.638191 -94.712534)
			(xy 16.586856 -94.704404) (xy 16.537426 -94.688343) (xy 16.491116 -94.664747) (xy 16.449068 -94.634197)
			(xy 16.412317 -94.597446) (xy 16.381767 -94.555398) (xy 16.358171 -94.509088) (xy 16.34211 -94.459658)
			(xy 16.33398 -94.408323) (xy 16.0782 -94.408323) (xy 16.0782 -95.208169) (xy 16.33398 -95.208169)
			(xy 16.33398 -95.156195) (xy 16.34211 -95.10486) (xy 16.358171 -95.05543) (xy 16.381767 -95.00912)
			(xy 16.412317 -94.967072) (xy 16.449068 -94.930321) (xy 16.491116 -94.899771) (xy 16.537426 -94.876175)
			(xy 16.586856 -94.860114) (xy 16.638191 -94.851984) (xy 16.690165 -94.851984) (xy 16.7415 -94.860114)
			(xy 16.79093 -94.876175) (xy 16.83724 -94.899771) (xy 16.879288 -94.930321) (xy 16.916039 -94.967072)
			(xy 16.946589 -95.00912) (xy 16.970185 -95.05543) (xy 16.986246 -95.10486) (xy 16.994376 -95.156195)
			(xy 16.994886 -95.182182) (xy 16.994376 -95.208169) (xy 17.13408 -95.208169) (xy 17.13408 -95.156195)
			(xy 17.14221 -95.10486) (xy 17.158271 -95.05543) (xy 17.181867 -95.00912) (xy 17.212417 -94.967072)
			(xy 17.249168 -94.930321) (xy 17.291216 -94.899771) (xy 17.337526 -94.876175) (xy 17.386956 -94.860114)
			(xy 17.438291 -94.851984) (xy 17.490265 -94.851984) (xy 17.5416 -94.860114) (xy 17.59103 -94.876175)
			(xy 17.63734 -94.899771) (xy 17.679388 -94.930321) (xy 17.716139 -94.967072) (xy 17.746689 -95.00912)
			(xy 17.770285 -95.05543) (xy 17.786346 -95.10486) (xy 17.794476 -95.156195) (xy 17.794986 -95.182182)
			(xy 17.794476 -95.208169) (xy 17.786346 -95.259504) (xy 17.770285 -95.308934) (xy 17.746689 -95.355244)
			(xy 17.716139 -95.397292) (xy 17.679388 -95.434043) (xy 17.63734 -95.464593) (xy 17.59103 -95.488189)
			(xy 17.5416 -95.50425) (xy 17.490265 -95.51238) (xy 17.438291 -95.51238) (xy 17.386956 -95.50425)
			(xy 17.337526 -95.488189) (xy 17.291216 -95.464593) (xy 17.249168 -95.434043) (xy 17.212417 -95.397292)
			(xy 17.181867 -95.355244) (xy 17.158271 -95.308934) (xy 17.14221 -95.259504) (xy 17.13408 -95.208169)
			(xy 16.994376 -95.208169) (xy 16.986246 -95.259504) (xy 16.970185 -95.308934) (xy 16.946589 -95.355244)
			(xy 16.916039 -95.397292) (xy 16.879288 -95.434043) (xy 16.83724 -95.464593) (xy 16.79093 -95.488189)
			(xy 16.7415 -95.50425) (xy 16.690165 -95.51238) (xy 16.638191 -95.51238) (xy 16.586856 -95.50425)
			(xy 16.537426 -95.488189) (xy 16.491116 -95.464593) (xy 16.449068 -95.434043) (xy 16.412317 -95.397292)
			(xy 16.381767 -95.355244) (xy 16.358171 -95.308934) (xy 16.34211 -95.259504) (xy 16.33398 -95.208169)
			(xy 16.0782 -95.208169) (xy 16.0782 -96.008269) (xy 17.13408 -96.008269) (xy 17.13408 -95.956295)
			(xy 17.14221 -95.90496) (xy 17.158271 -95.85553) (xy 17.181867 -95.80922) (xy 17.212417 -95.767172)
			(xy 17.249168 -95.730421) (xy 17.291216 -95.699871) (xy 17.337526 -95.676275) (xy 17.386956 -95.660214)
			(xy 17.438291 -95.652084) (xy 17.490265 -95.652084) (xy 17.5416 -95.660214) (xy 17.59103 -95.676275)
			(xy 17.63734 -95.699871) (xy 17.679388 -95.730421) (xy 17.716139 -95.767172) (xy 17.746689 -95.80922)
			(xy 17.770285 -95.85553) (xy 17.786346 -95.90496) (xy 17.794476 -95.956295) (xy 17.794986 -95.982282)
			(xy 17.794476 -96.008269) (xy 17.786346 -96.059604) (xy 17.770285 -96.109034) (xy 17.746689 -96.155344)
			(xy 17.716139 -96.197392) (xy 17.679388 -96.234143) (xy 17.63734 -96.264693) (xy 17.59103 -96.288289)
			(xy 17.5416 -96.30435) (xy 17.490265 -96.31248) (xy 17.438291 -96.31248) (xy 17.386956 -96.30435)
			(xy 17.337526 -96.288289) (xy 17.291216 -96.264693) (xy 17.249168 -96.234143) (xy 17.212417 -96.197392)
			(xy 17.181867 -96.155344) (xy 17.158271 -96.109034) (xy 17.14221 -96.059604) (xy 17.13408 -96.008269)
			(xy 16.0782 -96.008269) (xy 16.0782 -96.2406) (xy 15.7226 -96.5962) (xy 15.7226 -96.808369) (xy 16.33398 -96.808369)
			(xy 16.33398 -96.756395) (xy 16.34211 -96.70506) (xy 16.358171 -96.65563) (xy 16.381767 -96.60932)
			(xy 16.412317 -96.567272) (xy 16.449068 -96.530521) (xy 16.491116 -96.499971) (xy 16.537426 -96.476375)
			(xy 16.586856 -96.460314) (xy 16.638191 -96.452184) (xy 16.690165 -96.452184) (xy 16.7415 -96.460314)
			(xy 16.79093 -96.476375) (xy 16.83724 -96.499971) (xy 16.879288 -96.530521) (xy 16.916039 -96.567272)
			(xy 16.946589 -96.60932) (xy 16.970185 -96.65563) (xy 16.986246 -96.70506) (xy 16.994376 -96.756395)
			(xy 16.994886 -96.782382) (xy 16.994376 -96.808369) (xy 17.124428 -96.808369) (xy 17.124428 -96.756395)
			(xy 17.132558 -96.70506) (xy 17.148619 -96.65563) (xy 17.172215 -96.60932) (xy 17.202765 -96.567272)
			(xy 17.239516 -96.530521) (xy 17.281564 -96.499971) (xy 17.327874 -96.476375) (xy 17.377304 -96.460314)
			(xy 17.428639 -96.452184) (xy 17.480613 -96.452184) (xy 17.531948 -96.460314) (xy 17.581378 -96.476375)
			(xy 17.627688 -96.499971) (xy 17.669736 -96.530521) (xy 17.706487 -96.567272) (xy 17.737037 -96.60932)
			(xy 17.760633 -96.65563) (xy 17.776694 -96.70506) (xy 17.784824 -96.756395) (xy 17.785334 -96.782382)
			(xy 17.784824 -96.808369) (xy 17.776694 -96.859704) (xy 17.760633 -96.909134) (xy 17.737037 -96.955444)
			(xy 17.706487 -96.997492) (xy 17.669736 -97.034243) (xy 17.627688 -97.064793) (xy 17.581378 -97.088389)
			(xy 17.531948 -97.10445) (xy 17.480613 -97.11258) (xy 17.428639 -97.11258) (xy 17.377304 -97.10445)
			(xy 17.327874 -97.088389) (xy 17.281564 -97.064793) (xy 17.239516 -97.034243) (xy 17.202765 -96.997492)
			(xy 17.172215 -96.955444) (xy 17.148619 -96.909134) (xy 17.132558 -96.859704) (xy 17.124428 -96.808369)
			(xy 16.994376 -96.808369) (xy 16.986246 -96.859704) (xy 16.970185 -96.909134) (xy 16.946589 -96.955444)
			(xy 16.916039 -96.997492) (xy 16.879288 -97.034243) (xy 16.83724 -97.064793) (xy 16.79093 -97.088389)
			(xy 16.7415 -97.10445) (xy 16.690165 -97.11258) (xy 16.638191 -97.11258) (xy 16.586856 -97.10445)
			(xy 16.537426 -97.088389) (xy 16.491116 -97.064793) (xy 16.449068 -97.034243) (xy 16.412317 -96.997492)
			(xy 16.381767 -96.955444) (xy 16.358171 -96.909134) (xy 16.34211 -96.859704) (xy 16.33398 -96.808369)
			(xy 15.7226 -96.808369) (xy 15.7226 -97.608215) (xy 16.33398 -97.608215) (xy 16.33398 -97.556241)
			(xy 16.34211 -97.504906) (xy 16.358171 -97.455476) (xy 16.381767 -97.409166) (xy 16.412317 -97.367118)
			(xy 16.449068 -97.330367) (xy 16.491116 -97.299817) (xy 16.537426 -97.276221) (xy 16.586856 -97.26016)
			(xy 16.638191 -97.25203) (xy 16.690165 -97.25203) (xy 16.7415 -97.26016) (xy 16.79093 -97.276221)
			(xy 16.83724 -97.299817) (xy 16.879288 -97.330367) (xy 16.916039 -97.367118) (xy 16.946589 -97.409166)
			(xy 16.970185 -97.455476) (xy 16.986246 -97.504906) (xy 16.994376 -97.556241) (xy 16.994886 -97.582228)
			(xy 16.994376 -97.608215) (xy 16.986246 -97.65955) (xy 16.970185 -97.70898) (xy 16.946589 -97.75529)
			(xy 16.916039 -97.797338) (xy 16.879288 -97.834089) (xy 16.83724 -97.864639) (xy 16.79093 -97.888235)
			(xy 16.7415 -97.904296) (xy 16.690165 -97.912426) (xy 16.638191 -97.912426) (xy 16.586856 -97.904296)
			(xy 16.537426 -97.888235) (xy 16.491116 -97.864639) (xy 16.449068 -97.834089) (xy 16.412317 -97.797338)
			(xy 16.381767 -97.75529) (xy 16.358171 -97.70898) (xy 16.34211 -97.65955) (xy 16.33398 -97.608215)
			(xy 15.7226 -97.608215) (xy 15.7226 -98.408315) (xy 16.33398 -98.408315) (xy 16.33398 -98.356341)
			(xy 16.34211 -98.305006) (xy 16.358171 -98.255576) (xy 16.381767 -98.209266) (xy 16.412317 -98.167218)
			(xy 16.449068 -98.130467) (xy 16.491116 -98.099917) (xy 16.537426 -98.076321) (xy 16.586856 -98.06026)
			(xy 16.638191 -98.05213) (xy 16.690165 -98.05213) (xy 16.7415 -98.06026) (xy 16.79093 -98.076321)
			(xy 16.83724 -98.099917) (xy 16.879288 -98.130467) (xy 16.916039 -98.167218) (xy 16.946589 -98.209266)
			(xy 16.970185 -98.255576) (xy 16.986246 -98.305006) (xy 16.994376 -98.356341) (xy 16.994886 -98.382328)
			(xy 16.994376 -98.408315) (xy 16.986246 -98.45965) (xy 16.970185 -98.50908) (xy 16.946589 -98.55539)
			(xy 16.916039 -98.597438) (xy 16.879288 -98.634189) (xy 16.83724 -98.664739) (xy 16.79093 -98.688335)
			(xy 16.7415 -98.704396) (xy 16.690165 -98.712526) (xy 16.638191 -98.712526) (xy 16.586856 -98.704396)
			(xy 16.537426 -98.688335) (xy 16.491116 -98.664739) (xy 16.449068 -98.634189) (xy 16.412317 -98.597438)
			(xy 16.381767 -98.55539) (xy 16.358171 -98.50908) (xy 16.34211 -98.45965) (xy 16.33398 -98.408315)
			(xy 15.7226 -98.408315) (xy 15.7226 -98.5266) (xy 16.3068 -99.1108) (xy 18.4912 -99.1108)
		)
		(stroke
			(width 0)
			(type solid)
		)
		(fill yes)
		(layer "In7.Cu")
		(net "VCCIO1")
	)
	(gr_poly
		(pts
			(xy 77.834236 -64.882268) (xy 77.85586 -64.861287) (xy 77.904493 -64.825725) (xy 77.95811 -64.798246)
			(xy 78.015378 -64.779533) (xy 78.074876 -64.77005) (xy 78.105 -64.769492) (xy 78.117225 -64.769576)
			(xy 78.141628 -64.771099) (xy 78.153768 -64.77254) (xy 78.17866 -64.775842) (xy 78.299564 -64.654938)
			(xy 78.299564 -61.659008) (xy 78.300114 -61.630841) (xy 78.308915 -61.5752) (xy 78.326304 -61.521618)
			(xy 78.351851 -61.471411) (xy 78.38493 -61.425813) (xy 78.404466 -61.405516) (xy 78.623414 -61.186568)
			(xy 78.623414 -61.024516) (xy 78.577948 -61.01969) (xy 78.550191 -61.016246) (xy 78.496032 -61.002277)
			(xy 78.444491 -60.980553) (xy 78.396674 -60.951538) (xy 78.353604 -60.915855) (xy 78.316203 -60.874267)
			(xy 78.285274 -60.827665) (xy 78.261478 -60.777048) (xy 78.245325 -60.7235) (xy 78.23716 -60.668167)
			(xy 78.23716 -60.612236) (xy 78.245324 -60.556903) (xy 78.261477 -60.503355) (xy 78.285272 -60.452737)
			(xy 78.316202 -60.406136) (xy 78.353602 -60.364547) (xy 78.396672 -60.328863) (xy 78.444489 -60.299848)
			(xy 78.496029 -60.278124) (xy 78.550188 -60.264154) (xy 78.577948 -60.260738) (xy 78.623414 -60.255912)
			(xy 78.623414 -60.16371) (xy 78.577948 -60.158884) (xy 78.550191 -60.15544) (xy 78.496033 -60.141471)
			(xy 78.444493 -60.119747) (xy 78.396677 -60.090733) (xy 78.353608 -60.05505) (xy 78.316208 -60.013463)
			(xy 78.285279 -59.966862) (xy 78.261483 -59.916245) (xy 78.24533 -59.862698) (xy 78.237166 -59.807366)
			(xy 78.237166 -59.751435) (xy 78.24533 -59.696104) (xy 78.261482 -59.642556) (xy 78.285278 -59.59194)
			(xy 78.316207 -59.545339) (xy 78.353606 -59.503751) (xy 78.396676 -59.468068) (xy 78.444492 -59.439053)
			(xy 78.496031 -59.417329) (xy 78.55019 -59.40336) (xy 78.577948 -59.399932) (xy 78.623414 -59.395106)
			(xy 78.623414 -58.749946) (xy 78.577948 -58.74512) (xy 78.550194 -58.741681) (xy 78.496042 -58.727719)
			(xy 78.444508 -58.705999) (xy 78.3967 -58.676985) (xy 78.353642 -58.6413) (xy 78.316257 -58.599709)
			(xy 78.285348 -58.553104) (xy 78.261576 -58.502484) (xy 78.245452 -58.448935) (xy 78.237322 -58.393606)
			(xy 78.236826 -58.365644) (xy 78.237192 -58.341375) (xy 78.24331 -58.293224) (xy 78.249018 -58.269632)
			(xy 78.256384 -58.241438) (xy 75.266296 -55.25135) (xy 75.254358 -55.24754) (xy 75.22975 -55.239223)
			(xy 75.182869 -55.216856) (xy 75.139456 -55.188335) (xy 75.100313 -55.154188) (xy 75.066166 -55.115046)
			(xy 75.037645 -55.071633) (xy 75.015278 -55.024752) (xy 75.006962 -55.000144) (xy 75.003152 -54.988206)
			(xy 74.523092 -54.508146) (xy 74.487278 -54.539134) (xy 74.46914 -54.554289) (xy 74.429376 -54.579837)
			(xy 74.386381 -54.599469) (xy 74.341031 -54.612783) (xy 74.294248 -54.61951) (xy 74.270616 -54.619906)
			(xy 74.244626 -54.619424) (xy 74.193286 -54.611295) (xy 74.143849 -54.595234) (xy 74.097534 -54.571637)
			(xy 74.05548 -54.541085) (xy 74.018724 -54.50433) (xy 73.98817 -54.462278) (xy 73.964571 -54.415964)
			(xy 73.948508 -54.366528) (xy 73.940377 -54.315188) (xy 73.939908 -54.289198) (xy 73.940329 -54.265567)
			(xy 73.947052 -54.218785) (xy 73.960361 -54.173436) (xy 73.979986 -54.13044) (xy 74.005527 -54.090674)
			(xy 74.02068 -54.072536) (xy 74.026628 -54.065067) (xy 74.033002 -54.047084) (xy 74.032379 -54.028015)
			(xy 74.024844 -54.010486) (xy 74.018394 -54.003448) (xy 73.756266 -53.74132) (xy 73.749217 -53.734876)
			(xy 73.731697 -53.727309) (xy 73.712623 -53.72668) (xy 73.694642 -53.733075) (xy 73.687178 -53.739034)
			(xy 73.66904 -53.754189) (xy 73.629276 -53.779737) (xy 73.586281 -53.799369) (xy 73.540931 -53.812683)
			(xy 73.494148 -53.81941) (xy 73.470516 -53.819806) (xy 73.444526 -53.819324) (xy 73.393186 -53.811195)
			(xy 73.343749 -53.795134) (xy 73.297434 -53.771537) (xy 73.25538 -53.740985) (xy 73.218624 -53.70423)
			(xy 73.18807 -53.662178) (xy 73.164471 -53.615864) (xy 73.148408 -53.566428) (xy 73.140277 -53.515088)
			(xy 73.139808 -53.489098) (xy 73.140229 -53.465467) (xy 73.146952 -53.418685) (xy 73.160261 -53.373336)
			(xy 73.179886 -53.33034) (xy 73.205427 -53.290574) (xy 73.22058 -53.272436) (xy 73.251568 -53.236622)
			(xy 70.13956 -50.124614) (xy 65.621916 -50.124614) (xy 65.6209 -50.174144) (xy 65.61983 -50.19974)
			(xy 65.610769 -50.250159) (xy 65.594044 -50.298579) (xy 65.570054 -50.343842) (xy 65.539374 -50.384866)
			(xy 65.502736 -50.420669) (xy 65.461016 -50.450396) (xy 65.415213 -50.473337) (xy 65.36642 -50.488943)
			(xy 65.315806 -50.49684) (xy 65.264578 -50.49684) (xy 65.213964 -50.488943) (xy 65.165171 -50.473337)
			(xy 65.119368 -50.450396) (xy 65.077648 -50.420669) (xy 65.04101 -50.384866) (xy 65.01033 -50.343842)
			(xy 64.98634 -50.298579) (xy 64.969615 -50.250159) (xy 64.960554 -50.19974) (xy 64.959484 -50.174144)
			(xy 64.958468 -50.124614) (xy 64.821816 -50.124614) (xy 64.8208 -50.174144) (xy 64.81973 -50.19974)
			(xy 64.810669 -50.250159) (xy 64.793944 -50.298579) (xy 64.769954 -50.343842) (xy 64.739274 -50.384866)
			(xy 64.702636 -50.420669) (xy 64.660916 -50.450396) (xy 64.615113 -50.473337) (xy 64.56632 -50.488943)
			(xy 64.515706 -50.49684) (xy 64.464478 -50.49684) (xy 64.413864 -50.488943) (xy 64.365071 -50.473337)
			(xy 64.319268 -50.450396) (xy 64.277548 -50.420669) (xy 64.24091 -50.384866) (xy 64.21023 -50.343842)
			(xy 64.18624 -50.298579) (xy 64.169515 -50.250159) (xy 64.160454 -50.19974) (xy 64.159384 -50.174144)
			(xy 64.158368 -50.124614) (xy 64.02197 -50.124614) (xy 64.020954 -50.174144) (xy 64.019884 -50.19974)
			(xy 64.010823 -50.250159) (xy 63.994098 -50.298579) (xy 63.970108 -50.343842) (xy 63.939428 -50.384866)
			(xy 63.90279 -50.420669) (xy 63.86107 -50.450396) (xy 63.815267 -50.473337) (xy 63.766474 -50.488943)
			(xy 63.71586 -50.49684) (xy 63.664632 -50.49684) (xy 63.614018 -50.488943) (xy 63.565225 -50.473337)
			(xy 63.519422 -50.450396) (xy 63.477702 -50.420669) (xy 63.441064 -50.384866) (xy 63.410384 -50.343842)
			(xy 63.386394 -50.298579) (xy 63.369669 -50.250159) (xy 63.360608 -50.19974) (xy 63.359538 -50.174144)
			(xy 63.358522 -50.124614) (xy 63.22187 -50.124614) (xy 63.220854 -50.174144) (xy 63.219784 -50.19974)
			(xy 63.210723 -50.250159) (xy 63.193998 -50.298579) (xy 63.170008 -50.343842) (xy 63.139328 -50.384866)
			(xy 63.10269 -50.420669) (xy 63.06097 -50.450396) (xy 63.015167 -50.473337) (xy 62.966374 -50.488943)
			(xy 62.91576 -50.49684) (xy 62.864532 -50.49684) (xy 62.813918 -50.488943) (xy 62.765125 -50.473337)
			(xy 62.719322 -50.450396) (xy 62.677602 -50.420669) (xy 62.640964 -50.384866) (xy 62.610284 -50.343842)
			(xy 62.586294 -50.298579) (xy 62.569569 -50.250159) (xy 62.560508 -50.19974) (xy 62.559438 -50.174144)
			(xy 62.558422 -50.124614) (xy 62.422024 -50.124614) (xy 62.421008 -50.174144) (xy 62.419943 -50.199738)
			(xy 62.410889 -50.250154) (xy 62.394168 -50.298571) (xy 62.370179 -50.34383) (xy 62.339496 -50.384847)
			(xy 62.302854 -50.42064) (xy 62.26113 -50.450353) (xy 62.215322 -50.473276) (xy 62.166527 -50.488858)
			(xy 62.115912 -50.496728) (xy 62.0903 -50.497232) (xy 62.066971 -50.496851) (xy 62.020771 -50.490328)
			(xy 61.975948 -50.477368) (xy 61.933396 -50.45823) (xy 61.89396 -50.433295) (xy 61.875924 -50.418492)
			(xy 61.787278 -50.507138) (xy 61.787278 -50.583846) (xy 61.787796 -50.598786) (xy 61.796431 -50.627391)
			(xy 61.812978 -50.65227) (xy 61.836019 -50.671294) (xy 61.863582 -50.682832) (xy 61.893304 -50.685896)
			(xy 61.92264 -50.680224) (xy 61.936122 -50.673762) (xy 61.960029 -50.661756) (xy 62.010755 -50.644772)
			(xy 62.063553 -50.636168) (xy 62.0903 -50.635662) (xy 62.11629 -50.636172) (xy 62.167629 -50.644303)
			(xy 62.217064 -50.660365) (xy 62.263377 -50.683963) (xy 62.305429 -50.714516) (xy 62.342184 -50.751271)
			(xy 62.372737 -50.793323) (xy 62.396335 -50.839636) (xy 62.412397 -50.889071) (xy 62.420528 -50.94041)
			(xy 62.420528 -50.992357) (xy 62.559948 -50.992357) (xy 62.559948 -50.940383) (xy 62.568078 -50.889048)
			(xy 62.584139 -50.839618) (xy 62.607735 -50.793308) (xy 62.638285 -50.75126) (xy 62.675036 -50.714509)
			(xy 62.717084 -50.683959) (xy 62.763394 -50.660363) (xy 62.812824 -50.644302) (xy 62.864159 -50.636172)
			(xy 62.916133 -50.636172) (xy 62.967468 -50.644302) (xy 63.016898 -50.660363) (xy 63.063208 -50.683959)
			(xy 63.105256 -50.714509) (xy 63.142007 -50.75126) (xy 63.172557 -50.793308) (xy 63.196153 -50.839618)
			(xy 63.212214 -50.889048) (xy 63.220344 -50.940383) (xy 63.220854 -50.96637) (xy 63.220344 -50.992357)
			(xy 63.360048 -50.992357) (xy 63.360048 -50.940383) (xy 63.368178 -50.889048) (xy 63.384239 -50.839618)
			(xy 63.407835 -50.793308) (xy 63.438385 -50.75126) (xy 63.475136 -50.714509) (xy 63.517184 -50.683959)
			(xy 63.563494 -50.660363) (xy 63.612924 -50.644302) (xy 63.664259 -50.636172) (xy 63.716233 -50.636172)
			(xy 63.767568 -50.644302) (xy 63.816998 -50.660363) (xy 63.863308 -50.683959) (xy 63.905356 -50.714509)
			(xy 63.942107 -50.75126) (xy 63.972657 -50.793308) (xy 63.996253 -50.839618) (xy 64.012314 -50.889048)
			(xy 64.020444 -50.940383) (xy 64.020954 -50.96637) (xy 64.020444 -50.992357) (xy 64.159894 -50.992357)
			(xy 64.159894 -50.940383) (xy 64.168024 -50.889048) (xy 64.184085 -50.839618) (xy 64.207681 -50.793308)
			(xy 64.238231 -50.75126) (xy 64.274982 -50.714509) (xy 64.31703 -50.683959) (xy 64.36334 -50.660363)
			(xy 64.41277 -50.644302) (xy 64.464105 -50.636172) (xy 64.516079 -50.636172) (xy 64.567414 -50.644302)
			(xy 64.616844 -50.660363) (xy 64.663154 -50.683959) (xy 64.705202 -50.714509) (xy 64.741953 -50.75126)
			(xy 64.772503 -50.793308) (xy 64.796099 -50.839618) (xy 64.81216 -50.889048) (xy 64.82029 -50.940383)
			(xy 64.8208 -50.96637) (xy 64.82029 -50.992357) (xy 64.959994 -50.992357) (xy 64.959994 -50.940383)
			(xy 64.968124 -50.889048) (xy 64.984185 -50.839618) (xy 65.007781 -50.793308) (xy 65.038331 -50.75126)
			(xy 65.075082 -50.714509) (xy 65.11713 -50.683959) (xy 65.16344 -50.660363) (xy 65.21287 -50.644302)
			(xy 65.264205 -50.636172) (xy 65.316179 -50.636172) (xy 65.367514 -50.644302) (xy 65.416944 -50.660363)
			(xy 65.463254 -50.683959) (xy 65.505302 -50.714509) (xy 65.542053 -50.75126) (xy 65.572603 -50.793308)
			(xy 65.596199 -50.839618) (xy 65.61226 -50.889048) (xy 65.62039 -50.940383) (xy 65.6209 -50.96637)
			(xy 65.62039 -50.992357) (xy 65.61226 -51.043692) (xy 65.596199 -51.093122) (xy 65.572603 -51.139432)
			(xy 65.542053 -51.18148) (xy 65.505302 -51.218231) (xy 65.463254 -51.248781) (xy 65.416944 -51.272377)
			(xy 65.367514 -51.288438) (xy 65.316179 -51.296568) (xy 65.264205 -51.296568) (xy 65.21287 -51.288438)
			(xy 65.16344 -51.272377) (xy 65.11713 -51.248781) (xy 65.075082 -51.218231) (xy 65.038331 -51.18148)
			(xy 65.007781 -51.139432) (xy 64.984185 -51.093122) (xy 64.968124 -51.043692) (xy 64.959994 -50.992357)
			(xy 64.82029 -50.992357) (xy 64.81216 -51.043692) (xy 64.796099 -51.093122) (xy 64.772503 -51.139432)
			(xy 64.741953 -51.18148) (xy 64.705202 -51.218231) (xy 64.663154 -51.248781) (xy 64.616844 -51.272377)
			(xy 64.567414 -51.288438) (xy 64.516079 -51.296568) (xy 64.464105 -51.296568) (xy 64.41277 -51.288438)
			(xy 64.36334 -51.272377) (xy 64.31703 -51.248781) (xy 64.274982 -51.218231) (xy 64.238231 -51.18148)
			(xy 64.207681 -51.139432) (xy 64.184085 -51.093122) (xy 64.168024 -51.043692) (xy 64.159894 -50.992357)
			(xy 64.020444 -50.992357) (xy 64.012314 -51.043692) (xy 63.996253 -51.093122) (xy 63.972657 -51.139432)
			(xy 63.942107 -51.18148) (xy 63.905356 -51.218231) (xy 63.863308 -51.248781) (xy 63.816998 -51.272377)
			(xy 63.767568 -51.288438) (xy 63.716233 -51.296568) (xy 63.664259 -51.296568) (xy 63.612924 -51.288438)
			(xy 63.563494 -51.272377) (xy 63.517184 -51.248781) (xy 63.475136 -51.218231) (xy 63.438385 -51.18148)
			(xy 63.407835 -51.139432) (xy 63.384239 -51.093122) (xy 63.368178 -51.043692) (xy 63.360048 -50.992357)
			(xy 63.220344 -50.992357) (xy 63.212214 -51.043692) (xy 63.196153 -51.093122) (xy 63.172557 -51.139432)
			(xy 63.142007 -51.18148) (xy 63.105256 -51.218231) (xy 63.063208 -51.248781) (xy 63.016898 -51.272377)
			(xy 62.967468 -51.288438) (xy 62.916133 -51.296568) (xy 62.864159 -51.296568) (xy 62.812824 -51.288438)
			(xy 62.763394 -51.272377) (xy 62.717084 -51.248781) (xy 62.675036 -51.218231) (xy 62.638285 -51.18148)
			(xy 62.607735 -51.139432) (xy 62.584139 -51.093122) (xy 62.568078 -51.043692) (xy 62.559948 -50.992357)
			(xy 62.420528 -50.992357) (xy 62.420528 -50.99239) (xy 62.412397 -51.043729) (xy 62.396335 -51.093164)
			(xy 62.372737 -51.139477) (xy 62.342184 -51.181529) (xy 62.305429 -51.218284) (xy 62.263377 -51.248837)
			(xy 62.217064 -51.272435) (xy 62.167629 -51.288497) (xy 62.11629 -51.296628) (xy 62.0903 -51.297078)
			(xy 62.063553 -51.296565) (xy 62.010755 -51.287965) (xy 61.960026 -51.270988) (xy 61.936122 -51.258978)
			(xy 61.922657 -51.252499) (xy 61.893327 -51.246855) (xy 61.863618 -51.249938) (xy 61.836072 -51.261482)
			(xy 61.813042 -51.280502) (xy 61.7965 -51.30537) (xy 61.787858 -51.33396) (xy 61.787278 -51.348894)
			(xy 61.787278 -51.84902) (xy 61.905134 -51.966876) (xy 62.347094 -51.966876) (xy 62.358524 -51.9557)
			(xy 62.466728 -51.9557) (xy 62.481786 -51.955156) (xy 62.510595 -51.946376) (xy 62.535597 -51.929586)
			(xy 62.554625 -51.906242) (xy 62.566029 -51.878368) (xy 62.56882 -51.84838) (xy 62.566296 -51.833526)
			(xy 62.563076 -51.816949) (xy 62.559636 -51.783355) (xy 62.559438 -51.76647) (xy 62.559948 -51.740483)
			(xy 62.568078 -51.689148) (xy 62.584139 -51.639718) (xy 62.607735 -51.593408) (xy 62.638285 -51.55136)
			(xy 62.675036 -51.514609) (xy 62.717084 -51.484059) (xy 62.763394 -51.460463) (xy 62.812824 -51.444402)
			(xy 62.864159 -51.436272) (xy 62.916133 -51.436272) (xy 62.967468 -51.444402) (xy 63.016898 -51.460463)
			(xy 63.063208 -51.484059) (xy 63.105256 -51.514609) (xy 63.142007 -51.55136) (xy 63.172557 -51.593408)
			(xy 63.196153 -51.639718) (xy 63.212214 -51.689148) (xy 63.220344 -51.740483) (xy 63.220854 -51.76647)
			(xy 63.220641 -51.783354) (xy 63.217205 -51.816948) (xy 63.213996 -51.833526) (xy 63.211477 -51.848386)
			(xy 63.214245 -51.878383) (xy 63.225638 -51.906269) (xy 63.244668 -51.929622) (xy 63.269681 -51.94641)
			(xy 63.298502 -51.955176) (xy 63.313564 -51.9557) (xy 63.385446 -51.9557) (xy 63.385446 -51.895248)
			(xy 63.382144 -51.886358) (xy 63.371614 -51.857511) (xy 63.360229 -51.797171) (xy 63.359538 -51.76647)
			(xy 63.360048 -51.740483) (xy 63.368178 -51.689148) (xy 63.384239 -51.639718) (xy 63.407835 -51.593408)
			(xy 63.438385 -51.55136) (xy 63.475136 -51.514609) (xy 63.517184 -51.484059) (xy 63.563494 -51.460463)
			(xy 63.612924 -51.444402) (xy 63.664259 -51.436272) (xy 63.716233 -51.436272) (xy 63.767568 -51.444402)
			(xy 63.816998 -51.460463) (xy 63.863308 -51.484059) (xy 63.905356 -51.514609) (xy 63.942107 -51.55136)
			(xy 63.972657 -51.593408) (xy 63.996253 -51.639718) (xy 64.012314 -51.689148) (xy 64.020444 -51.740483)
			(xy 64.020954 -51.76647) (xy 64.020741 -51.783354) (xy 64.017305 -51.816948) (xy 64.014096 -51.833526)
			(xy 64.011577 -51.848386) (xy 64.014345 -51.878383) (xy 64.025738 -51.906269) (xy 64.044768 -51.929622)
			(xy 64.069781 -51.94641) (xy 64.098602 -51.955176) (xy 64.113664 -51.9557) (xy 69.525134 -51.9557)
			(xy 71.084519 -53.515085) (xy 72.340726 -53.515085) (xy 72.340726 -53.463111) (xy 72.348856 -53.411776)
			(xy 72.364917 -53.362346) (xy 72.388513 -53.316036) (xy 72.419063 -53.273988) (xy 72.455814 -53.237237)
			(xy 72.497862 -53.206687) (xy 72.544172 -53.183091) (xy 72.593602 -53.16703) (xy 72.644937 -53.1589)
			(xy 72.696911 -53.1589) (xy 72.748246 -53.16703) (xy 72.797676 -53.183091) (xy 72.843986 -53.206687)
			(xy 72.886034 -53.237237) (xy 72.922785 -53.273988) (xy 72.953335 -53.316036) (xy 72.976931 -53.362346)
			(xy 72.992992 -53.411776) (xy 73.001122 -53.463111) (xy 73.001632 -53.489098) (xy 73.001122 -53.515085)
			(xy 72.992992 -53.56642) (xy 72.976931 -53.61585) (xy 72.953335 -53.66216) (xy 72.922785 -53.704208)
			(xy 72.886034 -53.740959) (xy 72.843986 -53.771509) (xy 72.797676 -53.795105) (xy 72.748246 -53.811166)
			(xy 72.696911 -53.819296) (xy 72.644937 -53.819296) (xy 72.593602 -53.811166) (xy 72.544172 -53.795105)
			(xy 72.497862 -53.771509) (xy 72.455814 -53.740959) (xy 72.419063 -53.704208) (xy 72.388513 -53.66216)
			(xy 72.364917 -53.61585) (xy 72.348856 -53.56642) (xy 72.340726 -53.515085) (xy 71.084519 -53.515085)
			(xy 71.880555 -54.311121) (xy 72.340472 -54.311121) (xy 72.340472 -54.259147) (xy 72.348602 -54.207812)
			(xy 72.364663 -54.158382) (xy 72.388259 -54.112072) (xy 72.418809 -54.070024) (xy 72.45556 -54.033273)
			(xy 72.497608 -54.002723) (xy 72.543918 -53.979127) (xy 72.593348 -53.963066) (xy 72.644683 -53.954936)
			(xy 72.696657 -53.954936) (xy 72.747992 -53.963066) (xy 72.797422 -53.979127) (xy 72.843732 -54.002723)
			(xy 72.88578 -54.033273) (xy 72.922531 -54.070024) (xy 72.953081 -54.112072) (xy 72.976677 -54.158382)
			(xy 72.992738 -54.207812) (xy 73.000868 -54.259147) (xy 73.001378 -54.285134) (xy 73.000868 -54.311121)
			(xy 73.000224 -54.315185) (xy 73.140318 -54.315185) (xy 73.140318 -54.263211) (xy 73.148448 -54.211876)
			(xy 73.164509 -54.162446) (xy 73.188105 -54.116136) (xy 73.218655 -54.074088) (xy 73.255406 -54.037337)
			(xy 73.297454 -54.006787) (xy 73.343764 -53.983191) (xy 73.393194 -53.96713) (xy 73.444529 -53.959)
			(xy 73.496503 -53.959) (xy 73.547838 -53.96713) (xy 73.597268 -53.983191) (xy 73.643578 -54.006787)
			(xy 73.685626 -54.037337) (xy 73.722377 -54.074088) (xy 73.752927 -54.116136) (xy 73.776523 -54.162446)
			(xy 73.792584 -54.211876) (xy 73.800714 -54.263211) (xy 73.801224 -54.289198) (xy 73.800714 -54.315185)
			(xy 73.792584 -54.36652) (xy 73.776523 -54.41595) (xy 73.752927 -54.46226) (xy 73.722377 -54.504308)
			(xy 73.685626 -54.541059) (xy 73.643578 -54.571609) (xy 73.597268 -54.595205) (xy 73.547838 -54.611266)
			(xy 73.496503 -54.619396) (xy 73.444529 -54.619396) (xy 73.393194 -54.611266) (xy 73.343764 -54.595205)
			(xy 73.297454 -54.571609) (xy 73.255406 -54.541059) (xy 73.218655 -54.504308) (xy 73.188105 -54.46226)
			(xy 73.164509 -54.41595) (xy 73.148448 -54.36652) (xy 73.140318 -54.315185) (xy 73.000224 -54.315185)
			(xy 72.992738 -54.362456) (xy 72.976677 -54.411886) (xy 72.953081 -54.458196) (xy 72.922531 -54.500244)
			(xy 72.88578 -54.536995) (xy 72.843732 -54.567545) (xy 72.797422 -54.591141) (xy 72.747992 -54.607202)
			(xy 72.696657 -54.615332) (xy 72.644683 -54.615332) (xy 72.593348 -54.607202) (xy 72.543918 -54.591141)
			(xy 72.497608 -54.567545) (xy 72.45556 -54.536995) (xy 72.418809 -54.500244) (xy 72.388259 -54.458196)
			(xy 72.364663 -54.411886) (xy 72.348602 -54.362456) (xy 72.340472 -54.311121) (xy 71.880555 -54.311121)
			(xy 74.563224 -56.99379) (xy 74.563224 -58.37174) (xy 76.102972 -58.37174) (xy 76.103395 -58.345517)
			(xy 76.110598 -58.293566) (xy 76.124847 -58.243092) (xy 76.145874 -58.195044) (xy 76.173281 -58.150328)
			(xy 76.206554 -58.109786) (xy 76.245064 -58.074182) (xy 76.288087 -58.044186) (xy 76.311252 -58.031888)
			(xy 76.323498 -58.025093) (xy 76.344066 -58.006108) (xy 76.358704 -57.982249) (xy 76.366311 -57.955312)
			(xy 76.366316 -57.927321) (xy 76.358718 -57.900381) (xy 76.344087 -57.876518) (xy 76.323525 -57.857526)
			(xy 76.311252 -57.850786) (xy 76.288074 -57.838508) (xy 76.245038 -57.808523) (xy 76.206518 -57.772923)
			(xy 76.173241 -57.732379) (xy 76.145835 -57.687657) (xy 76.124817 -57.639601) (xy 76.110584 -57.589118)
			(xy 76.103404 -57.53716) (xy 76.102972 -57.510934) (xy 76.103458 -57.483683) (xy 76.111214 -57.429735)
			(xy 76.126569 -57.37744) (xy 76.149211 -57.327863) (xy 76.178677 -57.282013) (xy 76.214368 -57.240822)
			(xy 76.255559 -57.205131) (xy 76.301409 -57.175665) (xy 76.350986 -57.153023) (xy 76.403281 -57.137668)
			(xy 76.457229 -57.129912) (xy 76.511731 -57.129912) (xy 76.565679 -57.137668) (xy 76.617974 -57.153023)
			(xy 76.667551 -57.175665) (xy 76.713401 -57.205131) (xy 76.754592 -57.240822) (xy 76.790283 -57.282013)
			(xy 76.819749 -57.327863) (xy 76.842391 -57.37744) (xy 76.857746 -57.429735) (xy 76.865502 -57.483683)
			(xy 76.865988 -57.510934) (xy 76.865566 -57.537158) (xy 76.858365 -57.589109) (xy 76.844117 -57.639584)
			(xy 76.823092 -57.687633) (xy 76.795684 -57.73235) (xy 76.762411 -57.772892) (xy 76.723899 -57.808495)
			(xy 76.680874 -57.838489) (xy 76.657708 -57.850786) (xy 76.645429 -57.857497) (xy 76.62492 -57.876525)
			(xy 76.610333 -57.900397) (xy 76.602759 -57.927329) (xy 76.602763 -57.955305) (xy 76.610347 -57.982234)
			(xy 76.624942 -58.006101) (xy 76.645457 -58.025123) (xy 76.657708 -58.031888) (xy 76.680866 -58.044202)
			(xy 76.723903 -58.074181) (xy 76.762425 -58.109775) (xy 76.795704 -58.150313) (xy 76.823113 -58.19503)
			(xy 76.844134 -58.243082) (xy 76.858371 -58.293561) (xy 76.865554 -58.345516) (xy 76.865988 -58.37174)
			(xy 76.865502 -58.398991) (xy 76.857746 -58.452939) (xy 76.842391 -58.505234) (xy 76.819749 -58.554811)
			(xy 76.790283 -58.600661) (xy 76.754592 -58.641852) (xy 76.713401 -58.677543) (xy 76.667551 -58.707009)
			(xy 76.617974 -58.729651) (xy 76.565679 -58.745006) (xy 76.511731 -58.752762) (xy 76.457229 -58.752762)
			(xy 76.403281 -58.745006) (xy 76.350986 -58.729651) (xy 76.301409 -58.707009) (xy 76.255559 -58.677543)
			(xy 76.214368 -58.641852) (xy 76.178677 -58.600661) (xy 76.149211 -58.554811) (xy 76.126569 -58.505234)
			(xy 76.111214 -58.452939) (xy 76.103458 -58.398991) (xy 76.102972 -58.37174) (xy 74.563224 -58.37174)
			(xy 74.563224 -60.611512) (xy 74.528426 -60.64631) (xy 76.102972 -60.64631) (xy 76.103472 -60.619856)
			(xy 76.110797 -60.567458) (xy 76.125295 -60.516575) (xy 76.146687 -60.468184) (xy 76.174562 -60.423215)
			(xy 76.208386 -60.38253) (xy 76.247508 -60.346912) (xy 76.269088 -60.331604) (xy 76.280558 -60.323313)
			(xy 76.298669 -60.301573) (xy 76.310121 -60.275699) (xy 76.314033 -60.247676) (xy 76.310107 -60.219654)
			(xy 76.298644 -60.193785) (xy 76.280522 -60.172054) (xy 76.269088 -60.16371) (xy 76.247509 -60.148396)
			(xy 76.208368 -60.112791) (xy 76.174529 -60.072113) (xy 76.146642 -60.027145) (xy 76.125244 -59.978752)
			(xy 76.110745 -59.927865) (xy 76.103425 -59.87546) (xy 76.102972 -59.849004) (xy 76.103458 -59.821753)
			(xy 76.111214 -59.767805) (xy 76.126569 -59.71551) (xy 76.149211 -59.665933) (xy 76.178677 -59.620083)
			(xy 76.214368 -59.578892) (xy 76.255559 -59.543201) (xy 76.301409 -59.513735) (xy 76.350986 -59.491093)
			(xy 76.403281 -59.475738) (xy 76.457229 -59.467982) (xy 76.511731 -59.467982) (xy 76.565679 -59.475738)
			(xy 76.617974 -59.491093) (xy 76.667551 -59.513735) (xy 76.713401 -59.543201) (xy 76.754592 -59.578892)
			(xy 76.790283 -59.620083) (xy 76.819749 -59.665933) (xy 76.842391 -59.71551) (xy 76.857746 -59.767805)
			(xy 76.865502 -59.821753) (xy 76.865988 -59.849004) (xy 76.865516 -59.875459) (xy 76.858188 -59.927859)
			(xy 76.843687 -59.978744) (xy 76.822291 -60.027135) (xy 76.794411 -60.072104) (xy 76.760582 -60.112787)
			(xy 76.721454 -60.148404) (xy 76.699872 -60.16371) (xy 76.688526 -60.172133) (xy 76.670495 -60.193868)
			(xy 76.659093 -60.219706) (xy 76.655188 -60.247676) (xy 76.659079 -60.275647) (xy 76.670469 -60.30149)
			(xy 76.68849 -60.323234) (xy 76.699872 -60.331604) (xy 76.721449 -60.346921) (xy 76.760591 -60.382525)
			(xy 76.794432 -60.423201) (xy 76.82232 -60.468169) (xy 76.843719 -60.516561) (xy 76.858217 -60.567449)
			(xy 76.865536 -60.619854) (xy 76.865988 -60.64631) (xy 76.865502 -60.673561) (xy 76.857746 -60.727509)
			(xy 76.842391 -60.779804) (xy 76.819749 -60.829381) (xy 76.790283 -60.875231) (xy 76.754592 -60.916422)
			(xy 76.713401 -60.952113) (xy 76.667551 -60.981579) (xy 76.617974 -61.004221) (xy 76.565679 -61.019576)
			(xy 76.511731 -61.027332) (xy 76.457229 -61.027332) (xy 76.403281 -61.019576) (xy 76.350986 -61.004221)
			(xy 76.301409 -60.981579) (xy 76.255559 -60.952113) (xy 76.214368 -60.916422) (xy 76.178677 -60.875231)
			(xy 76.149211 -60.829381) (xy 76.126569 -60.779804) (xy 76.111214 -60.727509) (xy 76.103458 -60.673561)
			(xy 76.102972 -60.64631) (xy 74.528426 -60.64631) (xy 74.172318 -61.002418) (xy 74.172318 -62.106302)
			(xy 75.599034 -62.106302) (xy 75.603105 -62.05068) (xy 75.615231 -61.996243) (xy 75.635154 -61.944152)
			(xy 75.66245 -61.895517) (xy 75.696536 -61.851374) (xy 75.736685 -61.812665) (xy 75.782043 -61.780214)
			(xy 75.831643 -61.754713) (xy 75.884427 -61.736706) (xy 75.93927 -61.726576) (xy 75.995004 -61.724539)
			(xy 76.050441 -61.730639) (xy 76.104398 -61.744745) (xy 76.155727 -61.766557) (xy 76.203333 -61.795611)
			(xy 76.246201 -61.831286) (xy 76.283418 -61.872823) (xy 76.314191 -61.919336) (xy 76.337863 -61.969833)
			(xy 76.353931 -62.02324) (xy 76.362051 -62.078416) (xy 76.36256 -62.106302) (xy 76.362051 -62.134188)
			(xy 76.353931 -62.189364) (xy 76.337863 -62.242771) (xy 76.314191 -62.293268) (xy 76.283418 -62.339781)
			(xy 76.246201 -62.381318) (xy 76.203333 -62.416993) (xy 76.155727 -62.446047) (xy 76.104398 -62.467859)
			(xy 76.050441 -62.481965) (xy 75.995004 -62.488065) (xy 75.93927 -62.486028) (xy 75.884427 -62.475898)
			(xy 75.831643 -62.457891) (xy 75.782043 -62.43239) (xy 75.736685 -62.399939) (xy 75.696536 -62.36123)
			(xy 75.66245 -62.317087) (xy 75.635154 -62.268452) (xy 75.615231 -62.216361) (xy 75.603105 -62.161924)
			(xy 75.599034 -62.106302) (xy 74.172318 -62.106302) (xy 74.172318 -64.678052) (xy 74.312272 -64.817752)
			(xy 76.1492 -64.817752) (xy 76.174572 -64.818272) (xy 76.224627 -64.826604) (xy 76.272635 -64.843043)
			(xy 76.317291 -64.867142) (xy 76.337668 -64.882268)
		)
		(stroke
			(width 0)
			(type solid)
		)
		(fill yes)
		(layer "In7.Cu")
		(net "P0V6_DDR_VREF_AUX")
	)
	(gr_poly
		(pts
			(xy 60.930536 -67.265804) (xy 60.930536 -67.240658) (xy 60.930034 -67.225416) (xy 60.921058 -67.196285)
			(xy 60.903887 -67.171099) (xy 60.88005 -67.152099) (xy 60.851669 -67.140978) (xy 60.82127 -67.138724)
			(xy 60.791559 -67.145539) (xy 60.778136 -67.152774) (xy 60.756254 -67.164971) (xy 60.709978 -67.184162)
			(xy 60.661591 -67.197141) (xy 60.611923 -67.203685) (xy 60.586874 -67.204082) (xy 60.559626 -67.203594)
			(xy 60.505685 -67.195835) (xy 60.453397 -67.180479) (xy 60.403826 -67.157838) (xy 60.357982 -67.128373)
			(xy 60.316798 -67.092684) (xy 60.281112 -67.051497) (xy 60.25165 -67.005651) (xy 60.229012 -66.956079)
			(xy 60.213659 -66.90379) (xy 60.205904 -66.849848) (xy 60.205904 -66.795352) (xy 60.213659 -66.74141)
			(xy 60.229012 -66.689121) (xy 60.25165 -66.639549) (xy 60.281112 -66.593703) (xy 60.316798 -66.552516)
			(xy 60.357982 -66.516827) (xy 60.403826 -66.487362) (xy 60.453397 -66.464721) (xy 60.505685 -66.449365)
			(xy 60.559626 -66.441606) (xy 60.586874 -66.441066) (xy 60.611925 -66.441442) (xy 60.661599 -66.447967)
			(xy 60.70999 -66.460948) (xy 60.756261 -66.48016) (xy 60.778136 -66.492374) (xy 60.791598 -66.499488)
			(xy 60.821266 -66.506258) (xy 60.851613 -66.503986) (xy 60.879943 -66.492875) (xy 60.903743 -66.473911)
			(xy 60.920899 -66.448778) (xy 60.92989 -66.419705) (xy 60.930536 -66.40449) (xy 60.930536 -64.854836)
			(xy 58.576464 -62.500764) (xy 58.555382 -62.500764) (xy 58.528179 -62.500244) (xy 58.474335 -62.492441)
			(xy 58.422145 -62.477066) (xy 58.37267 -62.454432) (xy 58.326912 -62.424998) (xy 58.2858 -62.389361)
			(xy 58.25017 -62.348245) (xy 58.220742 -62.302483) (xy 58.198115 -62.253004) (xy 58.182748 -62.200812)
			(xy 58.174952 -62.146967) (xy 58.174382 -62.119764) (xy 58.174382 -62.098682) (xy 56.407812 -60.332112)
			(xy 56.397143 -60.322115) (xy 56.371471 -60.308145) (xy 56.342894 -60.302019) (xy 56.313752 -60.304239)
			(xy 56.286432 -60.314623) (xy 56.263173 -60.332321) (xy 56.24588 -60.355882) (xy 56.240426 -60.36945)
			(xy 56.230693 -60.394939) (xy 56.204593 -60.442851) (xy 56.171491 -60.48622) (xy 56.13216 -60.524031)
			(xy 56.087521 -60.555401) (xy 56.038619 -60.579594) (xy 55.9866 -60.596045) (xy 55.932679 -60.604367)
			(xy 55.9054 -60.604908) (xy 55.877417 -60.604359) (xy 55.82214 -60.595604) (xy 55.768913 -60.578309)
			(xy 55.719046 -60.552901) (xy 55.673769 -60.520005) (xy 55.634195 -60.480431) (xy 55.601299 -60.435154)
			(xy 55.575891 -60.385287) (xy 55.558596 -60.33206) (xy 55.549841 -60.276783) (xy 55.549292 -60.2488)
			(xy 55.549813 -60.221521) (xy 55.558137 -60.167601) (xy 55.574591 -60.115583) (xy 55.598789 -60.066685)
			(xy 55.630164 -60.02205) (xy 55.667982 -59.982726) (xy 55.711357 -59.949632) (xy 55.759274 -59.923544)
			(xy 55.78475 -59.913774) (xy 55.798321 -59.908349) (xy 55.821848 -59.89103) (xy 55.839517 -59.867765)
			(xy 55.849884 -59.840452) (xy 55.852104 -59.811322) (xy 55.845994 -59.782753) (xy 55.832053 -59.75708)
			(xy 55.822088 -59.746388) (xy 54.47665 -58.40095) (xy 54.466945 -58.391854) (xy 54.443926 -58.378549)
			(xy 54.41825 -58.371641) (xy 54.391662 -58.371599) (xy 54.365966 -58.378428) (xy 54.342906 -58.391663)
			(xy 54.33314 -58.400696) (xy 54.314426 -58.418656) (xy 54.272441 -58.449107) (xy 54.226213 -58.472621)
			(xy 54.176877 -58.488622) (xy 54.125647 -58.496714) (xy 54.099714 -58.497216) (xy 54.073724 -58.496734)
			(xy 54.022383 -58.488604) (xy 53.972946 -58.472544) (xy 53.92663 -58.448947) (xy 53.884576 -58.418395)
			(xy 53.847819 -58.38164) (xy 53.817265 -58.339588) (xy 53.793665 -58.293274) (xy 53.777601 -58.243838)
			(xy 53.769468 -58.192498) (xy 53.769006 -58.166508) (xy 53.769485 -58.141234) (xy 53.777181 -58.091276)
			(xy 53.792395 -58.043072) (xy 53.814771 -57.997747) (xy 53.843788 -57.956358) (xy 53.87877 -57.91987)
			(xy 53.898546 -57.904126) (xy 53.901086 -57.902094) (xy 53.93944 -57.86374) (xy 53.854858 -57.779158)
			(xy 53.624226 -57.779158) (xy 53.60964 -57.779628) (xy 53.581655 -57.787869) (xy 53.557143 -57.803687)
			(xy 53.538104 -57.82579) (xy 53.526092 -57.852375) (xy 53.522086 -57.881271) (xy 53.526415 -57.910121)
			(xy 53.538724 -57.93657) (xy 53.548026 -57.947814) (xy 53.563503 -57.966033) (xy 53.589599 -58.006085)
			(xy 53.60966 -58.049475) (xy 53.623271 -58.0953) (xy 53.630147 -58.142606) (xy 53.630576 -58.166508)
			(xy 53.630066 -58.192495) (xy 53.621936 -58.24383) (xy 53.605875 -58.29326) (xy 53.582279 -58.33957)
			(xy 53.551729 -58.381618) (xy 53.514978 -58.418369) (xy 53.47293 -58.448919) (xy 53.42662 -58.472515)
			(xy 53.37719 -58.488576) (xy 53.325855 -58.496706) (xy 53.273881 -58.496706) (xy 53.222546 -58.488576)
			(xy 53.173116 -58.472515) (xy 53.126806 -58.448919) (xy 53.084758 -58.418369) (xy 53.048007 -58.381618)
			(xy 53.017457 -58.33957) (xy 52.993861 -58.29326) (xy 52.9778 -58.24383) (xy 52.96967 -58.192495)
			(xy 52.96916 -58.166508) (xy 52.96958 -58.142606) (xy 52.976457 -58.095299) (xy 52.990069 -58.049474)
			(xy 53.010133 -58.006084) (xy 53.036231 -57.966032) (xy 53.05171 -57.947814) (xy 53.060987 -57.936551)
			(xy 53.073278 -57.910099) (xy 53.077597 -57.881252) (xy 53.073591 -57.852361) (xy 53.061586 -57.825777)
			(xy 53.042561 -57.803668) (xy 53.018065 -57.787833) (xy 52.990094 -57.779563) (xy 52.97551 -57.779158)
			(xy 52.824126 -57.779158) (xy 52.80954 -57.779628) (xy 52.781555 -57.787869) (xy 52.757043 -57.803687)
			(xy 52.738004 -57.82579) (xy 52.725992 -57.852375) (xy 52.721986 -57.881271) (xy 52.726315 -57.910121)
			(xy 52.738624 -57.93657) (xy 52.747926 -57.947814) (xy 52.763403 -57.966033) (xy 52.789499 -58.006085)
			(xy 52.80956 -58.049475) (xy 52.823171 -58.0953) (xy 52.830047 -58.142606) (xy 52.830476 -58.166508)
			(xy 52.829966 -58.192495) (xy 52.821836 -58.24383) (xy 52.805775 -58.29326) (xy 52.782179 -58.33957)
			(xy 52.751629 -58.381618) (xy 52.714878 -58.418369) (xy 52.67283 -58.448919) (xy 52.62652 -58.472515)
			(xy 52.57709 -58.488576) (xy 52.525755 -58.496706) (xy 52.473781 -58.496706) (xy 52.422446 -58.488576)
			(xy 52.373016 -58.472515) (xy 52.326706 -58.448919) (xy 52.284658 -58.418369) (xy 52.247907 -58.381618)
			(xy 52.217357 -58.33957) (xy 52.193761 -58.29326) (xy 52.1777 -58.24383) (xy 52.16957 -58.192495)
			(xy 52.16906 -58.166508) (xy 52.16948 -58.142606) (xy 52.176357 -58.095299) (xy 52.189969 -58.049474)
			(xy 52.210033 -58.006084) (xy 52.236131 -57.966032) (xy 52.25161 -57.947814) (xy 52.260887 -57.936551)
			(xy 52.273178 -57.910099) (xy 52.277497 -57.881252) (xy 52.273491 -57.852361) (xy 52.261486 -57.825777)
			(xy 52.242461 -57.803668) (xy 52.217965 -57.787833) (xy 52.189994 -57.779563) (xy 52.17541 -57.779158)
			(xy 52.024026 -57.779158) (xy 52.00944 -57.779628) (xy 51.981455 -57.787869) (xy 51.956943 -57.803687)
			(xy 51.937904 -57.82579) (xy 51.925892 -57.852375) (xy 51.921886 -57.881271) (xy 51.926215 -57.910121)
			(xy 51.938524 -57.93657) (xy 51.947826 -57.947814) (xy 51.963303 -57.966033) (xy 51.989399 -58.006085)
			(xy 52.00946 -58.049475) (xy 52.023071 -58.0953) (xy 52.029947 -58.142606) (xy 52.030376 -58.166508)
			(xy 52.029866 -58.192495) (xy 52.021736 -58.24383) (xy 52.005675 -58.29326) (xy 51.982079 -58.33957)
			(xy 51.951529 -58.381618) (xy 51.914778 -58.418369) (xy 51.87273 -58.448919) (xy 51.82642 -58.472515)
			(xy 51.77699 -58.488576) (xy 51.725655 -58.496706) (xy 51.673681 -58.496706) (xy 51.622346 -58.488576)
			(xy 51.572916 -58.472515) (xy 51.526606 -58.448919) (xy 51.484558 -58.418369) (xy 51.447807 -58.381618)
			(xy 51.417257 -58.33957) (xy 51.393661 -58.29326) (xy 51.3776 -58.24383) (xy 51.36947 -58.192495)
			(xy 51.36896 -58.166508) (xy 51.36938 -58.142606) (xy 51.376257 -58.095299) (xy 51.389869 -58.049474)
			(xy 51.409933 -58.006084) (xy 51.436031 -57.966032) (xy 51.45151 -57.947814) (xy 51.460787 -57.936551)
			(xy 51.473078 -57.910099) (xy 51.477397 -57.881252) (xy 51.473391 -57.852361) (xy 51.461386 -57.825777)
			(xy 51.442361 -57.803668) (xy 51.417865 -57.787833) (xy 51.389894 -57.779563) (xy 51.37531 -57.779158)
			(xy 51.2826 -57.779158) (xy 51.229514 -57.832244) (xy 51.155092 -57.832244) (xy 51.121056 -57.92089)
			(xy 51.14128 -57.939843) (xy 51.175721 -57.983264) (xy 51.202439 -58.031821) (xy 51.220682 -58.084154)
			(xy 51.229942 -58.138797) (xy 51.23053 -58.166508) (xy 51.23002 -58.192495) (xy 51.22189 -58.24383)
			(xy 51.205829 -58.29326) (xy 51.182233 -58.33957) (xy 51.151683 -58.381618) (xy 51.114932 -58.418369)
			(xy 51.072884 -58.448919) (xy 51.026574 -58.472515) (xy 50.977144 -58.488576) (xy 50.925809 -58.496706)
			(xy 50.873835 -58.496706) (xy 50.8225 -58.488576) (xy 50.77307 -58.472515) (xy 50.72676 -58.448919)
			(xy 50.684712 -58.418369) (xy 50.647961 -58.381618) (xy 50.617411 -58.33957) (xy 50.593815 -58.29326)
			(xy 50.577754 -58.24383) (xy 50.569624 -58.192495) (xy 50.569114 -58.166508) (xy 50.5697 -58.138798)
			(xy 50.578978 -58.08416) (xy 50.597228 -58.031831) (xy 50.623938 -57.983271) (xy 50.658362 -57.939839)
			(xy 50.678588 -57.92089) (xy 50.695352 -57.90565) (xy 50.695352 -57.832244) (xy 50.63109 -57.832244)
			(xy 50.366676 -57.56783) (xy 50.330862 -57.602882) (xy 50.312211 -57.620436) (xy 50.270501 -57.650158)
			(xy 50.22471 -57.673098) (xy 50.175932 -57.68871) (xy 50.12533 -57.69662) (xy 50.099722 -57.697116)
			(xy 50.073731 -57.696634) (xy 50.022389 -57.688506) (xy 49.97295 -57.672445) (xy 49.926632 -57.648848)
			(xy 49.884577 -57.618295) (xy 49.847819 -57.58154) (xy 49.817264 -57.539486) (xy 49.793663 -57.493171)
			(xy 49.777599 -57.443733) (xy 49.769467 -57.392391) (xy 49.769467 -57.340409) (xy 49.777599 -57.289067)
			(xy 49.793663 -57.239629) (xy 49.817264 -57.193314) (xy 49.847819 -57.15126) (xy 49.884577 -57.114505)
			(xy 49.926632 -57.083952) (xy 49.97295 -57.060355) (xy 50.022389 -57.044294) (xy 50.073731 -57.036166)
			(xy 50.099722 -57.0357) (xy 50.130423 -57.036395) (xy 50.190764 -57.047773) (xy 50.21961 -57.058306)
			(xy 50.232936 -57.062991) (xy 50.26105 -57.065617) (xy 50.288809 -57.060444) (xy 50.31409 -57.047868)
			(xy 50.33496 -57.028849) (xy 50.349825 -57.004842) (xy 50.357548 -56.977682) (xy 50.35804 -56.963564)
			(xy 50.35804 -56.396382) (xy 50.195226 -56.233568) (xy 49.665128 -56.233568) (xy 49.651541 -56.233994)
			(xy 49.625326 -56.241155) (xy 49.601929 -56.254976) (xy 49.583006 -56.274479) (xy 49.569897 -56.298283)
			(xy 49.563531 -56.324702) (xy 49.564359 -56.351864) (xy 49.572322 -56.377845) (xy 49.579276 -56.389524)
			(xy 49.591448 -56.409469) (xy 49.610661 -56.452061) (xy 49.623675 -56.496937) (xy 49.630228 -56.543199)
			(xy 49.630584 -56.566562) (xy 49.630074 -56.592549) (xy 49.621944 -56.643884) (xy 49.605883 -56.693314)
			(xy 49.582287 -56.739624) (xy 49.551737 -56.781672) (xy 49.514986 -56.818423) (xy 49.472938 -56.848973)
			(xy 49.426628 -56.872569) (xy 49.377198 -56.88863) (xy 49.325863 -56.89676) (xy 49.273889 -56.89676)
			(xy 49.222554 -56.88863) (xy 49.173124 -56.872569) (xy 49.126814 -56.848973) (xy 49.084766 -56.818423)
			(xy 49.048015 -56.781672) (xy 49.017465 -56.739624) (xy 48.993869 -56.693314) (xy 48.977808 -56.643884)
			(xy 48.969678 -56.592549) (xy 48.969168 -56.566562) (xy 48.969722 -56.539009) (xy 48.978864 -56.484667)
			(xy 48.996889 -56.432592) (xy 49.023299 -56.384227) (xy 49.057361 -56.340909) (xy 49.077372 -56.32196)
			(xy 49.093882 -56.30672) (xy 49.093882 -56.233568) (xy 48.975518 -56.233568) (xy 48.829976 -56.37911)
			(xy 48.829976 -56.54929) (xy 48.830484 -56.566308) (xy 48.829976 -56.583326) (xy 48.829976 -57.392395)
			(xy 48.969678 -57.392395) (xy 48.969678 -57.340421) (xy 48.977808 -57.289086) (xy 48.993869 -57.239656)
			(xy 49.017465 -57.193346) (xy 49.048015 -57.151298) (xy 49.084766 -57.114547) (xy 49.126814 -57.083997)
			(xy 49.173124 -57.060401) (xy 49.222554 -57.04434) (xy 49.273889 -57.03621) (xy 49.325863 -57.03621)
			(xy 49.377198 -57.04434) (xy 49.426628 -57.060401) (xy 49.472938 -57.083997) (xy 49.514986 -57.114547)
			(xy 49.551737 -57.151298) (xy 49.582287 -57.193346) (xy 49.605883 -57.239656) (xy 49.621944 -57.289086)
			(xy 49.630074 -57.340421) (xy 49.630584 -57.366408) (xy 49.630074 -57.392395) (xy 49.621944 -57.44373)
			(xy 49.605883 -57.49316) (xy 49.582287 -57.53947) (xy 49.551737 -57.581518) (xy 49.514986 -57.618269)
			(xy 49.472938 -57.648819) (xy 49.426628 -57.672415) (xy 49.377198 -57.688476) (xy 49.325863 -57.696606)
			(xy 49.273889 -57.696606) (xy 49.222554 -57.688476) (xy 49.173124 -57.672415) (xy 49.126814 -57.648819)
			(xy 49.084766 -57.618269) (xy 49.048015 -57.581518) (xy 49.017465 -57.53947) (xy 48.993869 -57.49316)
			(xy 48.977808 -57.44373) (xy 48.969678 -57.392395) (xy 48.829976 -57.392395) (xy 48.829976 -58.192495)
			(xy 48.969678 -58.192495) (xy 48.969678 -58.140521) (xy 48.977808 -58.089186) (xy 48.993869 -58.039756)
			(xy 49.017465 -57.993446) (xy 49.048015 -57.951398) (xy 49.084766 -57.914647) (xy 49.126814 -57.884097)
			(xy 49.173124 -57.860501) (xy 49.222554 -57.84444) (xy 49.273889 -57.83631) (xy 49.325863 -57.83631)
			(xy 49.377198 -57.84444) (xy 49.426628 -57.860501) (xy 49.472938 -57.884097) (xy 49.514986 -57.914647)
			(xy 49.551737 -57.951398) (xy 49.582287 -57.993446) (xy 49.605883 -58.039756) (xy 49.621944 -58.089186)
			(xy 49.630074 -58.140521) (xy 49.630584 -58.166508) (xy 49.630074 -58.192495) (xy 49.769524 -58.192495)
			(xy 49.769524 -58.140521) (xy 49.777654 -58.089186) (xy 49.793715 -58.039756) (xy 49.817311 -57.993446)
			(xy 49.847861 -57.951398) (xy 49.884612 -57.914647) (xy 49.92666 -57.884097) (xy 49.97297 -57.860501)
			(xy 50.0224 -57.84444) (xy 50.073735 -57.83631) (xy 50.125709 -57.83631) (xy 50.177044 -57.84444)
			(xy 50.226474 -57.860501) (xy 50.272784 -57.884097) (xy 50.314832 -57.914647) (xy 50.351583 -57.951398)
			(xy 50.382133 -57.993446) (xy 50.405729 -58.039756) (xy 50.42179 -58.089186) (xy 50.42992 -58.140521)
			(xy 50.43043 -58.166508) (xy 50.42992 -58.192495) (xy 50.42179 -58.24383) (xy 50.405729 -58.29326)
			(xy 50.382133 -58.33957) (xy 50.351583 -58.381618) (xy 50.314832 -58.418369) (xy 50.272784 -58.448919)
			(xy 50.226474 -58.472515) (xy 50.177044 -58.488576) (xy 50.125709 -58.496706) (xy 50.073735 -58.496706)
			(xy 50.0224 -58.488576) (xy 49.97297 -58.472515) (xy 49.92666 -58.448919) (xy 49.884612 -58.418369)
			(xy 49.847861 -58.381618) (xy 49.817311 -58.33957) (xy 49.793715 -58.29326) (xy 49.777654 -58.24383)
			(xy 49.769524 -58.192495) (xy 49.630074 -58.192495) (xy 49.621944 -58.24383) (xy 49.605883 -58.29326)
			(xy 49.582287 -58.33957) (xy 49.551737 -58.381618) (xy 49.514986 -58.418369) (xy 49.472938 -58.448919)
			(xy 49.426628 -58.472515) (xy 49.377198 -58.488576) (xy 49.325863 -58.496706) (xy 49.273889 -58.496706)
			(xy 49.222554 -58.488576) (xy 49.173124 -58.472515) (xy 49.126814 -58.448919) (xy 49.084766 -58.418369)
			(xy 49.048015 -58.381618) (xy 49.017465 -58.33957) (xy 48.993869 -58.29326) (xy 48.977808 -58.24383)
			(xy 48.969678 -58.192495) (xy 48.829976 -58.192495) (xy 48.829976 -59.190128) (xy 49.023016 -59.383168)
			(xy 49.085754 -59.383168) (xy 49.139348 -59.32932) (xy 49.145646 -59.322513) (xy 49.153305 -59.30564)
			(xy 49.154445 -59.287146) (xy 49.148917 -59.26946) (xy 49.137448 -59.254907) (xy 49.129696 -59.249818)
			(xy 49.109038 -59.236931) (xy 49.071403 -59.206042) (xy 49.03871 -59.169963) (xy 49.011668 -59.129476)
			(xy 48.990862 -59.085458) (xy 48.976743 -59.038862) (xy 48.969617 -58.990698) (xy 48.969168 -58.966354)
			(xy 48.969678 -58.940367) (xy 48.977808 -58.889032) (xy 48.993869 -58.839602) (xy 49.017465 -58.793292)
			(xy 49.048015 -58.751244) (xy 49.084766 -58.714493) (xy 49.126814 -58.683943) (xy 49.173124 -58.660347)
			(xy 49.222554 -58.644286) (xy 49.273889 -58.636156) (xy 49.325863 -58.636156) (xy 49.377198 -58.644286)
			(xy 49.426628 -58.660347) (xy 49.472938 -58.683943) (xy 49.514986 -58.714493) (xy 49.551737 -58.751244)
			(xy 49.582287 -58.793292) (xy 49.605883 -58.839602) (xy 49.621944 -58.889032) (xy 49.630074 -58.940367)
			(xy 49.630584 -58.966354) (xy 49.630047 -58.992772) (xy 49.621608 -59.044929) (xy 49.604985 -59.095082)
			(xy 49.593246 -59.118754) (xy 49.586812 -59.132225) (xy 49.581255 -59.161541) (xy 49.584408 -59.191213)
			(xy 49.596003 -59.218706) (xy 49.615049 -59.241676) (xy 49.639921 -59.258159) (xy 49.668496 -59.266751)
			(xy 49.683416 -59.267344) (xy 49.716182 -59.267344) (xy 49.731093 -59.266812) (xy 49.75964 -59.258181)
			(xy 49.784481 -59.241678) (xy 49.8035 -59.218707) (xy 49.81508 -59.191223) (xy 49.818234 -59.161567)
			(xy 49.812695 -59.132263) (xy 49.806352 -59.118754) (xy 49.794616 -59.09508) (xy 49.777988 -59.044929)
			(xy 49.769547 -58.992772) (xy 49.769014 -58.966354) (xy 49.769524 -58.940367) (xy 49.777654 -58.889032)
			(xy 49.793715 -58.839602) (xy 49.817311 -58.793292) (xy 49.847861 -58.751244) (xy 49.884612 -58.714493)
			(xy 49.92666 -58.683943) (xy 49.97297 -58.660347) (xy 50.0224 -58.644286) (xy 50.073735 -58.636156)
			(xy 50.125709 -58.636156) (xy 50.177044 -58.644286) (xy 50.226474 -58.660347) (xy 50.272784 -58.683943)
			(xy 50.314832 -58.714493) (xy 50.351583 -58.751244) (xy 50.382133 -58.793292) (xy 50.405729 -58.839602)
			(xy 50.42179 -58.889032) (xy 50.42992 -58.940367) (xy 50.43043 -58.966354) (xy 50.429893 -58.992771)
			(xy 50.421452 -59.044928) (xy 50.404827 -59.09508) (xy 50.393092 -59.118754) (xy 50.38666 -59.132227)
			(xy 50.381106 -59.161547) (xy 50.384261 -59.191222) (xy 50.395854 -59.218719) (xy 50.414898 -59.241694)
			(xy 50.439767 -59.258187) (xy 50.468341 -59.266792) (xy 50.483262 -59.267344) (xy 50.516282 -59.267344)
			(xy 50.531193 -59.266812) (xy 50.55974 -59.258181) (xy 50.584581 -59.241678) (xy 50.6036 -59.218707)
			(xy 50.61518 -59.191223) (xy 50.618334 -59.161567) (xy 50.612795 -59.132263) (xy 50.606452 -59.118754)
			(xy 50.594716 -59.09508) (xy 50.578088 -59.044929) (xy 50.569647 -58.992772) (xy 50.569114 -58.966354)
			(xy 50.569624 -58.940367) (xy 50.577754 -58.889032) (xy 50.593815 -58.839602) (xy 50.617411 -58.793292)
			(xy 50.647961 -58.751244) (xy 50.684712 -58.714493) (xy 50.72676 -58.683943) (xy 50.77307 -58.660347)
			(xy 50.8225 -58.644286) (xy 50.873835 -58.636156) (xy 50.925809 -58.636156) (xy 50.977144 -58.644286)
			(xy 51.026574 -58.660347) (xy 51.072884 -58.683943) (xy 51.114932 -58.714493) (xy 51.151683 -58.751244)
			(xy 51.182233 -58.793292) (xy 51.205829 -58.839602) (xy 51.22189 -58.889032) (xy 51.23002 -58.940367)
			(xy 51.23053 -58.966354) (xy 51.230042 -58.992452) (xy 51.221851 -59.044) (xy 51.205664 -59.093622)
			(xy 51.181885 -59.140085) (xy 51.151102 -59.182237) (xy 51.114081 -59.21903) (xy 51.07174 -59.249552)
			(xy 51.048666 -59.261756) (xy 51.041554 -59.265312) (xy 50.999644 -59.306968) (xy 51.075844 -59.383168)
			(xy 51.392582 -59.383168) (xy 51.449224 -59.326526) (xy 51.459773 -59.315233) (xy 51.47413 -59.287883)
			(xy 51.479679 -59.257496) (xy 51.475916 -59.226837) (xy 51.463184 -59.198694) (xy 51.453288 -59.186826)
			(xy 51.437509 -59.168542) (xy 51.410873 -59.128258) (xy 51.390381 -59.084527) (xy 51.376471 -59.03828)
			(xy 51.369436 -58.990501) (xy 51.36896 -58.966354) (xy 51.36947 -58.940367) (xy 51.3776 -58.889032)
			(xy 51.393661 -58.839602) (xy 51.417257 -58.793292) (xy 51.447807 -58.751244) (xy 51.484558 -58.714493)
			(xy 51.526606 -58.683943) (xy 51.572916 -58.660347) (xy 51.622346 -58.644286) (xy 51.673681 -58.636156)
			(xy 51.725655 -58.636156) (xy 51.77699 -58.644286) (xy 51.82642 -58.660347) (xy 51.87273 -58.683943)
			(xy 51.914778 -58.714493) (xy 51.951529 -58.751244) (xy 51.982079 -58.793292) (xy 52.005675 -58.839602)
			(xy 52.021736 -58.889032) (xy 52.029866 -58.940367) (xy 52.030376 -58.966354) (xy 52.029846 -58.992726)
			(xy 52.021429 -59.044794) (xy 52.013612 -59.069986) (xy 52.009754 -59.083165) (xy 52.008444 -59.110582)
			(xy 52.014489 -59.137357) (xy 52.027452 -59.161552) (xy 52.046396 -59.181417) (xy 52.069949 -59.195513)
			(xy 52.096407 -59.202821) (xy 52.110132 -59.203336) (xy 52.217574 -59.203336) (xy 52.217574 -59.139328)
			(xy 52.211224 -59.127644) (xy 52.198019 -59.102828) (xy 52.179251 -59.049847) (xy 52.169699 -58.994457)
			(xy 52.16906 -58.966354) (xy 52.16957 -58.940367) (xy 52.1777 -58.889032) (xy 52.193761 -58.839602)
			(xy 52.217357 -58.793292) (xy 52.247907 -58.751244) (xy 52.284658 -58.714493) (xy 52.326706 -58.683943)
			(xy 52.373016 -58.660347) (xy 52.422446 -58.644286) (xy 52.473781 -58.636156) (xy 52.525755 -58.636156)
			(xy 52.57709 -58.644286) (xy 52.62652 -58.660347) (xy 52.67283 -58.683943) (xy 52.714878 -58.714493)
			(xy 52.751629 -58.751244) (xy 52.782179 -58.793292) (xy 52.805775 -58.839602) (xy 52.821836 -58.889032)
			(xy 52.829966 -58.940367) (xy 52.830476 -58.966354) (xy 52.829946 -58.992726) (xy 52.821529 -59.044794)
			(xy 52.813712 -59.069986) (xy 52.809854 -59.083165) (xy 52.808544 -59.110582) (xy 52.814589 -59.137357)
			(xy 52.827552 -59.161552) (xy 52.846496 -59.181417) (xy 52.870049 -59.195513) (xy 52.896507 -59.202821)
			(xy 52.910232 -59.203336) (xy 53.017674 -59.203336) (xy 53.017674 -59.139328) (xy 53.011324 -59.127644)
			(xy 52.998119 -59.102828) (xy 52.979351 -59.049847) (xy 52.969799 -58.994457) (xy 52.96916 -58.966354)
			(xy 52.96967 -58.940367) (xy 52.9778 -58.889032) (xy 52.993861 -58.839602) (xy 53.017457 -58.793292)
			(xy 53.048007 -58.751244) (xy 53.084758 -58.714493) (xy 53.126806 -58.683943) (xy 53.173116 -58.660347)
			(xy 53.222546 -58.644286) (xy 53.273881 -58.636156) (xy 53.325855 -58.636156) (xy 53.37719 -58.644286)
			(xy 53.42662 -58.660347) (xy 53.47293 -58.683943) (xy 53.514978 -58.714493) (xy 53.551729 -58.751244)
			(xy 53.582279 -58.793292) (xy 53.605875 -58.839602) (xy 53.621936 -58.889032) (xy 53.630066 -58.940367)
			(xy 53.630576 -58.966354) (xy 53.630162 -58.98982) (xy 53.629802 -58.992341) (xy 53.769516 -58.992341)
			(xy 53.769516 -58.940367) (xy 53.777646 -58.889032) (xy 53.793707 -58.839602) (xy 53.817303 -58.793292)
			(xy 53.847853 -58.751244) (xy 53.884604 -58.714493) (xy 53.926652 -58.683943) (xy 53.972962 -58.660347)
			(xy 54.022392 -58.644286) (xy 54.073727 -58.636156) (xy 54.125701 -58.636156) (xy 54.177036 -58.644286)
			(xy 54.226466 -58.660347) (xy 54.272776 -58.683943) (xy 54.314824 -58.714493) (xy 54.351575 -58.751244)
			(xy 54.382125 -58.793292) (xy 54.405721 -58.839602) (xy 54.421782 -58.889032) (xy 54.429912 -58.940367)
			(xy 54.430422 -58.966354) (xy 54.429912 -58.992341) (xy 54.421782 -59.043676) (xy 54.405721 -59.093106)
			(xy 54.382125 -59.139416) (xy 54.351575 -59.181464) (xy 54.314824 -59.218215) (xy 54.272776 -59.248765)
			(xy 54.226466 -59.272361) (xy 54.177036 -59.288422) (xy 54.125701 -59.296552) (xy 54.073727 -59.296552)
			(xy 54.022392 -59.288422) (xy 53.972962 -59.272361) (xy 53.926652 -59.248765) (xy 53.884604 -59.218215)
			(xy 53.847853 -59.181464) (xy 53.817303 -59.139416) (xy 53.793707 -59.093106) (xy 53.777646 -59.043676)
			(xy 53.769516 -58.992341) (xy 53.629802 -58.992341) (xy 53.623521 -59.03628) (xy 53.610379 -59.081335)
			(xy 53.591001 -59.12408) (xy 53.565775 -59.163657) (xy 53.55082 -59.181746) (xy 53.544857 -59.189216)
			(xy 53.538496 -59.207224) (xy 53.539208 -59.226309) (xy 53.546893 -59.243793) (xy 53.55336 -59.250834)
			(xy 55.738014 -61.435488) (xy 55.749344 -61.44606) (xy 55.776789 -61.460415) (xy 55.807274 -61.465892)
			(xy 55.838 -61.461988) (xy 55.866147 -61.449061) (xy 55.877968 -61.439044) (xy 55.899128 -61.420583)
			(xy 55.945848 -61.389433) (xy 55.99663 -61.365467) (xy 56.050375 -61.349201) (xy 56.105923 -61.340986)
			(xy 56.134 -61.340492) (xy 56.161251 -61.340978) (xy 56.215199 -61.348734) (xy 56.267494 -61.364089)
			(xy 56.317071 -61.386731) (xy 56.362921 -61.416197) (xy 56.404112 -61.451888) (xy 56.439803 -61.493079)
			(xy 56.469269 -61.538929) (xy 56.491911 -61.588506) (xy 56.507266 -61.640801) (xy 56.515022 -61.694749)
			(xy 56.515508 -61.722) (xy 56.515012 -61.750076) (xy 56.506789 -61.805623) (xy 56.490522 -61.859367)
			(xy 56.46656 -61.91015) (xy 56.435421 -61.956877) (xy 56.416956 -61.978032) (xy 56.407001 -61.989891)
			(xy 56.394107 -62.018023) (xy 56.390213 -62.048724) (xy 56.395676 -62.079185) (xy 56.409996 -62.10662)
			(xy 56.420512 -62.117986) (xy 56.693816 -62.39129) (xy 56.704487 -62.401299) (xy 56.730168 -62.415289)
			(xy 56.758761 -62.421431) (xy 56.787922 -62.419221) (xy 56.815263 -62.40884) (xy 56.838542 -62.391138)
			(xy 56.855853 -62.367567) (xy 56.861202 -62.353952) (xy 56.871667 -62.326713) (xy 56.899676 -62.275524)
			(xy 56.935153 -62.229197) (xy 56.97727 -62.188812) (xy 57.025044 -62.15531) (xy 57.077363 -62.129474)
			(xy 57.133006 -62.111905) (xy 57.190675 -62.103013) (xy 57.21985 -62.102492) (xy 57.247105 -62.102952)
			(xy 57.301062 -62.110703) (xy 57.353365 -62.126055) (xy 57.402952 -62.148694) (xy 57.448811 -62.178161)
			(xy 57.49001 -62.213855) (xy 57.525709 -62.255049) (xy 57.555182 -62.300904) (xy 57.577828 -62.350488)
			(xy 57.593186 -62.40279) (xy 57.600945 -62.456745) (xy 57.601358 -62.484) (xy 57.600804 -62.513174)
			(xy 57.591918 -62.57084) (xy 57.574355 -62.626481) (xy 57.548522 -62.678798) (xy 57.515024 -62.726571)
			(xy 57.474641 -62.768686) (xy 57.428316 -62.804159) (xy 57.377129 -62.832164) (xy 57.349898 -62.842648)
			(xy 57.336325 -62.848069) (xy 57.312791 -62.865383) (xy 57.295119 -62.888648) (xy 57.284751 -62.915962)
			(xy 57.282535 -62.945094) (xy 57.288652 -62.973663) (xy 57.302602 -62.999333) (xy 57.31256 -63.010034)
			(xy 59.124342 -64.821816) (xy 59.124342 -65.376298) (xy 59.993782 -65.376298) (xy 59.997853 -65.320676)
			(xy 60.009979 -65.266239) (xy 60.029902 -65.214148) (xy 60.057198 -65.165513) (xy 60.091284 -65.12137)
			(xy 60.131433 -65.082661) (xy 60.176791 -65.05021) (xy 60.226391 -65.024709) (xy 60.279175 -65.006702)
			(xy 60.334018 -64.996572) (xy 60.389752 -64.994535) (xy 60.445189 -65.000635) (xy 60.499146 -65.014741)
			(xy 60.550475 -65.036553) (xy 60.598081 -65.065607) (xy 60.640949 -65.101282) (xy 60.678166 -65.142819)
			(xy 60.708939 -65.189332) (xy 60.732611 -65.239829) (xy 60.748679 -65.293236) (xy 60.756799 -65.348412)
			(xy 60.757308 -65.376298) (xy 60.756799 -65.404184) (xy 60.748679 -65.45936) (xy 60.732611 -65.512767)
			(xy 60.708939 -65.563264) (xy 60.678166 -65.609777) (xy 60.640949 -65.651314) (xy 60.598081 -65.686989)
			(xy 60.550475 -65.716043) (xy 60.499146 -65.737855) (xy 60.445189 -65.751961) (xy 60.389752 -65.758061)
			(xy 60.334018 -65.756024) (xy 60.279175 -65.745894) (xy 60.226391 -65.727887) (xy 60.176791 -65.702386)
			(xy 60.131433 -65.669935) (xy 60.091284 -65.631226) (xy 60.057198 -65.587083) (xy 60.029902 -65.538448)
			(xy 60.009979 -65.486357) (xy 59.997853 -65.43192) (xy 59.993782 -65.376298) (xy 59.124342 -65.376298)
			(xy 59.124342 -65.981072) (xy 59.155076 -65.99428) (xy 59.18038 -66.005742) (xy 59.227657 -66.034905)
			(xy 59.27021 -66.070611) (xy 59.307141 -66.112105) (xy 59.337669 -66.158512) (xy 59.361152 -66.208853)
			(xy 59.377093 -66.262066) (xy 59.385155 -66.317026) (xy 59.385708 -66.3448) (xy 59.385278 -66.370941)
			(xy 59.378139 -66.422734) (xy 59.363994 -66.473067) (xy 59.343109 -66.520996) (xy 59.315874 -66.565625)
			(xy 59.2828 -66.606117) (xy 59.244506 -66.641712) (xy 59.201711 -66.671746) (xy 59.155215 -66.695654)
			(xy 59.130692 -66.704718) (xy 59.11977 -66.708528) (xy 58.71464 -67.113658) (xy 58.71464 -67.64655)
			(xy 58.734581 -67.66383) (xy 58.769988 -67.702952) (xy 58.799675 -67.746573) (xy 58.823077 -67.793865)
			(xy 58.839751 -67.843926) (xy 58.849378 -67.895806) (xy 58.851038 -67.92214) (xy 58.8518 -67.941952)
			(xy 59.006994 -68.097146) (xy 59.03468 -68.090288) (xy 59.056756 -68.085283) (xy 59.101708 -68.079937)
			(xy 59.124342 -68.07962) (xy 59.158023 -68.080353) (xy 59.224331 -68.092227) (xy 59.256168 -68.103242)
			(xy 59.264804 -68.10629) (xy 60.09005 -68.10629)
		)
		(stroke
			(width 0)
			(type solid)
		)
		(fill yes)
		(layer "In7.Cu")
		(net "PGPPA_BMC_AUX_SENSOR")
	)
	(gr_poly
		(pts
			(xy 64.61252 -72.94626) (xy 64.61252 -70.453504) (xy 64.377824 -70.218808) (xy 63.173356 -70.218808)
			(xy 62.88532 -69.930772) (xy 62.88532 -69.00926) (xy 62.884895 -68.999595) (xy 62.877743 -68.981636)
			(xy 62.864466 -68.967587) (xy 62.846939 -68.959433) (xy 62.837314 -68.95846) (xy 62.809787 -68.95652)
			(xy 62.755674 -68.945705) (xy 62.703684 -68.927207) (xy 62.654902 -68.901411) (xy 62.610346 -68.868855)
			(xy 62.570945 -68.830219) (xy 62.537522 -68.78631) (xy 62.510775 -68.738043) (xy 62.49126 -68.686426)
			(xy 62.479386 -68.632536) (xy 62.475401 -68.577498) (xy 62.479387 -68.522459) (xy 62.491261 -68.468569)
			(xy 62.510776 -68.416953) (xy 62.537525 -68.368686) (xy 62.570948 -68.324777) (xy 62.610349 -68.286142)
			(xy 62.654906 -68.253587) (xy 62.703688 -68.227791) (xy 62.755678 -68.209294) (xy 62.809791 -68.198479)
			(xy 62.837314 -68.19646) (xy 62.846953 -68.195518) (xy 62.864513 -68.187389) (xy 62.877806 -68.173327)
			(xy 62.884934 -68.155336) (xy 62.88532 -68.14566) (xy 62.88532 -64.339724) (xy 57.066688 -58.521346)
			(xy 57.066688 -58.410348) (xy 57.045643 -58.39022) (xy 57.010261 -58.343973) (xy 56.99633 -58.3184)
			(xy 56.992774 -58.311288) (xy 56.955436 -58.27395) (xy 56.945203 -58.264349) (xy 56.920721 -58.250661)
			(xy 56.893437 -58.244151) (xy 56.865412 -58.245309) (xy 56.838759 -58.254047) (xy 56.815488 -58.269707)
			(xy 56.797356 -58.291108) (xy 56.791098 -58.303668) (xy 56.779403 -58.328035) (xy 56.749291 -58.372915)
			(xy 56.712279 -58.412298) (xy 56.669353 -58.445135) (xy 56.621657 -58.470553) (xy 56.570462 -58.487872)
			(xy 56.517131 -58.496633) (xy 56.490108 -58.497216) (xy 56.46412 -58.496707) (xy 56.412784 -58.488578)
			(xy 56.363352 -58.472517) (xy 56.317041 -58.448922) (xy 56.274991 -58.418373) (xy 56.238238 -58.381621)
			(xy 56.207686 -58.339573) (xy 56.184089 -58.293263) (xy 56.168026 -58.243831) (xy 56.159894 -58.192496)
			(xy 56.1594 -58.166508) (xy 56.159944 -58.139488) (xy 56.16874 -58.086167) (xy 56.186084 -58.034984)
			(xy 56.211513 -57.9873) (xy 56.244354 -57.944382) (xy 56.283732 -57.907371) (xy 56.3286 -57.87725)
			(xy 56.352948 -57.865518) (xy 56.365522 -57.859288) (xy 56.386911 -57.84114) (xy 56.402562 -57.817861)
			(xy 56.411297 -57.791204) (xy 56.412458 -57.763177) (xy 56.405957 -57.735889) (xy 56.392285 -57.711396)
			(xy 56.382666 -57.70118) (xy 56.334152 -57.652666) (xy 56.309552 -57.637714) (xy 56.265471 -57.600698)
			(xy 56.228461 -57.556612) (xy 56.213502 -57.532016) (xy 56.16194 -57.480454) (xy 56.151809 -57.470918)
			(xy 56.127574 -57.457276) (xy 56.100555 -57.450684) (xy 56.072759 -57.451631) (xy 56.046252 -57.460048)
			(xy 56.023001 -57.475308) (xy 56.004733 -57.496278) (xy 55.998364 -57.508648) (xy 55.986418 -57.532449)
			(xy 55.956089 -57.576219) (xy 55.919145 -57.614569) (xy 55.876537 -57.64651) (xy 55.829366 -57.671219)
			(xy 55.778848 -57.688057) (xy 55.726285 -57.696591) (xy 55.69966 -57.697116) (xy 55.673675 -57.696603)
			(xy 55.622345 -57.688468) (xy 55.572919 -57.672404) (xy 55.526614 -57.648806) (xy 55.484571 -57.618255)
			(xy 55.447824 -57.581505) (xy 55.417278 -57.539458) (xy 55.393684 -57.493152) (xy 55.377625 -57.443724)
			(xy 55.369494 -57.392393) (xy 55.368952 -57.366408) (xy 55.369484 -57.339782) (xy 55.37801 -57.287217)
			(xy 55.394843 -57.236695) (xy 55.419548 -57.189521) (xy 55.451489 -57.146911) (xy 55.48984 -57.109966)
			(xy 55.533613 -57.079639) (xy 55.55742 -57.067704) (xy 55.569756 -57.061294) (xy 55.590683 -57.043011)
			(xy 55.605911 -57.019766) (xy 55.614316 -56.993279) (xy 55.615274 -56.965507) (xy 55.608716 -56.938503)
			(xy 55.595127 -56.914264) (xy 55.585614 -56.904128) (xy 55.53456 -56.853074) (xy 55.509762 -56.838086)
			(xy 55.465375 -56.80085) (xy 55.428153 -56.75645) (xy 55.413148 -56.731662) (xy 55.362094 -56.680608)
			(xy 55.35196 -56.671068) (xy 55.327717 -56.657417) (xy 55.300689 -56.650816) (xy 55.272882 -56.651755)
			(xy 55.246361 -56.660164) (xy 55.223093 -56.67542) (xy 55.204807 -56.696388) (xy 55.198518 -56.708802)
			(xy 55.186574 -56.732604) (xy 55.156246 -56.776374) (xy 55.119302 -56.814725) (xy 55.076694 -56.846665)
			(xy 55.029522 -56.871371) (xy 54.979002 -56.888205) (xy 54.926439 -56.896734) (xy 54.899814 -56.89727)
			(xy 54.873825 -56.896788) (xy 54.822487 -56.888658) (xy 54.773053 -56.872597) (xy 54.726741 -56.848999)
			(xy 54.68469 -56.818446) (xy 54.647938 -56.781691) (xy 54.617388 -56.739639) (xy 54.593794 -56.693325)
			(xy 54.577736 -56.64389) (xy 54.56961 -56.592551) (xy 54.569106 -56.566562) (xy 54.569642 -56.539939)
			(xy 54.578175 -56.48738) (xy 54.595014 -56.436867) (xy 54.619725 -56.389702) (xy 54.65167 -56.347102)
			(xy 54.690024 -56.310168) (xy 54.733798 -56.279852) (xy 54.757574 -56.267858) (xy 54.76991 -56.261451)
			(xy 54.790835 -56.243173) (xy 54.80606 -56.219931) (xy 54.814459 -56.193447) (xy 54.81541 -56.165679)
			(xy 54.808842 -56.138682) (xy 54.795242 -56.114454) (xy 54.785768 -56.104282) (xy 54.763162 -56.081676)
			(xy 54.754526 -56.077612) (xy 54.732825 -56.067378) (xy 54.692378 -56.041573) (xy 54.656085 -56.010193)
			(xy 54.624708 -55.973897) (xy 54.598907 -55.933447) (xy 54.588664 -55.91175) (xy 54.5846 -55.903114)
			(xy 54.561994 -55.880508) (xy 54.55186 -55.870968) (xy 54.527617 -55.857317) (xy 54.500589 -55.850716)
			(xy 54.472782 -55.851655) (xy 54.446261 -55.860064) (xy 54.422993 -55.87532) (xy 54.404707 -55.896288)
			(xy 54.398418 -55.908702) (xy 54.386474 -55.932504) (xy 54.356146 -55.976274) (xy 54.319202 -56.014625)
			(xy 54.276594 -56.046565) (xy 54.229422 -56.071271) (xy 54.178902 -56.088105) (xy 54.126339 -56.096634)
			(xy 54.099714 -56.09717) (xy 54.073725 -56.096688) (xy 54.022387 -56.088558) (xy 53.972953 -56.072497)
			(xy 53.926641 -56.048899) (xy 53.88459 -56.018346) (xy 53.847838 -55.981591) (xy 53.817288 -55.939539)
			(xy 53.793694 -55.893225) (xy 53.777636 -55.84379) (xy 53.76951 -55.792451) (xy 53.769006 -55.766462)
			(xy 53.769542 -55.739839) (xy 53.778075 -55.68728) (xy 53.794914 -55.636767) (xy 53.819625 -55.589602)
			(xy 53.85157 -55.547002) (xy 53.889924 -55.510068) (xy 53.933698 -55.479752) (xy 53.957474 -55.467758)
			(xy 53.96981 -55.461351) (xy 53.990735 -55.443073) (xy 54.00596 -55.419831) (xy 54.014359 -55.393347)
			(xy 54.01531 -55.365579) (xy 54.008742 -55.338582) (xy 53.995142 -55.314354) (xy 53.985668 -55.304182)
			(xy 53.968142 -55.286656) (xy 51.51882 -55.286656) (xy 51.193954 -55.611522) (xy 51.2064 -55.642764)
			(xy 51.217625 -55.67245) (xy 51.22978 -55.734734) (xy 51.23053 -55.766462) (xy 51.23005 -55.792449)
			(xy 51.36947 -55.792449) (xy 51.36947 -55.740475) (xy 51.3776 -55.68914) (xy 51.393661 -55.63971)
			(xy 51.417257 -55.5934) (xy 51.447807 -55.551352) (xy 51.484558 -55.514601) (xy 51.526606 -55.484051)
			(xy 51.572916 -55.460455) (xy 51.622346 -55.444394) (xy 51.673681 -55.436264) (xy 51.725655 -55.436264)
			(xy 51.77699 -55.444394) (xy 51.82642 -55.460455) (xy 51.87273 -55.484051) (xy 51.914778 -55.514601)
			(xy 51.951529 -55.551352) (xy 51.982079 -55.5934) (xy 52.005675 -55.63971) (xy 52.021736 -55.68914)
			(xy 52.029866 -55.740475) (xy 52.030376 -55.766462) (xy 52.029866 -55.792449) (xy 52.16957 -55.792449)
			(xy 52.16957 -55.740475) (xy 52.1777 -55.68914) (xy 52.193761 -55.63971) (xy 52.217357 -55.5934)
			(xy 52.247907 -55.551352) (xy 52.284658 -55.514601) (xy 52.326706 -55.484051) (xy 52.373016 -55.460455)
			(xy 52.422446 -55.444394) (xy 52.473781 -55.436264) (xy 52.525755 -55.436264) (xy 52.57709 -55.444394)
			(xy 52.62652 -55.460455) (xy 52.67283 -55.484051) (xy 52.714878 -55.514601) (xy 52.751629 -55.551352)
			(xy 52.782179 -55.5934) (xy 52.805775 -55.63971) (xy 52.821836 -55.68914) (xy 52.829966 -55.740475)
			(xy 52.830476 -55.766462) (xy 52.829966 -55.792449) (xy 52.821836 -55.843784) (xy 52.805775 -55.893214)
			(xy 52.782179 -55.939524) (xy 52.751629 -55.981572) (xy 52.714878 -56.018323) (xy 52.67283 -56.048873)
			(xy 52.62652 -56.072469) (xy 52.57709 -56.08853) (xy 52.525755 -56.09666) (xy 52.473781 -56.09666)
			(xy 52.422446 -56.08853) (xy 52.373016 -56.072469) (xy 52.326706 -56.048873) (xy 52.284658 -56.018323)
			(xy 52.247907 -55.981572) (xy 52.217357 -55.939524) (xy 52.193761 -55.893214) (xy 52.1777 -55.843784)
			(xy 52.16957 -55.792449) (xy 52.029866 -55.792449) (xy 52.021736 -55.843784) (xy 52.005675 -55.893214)
			(xy 51.982079 -55.939524) (xy 51.951529 -55.981572) (xy 51.914778 -56.018323) (xy 51.87273 -56.048873)
			(xy 51.82642 -56.072469) (xy 51.77699 -56.08853) (xy 51.725655 -56.09666) (xy 51.673681 -56.09666)
			(xy 51.622346 -56.08853) (xy 51.572916 -56.072469) (xy 51.526606 -56.048873) (xy 51.484558 -56.018323)
			(xy 51.447807 -55.981572) (xy 51.417257 -55.939524) (xy 51.393661 -55.893214) (xy 51.3776 -55.843784)
			(xy 51.36947 -55.792449) (xy 51.23005 -55.792449) (xy 51.23005 -55.792454) (xy 51.221923 -55.843798)
			(xy 51.205865 -55.893239) (xy 51.182269 -55.939559) (xy 51.151718 -55.981618) (xy 51.114964 -56.018379)
			(xy 51.072911 -56.048938) (xy 51.026595 -56.072542) (xy 50.977157 -56.088609) (xy 50.925814 -56.096745)
			(xy 50.899822 -56.09717) (xy 50.868092 -56.096427) (xy 50.805805 -56.084282) (xy 50.776124 -56.07304)
			(xy 50.744882 -56.060594) (xy 50.618136 -56.18734) (xy 50.618136 -56.262778) (xy 50.61846 -56.272248)
			(xy 50.625222 -56.289934) (xy 50.637943 -56.303959) (xy 50.654887 -56.31241) (xy 50.673744 -56.314133)
			(xy 50.691939 -56.308893) (xy 50.69967 -56.303418) (xy 50.721382 -56.287536) (xy 50.768883 -56.262296)
			(xy 50.819847 -56.24509) (xy 50.872927 -56.236374) (xy 50.899822 -56.235854) (xy 50.925811 -56.236365)
			(xy 50.977149 -56.2445) (xy 51.026582 -56.260564) (xy 51.072894 -56.284164) (xy 51.114944 -56.314718)
			(xy 51.151697 -56.351473) (xy 51.182247 -56.393525) (xy 51.205844 -56.439838) (xy 51.221906 -56.489273)
			(xy 51.230036 -56.540611) (xy 51.230036 -56.592549) (xy 51.36947 -56.592549) (xy 51.36947 -56.540575)
			(xy 51.3776 -56.48924) (xy 51.393661 -56.43981) (xy 51.417257 -56.3935) (xy 51.447807 -56.351452)
			(xy 51.484558 -56.314701) (xy 51.526606 -56.284151) (xy 51.572916 -56.260555) (xy 51.622346 -56.244494)
			(xy 51.673681 -56.236364) (xy 51.725655 -56.236364) (xy 51.77699 -56.244494) (xy 51.82642 -56.260555)
			(xy 51.87273 -56.284151) (xy 51.914778 -56.314701) (xy 51.951529 -56.351452) (xy 51.982079 -56.3935)
			(xy 52.005675 -56.43981) (xy 52.021736 -56.48924) (xy 52.029866 -56.540575) (xy 52.030376 -56.566562)
			(xy 52.029866 -56.592549) (xy 52.16957 -56.592549) (xy 52.16957 -56.540575) (xy 52.1777 -56.48924)
			(xy 52.193761 -56.43981) (xy 52.217357 -56.3935) (xy 52.247907 -56.351452) (xy 52.284658 -56.314701)
			(xy 52.326706 -56.284151) (xy 52.373016 -56.260555) (xy 52.422446 -56.244494) (xy 52.473781 -56.236364)
			(xy 52.525755 -56.236364) (xy 52.57709 -56.244494) (xy 52.62652 -56.260555) (xy 52.67283 -56.284151)
			(xy 52.714878 -56.314701) (xy 52.751629 -56.351452) (xy 52.782179 -56.3935) (xy 52.805775 -56.43981)
			(xy 52.821836 -56.48924) (xy 52.829966 -56.540575) (xy 52.830476 -56.566562) (xy 52.829966 -56.592549)
			(xy 52.96967 -56.592549) (xy 52.96967 -56.540575) (xy 52.9778 -56.48924) (xy 52.993861 -56.43981)
			(xy 53.017457 -56.3935) (xy 53.048007 -56.351452) (xy 53.084758 -56.314701) (xy 53.126806 -56.284151)
			(xy 53.173116 -56.260555) (xy 53.222546 -56.244494) (xy 53.273881 -56.236364) (xy 53.325855 -56.236364)
			(xy 53.37719 -56.244494) (xy 53.42662 -56.260555) (xy 53.47293 -56.284151) (xy 53.514978 -56.314701)
			(xy 53.551729 -56.351452) (xy 53.582279 -56.3935) (xy 53.605875 -56.43981) (xy 53.621936 -56.48924)
			(xy 53.630066 -56.540575) (xy 53.630576 -56.566562) (xy 53.630066 -56.592549) (xy 53.628578 -56.601947)
			(xy 53.769516 -56.601947) (xy 53.769516 -56.549973) (xy 53.777646 -56.498638) (xy 53.793707 -56.449208)
			(xy 53.817303 -56.402898) (xy 53.847853 -56.36085) (xy 53.884604 -56.324099) (xy 53.926652 -56.293549)
			(xy 53.972962 -56.269953) (xy 54.022392 -56.253892) (xy 54.073727 -56.245762) (xy 54.125701 -56.245762)
			(xy 54.177036 -56.253892) (xy 54.226466 -56.269953) (xy 54.272776 -56.293549) (xy 54.314824 -56.324099)
			(xy 54.351575 -56.36085) (xy 54.382125 -56.402898) (xy 54.405721 -56.449208) (xy 54.421782 -56.498638)
			(xy 54.429912 -56.549973) (xy 54.430422 -56.57596) (xy 54.429912 -56.601947) (xy 54.421782 -56.653282)
			(xy 54.405721 -56.702712) (xy 54.382125 -56.749022) (xy 54.351575 -56.79107) (xy 54.314824 -56.827821)
			(xy 54.272776 -56.858371) (xy 54.226466 -56.881967) (xy 54.177036 -56.898028) (xy 54.125701 -56.906158)
			(xy 54.073727 -56.906158) (xy 54.022392 -56.898028) (xy 53.972962 -56.881967) (xy 53.926652 -56.858371)
			(xy 53.884604 -56.827821) (xy 53.847853 -56.79107) (xy 53.817303 -56.749022) (xy 53.793707 -56.702712)
			(xy 53.777646 -56.653282) (xy 53.769516 -56.601947) (xy 53.628578 -56.601947) (xy 53.621936 -56.643884)
			(xy 53.605875 -56.693314) (xy 53.582279 -56.739624) (xy 53.551729 -56.781672) (xy 53.514978 -56.818423)
			(xy 53.47293 -56.848973) (xy 53.42662 -56.872569) (xy 53.37719 -56.88863) (xy 53.325855 -56.89676)
			(xy 53.273881 -56.89676) (xy 53.222546 -56.88863) (xy 53.173116 -56.872569) (xy 53.126806 -56.848973)
			(xy 53.084758 -56.818423) (xy 53.048007 -56.781672) (xy 53.017457 -56.739624) (xy 52.993861 -56.693314)
			(xy 52.9778 -56.643884) (xy 52.96967 -56.592549) (xy 52.829966 -56.592549) (xy 52.821836 -56.643884)
			(xy 52.805775 -56.693314) (xy 52.782179 -56.739624) (xy 52.751629 -56.781672) (xy 52.714878 -56.818423)
			(xy 52.67283 -56.848973) (xy 52.62652 -56.872569) (xy 52.57709 -56.88863) (xy 52.525755 -56.89676)
			(xy 52.473781 -56.89676) (xy 52.422446 -56.88863) (xy 52.373016 -56.872569) (xy 52.326706 -56.848973)
			(xy 52.284658 -56.818423) (xy 52.247907 -56.781672) (xy 52.217357 -56.739624) (xy 52.193761 -56.693314)
			(xy 52.1777 -56.643884) (xy 52.16957 -56.592549) (xy 52.029866 -56.592549) (xy 52.021736 -56.643884)
			(xy 52.005675 -56.693314) (xy 51.982079 -56.739624) (xy 51.951529 -56.781672) (xy 51.914778 -56.818423)
			(xy 51.87273 -56.848973) (xy 51.82642 -56.872569) (xy 51.77699 -56.88863) (xy 51.725655 -56.89676)
			(xy 51.673681 -56.89676) (xy 51.622346 -56.88863) (xy 51.572916 -56.872569) (xy 51.526606 -56.848973)
			(xy 51.484558 -56.818423) (xy 51.447807 -56.781672) (xy 51.417257 -56.739624) (xy 51.393661 -56.693314)
			(xy 51.3776 -56.643884) (xy 51.36947 -56.592549) (xy 51.230036 -56.592549) (xy 51.230036 -56.592589)
			(xy 51.221906 -56.643927) (xy 51.205844 -56.693362) (xy 51.182247 -56.739675) (xy 51.151697 -56.781727)
			(xy 51.114944 -56.818482) (xy 51.072894 -56.849036) (xy 51.026582 -56.872636) (xy 50.977149 -56.8887)
			(xy 50.925811 -56.896835) (xy 50.899822 -56.89727) (xy 50.876149 -56.896843) (xy 50.829287 -56.890097)
			(xy 50.78386 -56.876754) (xy 50.762154 -56.867298) (xy 50.748737 -56.861642) (xy 50.719938 -56.857429)
			(xy 50.691119 -56.861508) (xy 50.66462 -56.873547) (xy 50.642591 -56.892569) (xy 50.626819 -56.917031)
			(xy 50.618585 -56.944948) (xy 50.618136 -56.9595) (xy 50.618136 -57.375806) (xy 50.82032 -57.577736)
			(xy 51.124104 -57.577736) (xy 51.17719 -57.524904) (xy 51.27117 -57.524904) (xy 51.285597 -57.524353)
			(xy 51.313278 -57.516195) (xy 51.337581 -57.500633) (xy 51.356572 -57.478905) (xy 51.368742 -57.452739)
			(xy 51.373122 -57.424215) (xy 51.371754 -57.409842) (xy 51.370429 -57.399033) (xy 51.369031 -57.377298)
			(xy 51.36896 -57.366408) (xy 51.36947 -57.340421) (xy 51.3776 -57.289086) (xy 51.393661 -57.239656)
			(xy 51.417257 -57.193346) (xy 51.447807 -57.151298) (xy 51.484558 -57.114547) (xy 51.526606 -57.083997)
			(xy 51.572916 -57.060401) (xy 51.622346 -57.04434) (xy 51.673681 -57.03621) (xy 51.725655 -57.03621)
			(xy 51.77699 -57.04434) (xy 51.82642 -57.060401) (xy 51.87273 -57.083997) (xy 51.914778 -57.114547)
			(xy 51.951529 -57.151298) (xy 51.982079 -57.193346) (xy 52.005675 -57.239656) (xy 52.021736 -57.289086)
			(xy 52.029866 -57.340421) (xy 52.030376 -57.366408) (xy 52.030304 -57.377298) (xy 52.028905 -57.399033)
			(xy 52.027582 -57.409842) (xy 52.026154 -57.424226) (xy 52.030475 -57.452792) (xy 52.042629 -57.479003)
			(xy 52.061642 -57.500757) (xy 52.08599 -57.51631) (xy 52.11372 -57.524417) (xy 52.128166 -57.524904)
			(xy 52.184554 -57.524904) (xy 52.184554 -57.466738) (xy 52.182522 -57.459626) (xy 52.176228 -57.436838)
			(xy 52.169475 -57.390046) (xy 52.16906 -57.366408) (xy 52.16957 -57.340421) (xy 52.1777 -57.289086)
			(xy 52.193761 -57.239656) (xy 52.217357 -57.193346) (xy 52.247907 -57.151298) (xy 52.284658 -57.114547)
			(xy 52.326706 -57.083997) (xy 52.373016 -57.060401) (xy 52.422446 -57.04434) (xy 52.473781 -57.03621)
			(xy 52.525755 -57.03621) (xy 52.57709 -57.04434) (xy 52.62652 -57.060401) (xy 52.67283 -57.083997)
			(xy 52.714878 -57.114547) (xy 52.751629 -57.151298) (xy 52.782179 -57.193346) (xy 52.805775 -57.239656)
			(xy 52.821836 -57.289086) (xy 52.829966 -57.340421) (xy 52.830476 -57.366408) (xy 52.830404 -57.377298)
			(xy 52.829005 -57.399033) (xy 52.827682 -57.409842) (xy 52.826254 -57.424226) (xy 52.830575 -57.452792)
			(xy 52.842729 -57.479003) (xy 52.861742 -57.500757) (xy 52.88609 -57.51631) (xy 52.91382 -57.524417)
			(xy 52.928266 -57.524904) (xy 52.984654 -57.524904) (xy 52.984654 -57.466738) (xy 52.982622 -57.459626)
			(xy 52.976328 -57.436838) (xy 52.969575 -57.390046) (xy 52.96916 -57.366408) (xy 52.96967 -57.340421)
			(xy 52.9778 -57.289086) (xy 52.993861 -57.239656) (xy 53.017457 -57.193346) (xy 53.048007 -57.151298)
			(xy 53.084758 -57.114547) (xy 53.126806 -57.083997) (xy 53.173116 -57.060401) (xy 53.222546 -57.04434)
			(xy 53.273881 -57.03621) (xy 53.325855 -57.03621) (xy 53.37719 -57.04434) (xy 53.42662 -57.060401)
			(xy 53.47293 -57.083997) (xy 53.514978 -57.114547) (xy 53.551729 -57.151298) (xy 53.582279 -57.193346)
			(xy 53.605875 -57.239656) (xy 53.621936 -57.289086) (xy 53.630066 -57.340421) (xy 53.630576 -57.366408)
			(xy 53.630504 -57.377298) (xy 53.629105 -57.399033) (xy 53.627782 -57.409842) (xy 53.626354 -57.424226)
			(xy 53.630675 -57.452792) (xy 53.642829 -57.479003) (xy 53.661842 -57.500757) (xy 53.68619 -57.51631)
			(xy 53.71392 -57.524417) (xy 53.728366 -57.524904) (xy 53.781706 -57.524904) (xy 53.781706 -57.467246)
			(xy 53.780182 -57.460896) (xy 53.774969 -57.440075) (xy 53.769357 -57.397521) (xy 53.769006 -57.37606)
			(xy 53.769516 -57.350073) (xy 53.777646 -57.298738) (xy 53.793707 -57.249308) (xy 53.817303 -57.202998)
			(xy 53.847853 -57.16095) (xy 53.884604 -57.124199) (xy 53.926652 -57.093649) (xy 53.972962 -57.070053)
			(xy 54.022392 -57.053992) (xy 54.073727 -57.045862) (xy 54.125701 -57.045862) (xy 54.177036 -57.053992)
			(xy 54.226466 -57.070053) (xy 54.272776 -57.093649) (xy 54.314824 -57.124199) (xy 54.351575 -57.16095)
			(xy 54.382125 -57.202998) (xy 54.405721 -57.249308) (xy 54.421782 -57.298738) (xy 54.429912 -57.350073)
			(xy 54.430422 -57.37606) (xy 54.429908 -57.402731) (xy 54.421338 -57.45538) (xy 54.404429 -57.505971)
			(xy 54.379619 -57.553193) (xy 54.347553 -57.59582) (xy 54.309061 -57.632749) (xy 54.28742 -57.648348)
			(xy 54.275494 -57.65722) (xy 54.25695 -57.680433) (xy 54.245858 -57.707995) (xy 54.243154 -57.737583)
			(xy 54.249066 -57.766699) (xy 54.263096 -57.792889) (xy 54.273196 -57.803796) (xy 54.661995 -58.192495)
			(xy 55.360064 -58.192495) (xy 55.360064 -58.140521) (xy 55.368194 -58.089186) (xy 55.384255 -58.039756)
			(xy 55.407851 -57.993446) (xy 55.438401 -57.951398) (xy 55.475152 -57.914647) (xy 55.5172 -57.884097)
			(xy 55.56351 -57.860501) (xy 55.61294 -57.84444) (xy 55.664275 -57.83631) (xy 55.716249 -57.83631)
			(xy 55.767584 -57.84444) (xy 55.817014 -57.860501) (xy 55.863324 -57.884097) (xy 55.905372 -57.914647)
			(xy 55.942123 -57.951398) (xy 55.972673 -57.993446) (xy 55.996269 -58.039756) (xy 56.01233 -58.089186)
			(xy 56.02046 -58.140521) (xy 56.02097 -58.166508) (xy 56.02046 -58.192495) (xy 56.01233 -58.24383)
			(xy 55.996269 -58.29326) (xy 55.972673 -58.33957) (xy 55.942123 -58.381618) (xy 55.905372 -58.418369)
			(xy 55.863324 -58.448919) (xy 55.817014 -58.472515) (xy 55.767584 -58.488576) (xy 55.716249 -58.496706)
			(xy 55.664275 -58.496706) (xy 55.61294 -58.488576) (xy 55.56351 -58.472515) (xy 55.5172 -58.448919)
			(xy 55.475152 -58.418369) (xy 55.438401 -58.381618) (xy 55.407851 -58.33957) (xy 55.384255 -58.29326)
			(xy 55.368194 -58.24383) (xy 55.360064 -58.192495) (xy 54.661995 -58.192495) (xy 55.262526 -58.792872)
			(xy 55.273397 -58.803027) (xy 55.299582 -58.817115) (xy 55.328718 -58.823052) (xy 55.358327 -58.820334)
			(xy 55.385896 -58.809193) (xy 55.40908 -58.790575) (xy 55.417974 -58.778648) (xy 55.433532 -58.756976)
			(xy 55.470467 -58.718484) (xy 55.513103 -58.686422) (xy 55.560333 -58.66162) (xy 55.610933 -58.644723)
			(xy 55.663589 -58.636168) (xy 55.690262 -58.635646) (xy 55.716252 -58.636153) (xy 55.767594 -58.644278)
			(xy 55.817033 -58.660335) (xy 55.863351 -58.683928) (xy 55.905408 -58.714477) (xy 55.942169 -58.751228)
			(xy 55.972728 -58.793277) (xy 55.996333 -58.839589) (xy 56.012402 -58.889024) (xy 56.020541 -58.940364)
			(xy 56.02097 -58.966354) (xy 56.020457 -58.993026) (xy 56.011889 -59.045677) (xy 55.994982 -59.09627)
			(xy 55.970175 -59.143495) (xy 55.938112 -59.186127) (xy 55.899623 -59.223061) (xy 55.877968 -59.238642)
			(xy 55.866036 -59.247511) (xy 55.847482 -59.270723) (xy 55.836383 -59.298288) (xy 55.833676 -59.327881)
			(xy 55.839591 -59.357003) (xy 55.853628 -59.383195) (xy 55.863744 -59.39409) (xy 58.301382 -61.831728)
			(xy 58.336434 -61.807344) (xy 58.360653 -61.79093) (xy 58.413062 -61.764932) (xy 58.468826 -61.747242)
			(xy 58.526639 -61.738276) (xy 58.55589 -61.737748) (xy 58.583143 -61.738233) (xy 58.637094 -61.745988)
			(xy 58.689392 -61.761342) (xy 58.738974 -61.783982) (xy 58.784829 -61.813447) (xy 58.826024 -61.849138)
			(xy 58.86172 -61.890328) (xy 58.891192 -61.936179) (xy 58.913839 -61.985757) (xy 58.9292 -62.038053)
			(xy 58.936963 -62.092003) (xy 58.937398 -62.119256) (xy 58.936819 -62.148504) (xy 58.927855 -62.20631)
			(xy 58.910175 -62.262072) (xy 58.884195 -62.314483) (xy 58.867802 -62.338712) (xy 58.843418 -62.373764)
			(xy 59.483244 -63.01359) (xy 60.001402 -63.01359) (xy 60.005473 -62.957968) (xy 60.017599 -62.903531)
			(xy 60.037522 -62.85144) (xy 60.064818 -62.802805) (xy 60.098904 -62.758662) (xy 60.139053 -62.719953)
			(xy 60.184411 -62.687502) (xy 60.234011 -62.662001) (xy 60.286795 -62.643994) (xy 60.341638 -62.633864)
			(xy 60.397372 -62.631827) (xy 60.452809 -62.637927) (xy 60.506766 -62.652033) (xy 60.558095 -62.673845)
			(xy 60.605701 -62.702899) (xy 60.648569 -62.738574) (xy 60.685786 -62.780111) (xy 60.716559 -62.826624)
			(xy 60.740231 -62.877121) (xy 60.756299 -62.930528) (xy 60.764419 -62.985704) (xy 60.764928 -63.01359)
			(xy 60.764419 -63.041476) (xy 60.756299 -63.096652) (xy 60.740231 -63.150059) (xy 60.716559 -63.200556)
			(xy 60.685786 -63.247069) (xy 60.648569 -63.288606) (xy 60.605701 -63.324281) (xy 60.558095 -63.353335)
			(xy 60.506766 -63.375147) (xy 60.452809 -63.389253) (xy 60.397372 -63.395353) (xy 60.341638 -63.393316)
			(xy 60.286795 -63.383186) (xy 60.234011 -63.365179) (xy 60.184411 -63.339678) (xy 60.139053 -63.307227)
			(xy 60.098904 -63.268518) (xy 60.064818 -63.224375) (xy 60.037522 -63.17574) (xy 60.017599 -63.123649)
			(xy 60.005473 -63.069212) (xy 60.001402 -63.01359) (xy 59.483244 -63.01359) (xy 61.1505 -64.680846)
			(xy 61.160249 -64.690029) (xy 61.183449 -64.703389) (xy 61.209327 -64.710251) (xy 61.2361 -64.710141)
			(xy 61.261921 -64.703068) (xy 61.285011 -64.689518) (xy 61.30378 -64.670426) (xy 61.310774 -64.659002)
			(xy 61.325388 -64.634124) (xy 61.360944 -64.588685) (xy 61.402938 -64.549121) (xy 61.450413 -64.516333)
			(xy 61.502285 -64.491071) (xy 61.55737 -64.473911) (xy 61.614412 -64.465244) (xy 61.64326 -64.464692)
			(xy 61.670515 -64.465153) (xy 61.72447 -64.472905) (xy 61.776773 -64.488258) (xy 61.826358 -64.510898)
			(xy 61.872216 -64.540365) (xy 61.913413 -64.576058) (xy 61.949111 -64.617252) (xy 61.978583 -64.663107)
			(xy 62.001228 -64.71269) (xy 62.016587 -64.764991) (xy 62.024345 -64.818945) (xy 62.024345 -64.873455)
			(xy 62.016587 -64.927409) (xy 62.001228 -64.97971) (xy 61.978583 -65.029293) (xy 61.949111 -65.075148)
			(xy 61.913413 -65.116342) (xy 61.872216 -65.152035) (xy 61.826358 -65.181502) (xy 61.776773 -65.204142)
			(xy 61.72447 -65.219495) (xy 61.670515 -65.227247) (xy 61.64326 -65.227708) (xy 61.615288 -65.227236)
			(xy 61.55994 -65.219099) (xy 61.506375 -65.202963) (xy 61.455743 -65.179174) (xy 61.40913 -65.148242)
			(xy 61.38799 -65.129918) (xy 61.376774 -65.12049) (xy 61.350328 -65.107904) (xy 61.321398 -65.103339)
			(xy 61.292362 -65.107168) (xy 61.265604 -65.119077) (xy 61.243325 -65.138089) (xy 61.227355 -65.16264)
			(xy 61.219006 -65.190713) (xy 61.218572 -65.205356) (xy 61.218572 -67.337178) (xy 61.185044 -67.37096)
			(xy 61.185044 -67.371214) (xy 60.822586 -67.733672) (xy 60.8134 -67.743505) (xy 60.800084 -67.766878)
			(xy 60.793334 -67.792918) (xy 60.793618 -67.819817) (xy 60.800915 -67.845708) (xy 60.814721 -67.868796)
			(xy 60.834076 -67.887477) (xy 60.857638 -67.900457) (xy 60.870592 -67.904106) (xy 60.89802 -67.911205)
			(xy 60.950561 -67.932401) (xy 60.999387 -67.961137) (xy 61.043425 -67.996779) (xy 61.081706 -68.038545)
			(xy 61.113386 -68.085514) (xy 61.13777 -68.136653) (xy 61.15432 -68.190837) (xy 61.162672 -68.246872)
			(xy 61.1632 -68.2752) (xy 61.162737 -68.302453) (xy 61.15498 -68.356403) (xy 61.139624 -68.408701)
			(xy 61.116981 -68.45828) (xy 61.087513 -68.504133) (xy 61.051819 -68.545325) (xy 61.010626 -68.581018)
			(xy 60.964773 -68.610485) (xy 60.915193 -68.633126) (xy 60.862895 -68.648481) (xy 60.808945 -68.656237)
			(xy 60.781692 -68.656708) (xy 60.753511 -68.656202) (xy 60.697763 -68.647908) (xy 60.643842 -68.631503)
			(xy 60.592922 -68.607344) (xy 60.546109 -68.575956) (xy 60.524898 -68.557394) (xy 60.513699 -68.547882)
			(xy 60.487237 -68.535138) (xy 60.458243 -68.53045) (xy 60.429114 -68.534203) (xy 60.402256 -68.546089)
			(xy 60.379889 -68.565125) (xy 60.363862 -68.589738) (xy 60.3555 -68.617893) (xy 60.354972 -68.632578)
			(xy 60.354972 -68.942458) (xy 61.10859 -68.942458) (xy 61.10915 -68.913519) (xy 61.117885 -68.856304)
			(xy 61.135162 -68.801064) (xy 61.160585 -68.749069) (xy 61.193571 -68.701511) (xy 61.233363 -68.659481)
			(xy 61.279047 -68.623945) (xy 61.329576 -68.595717) (xy 61.356494 -68.58508) (xy 61.369018 -68.579934)
			(xy 61.39102 -68.564174) (xy 61.408107 -68.543186) (xy 61.419078 -68.518445) (xy 61.423162 -68.491691)
			(xy 61.420072 -68.464804) (xy 61.410025 -68.439674) (xy 61.402214 -68.428616) (xy 61.384111 -68.403663)
			(xy 61.355395 -68.349114) (xy 61.335811 -68.290661) (xy 61.325865 -68.229823) (xy 61.325252 -68.199)
			(xy 61.325738 -68.171749) (xy 61.333494 -68.117801) (xy 61.348849 -68.065506) (xy 61.371491 -68.015929)
			(xy 61.400957 -67.970079) (xy 61.436648 -67.928888) (xy 61.477839 -67.893197) (xy 61.523689 -67.863731)
			(xy 61.573266 -67.841089) (xy 61.625561 -67.825734) (xy 61.679509 -67.817978) (xy 61.734011 -67.817978)
			(xy 61.787959 -67.825734) (xy 61.840254 -67.841089) (xy 61.889831 -67.863731) (xy 61.935681 -67.893197)
			(xy 61.976872 -67.928888) (xy 62.012563 -67.970079) (xy 62.042029 -68.015929) (xy 62.064671 -68.065506)
			(xy 62.080026 -68.117801) (xy 62.087782 -68.171749) (xy 62.088268 -68.199) (xy 62.087698 -68.227939)
			(xy 62.078969 -68.285155) (xy 62.061695 -68.340396) (xy 62.036274 -68.392392) (xy 62.003289 -68.439951)
			(xy 61.963497 -68.481981) (xy 61.917812 -68.517516) (xy 61.867283 -68.545742) (xy 61.840364 -68.556378)
			(xy 61.827811 -68.561464) (xy 61.805795 -68.577228) (xy 61.788699 -68.598226) (xy 61.777726 -68.622981)
			(xy 61.773649 -68.649749) (xy 61.776753 -68.676648) (xy 61.786821 -68.701784) (xy 61.794644 -68.712842)
			(xy 61.812724 -68.737811) (xy 61.841446 -68.792355) (xy 61.861037 -68.850802) (xy 61.87099 -68.911637)
			(xy 61.871606 -68.942458) (xy 61.87112 -68.969709) (xy 61.863364 -69.023657) (xy 61.848009 -69.075952)
			(xy 61.825367 -69.125529) (xy 61.795901 -69.171379) (xy 61.76021 -69.21257) (xy 61.719019 -69.248261)
			(xy 61.673169 -69.277727) (xy 61.623592 -69.300369) (xy 61.571297 -69.315724) (xy 61.517349 -69.32348)
			(xy 61.462847 -69.32348) (xy 61.408899 -69.315724) (xy 61.356604 -69.300369) (xy 61.307027 -69.277727)
			(xy 61.261177 -69.248261) (xy 61.219986 -69.21257) (xy 61.184295 -69.171379) (xy 61.154829 -69.125529)
			(xy 61.132187 -69.075952) (xy 61.116832 -69.023657) (xy 61.109076 -68.969709) (xy 61.10859 -68.942458)
			(xy 60.354972 -68.942458) (xy 60.354972 -69.451982) (xy 62.838584 -71.935594) (xy 62.838584 -72.584564)
			(xy 62.84214 -72.58812) (xy 62.84214 -72.886316) (xy 63.05423 -73.098406) (xy 64.460374 -73.098406)
		)
		(stroke
			(width 0)
			(type solid)
		)
		(fill yes)
		(layer "In7.Cu")
		(net "P5V_SENSOR")
	)
	(gr_poly
		(pts
			(xy 63.986664 -69.915786) (xy 64.000992 -69.915261) (xy 64.0285 -69.907226) (xy 64.052693 -69.891863)
			(xy 64.071663 -69.870382) (xy 64.083917 -69.844476) (xy 64.08849 -69.816185) (xy 64.08502 -69.787737)
			(xy 64.073782 -69.761374) (xy 64.06515 -69.749924) (xy 64.048913 -69.729399) (xy 64.021625 -69.684742)
			(xy 64.000708 -69.63677) (xy 63.986556 -69.586385) (xy 63.979435 -69.534538) (xy 63.979044 -69.50837)
			(xy 63.97953 -69.481119) (xy 63.987286 -69.427171) (xy 64.002641 -69.374876) (xy 64.025283 -69.325299)
			(xy 64.054749 -69.279449) (xy 64.09044 -69.238258) (xy 64.131631 -69.202567) (xy 64.177481 -69.173101)
			(xy 64.227058 -69.150459) (xy 64.279353 -69.135104) (xy 64.333301 -69.127348) (xy 64.387803 -69.127348)
			(xy 64.441751 -69.135104) (xy 64.494046 -69.150459) (xy 64.543623 -69.173101) (xy 64.589473 -69.202567)
			(xy 64.630664 -69.238258) (xy 64.666355 -69.279449) (xy 64.695821 -69.325299) (xy 64.718463 -69.374876)
			(xy 64.733818 -69.427171) (xy 64.741574 -69.481119) (xy 64.74206 -69.50837) (xy 64.741626 -69.534534)
			(xy 64.734477 -69.58637) (xy 64.720322 -69.636747) (xy 64.699427 -69.684722) (xy 64.672181 -69.729396)
			(xy 64.655954 -69.749924) (xy 64.647266 -69.761341) (xy 64.636021 -69.78772) (xy 64.632549 -69.816185)
			(xy 64.637124 -69.844494) (xy 64.649386 -69.870417) (xy 64.668369 -69.891911) (xy 64.692577 -69.907283)
			(xy 64.720103 -69.915322) (xy 64.73444 -69.915786) (xy 64.976248 -69.915786) (xy 65.180972 -69.711316)
			(xy 65.180972 -68.84924) (xy 64.6049 -68.273168) (xy 64.6049 -66.64198) (xy 64.740536 -66.506344)
			(xy 64.750693 -66.495574) (xy 64.764856 -66.469592) (xy 64.770962 -66.440637) (xy 64.768496 -66.411149)
			(xy 64.757666 -66.383611) (xy 64.739384 -66.360342) (xy 64.727582 -66.351404) (xy 64.706567 -66.33602)
			(xy 64.668512 -66.300465) (xy 64.635651 -66.26006) (xy 64.608596 -66.215557) (xy 64.587852 -66.167786)
			(xy 64.573804 -66.117636) (xy 64.566714 -66.06604) (xy 64.566292 -66.04) (xy 64.566778 -66.012749)
			(xy 64.574534 -65.958801) (xy 64.589889 -65.906506) (xy 64.612531 -65.856929) (xy 64.641997 -65.811079)
			(xy 64.677688 -65.769888) (xy 64.718879 -65.734197) (xy 64.764729 -65.704731) (xy 64.814306 -65.682089)
			(xy 64.866601 -65.666734) (xy 64.920549 -65.658978) (xy 64.9478 -65.658492) (xy 64.974117 -65.658952)
			(xy 65.026246 -65.666217) (xy 65.051686 -65.67297) (xy 65.064721 -65.676239) (xy 65.091584 -65.67657)
			(xy 65.117603 -65.669883) (xy 65.140977 -65.656641) (xy 65.160088 -65.63776) (xy 65.173613 -65.614548)
			(xy 65.180615 -65.588612) (xy 65.180972 -65.57518) (xy 65.180972 -60.368434) (xy 64.839088 -60.02655)
			(xy 64.82805 -60.016265) (xy 64.801439 -60.002084) (xy 64.771844 -59.996302) (xy 64.741852 -59.999427)
			(xy 64.714084 -60.011183) (xy 64.702182 -60.020454) (xy 64.679686 -60.038445) (xy 64.629762 -60.06717)
			(xy 64.575619 -60.086816) (xy 64.518891 -60.096789) (xy 64.490092 -60.097416) (xy 63.690246 -60.097416)
			(xy 63.677038 -60.096908) (xy 63.666128 -60.096986) (xy 63.645947 -60.105216) (xy 63.630992 -60.121072)
			(xy 63.623954 -60.141699) (xy 63.6261 -60.163389) (xy 63.631064 -60.173108) (xy 63.645888 -60.200284)
			(xy 63.666954 -60.258486) (xy 63.677657 -60.319451) (xy 63.678308 -60.3504) (xy 63.67781 -60.377049)
			(xy 63.669867 -60.429753) (xy 63.654157 -60.480683) (xy 63.631031 -60.528704) (xy 63.601007 -60.572741)
			(xy 63.564755 -60.611812) (xy 63.523084 -60.645043) (xy 63.476926 -60.671692) (xy 63.427312 -60.691164)
			(xy 63.37535 -60.703024) (xy 63.3222 -60.707008) (xy 63.26905 -60.703024) (xy 63.217088 -60.691164)
			(xy 63.167474 -60.671692) (xy 63.121316 -60.645043) (xy 63.079645 -60.611812) (xy 63.043393 -60.572741)
			(xy 63.013369 -60.528704) (xy 62.990243 -60.480683) (xy 62.974533 -60.429753) (xy 62.96659 -60.377049)
			(xy 62.966092 -60.3504) (xy 62.966553 -60.324159) (xy 62.974243 -60.272244) (xy 62.989472 -60.222021)
			(xy 63.011909 -60.174577) (xy 63.041068 -60.130942) (xy 63.076317 -60.09206) (xy 63.116893 -60.058774)
			(xy 63.161915 -60.031806) (xy 63.210409 -60.011741) (xy 63.261324 -59.999012) (xy 63.287402 -59.99607)
			(xy 63.302313 -59.994026) (xy 63.330069 -59.98243) (xy 63.35325 -59.96326) (xy 63.36985 -59.938174)
			(xy 63.378432 -59.909344) (xy 63.378255 -59.879263) (xy 63.37427 -59.864752) (xy 63.367271 -59.840783)
			(xy 63.359751 -59.79142) (xy 63.359284 -59.766454) (xy 63.359798 -59.740451) (xy 63.367941 -59.689085)
			(xy 63.384019 -59.639626) (xy 63.407636 -59.59329) (xy 63.43821 -59.55122) (xy 63.47499 -59.514451)
			(xy 63.517069 -59.483888) (xy 63.563411 -59.460283) (xy 63.612875 -59.444219) (xy 63.664242 -59.436091)
			(xy 63.690246 -59.435492) (xy 64.00292 -59.435492) (xy 64.017899 -59.434972) (xy 64.046571 -59.426297)
			(xy 64.071491 -59.409672) (xy 64.09051 -59.386528) (xy 64.101991 -59.35886) (xy 64.104945 -59.329049)
			(xy 64.099117 -59.299665) (xy 64.085009 -59.273239) (xy 64.074802 -59.262264) (xy 64.038988 -59.22645)
			(xy 64.02795 -59.216165) (xy 64.001339 -59.201984) (xy 63.971744 -59.196202) (xy 63.941752 -59.199327)
			(xy 63.913984 -59.211083) (xy 63.902082 -59.220354) (xy 63.879595 -59.238286) (xy 63.829716 -59.266915)
			(xy 63.775643 -59.286501) (xy 63.719001 -59.296456) (xy 63.690246 -59.297062) (xy 63.664256 -59.296582)
			(xy 63.612914 -59.288456) (xy 63.563477 -59.272398) (xy 63.51716 -59.248802) (xy 63.475106 -59.218249)
			(xy 63.438351 -59.181494) (xy 63.407798 -59.13944) (xy 63.384202 -59.093123) (xy 63.368144 -59.043686)
			(xy 63.360018 -58.992344) (xy 63.359538 -58.966354) (xy 63.360137 -58.93803) (xy 63.369839 -58.882218)
			(xy 63.378842 -58.855356) (xy 63.352157 -58.843168) (xy 63.30357 -58.810305) (xy 63.282322 -58.790078)
			(xy 63.243968 -58.75147) (xy 63.184278 -58.81116) (xy 63.196978 -58.842402) (xy 63.208214 -58.872151)
			(xy 63.220371 -58.934563) (xy 63.221108 -58.966354) (xy 63.220602 -58.992365) (xy 63.212471 -59.043747)
			(xy 63.196402 -59.093225) (xy 63.172791 -59.139579) (xy 63.14222 -59.18167) (xy 63.10544 -59.21846)
			(xy 63.063358 -59.249043) (xy 63.01701 -59.272667) (xy 62.967537 -59.288749) (xy 62.916157 -59.296894)
			(xy 62.890146 -59.297316) (xy 62.0903 -59.297316) (xy 62.064296 -59.296806) (xy 62.01293 -59.28867)
			(xy 61.963468 -59.272599) (xy 61.91713 -59.248988) (xy 61.875055 -59.218419) (xy 61.838281 -59.181645)
			(xy 61.807712 -59.13957) (xy 61.784101 -59.093232) (xy 61.76803 -59.04377) (xy 61.759894 -58.992404)
			(xy 61.759894 -58.940396) (xy 61.76803 -58.88903) (xy 61.784101 -58.839568) (xy 61.807712 -58.79323)
			(xy 61.838281 -58.751155) (xy 61.875055 -58.714381) (xy 61.91713 -58.683812) (xy 61.963468 -58.660201)
			(xy 62.01293 -58.64413) (xy 62.064296 -58.635994) (xy 62.0903 -58.635392) (xy 62.890146 -58.635392)
			(xy 62.921941 -58.636111) (xy 62.984359 -58.648252) (xy 63.014098 -58.659522) (xy 63.04534 -58.672222)
			(xy 63.10503 -58.612532) (xy 62.68212 -58.189876) (xy 62.662519 -58.169328) (xy 62.630438 -58.12248)
			(xy 62.607484 -58.070546) (xy 62.600332 -58.043064) (xy 62.591188 -58.003948) (xy 62.527688 -58.003948)
			(xy 62.513178 -58.004464) (xy 62.485332 -58.012634) (xy 62.46091 -58.02831) (xy 62.441887 -58.050225)
			(xy 62.4298 -58.076608) (xy 62.425626 -58.105326) (xy 62.427104 -58.119772) (xy 62.428665 -58.131393)
			(xy 62.43032 -58.154783) (xy 62.430406 -58.166508) (xy 62.429896 -58.192495) (xy 62.421766 -58.24383)
			(xy 62.405705 -58.29326) (xy 62.382109 -58.33957) (xy 62.351559 -58.381618) (xy 62.314808 -58.418369)
			(xy 62.27276 -58.448919) (xy 62.22645 -58.472515) (xy 62.17702 -58.488576) (xy 62.125685 -58.496706)
			(xy 62.073711 -58.496706) (xy 62.022376 -58.488576) (xy 61.972946 -58.472515) (xy 61.926636 -58.448919)
			(xy 61.884588 -58.418369) (xy 61.847837 -58.381618) (xy 61.817287 -58.33957) (xy 61.793691 -58.29326)
			(xy 61.77763 -58.24383) (xy 61.7695 -58.192495) (xy 61.76899 -58.166508) (xy 61.769438 -58.141943)
			(xy 61.776708 -58.093354) (xy 61.783468 -58.069734) (xy 61.785754 -58.062368) (xy 61.785754 -58.003948)
			(xy 61.620908 -58.003948) (xy 61.620908 -58.166508) (xy 61.620398 -58.192495) (xy 61.612268 -58.24383)
			(xy 61.596207 -58.29326) (xy 61.572611 -58.33957) (xy 61.542061 -58.381618) (xy 61.50531 -58.418369)
			(xy 61.463262 -58.448919) (xy 61.416952 -58.472515) (xy 61.367522 -58.488576) (xy 61.316187 -58.496706)
			(xy 61.264213 -58.496706) (xy 61.212878 -58.488576) (xy 61.163448 -58.472515) (xy 61.117138 -58.448919)
			(xy 61.07509 -58.418369) (xy 61.038339 -58.381618) (xy 61.007789 -58.33957) (xy 60.984193 -58.29326)
			(xy 60.968132 -58.24383) (xy 60.960002 -58.192495) (xy 60.959492 -58.166508) (xy 60.959492 -58.003948)
			(xy 60.126118 -58.003948) (xy 60.111422 -58.004475) (xy 60.083262 -58.01291) (xy 60.058663 -58.029003)
			(xy 60.039654 -58.051424) (xy 60.027803 -58.078325) (xy 60.024089 -58.107485) (xy 60.026042 -58.122058)
			(xy 60.02809 -58.135425) (xy 60.030252 -58.162383) (xy 60.03036 -58.175906) (xy 60.02985 -58.201893)
			(xy 60.02172 -58.253228) (xy 60.005659 -58.302658) (xy 59.982063 -58.348968) (xy 59.951513 -58.391016)
			(xy 59.914762 -58.427767) (xy 59.872714 -58.458317) (xy 59.826404 -58.481913) (xy 59.776974 -58.497974)
			(xy 59.725639 -58.506104) (xy 59.673665 -58.506104) (xy 59.62233 -58.497974) (xy 59.5729 -58.481913)
			(xy 59.52659 -58.458317) (xy 59.484542 -58.427767) (xy 59.447791 -58.391016) (xy 59.417241 -58.348968)
			(xy 59.393645 -58.302658) (xy 59.377584 -58.253228) (xy 59.369454 -58.201893) (xy 59.368944 -58.175906)
			(xy 59.369572 -58.147725) (xy 59.379151 -58.092181) (xy 59.387994 -58.065416) (xy 59.398662 -58.03519)
			(xy 59.3217 -57.958228) (xy 59.186826 -57.958228) (xy 59.186826 -58.020204) (xy 59.191398 -58.03011)
			(xy 59.200701 -58.051633) (xy 59.213822 -58.096647) (xy 59.220448 -58.143064) (xy 59.220862 -58.166508)
			(xy 59.220352 -58.192491) (xy 59.212221 -58.243816) (xy 59.196163 -58.293238) (xy 59.172571 -58.339539)
			(xy 59.142026 -58.38158) (xy 59.105281 -58.418325) (xy 59.063241 -58.448869) (xy 59.01694 -58.472462)
			(xy 58.967518 -58.488521) (xy 58.916193 -58.496651) (xy 58.864227 -58.496653) (xy 58.812902 -58.488526)
			(xy 58.763479 -58.47247) (xy 58.717177 -58.44888) (xy 58.675134 -58.418338) (xy 58.638387 -58.381595)
			(xy 58.60784 -58.339556) (xy 58.584245 -58.293256) (xy 58.568183 -58.243835) (xy 58.56005 -58.192511)
			(xy 58.560046 -58.140545) (xy 58.56817 -58.089219) (xy 58.584224 -58.039796) (xy 58.607811 -57.993492)
			(xy 58.638351 -57.951448) (xy 58.675091 -57.914699) (xy 58.717129 -57.884149) (xy 58.763427 -57.860552)
			(xy 58.812847 -57.844487) (xy 58.864171 -57.836351) (xy 58.890154 -57.8358) (xy 58.91657 -57.836816)
			(xy 58.939938 -57.838594) (xy 58.992262 -57.78627) (xy 58.913268 -57.707022) (xy 58.892948 -57.706768)
			(xy 58.867658 -57.705762) (xy 58.817809 -57.697017) (xy 58.769874 -57.68078) (xy 58.724973 -57.657429)
			(xy 58.684153 -57.627509) (xy 58.648368 -57.591721) (xy 58.618453 -57.550898) (xy 58.595107 -57.505994)
			(xy 58.578874 -57.458057) (xy 58.570134 -57.408207) (xy 58.569098 -57.382918) (xy 58.568844 -57.362598)
			(xy 58.480706 -57.27446) (xy 58.42889 -57.32653) (xy 58.429906 -57.349136) (xy 58.430414 -57.366408)
			(xy 58.429904 -57.392396) (xy 58.421772 -57.443731) (xy 58.405709 -57.493162) (xy 58.382112 -57.539471)
			(xy 58.351561 -57.58152) (xy 58.314808 -57.618271) (xy 58.272758 -57.64882) (xy 58.226448 -57.672415)
			(xy 58.177016 -57.688475) (xy 58.12568 -57.696605) (xy 58.073705 -57.696604) (xy 58.02237 -57.688472)
			(xy 57.972939 -57.67241) (xy 57.926629 -57.648812) (xy 57.884581 -57.618261) (xy 57.84783 -57.581508)
			(xy 57.81728 -57.539459) (xy 57.793685 -57.493148) (xy 57.777625 -57.443716) (xy 57.769495 -57.392381)
			(xy 57.769496 -57.340406) (xy 57.777628 -57.289071) (xy 57.79369 -57.239639) (xy 57.817287 -57.19333)
			(xy 57.847838 -57.151281) (xy 57.884591 -57.11453) (xy 57.92664 -57.083981) (xy 57.972951 -57.060385)
			(xy 58.022383 -57.044325) (xy 58.073718 -57.036195) (xy 58.099706 -57.0357) (xy 58.116978 -57.036208)
			(xy 58.139584 -57.037224) (xy 58.191654 -56.985408) (xy 58.104024 -56.897778) (xy 58.084212 -56.897016)
			(xy 58.057105 -56.895197) (xy 58.003985 -56.88382) (xy 57.953438 -56.863917) (xy 57.906822 -56.836022)
			(xy 57.865391 -56.800885) (xy 57.830258 -56.75945) (xy 57.802368 -56.712832) (xy 57.78247 -56.662283)
			(xy 57.771099 -56.609162) (xy 57.769252 -56.582056) (xy 57.76849 -56.562244) (xy 57.680606 -56.47436)
			(xy 57.628282 -56.526684) (xy 57.629806 -56.549544) (xy 57.630568 -56.57088) (xy 57.63006 -56.596864)
			(xy 57.621933 -56.648192) (xy 57.605878 -56.697617) (xy 57.582288 -56.743921) (xy 57.551745 -56.785966)
			(xy 57.515002 -56.822715) (xy 57.472961 -56.853264) (xy 57.42666 -56.87686) (xy 57.377237 -56.892922)
			(xy 57.32591 -56.901056) (xy 57.273943 -56.90106) (xy 57.222615 -56.892935) (xy 57.173189 -56.87688)
			(xy 57.126884 -56.853292) (xy 57.084839 -56.82275) (xy 57.048089 -56.786007) (xy 57.01754 -56.743967)
			(xy 56.993943 -56.697666) (xy 56.977879 -56.648244) (xy 56.969745 -56.596917) (xy 56.969739 -56.54495)
			(xy 56.977863 -56.493621) (xy 56.993917 -56.444196) (xy 57.017505 -56.39789) (xy 57.048046 -56.355844)
			(xy 57.084788 -56.319094) (xy 57.126827 -56.288543) (xy 57.173128 -56.264945) (xy 57.22255 -56.248881)
			(xy 57.273876 -56.240745) (xy 57.29986 -56.240172) (xy 57.321196 -56.240934) (xy 57.344056 -56.242458)
			(xy 57.39638 -56.190134) (xy 57.30367 -56.097424) (xy 57.28335 -56.09717) (xy 57.25806 -56.096164)
			(xy 57.208211 -56.08742) (xy 57.160275 -56.071182) (xy 57.115373 -56.047831) (xy 57.074553 -56.017912)
			(xy 57.038768 -55.982123) (xy 57.008852 -55.9413) (xy 56.985506 -55.896396) (xy 56.969273 -55.84846)
			(xy 56.960533 -55.798609) (xy 56.9595 -55.77332) (xy 56.959246 -55.753) (xy 56.870346 -55.664354)
			(xy 56.818022 -55.716678) (xy 56.8198 -55.740046) (xy 56.820816 -55.766462) (xy 56.820336 -55.792453)
			(xy 56.81221 -55.843795) (xy 56.796152 -55.893234) (xy 56.772558 -55.939552) (xy 56.742008 -55.981609)
			(xy 56.705255 -56.018368) (xy 56.663204 -56.048926) (xy 56.61689 -56.072529) (xy 56.567454 -56.088596)
			(xy 56.516113 -56.096731) (xy 56.464132 -56.096735) (xy 56.41279 -56.088606) (xy 56.363352 -56.072546)
			(xy 56.317035 -56.04895) (xy 56.27498 -56.018398) (xy 56.238222 -55.981643) (xy 56.207666 -55.939591)
			(xy 56.184065 -55.893276) (xy 56.168001 -55.843839) (xy 56.159868 -55.792498) (xy 56.159867 -55.740517)
			(xy 56.167997 -55.689175) (xy 56.18406 -55.639738) (xy 56.207659 -55.593422) (xy 56.238212 -55.551368)
			(xy 56.274969 -55.514612) (xy 56.317023 -55.484058) (xy 56.363338 -55.46046) (xy 56.412776 -55.444397)
			(xy 56.464117 -55.436267) (xy 56.490108 -55.435754) (xy 56.514999 -55.4362) (xy 56.564219 -55.443666)
			(xy 56.611759 -55.45844) (xy 56.656539 -55.480189) (xy 56.677306 -55.49392) (xy 56.686764 -55.499722)
			(xy 56.708623 -55.503386) (xy 56.729996 -55.497515) (xy 56.746916 -55.483198) (xy 56.756243 -55.463092)
			(xy 56.756808 -55.45201) (xy 56.756808 -55.39359) (xy 55.830978 -54.467506) (xy 55.800752 -54.478174)
			(xy 55.774002 -54.487075) (xy 55.718448 -54.496648) (xy 55.690262 -54.497224) (xy 55.664276 -54.496712)
			(xy 55.612945 -54.488576) (xy 55.563519 -54.472512) (xy 55.517214 -54.448915) (xy 55.475169 -54.418365)
			(xy 55.438421 -54.381614) (xy 55.407874 -54.339568) (xy 55.384279 -54.293261) (xy 55.368218 -54.243833)
			(xy 55.360087 -54.192502) (xy 55.359554 -54.166516) (xy 55.360182 -54.138335) (xy 55.369759 -54.082791)
			(xy 55.378604 -54.056026) (xy 55.389272 -54.0258) (xy 55.078122 -53.71465) (xy 53.00218 -53.71465)
			(xy 52.900072 -53.816758) (xy 52.900072 -54.192503) (xy 53.769516 -54.192503) (xy 53.769516 -54.140529)
			(xy 53.777646 -54.089194) (xy 53.793707 -54.039764) (xy 53.817303 -53.993454) (xy 53.847853 -53.951406)
			(xy 53.884604 -53.914655) (xy 53.926652 -53.884105) (xy 53.972962 -53.860509) (xy 54.022392 -53.844448)
			(xy 54.073727 -53.836318) (xy 54.125701 -53.836318) (xy 54.177036 -53.844448) (xy 54.226466 -53.860509)
			(xy 54.272776 -53.884105) (xy 54.314824 -53.914655) (xy 54.351575 -53.951406) (xy 54.382125 -53.993454)
			(xy 54.405721 -54.039764) (xy 54.421782 -54.089194) (xy 54.429912 -54.140529) (xy 54.430422 -54.166516)
			(xy 54.429912 -54.192503) (xy 54.421782 -54.243838) (xy 54.405721 -54.293268) (xy 54.382125 -54.339578)
			(xy 54.351575 -54.381626) (xy 54.314824 -54.418377) (xy 54.272776 -54.448927) (xy 54.226466 -54.472523)
			(xy 54.177036 -54.488584) (xy 54.125701 -54.496714) (xy 54.073727 -54.496714) (xy 54.022392 -54.488584)
			(xy 53.972962 -54.472523) (xy 53.926652 -54.448927) (xy 53.884604 -54.418377) (xy 53.847853 -54.381626)
			(xy 53.817303 -54.339578) (xy 53.793707 -54.293268) (xy 53.777646 -54.243838) (xy 53.769516 -54.192503)
			(xy 52.900072 -54.192503) (xy 52.900072 -54.835806) (xy 53.085746 -55.02148) (xy 54.04993 -55.02148)
			(xy 54.060852 -55.032148) (xy 54.073552 -55.032148) (xy 54.584092 -55.542688) (xy 54.591458 -55.549528)
			(xy 54.609991 -55.55727) (xy 54.630075 -55.55727) (xy 54.648608 -55.549528) (xy 54.655974 -55.542688)
			(xy 54.674692 -55.524574) (xy 54.716774 -55.493879) (xy 54.763152 -55.470169) (xy 54.812676 -55.454032)
			(xy 54.864118 -55.445867) (xy 54.890162 -55.445406) (xy 54.916153 -55.445886) (xy 54.967495 -55.454013)
			(xy 55.016934 -55.470072) (xy 55.063251 -55.493668) (xy 55.105307 -55.52422) (xy 55.142065 -55.560975)
			(xy 55.17262 -55.603028) (xy 55.196219 -55.649344) (xy 55.212281 -55.698781) (xy 55.220412 -55.750123)
			(xy 55.22087 -55.776114) (xy 55.220563 -55.792449) (xy 55.360064 -55.792449) (xy 55.360064 -55.740475)
			(xy 55.368194 -55.68914) (xy 55.384255 -55.63971) (xy 55.407851 -55.5934) (xy 55.438401 -55.551352)
			(xy 55.475152 -55.514601) (xy 55.5172 -55.484051) (xy 55.56351 -55.460455) (xy 55.61294 -55.444394)
			(xy 55.664275 -55.436264) (xy 55.716249 -55.436264) (xy 55.767584 -55.444394) (xy 55.817014 -55.460455)
			(xy 55.863324 -55.484051) (xy 55.905372 -55.514601) (xy 55.942123 -55.551352) (xy 55.972673 -55.5934)
			(xy 55.996269 -55.63971) (xy 56.01233 -55.68914) (xy 56.02046 -55.740475) (xy 56.02097 -55.766462)
			(xy 56.02046 -55.792449) (xy 56.01233 -55.843784) (xy 55.996269 -55.893214) (xy 55.972673 -55.939524)
			(xy 55.942123 -55.981572) (xy 55.905372 -56.018323) (xy 55.863324 -56.048873) (xy 55.817014 -56.072469)
			(xy 55.767584 -56.08853) (xy 55.716249 -56.09666) (xy 55.664275 -56.09666) (xy 55.61294 -56.08853)
			(xy 55.56351 -56.072469) (xy 55.5172 -56.048873) (xy 55.475152 -56.018323) (xy 55.438401 -55.981572)
			(xy 55.407851 -55.939524) (xy 55.384255 -55.893214) (xy 55.368194 -55.843784) (xy 55.360064 -55.792449)
			(xy 55.220563 -55.792449) (xy 55.220381 -55.802156) (xy 55.212211 -55.853594) (xy 55.196077 -55.903115)
			(xy 55.172376 -55.949493) (xy 55.141696 -55.991581) (xy 55.123588 -56.010302) (xy 55.08752 -56.04637)
			(xy 55.34914 -56.30799) (xy 55.360233 -56.318297) (xy 55.386964 -56.332488) (xy 55.416678 -56.338229)
			(xy 55.446772 -56.335018) (xy 55.474606 -56.323137) (xy 55.486554 -56.313832) (xy 55.504513 -56.299182)
			(xy 55.543757 -56.274526) (xy 55.586061 -56.255597) (xy 55.630596 -56.242765) (xy 55.676487 -56.236283)
			(xy 55.69966 -56.235854) (xy 55.725652 -56.236334) (xy 55.776998 -56.24446) (xy 55.82644 -56.260518)
			(xy 55.872762 -56.284113) (xy 55.914822 -56.314664) (xy 55.951585 -56.351419) (xy 55.982146 -56.393472)
			(xy 56.005752 -56.439787) (xy 56.021822 -56.489226) (xy 56.02996 -56.54057) (xy 56.030368 -56.566562)
			(xy 56.029803 -56.592549) (xy 56.169562 -56.592549) (xy 56.169562 -56.540575) (xy 56.177692 -56.48924)
			(xy 56.193753 -56.43981) (xy 56.217349 -56.3935) (xy 56.247899 -56.351452) (xy 56.28465 -56.314701)
			(xy 56.326698 -56.284151) (xy 56.373008 -56.260555) (xy 56.422438 -56.244494) (xy 56.473773 -56.236364)
			(xy 56.525747 -56.236364) (xy 56.577082 -56.244494) (xy 56.626512 -56.260555) (xy 56.672822 -56.284151)
			(xy 56.71487 -56.314701) (xy 56.751621 -56.351452) (xy 56.782171 -56.3935) (xy 56.805767 -56.43981)
			(xy 56.821828 -56.48924) (xy 56.829958 -56.540575) (xy 56.830468 -56.566562) (xy 56.829958 -56.592549)
			(xy 56.821828 -56.643884) (xy 56.805767 -56.693314) (xy 56.782171 -56.739624) (xy 56.751621 -56.781672)
			(xy 56.71487 -56.818423) (xy 56.672822 -56.848973) (xy 56.626512 -56.872569) (xy 56.577082 -56.88863)
			(xy 56.525747 -56.89676) (xy 56.473773 -56.89676) (xy 56.422438 -56.88863) (xy 56.373008 -56.872569)
			(xy 56.326698 -56.848973) (xy 56.28465 -56.818423) (xy 56.247899 -56.781672) (xy 56.217349 -56.739624)
			(xy 56.193753 -56.693314) (xy 56.177692 -56.643884) (xy 56.169562 -56.592549) (xy 56.029803 -56.592549)
			(xy 56.029738 -56.595534) (xy 56.019592 -56.652585) (xy 55.999675 -56.707) (xy 55.970593 -56.757119)
			(xy 55.95239 -56.779668) (xy 55.943055 -56.791595) (xy 55.931173 -56.819437) (xy 55.927965 -56.849539)
			(xy 55.933714 -56.87926) (xy 55.947915 -56.905994) (xy 55.958232 -56.917082) (xy 56.148986 -57.107836)
			(xy 56.16008 -57.118147) (xy 56.186816 -57.132346) (xy 56.216537 -57.138099) (xy 56.24664 -57.1349)
			(xy 56.274488 -57.123031) (xy 56.2864 -57.113678) (xy 56.304386 -57.099024) (xy 56.343684 -57.074365)
			(xy 56.38604 -57.055433) (xy 56.430624 -57.042601) (xy 56.476563 -57.036118) (xy 56.49976 -57.0357)
			(xy 56.525751 -57.03618) (xy 56.577094 -57.044306) (xy 56.626533 -57.060365) (xy 56.672852 -57.083961)
			(xy 56.714908 -57.114513) (xy 56.751667 -57.151268) (xy 56.782222 -57.193321) (xy 56.805822 -57.239637)
			(xy 56.821886 -57.289075) (xy 56.830017 -57.340417) (xy 56.830468 -57.366408) (xy 56.830077 -57.389606)
			(xy 56.829683 -57.392395) (xy 56.969662 -57.392395) (xy 56.969662 -57.340421) (xy 56.977792 -57.289086)
			(xy 56.993853 -57.239656) (xy 57.017449 -57.193346) (xy 57.047999 -57.151298) (xy 57.08475 -57.114547)
			(xy 57.126798 -57.083997) (xy 57.173108 -57.060401) (xy 57.222538 -57.04434) (xy 57.273873 -57.03621)
			(xy 57.325847 -57.03621) (xy 57.377182 -57.04434) (xy 57.426612 -57.060401) (xy 57.472922 -57.083997)
			(xy 57.51497 -57.114547) (xy 57.551721 -57.151298) (xy 57.582271 -57.193346) (xy 57.605867 -57.239656)
			(xy 57.621928 -57.289086) (xy 57.630058 -57.340421) (xy 57.630568 -57.366408) (xy 57.630058 -57.392395)
			(xy 57.621928 -57.44373) (xy 57.605867 -57.49316) (xy 57.582271 -57.53947) (xy 57.551721 -57.581518)
			(xy 57.51497 -57.618269) (xy 57.472922 -57.648819) (xy 57.426612 -57.672415) (xy 57.377182 -57.688476)
			(xy 57.325847 -57.696606) (xy 57.273873 -57.696606) (xy 57.222538 -57.688476) (xy 57.173108 -57.672415)
			(xy 57.126798 -57.648819) (xy 57.08475 -57.618269) (xy 57.047999 -57.581518) (xy 57.017449 -57.53947)
			(xy 56.993853 -57.49316) (xy 56.977792 -57.44373) (xy 56.969662 -57.392395) (xy 56.829683 -57.392395)
			(xy 56.823592 -57.435546) (xy 56.810751 -57.480129) (xy 56.791807 -57.52248) (xy 56.767129 -57.561768)
			(xy 56.75249 -57.579768) (xy 56.743155 -57.591695) (xy 56.731273 -57.619537) (xy 56.728065 -57.649639)
			(xy 56.733814 -57.67936) (xy 56.748015 -57.706094) (xy 56.758332 -57.717182) (xy 56.944768 -57.903618)
			(xy 56.955727 -57.91383) (xy 56.982124 -57.927956) (xy 57.011484 -57.933821) (xy 57.041282 -57.930923)
			(xy 57.068961 -57.919509) (xy 57.080912 -57.910476) (xy 57.103228 -57.892984) (xy 57.152597 -57.865105)
			(xy 57.205995 -57.846047) (xy 57.26186 -57.836369) (xy 57.290208 -57.8358) (xy 57.316195 -57.83631)
			(xy 57.367528 -57.844442) (xy 57.416957 -57.860504) (xy 57.463264 -57.8841) (xy 57.505311 -57.91465)
			(xy 57.54206 -57.951401) (xy 57.572608 -57.993449) (xy 57.596203 -58.039758) (xy 57.612262 -58.089188)
			(xy 57.620391 -58.140521) (xy 57.620916 -58.166508) (xy 57.620509 -58.189869) (xy 57.620136 -58.192495)
			(xy 57.76011 -58.192495) (xy 57.76011 -58.140521) (xy 57.76824 -58.089186) (xy 57.784301 -58.039756)
			(xy 57.807897 -57.993446) (xy 57.838447 -57.951398) (xy 57.875198 -57.914647) (xy 57.917246 -57.884097)
			(xy 57.963556 -57.860501) (xy 58.012986 -57.84444) (xy 58.064321 -57.83631) (xy 58.116295 -57.83631)
			(xy 58.16763 -57.84444) (xy 58.21706 -57.860501) (xy 58.26337 -57.884097) (xy 58.305418 -57.914647)
			(xy 58.342169 -57.951398) (xy 58.372719 -57.993446) (xy 58.396315 -58.039756) (xy 58.412376 -58.089186)
			(xy 58.420506 -58.140521) (xy 58.421016 -58.166508) (xy 58.420506 -58.192495) (xy 58.412376 -58.24383)
			(xy 58.396315 -58.29326) (xy 58.372719 -58.33957) (xy 58.342169 -58.381618) (xy 58.305418 -58.418369)
			(xy 58.26337 -58.448919) (xy 58.21706 -58.472515) (xy 58.16763 -58.488576) (xy 58.116295 -58.496706)
			(xy 58.064321 -58.496706) (xy 58.012986 -58.488576) (xy 57.963556 -58.472515) (xy 57.917246 -58.448919)
			(xy 57.875198 -58.418369) (xy 57.838447 -58.381618) (xy 57.807897 -58.33957) (xy 57.784301 -58.29326)
			(xy 57.76824 -58.24383) (xy 57.76011 -58.192495) (xy 57.620136 -58.192495) (xy 57.613931 -58.236127)
			(xy 57.600922 -58.281002) (xy 57.581739 -58.323605) (xy 57.556763 -58.363092) (xy 57.541922 -58.381138)
			(xy 57.532474 -58.39303) (xy 57.520385 -58.420873) (xy 57.51703 -58.451042) (xy 57.522706 -58.480861)
			(xy 57.536911 -58.507687) (xy 57.547256 -58.518806) (xy 58.020791 -58.992341) (xy 58.559956 -58.992341)
			(xy 58.559956 -58.940367) (xy 58.568086 -58.889032) (xy 58.584147 -58.839602) (xy 58.607743 -58.793292)
			(xy 58.638293 -58.751244) (xy 58.675044 -58.714493) (xy 58.717092 -58.683943) (xy 58.763402 -58.660347)
			(xy 58.812832 -58.644286) (xy 58.864167 -58.636156) (xy 58.916141 -58.636156) (xy 58.967476 -58.644286)
			(xy 59.016906 -58.660347) (xy 59.063216 -58.683943) (xy 59.105264 -58.714493) (xy 59.142015 -58.751244)
			(xy 59.172565 -58.793292) (xy 59.196161 -58.839602) (xy 59.212222 -58.889032) (xy 59.220352 -58.940367)
			(xy 59.220862 -58.966354) (xy 59.220352 -58.992341) (xy 60.960002 -58.992341) (xy 60.960002 -58.940367)
			(xy 60.968132 -58.889032) (xy 60.984193 -58.839602) (xy 61.007789 -58.793292) (xy 61.038339 -58.751244)
			(xy 61.07509 -58.714493) (xy 61.117138 -58.683943) (xy 61.163448 -58.660347) (xy 61.212878 -58.644286)
			(xy 61.264213 -58.636156) (xy 61.316187 -58.636156) (xy 61.367522 -58.644286) (xy 61.416952 -58.660347)
			(xy 61.463262 -58.683943) (xy 61.50531 -58.714493) (xy 61.542061 -58.751244) (xy 61.572611 -58.793292)
			(xy 61.596207 -58.839602) (xy 61.612268 -58.889032) (xy 61.620398 -58.940367) (xy 61.620908 -58.966354)
			(xy 61.620398 -58.992341) (xy 61.612268 -59.043676) (xy 61.596207 -59.093106) (xy 61.572611 -59.139416)
			(xy 61.542061 -59.181464) (xy 61.50531 -59.218215) (xy 61.463262 -59.248765) (xy 61.416952 -59.272361)
			(xy 61.367522 -59.288422) (xy 61.316187 -59.296552) (xy 61.264213 -59.296552) (xy 61.212878 -59.288422)
			(xy 61.163448 -59.272361) (xy 61.117138 -59.248765) (xy 61.07509 -59.218215) (xy 61.038339 -59.181464)
			(xy 61.007789 -59.139416) (xy 60.984193 -59.093106) (xy 60.968132 -59.043676) (xy 60.960002 -58.992341)
			(xy 59.220352 -58.992341) (xy 59.212222 -59.043676) (xy 59.196161 -59.093106) (xy 59.172565 -59.139416)
			(xy 59.142015 -59.181464) (xy 59.105264 -59.218215) (xy 59.063216 -59.248765) (xy 59.016906 -59.272361)
			(xy 58.967476 -59.288422) (xy 58.916141 -59.296552) (xy 58.864167 -59.296552) (xy 58.812832 -59.288422)
			(xy 58.763402 -59.272361) (xy 58.717092 -59.248765) (xy 58.675044 -59.218215) (xy 58.638293 -59.181464)
			(xy 58.607743 -59.139416) (xy 58.584147 -59.093106) (xy 58.568086 -59.043676) (xy 58.559956 -58.992341)
			(xy 58.020791 -58.992341) (xy 58.884566 -59.856116) (xy 60.281312 -59.856116) (xy 60.281822 -59.830129)
			(xy 60.289952 -59.778794) (xy 60.306013 -59.729364) (xy 60.329609 -59.683054) (xy 60.360159 -59.641006)
			(xy 60.39691 -59.604255) (xy 60.438958 -59.573705) (xy 60.485268 -59.550109) (xy 60.534698 -59.534048)
			(xy 60.586033 -59.525918) (xy 60.638007 -59.525918) (xy 60.689342 -59.534048) (xy 60.738772 -59.550109)
			(xy 60.785082 -59.573705) (xy 60.82713 -59.604255) (xy 60.863881 -59.641006) (xy 60.894431 -59.683054)
			(xy 60.918027 -59.729364) (xy 60.934088 -59.778794) (xy 60.942218 -59.830129) (xy 60.942728 -59.856116)
			(xy 60.94263 -59.867777) (xy 60.940976 -59.89104) (xy 60.939426 -59.902598) (xy 60.937801 -59.917054)
			(xy 60.941954 -59.945837) (xy 60.954045 -59.972285) (xy 60.973097 -59.994257) (xy 60.997565 -60.009973)
			(xy 61.025469 -60.018161) (xy 61.04001 -60.018676) (xy 61.55944 -60.018676) (xy 61.574673 -60.018178)
			(xy 61.603783 -60.009187) (xy 61.628951 -59.992017) (xy 61.647941 -59.968192) (xy 61.659066 -59.939829)
			(xy 61.661338 -59.909447) (xy 61.6585 -59.89447) (xy 61.654691 -59.876487) (xy 61.65062 -59.839952)
			(xy 61.650372 -59.821572) (xy 61.650882 -59.795585) (xy 61.659012 -59.74425) (xy 61.675073 -59.69482)
			(xy 61.698669 -59.64851) (xy 61.729219 -59.606462) (xy 61.76597 -59.569711) (xy 61.808018 -59.539161)
			(xy 61.854328 -59.515565) (xy 61.903758 -59.499504) (xy 61.955093 -59.491374) (xy 62.007067 -59.491374)
			(xy 62.058402 -59.499504) (xy 62.107832 -59.515565) (xy 62.154142 -59.539161) (xy 62.19619 -59.569711)
			(xy 62.232941 -59.606462) (xy 62.263491 -59.64851) (xy 62.287087 -59.69482) (xy 62.303148 -59.74425)
			(xy 62.311278 -59.795585) (xy 62.311788 -59.821572) (xy 62.311297 -59.846239) (xy 62.303946 -59.895024)
			(xy 62.289433 -59.942176) (xy 62.268079 -59.98665) (xy 62.240358 -60.027461) (xy 62.206884 -60.063703)
			(xy 62.1684 -60.094572) (xy 62.125758 -60.119385) (xy 62.103 -60.128912) (xy 62.089115 -60.13505)
			(xy 62.065444 -60.154027) (xy 62.048386 -60.179117) (xy 62.039444 -60.208109) (xy 62.039408 -60.238448)
			(xy 62.04331 -60.253118) (xy 62.050033 -60.276617) (xy 62.057309 -60.324947) (xy 62.057788 -60.349384)
			(xy 62.057309 -60.375387) (xy 62.049172 -60.426751) (xy 62.033095 -60.476209) (xy 62.009475 -60.52254)
			(xy 61.978895 -60.564604) (xy 61.942107 -60.601363) (xy 61.90002 -60.63191) (xy 61.85367 -60.655494)
			(xy 61.8042 -60.671532) (xy 61.752829 -60.679629) (xy 61.726826 -60.680092) (xy 60.92698 -60.680092)
			(xy 60.900991 -60.679617) (xy 60.849655 -60.671483) (xy 60.800223 -60.655418) (xy 60.753912 -60.631818)
			(xy 60.711863 -60.601265) (xy 60.675112 -60.564509) (xy 60.644563 -60.522457) (xy 60.620968 -60.476144)
			(xy 60.604909 -60.42671) (xy 60.59678 -60.375373) (xy 60.596272 -60.349384) (xy 60.596363 -60.334897)
			(xy 60.59878 -60.306026) (xy 60.601098 -60.291726) (xy 60.603191 -60.276714) (xy 60.599555 -60.246642)
			(xy 60.587259 -60.218959) (xy 60.567384 -60.196099) (xy 60.541679 -60.180075) (xy 60.527184 -60.175648)
			(xy 60.501123 -60.168147) (xy 60.451681 -60.145875) (xy 60.406535 -60.115834) (xy 60.366896 -60.07883)
			(xy 60.333824 -60.035855) (xy 60.308208 -59.98806) (xy 60.290733 -59.936727) (xy 60.281867 -59.883229)
			(xy 60.281312 -59.856116) (xy 58.884566 -59.856116) (xy 62.002416 -62.973966) (xy 62.530988 -62.973966)
			(xy 62.535059 -62.918344) (xy 62.547185 -62.863907) (xy 62.567108 -62.811816) (xy 62.594404 -62.763181)
			(xy 62.62849 -62.719038) (xy 62.668639 -62.680329) (xy 62.713997 -62.647878) (xy 62.763597 -62.622377)
			(xy 62.816381 -62.60437) (xy 62.871224 -62.59424) (xy 62.926958 -62.592203) (xy 62.982395 -62.598303)
			(xy 63.036352 -62.612409) (xy 63.087681 -62.634221) (xy 63.135287 -62.663275) (xy 63.178155 -62.69895)
			(xy 63.215372 -62.740487) (xy 63.246145 -62.787) (xy 63.269817 -62.837497) (xy 63.285885 -62.890904)
			(xy 63.294005 -62.94608) (xy 63.29431 -62.96279) (xy 63.788288 -62.96279) (xy 63.792359 -62.907168)
			(xy 63.804485 -62.852731) (xy 63.824408 -62.80064) (xy 63.851704 -62.752005) (xy 63.88579 -62.707862)
			(xy 63.925939 -62.669153) (xy 63.971297 -62.636702) (xy 64.020897 -62.611201) (xy 64.073681 -62.593194)
			(xy 64.128524 -62.583064) (xy 64.184258 -62.581027) (xy 64.239695 -62.587127) (xy 64.293652 -62.601233)
			(xy 64.344981 -62.623045) (xy 64.392587 -62.652099) (xy 64.435455 -62.687774) (xy 64.472672 -62.729311)
			(xy 64.503445 -62.775824) (xy 64.527117 -62.826321) (xy 64.543185 -62.879728) (xy 64.551305 -62.934904)
			(xy 64.551814 -62.96279) (xy 64.551305 -62.990676) (xy 64.543185 -63.045852) (xy 64.527117 -63.099259)
			(xy 64.503445 -63.149756) (xy 64.472672 -63.196269) (xy 64.435455 -63.237806) (xy 64.392587 -63.273481)
			(xy 64.344981 -63.302535) (xy 64.293652 -63.324347) (xy 64.239695 -63.338453) (xy 64.184258 -63.344553)
			(xy 64.128524 -63.342516) (xy 64.073681 -63.332386) (xy 64.020897 -63.314379) (xy 63.971297 -63.288878)
			(xy 63.925939 -63.256427) (xy 63.88579 -63.217718) (xy 63.851704 -63.173575) (xy 63.824408 -63.12494)
			(xy 63.804485 -63.072849) (xy 63.792359 -63.018412) (xy 63.788288 -62.96279) (xy 63.29431 -62.96279)
			(xy 63.294514 -62.973966) (xy 63.294005 -63.001852) (xy 63.285885 -63.057028) (xy 63.269817 -63.110435)
			(xy 63.246145 -63.160932) (xy 63.215372 -63.207445) (xy 63.178155 -63.248982) (xy 63.135287 -63.284657)
			(xy 63.087681 -63.313711) (xy 63.036352 -63.335523) (xy 62.982395 -63.349629) (xy 62.926958 -63.355729)
			(xy 62.871224 -63.353692) (xy 62.816381 -63.343562) (xy 62.763597 -63.325555) (xy 62.713997 -63.300054)
			(xy 62.668639 -63.267603) (xy 62.62849 -63.228894) (xy 62.594404 -63.184751) (xy 62.567108 -63.136116)
			(xy 62.547185 -63.084025) (xy 62.535059 -63.029588) (xy 62.530988 -62.973966) (xy 62.002416 -62.973966)
			(xy 63.286894 -64.258444) (xy 63.286894 -65.4812) (xy 63.905892 -65.4812) (xy 63.90636 -65.453626)
			(xy 63.914313 -65.399053) (xy 63.930038 -65.346193) (xy 63.953207 -65.296147) (xy 63.983339 -65.249958)
			(xy 64.019805 -65.208586) (xy 64.040512 -65.19037) (xy 64.051317 -65.180474) (xy 64.067327 -65.155953)
			(xy 64.075728 -65.127899) (xy 64.075831 -65.098614) (xy 64.067628 -65.070502) (xy 64.051791 -65.045868)
			(xy 64.04102 -65.035938) (xy 64.020621 -65.017717) (xy 63.984689 -64.976481) (xy 63.955015 -64.930537)
			(xy 63.932207 -64.880825) (xy 63.916732 -64.828365) (xy 63.908908 -64.774233) (xy 63.908432 -64.746886)
			(xy 63.908918 -64.719635) (xy 63.916674 -64.665687) (xy 63.932029 -64.613392) (xy 63.954671 -64.563815)
			(xy 63.984137 -64.517965) (xy 64.019828 -64.476774) (xy 64.061019 -64.441083) (xy 64.106869 -64.411617)
			(xy 64.156446 -64.388975) (xy 64.208741 -64.37362) (xy 64.262689 -64.365864) (xy 64.317191 -64.365864)
			(xy 64.371139 -64.37362) (xy 64.423434 -64.388975) (xy 64.473011 -64.411617) (xy 64.518861 -64.441083)
			(xy 64.560052 -64.476774) (xy 64.595743 -64.517965) (xy 64.625209 -64.563815) (xy 64.647851 -64.613392)
			(xy 64.663206 -64.665687) (xy 64.670962 -64.719635) (xy 64.671448 -64.746886) (xy 64.670991 -64.774461)
			(xy 64.663039 -64.829035) (xy 64.647314 -64.881896) (xy 64.624142 -64.931942) (xy 64.594007 -64.978131)
			(xy 64.557537 -65.019501) (xy 64.536828 -65.037716) (xy 64.525933 -65.047523) (xy 64.50992 -65.072068)
			(xy 64.501526 -65.100146) (xy 64.501438 -65.129452) (xy 64.509666 -65.15758) (xy 64.525532 -65.18222)
			(xy 64.53632 -65.192148) (xy 64.556769 -65.210316) (xy 64.592695 -65.251564) (xy 64.622362 -65.29752)
			(xy 64.645161 -65.347242) (xy 64.660625 -65.399711) (xy 64.668438 -65.45385) (xy 64.668908 -65.4812)
			(xy 64.668422 -65.508451) (xy 64.660666 -65.562399) (xy 64.645311 -65.614694) (xy 64.622669 -65.664271)
			(xy 64.593203 -65.710121) (xy 64.557512 -65.751312) (xy 64.516321 -65.787003) (xy 64.470471 -65.816469)
			(xy 64.420894 -65.839111) (xy 64.368599 -65.854466) (xy 64.314651 -65.862222) (xy 64.260149 -65.862222)
			(xy 64.206201 -65.854466) (xy 64.153906 -65.839111) (xy 64.104329 -65.816469) (xy 64.058479 -65.787003)
			(xy 64.017288 -65.751312) (xy 63.981597 -65.710121) (xy 63.952131 -65.664271) (xy 63.929489 -65.614694)
			(xy 63.914134 -65.562399) (xy 63.906378 -65.508451) (xy 63.905892 -65.4812) (xy 63.286894 -65.4812)
			(xy 63.286894 -69.696076) (xy 63.506604 -69.915786)
		)
		(stroke
			(width 0)
			(type solid)
		)
		(fill yes)
		(layer "In7.Cu")
		(net "PGPPA_BMC_AUX")
	)
	(gr_poly
		(pts
			(xy 7.314946 -80.256888) (xy 7.328586 -80.256445) (xy 7.354891 -80.249214) (xy 7.378345 -80.235279)
			(xy 7.397274 -80.215635) (xy 7.410331 -80.191681) (xy 7.416583 -80.165126) (xy 7.416546 -80.151478)
			(xy 7.416292 -80.137) (xy 7.416778 -80.109749) (xy 7.424534 -80.055801) (xy 7.439889 -80.003506)
			(xy 7.462531 -79.953929) (xy 7.491997 -79.908079) (xy 7.527688 -79.866888) (xy 7.568879 -79.831197)
			(xy 7.614729 -79.801731) (xy 7.664306 -79.779089) (xy 7.716601 -79.763734) (xy 7.770549 -79.755978)
			(xy 7.825051 -79.755978) (xy 7.878999 -79.763734) (xy 7.931294 -79.779089) (xy 7.980871 -79.801731)
			(xy 8.026721 -79.831197) (xy 8.067912 -79.866888) (xy 8.103603 -79.908079) (xy 8.133069 -79.953929)
			(xy 8.155711 -80.003506) (xy 8.171066 -80.055801) (xy 8.178822 -80.109749) (xy 8.179308 -80.137)
			(xy 8.179054 -80.151478) (xy 8.17898 -80.165128) (xy 8.185218 -80.191691) (xy 8.198276 -80.21565)
			(xy 8.217218 -80.23529) (xy 8.24069 -80.249205) (xy 8.26701 -80.256399) (xy 8.280654 -80.256888)
			(xy 8.77951 -80.256888) (xy 8.792972 -80.25638) (xy 9.760712 -80.25638) (xy 10.6426 -79.374492) (xy 10.6426 -76.121006)
			(xy 12.18311 -74.580496) (xy 12.18311 -70.74281) (xy 12.182579 -70.727816) (xy 12.173877 -70.699118)
			(xy 12.157218 -70.674183) (xy 12.134038 -70.655157) (xy 12.106333 -70.643679) (xy 12.076489 -70.640739)
			(xy 12.047077 -70.646589) (xy 12.02063 -70.660725) (xy 12.009628 -70.670928) (xy 11.988012 -70.691705)
			(xy 11.939506 -70.726939) (xy 11.886087 -70.754156) (xy 11.82907 -70.772685) (xy 11.769856 -70.782072)
			(xy 11.73988 -70.782688) (xy 11.71263 -70.7822) (xy 11.658686 -70.774441) (xy 11.606395 -70.759084)
			(xy 11.556821 -70.736442) (xy 11.510975 -70.706975) (xy 11.469789 -70.671283) (xy 11.434101 -70.630093)
			(xy 11.404639 -70.584244) (xy 11.382002 -70.534668) (xy 11.36665 -70.482375) (xy 11.358897 -70.42843)
			(xy 11.358372 -70.40118) (xy 11.359018 -70.369935) (xy 11.369225 -70.308282) (xy 11.378692 -70.278498)
			(xy 11.381232 -70.27037) (xy 11.381232 -67.202558) (xy 11.365647 -67.17965) (xy 11.340961 -67.130047)
			(xy 11.324183 -67.077243) (xy 11.31571 -67.022489) (xy 11.315192 -66.994786) (xy 11.315192 -59.143392)
			(xy 9.6012 -57.4294) (xy 9.6012 -55.736744) (xy 10.727944 -54.61) (xy 10.727944 -50.57267) (xy 12.493752 -48.806608)
			(xy 12.493752 -45.4914) (xy 12.494327 -45.463226) (xy 12.503184 -45.407577) (xy 12.520632 -45.353997)
			(xy 12.546243 -45.303804) (xy 12.579386 -45.258232) (xy 12.598908 -45.237908) (xy 13.369544 -44.467272)
			(xy 13.369544 -33.381696) (xy 13.369109 -33.368376) (xy 13.362215 -33.342642) (xy 13.348897 -33.319569)
			(xy 13.330063 -33.300727) (xy 13.306995 -33.2874) (xy 13.281264 -33.280496) (xy 13.267944 -33.280096)
			(xy 13.237831 -33.279507) (xy 13.178359 -33.269999) (xy 13.121121 -33.25126) (xy 13.067541 -33.223755)
			(xy 13.0429 -33.206436) (xy 13.030598 -33.19809) (xy 13.002571 -33.188218) (xy 12.972889 -33.186828)
			(xy 12.944062 -33.194037) (xy 12.918528 -33.209235) (xy 12.898448 -33.231138) (xy 12.885518 -33.257892)
			(xy 12.882626 -33.272476) (xy 12.877923 -33.299025) (xy 12.862024 -33.350543) (xy 12.839032 -33.399311)
			(xy 12.809404 -33.444357) (xy 12.77373 -33.484784) (xy 12.73272 -33.519786) (xy 12.687192 -33.548668)
			(xy 12.638052 -33.570853) (xy 12.586278 -33.5859) (xy 12.532902 -33.59351) (xy 12.505944 -33.59404)
			(xy 12.478688 -33.59358) (xy 12.424731 -33.585828) (xy 12.372426 -33.570477) (xy 12.322838 -33.547837)
			(xy 12.276977 -33.518371) (xy 12.235776 -33.482677) (xy 12.200075 -33.441484) (xy 12.170599 -33.395629)
			(xy 12.14795 -33.346046) (xy 12.132588 -33.293744) (xy 12.124825 -33.239788) (xy 12.124436 -33.212532)
			(xy 12.124968 -33.183615) (xy 12.133691 -33.126442) (xy 12.150943 -33.07124) (xy 12.176328 -33.019274)
			(xy 12.209265 -32.971734) (xy 12.248999 -32.92971) (xy 12.271502 -32.911542) (xy 12.283311 -32.901644)
			(xy 12.300835 -32.876317) (xy 12.310017 -32.846919) (xy 12.310023 -32.81612) (xy 12.300852 -32.786719)
			(xy 12.283338 -32.761385) (xy 12.271502 -32.751522) (xy 12.249019 -32.733331) (xy 12.209282 -32.691314)
			(xy 12.176344 -32.643779) (xy 12.150959 -32.591817) (xy 12.133709 -32.536618) (xy 12.124989 -32.479448)
			(xy 12.124436 -32.450532) (xy 12.124922 -32.423281) (xy 12.132678 -32.369333) (xy 12.148033 -32.317038)
			(xy 12.170675 -32.267461) (xy 12.200141 -32.221611) (xy 12.235832 -32.18042) (xy 12.277023 -32.144729)
			(xy 12.322873 -32.115263) (xy 12.37245 -32.092621) (xy 12.424745 -32.077266) (xy 12.478693 -32.06951)
			(xy 12.533195 -32.06951) (xy 12.587143 -32.077266) (xy 12.639438 -32.092621) (xy 12.689015 -32.115263)
			(xy 12.734865 -32.144729) (xy 12.776056 -32.18042) (xy 12.811747 -32.221611) (xy 12.841213 -32.267461)
			(xy 12.863855 -32.317038) (xy 12.87921 -32.369333) (xy 12.886966 -32.423281) (xy 12.887452 -32.450532)
			(xy 12.886915 -32.479447) (xy 12.878184 -32.536614) (xy 12.860925 -32.591809) (xy 12.835534 -32.643768)
			(xy 12.802593 -32.691299) (xy 12.762856 -32.733315) (xy 12.740386 -32.751522) (xy 12.728588 -32.761421)
			(xy 12.711085 -32.786742) (xy 12.70192 -32.816128) (xy 12.701926 -32.846911) (xy 12.711102 -32.876293)
			(xy 12.728616 -32.901608) (xy 12.740386 -32.911542) (xy 12.756196 -32.924199) (xy 12.785337 -32.952328)
			(xy 12.798552 -32.967676) (xy 12.805831 -32.975582) (xy 12.825158 -32.984937) (xy 12.84662 -32.985582)
			(xy 12.866474 -32.977406) (xy 12.881258 -32.961834) (xy 12.888392 -32.941583) (xy 12.88796 -32.930846)
			(xy 12.88669 -32.898588) (xy 12.887176 -32.871349) (xy 12.894927 -32.817425) (xy 12.91027 -32.765151)
			(xy 12.932894 -32.715592) (xy 12.962337 -32.669756) (xy 12.998001 -32.628573) (xy 13.03916 -32.592883)
			(xy 13.084978 -32.563411) (xy 13.134523 -32.540756) (xy 13.186786 -32.525379) (xy 13.240705 -32.517593)
			(xy 13.267944 -32.51708) (xy 13.281258 -32.51664) (xy 13.306976 -32.509738) (xy 13.330032 -32.496416)
			(xy 13.348855 -32.477581) (xy 13.362163 -32.454517) (xy 13.369049 -32.428794) (xy 13.369544 -32.41548)
			(xy 13.369544 -29.150564) (xy 13.202666 -28.983686) (xy 7.48411 -28.983686) (xy 6.722364 -29.745432)
			(xy 6.707074 -29.768474) (xy 6.670905 -29.810305) (xy 6.629074 -29.846474) (xy 6.606032 -29.861764)
			(xy 3.866134 -32.601662) (xy 3.866134 -33.212532) (xy 5.647436 -33.212532) (xy 5.647964 -33.183615)
			(xy 5.656689 -33.126444) (xy 5.673944 -33.071245) (xy 5.699334 -33.019283) (xy 5.732276 -32.971749)
			(xy 5.772017 -32.929732) (xy 5.794502 -32.911542) (xy 5.806274 -32.901609) (xy 5.823789 -32.876294)
			(xy 5.832967 -32.846911) (xy 5.832973 -32.816128) (xy 5.823806 -32.786741) (xy 5.806301 -32.76142)
			(xy 5.794502 -32.751522) (xy 5.772029 -32.733318) (xy 5.732293 -32.691301) (xy 5.699353 -32.643769)
			(xy 5.673963 -32.59181) (xy 5.656704 -32.536615) (xy 5.647973 -32.479447) (xy 5.647436 -32.450532)
			(xy 5.647922 -32.423281) (xy 5.655678 -32.369333) (xy 5.671033 -32.317038) (xy 5.693675 -32.267461)
			(xy 5.723141 -32.221611) (xy 5.758832 -32.18042) (xy 5.800023 -32.144729) (xy 5.845873 -32.115263)
			(xy 5.89545 -32.092621) (xy 5.947745 -32.077266) (xy 6.001693 -32.06951) (xy 6.056195 -32.06951)
			(xy 6.110143 -32.077266) (xy 6.162438 -32.092621) (xy 6.212015 -32.115263) (xy 6.257865 -32.144729)
			(xy 6.299056 -32.18042) (xy 6.334747 -32.221611) (xy 6.364213 -32.267461) (xy 6.386855 -32.317038)
			(xy 6.40221 -32.369333) (xy 6.409966 -32.423281) (xy 6.410452 -32.450532) (xy 6.409903 -32.479448)
			(xy 6.401183 -32.536619) (xy 6.383932 -32.591817) (xy 6.358546 -32.64378) (xy 6.325607 -32.691314)
			(xy 6.28587 -32.733331) (xy 6.263386 -32.751522) (xy 6.251551 -32.761386) (xy 6.234039 -32.78672)
			(xy 6.224869 -32.816121) (xy 6.224875 -32.846918) (xy 6.234056 -32.876316) (xy 6.251579 -32.901643)
			(xy 6.263386 -32.911542) (xy 6.285867 -32.929736) (xy 6.325602 -32.971755) (xy 6.358541 -33.01929)
			(xy 6.38393 -33.07125) (xy 6.401187 -33.126447) (xy 6.409917 -33.183616) (xy 6.410452 -33.212532)
			(xy 7.806436 -33.212532) (xy 7.806964 -33.183615) (xy 7.815689 -33.126444) (xy 7.832944 -33.071245)
			(xy 7.858334 -33.019283) (xy 7.891276 -32.971749) (xy 7.931017 -32.929732) (xy 7.953502 -32.911542)
			(xy 7.965274 -32.901609) (xy 7.982789 -32.876294) (xy 7.991967 -32.846911) (xy 7.991973 -32.816128)
			(xy 7.982806 -32.786741) (xy 7.965301 -32.76142) (xy 7.953502 -32.751522) (xy 7.931029 -32.733318)
			(xy 7.891293 -32.691301) (xy 7.858353 -32.643769) (xy 7.832963 -32.59181) (xy 7.815704 -32.536615)
			(xy 7.806973 -32.479447) (xy 7.806436 -32.450532) (xy 7.806922 -32.423281) (xy 7.814678 -32.369333)
			(xy 7.830033 -32.317038) (xy 7.852675 -32.267461) (xy 7.882141 -32.221611) (xy 7.917832 -32.18042)
			(xy 7.959023 -32.144729) (xy 8.004873 -32.115263) (xy 8.05445 -32.092621) (xy 8.106745 -32.077266)
			(xy 8.160693 -32.06951) (xy 8.215195 -32.06951) (xy 8.269143 -32.077266) (xy 8.321438 -32.092621)
			(xy 8.371015 -32.115263) (xy 8.416865 -32.144729) (xy 8.458056 -32.18042) (xy 8.493747 -32.221611)
			(xy 8.523213 -32.267461) (xy 8.545855 -32.317038) (xy 8.56121 -32.369333) (xy 8.568966 -32.423281)
			(xy 8.569452 -32.450532) (xy 8.568903 -32.479448) (xy 8.560183 -32.536619) (xy 8.542932 -32.591817)
			(xy 8.517546 -32.64378) (xy 8.484607 -32.691314) (xy 8.44487 -32.733331) (xy 8.422386 -32.751522)
			(xy 8.410551 -32.761386) (xy 8.393039 -32.78672) (xy 8.383869 -32.816121) (xy 8.383875 -32.846918)
			(xy 8.393056 -32.876316) (xy 8.410579 -32.901643) (xy 8.422386 -32.911542) (xy 8.444887 -32.929713)
			(xy 8.484621 -32.971736) (xy 8.517559 -33.019275) (xy 8.542944 -33.071241) (xy 8.560197 -33.126442)
			(xy 8.56892 -33.183615) (xy 8.569452 -33.212532) (xy 9.965436 -33.212532) (xy 9.965964 -33.183615)
			(xy 9.974689 -33.126444) (xy 9.991944 -33.071245) (xy 10.017334 -33.019283) (xy 10.050276 -32.971749)
			(xy 10.090017 -32.929732) (xy 10.112502 -32.911542) (xy 10.124274 -32.901609) (xy 10.141789 -32.876294)
			(xy 10.150967 -32.846911) (xy 10.150973 -32.816128) (xy 10.141806 -32.786741) (xy 10.124301 -32.76142)
			(xy 10.112502 -32.751522) (xy 10.090029 -32.733318) (xy 10.050293 -32.691301) (xy 10.017353 -32.643769)
			(xy 9.991963 -32.59181) (xy 9.974704 -32.536615) (xy 9.965973 -32.479447) (xy 9.965436 -32.450532)
			(xy 9.965922 -32.423281) (xy 9.973678 -32.369333) (xy 9.989033 -32.317038) (xy 10.011675 -32.267461)
			(xy 10.041141 -32.221611) (xy 10.076832 -32.18042) (xy 10.118023 -32.144729) (xy 10.163873 -32.115263)
			(xy 10.21345 -32.092621) (xy 10.265745 -32.077266) (xy 10.319693 -32.06951) (xy 10.374195 -32.06951)
			(xy 10.428143 -32.077266) (xy 10.480438 -32.092621) (xy 10.530015 -32.115263) (xy 10.575865 -32.144729)
			(xy 10.617056 -32.18042) (xy 10.652747 -32.221611) (xy 10.682213 -32.267461) (xy 10.704855 -32.317038)
			(xy 10.72021 -32.369333) (xy 10.727966 -32.423281) (xy 10.728452 -32.450532) (xy 10.727903 -32.479448)
			(xy 10.719183 -32.536619) (xy 10.701932 -32.591817) (xy 10.676546 -32.64378) (xy 10.643607 -32.691314)
			(xy 10.60387 -32.733331) (xy 10.581386 -32.751522) (xy 10.569551 -32.761386) (xy 10.552039 -32.78672)
			(xy 10.542869 -32.816121) (xy 10.542875 -32.846918) (xy 10.552056 -32.876316) (xy 10.569579 -32.901643)
			(xy 10.581386 -32.911542) (xy 10.603887 -32.929713) (xy 10.643621 -32.971736) (xy 10.676559 -33.019275)
			(xy 10.701944 -33.071241) (xy 10.719197 -33.126442) (xy 10.72792 -33.183615) (xy 10.728452 -33.212532)
			(xy 10.727966 -33.239783) (xy 10.72021 -33.293731) (xy 10.704855 -33.346026) (xy 10.682213 -33.395603)
			(xy 10.652747 -33.441453) (xy 10.617056 -33.482644) (xy 10.575865 -33.518335) (xy 10.530015 -33.547801)
			(xy 10.480438 -33.570443) (xy 10.428143 -33.585798) (xy 10.374195 -33.593554) (xy 10.319693 -33.593554)
			(xy 10.265745 -33.585798) (xy 10.21345 -33.570443) (xy 10.163873 -33.547801) (xy 10.118023 -33.518335)
			(xy 10.076832 -33.482644) (xy 10.041141 -33.441453) (xy 10.011675 -33.395603) (xy 9.989033 -33.346026)
			(xy 9.973678 -33.293731) (xy 9.965922 -33.239783) (xy 9.965436 -33.212532) (xy 8.569452 -33.212532)
			(xy 8.568966 -33.239783) (xy 8.56121 -33.293731) (xy 8.545855 -33.346026) (xy 8.523213 -33.395603)
			(xy 8.493747 -33.441453) (xy 8.458056 -33.482644) (xy 8.416865 -33.518335) (xy 8.371015 -33.547801)
			(xy 8.321438 -33.570443) (xy 8.269143 -33.585798) (xy 8.215195 -33.593554) (xy 8.160693 -33.593554)
			(xy 8.106745 -33.585798) (xy 8.05445 -33.570443) (xy 8.004873 -33.547801) (xy 7.959023 -33.518335)
			(xy 7.917832 -33.482644) (xy 7.882141 -33.441453) (xy 7.852675 -33.395603) (xy 7.830033 -33.346026)
			(xy 7.814678 -33.293731) (xy 7.806922 -33.239783) (xy 7.806436 -33.212532) (xy 6.410452 -33.212532)
			(xy 6.409966 -33.239783) (xy 6.40221 -33.293731) (xy 6.386855 -33.346026) (xy 6.364213 -33.395603)
			(xy 6.334747 -33.441453) (xy 6.299056 -33.482644) (xy 6.257865 -33.518335) (xy 6.212015 -33.547801)
			(xy 6.162438 -33.570443) (xy 6.110143 -33.585798) (xy 6.056195 -33.593554) (xy 6.001693 -33.593554)
			(xy 5.947745 -33.585798) (xy 5.89545 -33.570443) (xy 5.845873 -33.547801) (xy 5.800023 -33.518335)
			(xy 5.758832 -33.482644) (xy 5.723141 -33.441453) (xy 5.693675 -33.395603) (xy 5.671033 -33.346026)
			(xy 5.655678 -33.293731) (xy 5.647922 -33.239783) (xy 5.647436 -33.212532) (xy 3.866134 -33.212532)
			(xy 3.866134 -47.60468) (xy 4.469382 -47.60468) (xy 4.473453 -47.549058) (xy 4.485579 -47.494621)
			(xy 4.505502 -47.44253) (xy 4.532798 -47.393895) (xy 4.566884 -47.349752) (xy 4.607033 -47.311043)
			(xy 4.652391 -47.278592) (xy 4.701991 -47.253091) (xy 4.754775 -47.235084) (xy 4.809618 -47.224954)
			(xy 4.865352 -47.222917) (xy 4.920789 -47.229017) (xy 4.974746 -47.243123) (xy 5.026075 -47.264935)
			(xy 5.073681 -47.293989) (xy 5.116549 -47.329664) (xy 5.153766 -47.371201) (xy 5.184539 -47.417714)
			(xy 5.208211 -47.468211) (xy 5.224279 -47.521618) (xy 5.232399 -47.576794) (xy 5.232908 -47.60468)
			(xy 5.232399 -47.632566) (xy 5.224279 -47.687742) (xy 5.208211 -47.741149) (xy 5.184539 -47.791646)
			(xy 5.153766 -47.838159) (xy 5.116549 -47.879696) (xy 5.073681 -47.915371) (xy 5.026075 -47.944425)
			(xy 4.974746 -47.966237) (xy 4.920789 -47.980343) (xy 4.865352 -47.986443) (xy 4.809618 -47.984406)
			(xy 4.754775 -47.974276) (xy 4.701991 -47.956269) (xy 4.652391 -47.930768) (xy 4.607033 -47.898317)
			(xy 4.566884 -47.859608) (xy 4.532798 -47.815465) (xy 4.505502 -47.76683) (xy 4.485579 -47.714739)
			(xy 4.473453 -47.660302) (xy 4.469382 -47.60468) (xy 3.866134 -47.60468) (xy 3.866134 -49.78146)
			(xy 9.627614 -49.78146) (xy 9.631685 -49.725838) (xy 9.643811 -49.671401) (xy 9.663734 -49.61931)
			(xy 9.69103 -49.570675) (xy 9.725116 -49.526532) (xy 9.765265 -49.487823) (xy 9.810623 -49.455372)
			(xy 9.860223 -49.429871) (xy 9.913007 -49.411864) (xy 9.96785 -49.401734) (xy 10.023584 -49.399697)
			(xy 10.079021 -49.405797) (xy 10.132978 -49.419903) (xy 10.184307 -49.441715) (xy 10.231913 -49.470769)
			(xy 10.274781 -49.506444) (xy 10.311998 -49.547981) (xy 10.342771 -49.594494) (xy 10.366443 -49.644991)
			(xy 10.382511 -49.698398) (xy 10.390631 -49.753574) (xy 10.39114 -49.78146) (xy 10.390631 -49.809346)
			(xy 10.382511 -49.864522) (xy 10.366443 -49.917929) (xy 10.342771 -49.968426) (xy 10.311998 -50.014939)
			(xy 10.274781 -50.056476) (xy 10.231913 -50.092151) (xy 10.184307 -50.121205) (xy 10.132978 -50.143017)
			(xy 10.079021 -50.157123) (xy 10.023584 -50.163223) (xy 9.96785 -50.161186) (xy 9.913007 -50.151056)
			(xy 9.860223 -50.133049) (xy 9.810623 -50.107548) (xy 9.765265 -50.075097) (xy 9.725116 -50.036388)
			(xy 9.69103 -49.992245) (xy 9.663734 -49.94361) (xy 9.643811 -49.891519) (xy 9.631685 -49.837082)
			(xy 9.627614 -49.78146) (xy 3.866134 -49.78146) (xy 3.866134 -54.3052) (xy 9.727692 -54.3052) (xy 9.728178 -54.27773)
			(xy 9.736065 -54.22336) (xy 9.751661 -54.170681) (xy 9.774645 -54.12078) (xy 9.804542 -54.074687)
			(xy 9.840735 -54.033354) (xy 9.861296 -54.015132) (xy 9.871707 -54.005682) (xy 9.887289 -53.98229)
			(xy 9.895905 -53.955536) (xy 9.896903 -53.927447) (xy 9.890207 -53.90015) (xy 9.876324 -53.875711)
			(xy 9.86663 -53.865526) (xy 9.845522 -53.843875) (xy 9.809718 -53.795153) (xy 9.782049 -53.741391)
			(xy 9.763209 -53.683938) (xy 9.75367 -53.624232) (xy 9.753092 -53.594) (xy 9.753578 -53.566749) (xy 9.761334 -53.512801)
			(xy 9.776689 -53.460506) (xy 9.799331 -53.410929) (xy 9.828797 -53.365079) (xy 9.864488 -53.323888)
			(xy 9.905679 -53.288197) (xy 9.951529 -53.258731) (xy 10.001106 -53.236089) (xy 10.053401 -53.220734)
			(xy 10.107349 -53.212978) (xy 10.161851 -53.212978) (xy 10.215799 -53.220734) (xy 10.268094 -53.236089)
			(xy 10.317671 -53.258731) (xy 10.363521 -53.288197) (xy 10.404712 -53.323888) (xy 10.440403 -53.365079)
			(xy 10.469869 -53.410929) (xy 10.492511 -53.460506) (xy 10.507866 -53.512801) (xy 10.515622 -53.566749)
			(xy 10.516108 -53.594) (xy 10.515622 -53.62147) (xy 10.507735 -53.67584) (xy 10.492139 -53.728519)
			(xy 10.469155 -53.77842) (xy 10.439258 -53.824513) (xy 10.403065 -53.865846) (xy 10.382504 -53.884068)
			(xy 10.372093 -53.893518) (xy 10.356511 -53.91691) (xy 10.347895 -53.943664) (xy 10.346897 -53.971753)
			(xy 10.353593 -53.99905) (xy 10.367476 -54.023489) (xy 10.37717 -54.033674) (xy 10.398278 -54.055325)
			(xy 10.434082 -54.104047) (xy 10.461751 -54.157809) (xy 10.480591 -54.215262) (xy 10.49013 -54.274968)
			(xy 10.490708 -54.3052) (xy 10.490222 -54.332451) (xy 10.482466 -54.386399) (xy 10.467111 -54.438694)
			(xy 10.444469 -54.488271) (xy 10.415003 -54.534121) (xy 10.379312 -54.575312) (xy 10.338121 -54.611003)
			(xy 10.292271 -54.640469) (xy 10.242694 -54.663111) (xy 10.190399 -54.678466) (xy 10.136451 -54.686222)
			(xy 10.081949 -54.686222) (xy 10.028001 -54.678466) (xy 9.975706 -54.663111) (xy 9.926129 -54.640469)
			(xy 9.880279 -54.611003) (xy 9.839088 -54.575312) (xy 9.803397 -54.534121) (xy 9.773931 -54.488271)
			(xy 9.751289 -54.438694) (xy 9.735934 -54.386399) (xy 9.728178 -54.332451) (xy 9.727692 -54.3052)
			(xy 3.866134 -54.3052) (xy 3.866134 -55.372) (xy 8.685782 -55.372) (xy 8.689853 -55.316378) (xy 8.701979 -55.261941)
			(xy 8.721902 -55.20985) (xy 8.749198 -55.161215) (xy 8.783284 -55.117072) (xy 8.823433 -55.078363)
			(xy 8.868791 -55.045912) (xy 8.918391 -55.020411) (xy 8.971175 -55.002404) (xy 9.026018 -54.992274)
			(xy 9.081752 -54.990237) (xy 9.137189 -54.996337) (xy 9.191146 -55.010443) (xy 9.242475 -55.032255)
			(xy 9.290081 -55.061309) (xy 9.332949 -55.096984) (xy 9.370166 -55.138521) (xy 9.400939 -55.185034)
			(xy 9.424611 -55.235531) (xy 9.440679 -55.288938) (xy 9.448799 -55.344114) (xy 9.449308 -55.372)
			(xy 9.448799 -55.399886) (xy 9.440679 -55.455062) (xy 9.424611 -55.508469) (xy 9.400939 -55.558966)
			(xy 9.370166 -55.605479) (xy 9.332949 -55.647016) (xy 9.290081 -55.682691) (xy 9.242475 -55.711745)
			(xy 9.191146 -55.733557) (xy 9.137189 -55.747663) (xy 9.081752 -55.753763) (xy 9.026018 -55.751726)
			(xy 8.971175 -55.741596) (xy 8.918391 -55.723589) (xy 8.868791 -55.698088) (xy 8.823433 -55.665637)
			(xy 8.783284 -55.626928) (xy 8.749198 -55.582785) (xy 8.721902 -55.53415) (xy 8.701979 -55.482059)
			(xy 8.689853 -55.427622) (xy 8.685782 -55.372) (xy 3.866134 -55.372) (xy 3.866134 -56.1086) (xy 4.221734 -56.4642)
			(xy 5.6642 -56.4642) (xy 5.842 -56.642) (xy 5.842 -57.9374) (xy 5.5118 -58.2676) (xy 4.120134 -58.2676)
			(xy 3.866134 -58.5216) (xy 3.866134 -61.2648) (xy 8.660892 -61.2648) (xy 8.661375 -61.235881) (xy 8.670107 -61.178707)
			(xy 8.687369 -61.123506) (xy 8.712767 -61.071544) (xy 8.745719 -61.024011) (xy 8.785468 -60.981997)
			(xy 8.807958 -60.96381) (xy 8.819766 -60.953914) (xy 8.837288 -60.928591) (xy 8.846467 -60.899197)
			(xy 8.846467 -60.868403) (xy 8.837288 -60.839009) (xy 8.819766 -60.813686) (xy 8.807958 -60.80379)
			(xy 8.785461 -60.785615) (xy 8.745729 -60.743591) (xy 8.712792 -60.696052) (xy 8.687407 -60.644088)
			(xy 8.670153 -60.588888) (xy 8.661426 -60.531717) (xy 8.660892 -60.5028) (xy 8.661378 -60.475549)
			(xy 8.669134 -60.421601) (xy 8.684489 -60.369306) (xy 8.707131 -60.319729) (xy 8.736597 -60.273879)
			(xy 8.772288 -60.232688) (xy 8.813479 -60.196997) (xy 8.859329 -60.167531) (xy 8.908906 -60.144889)
			(xy 8.961201 -60.129534) (xy 9.015149 -60.121778) (xy 9.069651 -60.121778) (xy 9.123599 -60.129534)
			(xy 9.175894 -60.144889) (xy 9.225471 -60.167531) (xy 9.271321 -60.196997) (xy 9.312512 -60.232688)
			(xy 9.348203 -60.273879) (xy 9.377669 -60.319729) (xy 9.400311 -60.369306) (xy 9.415666 -60.421601)
			(xy 9.423422 -60.475549) (xy 9.423908 -60.5028) (xy 9.423425 -60.531719) (xy 9.414693 -60.588893)
			(xy 9.397431 -60.644094) (xy 9.372033 -60.696056) (xy 9.339081 -60.743589) (xy 9.299332 -60.785603)
			(xy 9.276842 -60.80379) (xy 9.265034 -60.813686) (xy 9.247512 -60.839009) (xy 9.238333 -60.868403)
			(xy 9.238333 -60.899197) (xy 9.247512 -60.928591) (xy 9.265034 -60.953914) (xy 9.276842 -60.96381)
			(xy 9.299339 -60.981985) (xy 9.339071 -61.024009) (xy 9.372008 -61.071548) (xy 9.397393 -61.123512)
			(xy 9.414647 -61.178712) (xy 9.423374 -61.235883) (xy 9.423908 -61.2648) (xy 9.423422 -61.292051)
			(xy 9.415666 -61.345999) (xy 9.400311 -61.398294) (xy 9.377669 -61.447871) (xy 9.348203 -61.493721)
			(xy 9.312512 -61.534912) (xy 9.271321 -61.570603) (xy 9.225471 -61.600069) (xy 9.175894 -61.622711)
			(xy 9.123599 -61.638066) (xy 9.069651 -61.645822) (xy 9.015149 -61.645822) (xy 8.961201 -61.638066)
			(xy 8.908906 -61.622711) (xy 8.859329 -61.600069) (xy 8.813479 -61.570603) (xy 8.772288 -61.534912)
			(xy 8.736597 -61.493721) (xy 8.707131 -61.447871) (xy 8.684489 -61.398294) (xy 8.669134 -61.345999)
			(xy 8.661378 -61.292051) (xy 8.660892 -61.2648) (xy 3.866134 -61.2648) (xy 3.866134 -63.2206) (xy 10.057382 -63.2206)
			(xy 10.061453 -63.164978) (xy 10.073579 -63.110541) (xy 10.093502 -63.05845) (xy 10.120798 -63.009815)
			(xy 10.154884 -62.965672) (xy 10.195033 -62.926963) (xy 10.240391 -62.894512) (xy 10.289991 -62.869011)
			(xy 10.342775 -62.851004) (xy 10.397618 -62.840874) (xy 10.453352 -62.838837) (xy 10.508789 -62.844937)
			(xy 10.562746 -62.859043) (xy 10.614075 -62.880855) (xy 10.661681 -62.909909) (xy 10.704549 -62.945584)
			(xy 10.741766 -62.987121) (xy 10.772539 -63.033634) (xy 10.796211 -63.084131) (xy 10.812279 -63.137538)
			(xy 10.820399 -63.192714) (xy 10.820908 -63.2206) (xy 10.820399 -63.248486) (xy 10.812279 -63.303662)
			(xy 10.796211 -63.357069) (xy 10.772539 -63.407566) (xy 10.741766 -63.454079) (xy 10.704549 -63.495616)
			(xy 10.661681 -63.531291) (xy 10.614075 -63.560345) (xy 10.562746 -63.582157) (xy 10.508789 -63.596263)
			(xy 10.453352 -63.602363) (xy 10.397618 -63.600326) (xy 10.342775 -63.590196) (xy 10.289991 -63.572189)
			(xy 10.240391 -63.546688) (xy 10.195033 -63.514237) (xy 10.154884 -63.475528) (xy 10.120798 -63.431385)
			(xy 10.093502 -63.38275) (xy 10.073579 -63.330659) (xy 10.061453 -63.276222) (xy 10.057382 -63.2206)
			(xy 3.866134 -63.2206) (xy 3.866134 -64.636396) (xy 3.866588 -64.650154) (xy 3.873939 -64.676671)
			(xy 3.888108 -64.70026) (xy 3.908065 -64.719204) (xy 3.932358 -64.732128) (xy 3.959221 -64.738091)
			(xy 3.986701 -64.736659) (xy 4.012799 -64.727937) (xy 4.035617 -64.712558) (xy 4.04495 -64.702436)
			(xy 4.063156 -64.68194) (xy 4.104437 -64.645867) (xy 4.150457 -64.616074) (xy 4.200267 -64.593176)
			(xy 4.252842 -64.577644) (xy 4.307099 -64.569798) (xy 4.33451 -64.56934) (xy 4.361761 -64.569826)
			(xy 4.415709 -64.577582) (xy 4.468004 -64.592938) (xy 4.517582 -64.615579) (xy 4.563433 -64.645045)
			(xy 4.604623 -64.680737) (xy 4.640315 -64.721927) (xy 4.669781 -64.767778) (xy 4.692422 -64.817356)
			(xy 4.707778 -64.869651) (xy 4.715534 -64.923599) (xy 4.715534 -64.978101) (xy 4.707778 -65.032049)
			(xy 4.692422 -65.084344) (xy 4.669781 -65.133922) (xy 4.640315 -65.179773) (xy 4.604623 -65.220963)
			(xy 4.563433 -65.256655) (xy 4.517582 -65.286121) (xy 4.468004 -65.308762) (xy 4.415709 -65.324118)
			(xy 4.361761 -65.331874) (xy 4.33451 -65.332356) (xy 4.3071 -65.331883) (xy 4.252843 -65.324038)
			(xy 4.200267 -65.30851) (xy 4.150455 -65.285617) (xy 4.104432 -65.255831) (xy 4.063146 -65.219765)
			(xy 4.04495 -65.19926) (xy 4.035659 -65.189091) (xy 4.012826 -65.173704) (xy 3.986712 -65.164977)
			(xy 3.959216 -65.163545) (xy 3.932336 -65.169511) (xy 3.908028 -65.182442) (xy 3.888059 -65.201398)
			(xy 3.873881 -65.225001) (xy 3.866524 -65.251533) (xy 3.866134 -65.2653) (xy 3.866134 -65.726818)
			(xy 5.893052 -65.726818) (xy 5.897123 -65.671196) (xy 5.909249 -65.616759) (xy 5.929172 -65.564668)
			(xy 5.956468 -65.516033) (xy 5.990554 -65.47189) (xy 6.030703 -65.433181) (xy 6.076061 -65.40073)
			(xy 6.125661 -65.375229) (xy 6.178445 -65.357222) (xy 6.233288 -65.347092) (xy 6.289022 -65.345055)
			(xy 6.344459 -65.351155) (xy 6.398416 -65.365261) (xy 6.449745 -65.387073) (xy 6.497351 -65.416127)
			(xy 6.540219 -65.451802) (xy 6.577436 -65.493339) (xy 6.608209 -65.539852) (xy 6.631881 -65.590349)
			(xy 6.647949 -65.643756) (xy 6.656069 -65.698932) (xy 6.656578 -65.726818) (xy 6.656393 -65.736978)
			(xy 9.139172 -65.736978) (xy 9.143243 -65.681356) (xy 9.155369 -65.626919) (xy 9.175292 -65.574828)
			(xy 9.202588 -65.526193) (xy 9.236674 -65.48205) (xy 9.276823 -65.443341) (xy 9.322181 -65.41089)
			(xy 9.371781 -65.385389) (xy 9.424565 -65.367382) (xy 9.479408 -65.357252) (xy 9.535142 -65.355215)
			(xy 9.590579 -65.361315) (xy 9.644536 -65.375421) (xy 9.695865 -65.397233) (xy 9.743471 -65.426287)
			(xy 9.786339 -65.461962) (xy 9.823556 -65.503499) (xy 9.854329 -65.550012) (xy 9.878001 -65.600509)
			(xy 9.894069 -65.653916) (xy 9.902189 -65.709092) (xy 9.902698 -65.736978) (xy 9.902189 -65.764864)
			(xy 9.894069 -65.82004) (xy 9.878001 -65.873447) (xy 9.854329 -65.923944) (xy 9.823556 -65.970457)
			(xy 9.786339 -66.011994) (xy 9.743471 -66.047669) (xy 9.695865 -66.076723) (xy 9.644536 -66.098535)
			(xy 9.590579 -66.112641) (xy 9.535142 -66.118741) (xy 9.479408 -66.116704) (xy 9.424565 -66.106574)
			(xy 9.371781 -66.088567) (xy 9.322181 -66.063066) (xy 9.276823 -66.030615) (xy 9.236674 -65.991906)
			(xy 9.202588 -65.947763) (xy 9.175292 -65.899128) (xy 9.155369 -65.847037) (xy 9.143243 -65.7926)
			(xy 9.139172 -65.736978) (xy 6.656393 -65.736978) (xy 6.656069 -65.754704) (xy 6.647949 -65.80988)
			(xy 6.631881 -65.863287) (xy 6.608209 -65.913784) (xy 6.577436 -65.960297) (xy 6.540219 -66.001834)
			(xy 6.497351 -66.037509) (xy 6.449745 -66.066563) (xy 6.398416 -66.088375) (xy 6.344459 -66.102481)
			(xy 6.289022 -66.108581) (xy 6.233288 -66.106544) (xy 6.178445 -66.096414) (xy 6.125661 -66.078407)
			(xy 6.076061 -66.052906) (xy 6.030703 -66.020455) (xy 5.990554 -65.981746) (xy 5.956468 -65.937603)
			(xy 5.929172 -65.888968) (xy 5.909249 -65.836877) (xy 5.897123 -65.78244) (xy 5.893052 -65.726818)
			(xy 3.866134 -65.726818) (xy 3.866134 -76.11491) (xy 3.866642 -76.118466) (xy 3.868432 -76.131856)
			(xy 3.870337 -76.158805) (xy 3.870452 -76.172314) (xy 3.870329 -76.185822) (xy 3.868419 -76.212771)
			(xy 3.866642 -76.226162) (xy 3.866134 -76.229718) (xy 3.866134 -76.975716) (xy 3.866642 -76.979272)
			(xy 3.868432 -76.992662) (xy 3.870336 -77.019612) (xy 3.870452 -77.03312) (xy 3.870333 -77.046628)
			(xy 3.868429 -77.073578) (xy 3.866642 -77.086968) (xy 3.866134 -77.090524) (xy 3.866134 -77.375004)
			(xy 5.26669 -77.375004) (xy 5.267155 -77.348782) (xy 5.274351 -77.296833) (xy 5.288592 -77.246359)
			(xy 5.309612 -77.198311) (xy 5.337014 -77.153595) (xy 5.370281 -77.113052) (xy 5.408787 -77.077447)
			(xy 5.451807 -77.047451) (xy 5.47497 -77.035152) (xy 5.487246 -77.028409) (xy 5.507814 -77.009413)
			(xy 5.52245 -76.985545) (xy 5.530054 -76.958599) (xy 5.530054 -76.930601) (xy 5.522451 -76.903656)
			(xy 5.507815 -76.879788) (xy 5.487247 -76.860792) (xy 5.47497 -76.85405) (xy 5.451797 -76.841763)
			(xy 5.408762 -76.811779) (xy 5.370242 -76.77618) (xy 5.336965 -76.735637) (xy 5.309558 -76.690917)
			(xy 5.288539 -76.642862) (xy 5.274304 -76.59238) (xy 5.267123 -76.540423) (xy 5.26669 -76.514198)
			(xy 5.267176 -76.486947) (xy 5.274932 -76.432999) (xy 5.290287 -76.380704) (xy 5.312929 -76.331127)
			(xy 5.342395 -76.285277) (xy 5.378086 -76.244086) (xy 5.419277 -76.208395) (xy 5.465127 -76.178929)
			(xy 5.514704 -76.156287) (xy 5.566999 -76.140932) (xy 5.620947 -76.133176) (xy 5.675449 -76.133176)
			(xy 5.729397 -76.140932) (xy 5.781692 -76.156287) (xy 5.831269 -76.178929) (xy 5.877119 -76.208395)
			(xy 5.91831 -76.244086) (xy 5.954001 -76.285277) (xy 5.983467 -76.331127) (xy 6.006109 -76.380704)
			(xy 6.021464 -76.432999) (xy 6.02922 -76.486947) (xy 6.029706 -76.514198) (xy 6.029244 -76.54042)
			(xy 6.022049 -76.592369) (xy 6.007807 -76.642843) (xy 5.986786 -76.690891) (xy 5.959384 -76.735608)
			(xy 5.926116 -76.776151) (xy 5.88761 -76.811756) (xy 5.84459 -76.841752) (xy 5.821426 -76.85405)
			(xy 5.809187 -76.86082) (xy 5.788698 -76.879844) (xy 5.774124 -76.903705) (xy 5.766554 -76.930621)
			(xy 5.766555 -76.95858) (xy 5.774124 -76.985496) (xy 5.788698 -77.009357) (xy 5.809188 -77.028381)
			(xy 5.821426 -77.035152) (xy 5.844599 -77.04744) (xy 5.887634 -77.077423) (xy 5.926154 -77.113022)
			(xy 5.959432 -77.153564) (xy 5.986839 -77.198285) (xy 6.007858 -77.24634) (xy 6.022092 -77.296822)
			(xy 6.029273 -77.348779) (xy 6.029605 -77.368908) (xy 7.400544 -77.368908) (xy 7.401038 -77.342687)
			(xy 7.408231 -77.290741) (xy 7.422471 -77.240269) (xy 7.443487 -77.192222) (xy 7.470885 -77.147506)
			(xy 7.504147 -77.106962) (xy 7.542649 -77.071356) (xy 7.585663 -77.041357) (xy 7.608824 -77.029056)
			(xy 7.621101 -77.02231) (xy 7.641677 -77.003319) (xy 7.656321 -76.979451) (xy 7.663929 -76.952503)
			(xy 7.663929 -76.924502) (xy 7.656322 -76.897553) (xy 7.64168 -76.873685) (xy 7.621104 -76.854693)
			(xy 7.608824 -76.847954) (xy 7.585654 -76.835662) (xy 7.542618 -76.805679) (xy 7.504098 -76.770081)
			(xy 7.470821 -76.729539) (xy 7.443414 -76.684819) (xy 7.422394 -76.636765) (xy 7.408159 -76.586283)
			(xy 7.400977 -76.534327) (xy 7.400544 -76.508102) (xy 7.40103 -76.480851) (xy 7.408786 -76.426903)
			(xy 7.424141 -76.374608) (xy 7.446783 -76.325031) (xy 7.476249 -76.279181) (xy 7.51194 -76.23799)
			(xy 7.553131 -76.202299) (xy 7.598981 -76.172833) (xy 7.648558 -76.150191) (xy 7.700853 -76.134836)
			(xy 7.754801 -76.12708) (xy 7.809303 -76.12708) (xy 7.863251 -76.134836) (xy 7.915546 -76.150191)
			(xy 7.965123 -76.172833) (xy 8.010973 -76.202299) (xy 8.052164 -76.23799) (xy 8.087855 -76.279181)
			(xy 8.117321 -76.325031) (xy 8.139963 -76.374608) (xy 8.155318 -76.426903) (xy 8.163074 -76.480851)
			(xy 8.16356 -76.508102) (xy 8.163072 -76.534323) (xy 8.155877 -76.58627) (xy 8.141637 -76.636742)
			(xy 8.12062 -76.684788) (xy 8.093221 -76.729505) (xy 8.059958 -76.770048) (xy 8.021456 -76.805654)
			(xy 7.978441 -76.835653) (xy 7.95528 -76.847954) (xy 7.943032 -76.854714) (xy 7.922532 -76.873736)
			(xy 7.90795 -76.897599) (xy 7.900376 -76.924519) (xy 7.900377 -76.952485) (xy 7.907952 -76.979405)
			(xy 7.922535 -77.003268) (xy 7.943036 -77.022288) (xy 7.95528 -77.029056) (xy 7.978451 -77.041346)
			(xy 8.021486 -77.07133) (xy 8.060006 -77.106928) (xy 8.093284 -77.14747) (xy 8.120691 -77.19219)
			(xy 8.14171 -77.240245) (xy 8.154785 -77.286612) (xy 9.534398 -77.286612) (xy 9.534894 -77.257996)
			(xy 9.543435 -77.201406) (xy 9.560341 -77.146729) (xy 9.585234 -77.095195) (xy 9.617552 -77.047962)
			(xy 9.656569 -77.006092) (xy 9.67867 -76.987908) (xy 9.690366 -76.978038) (xy 9.707665 -76.952806)
			(xy 9.716718 -76.923583) (xy 9.716714 -76.892991) (xy 9.707653 -76.863771) (xy 9.690348 -76.838543)
			(xy 9.67867 -76.82865) (xy 9.656589 -76.810445) (xy 9.617585 -76.768571) (xy 9.585275 -76.721339)
			(xy 9.560384 -76.66981) (xy 9.54347 -76.615141) (xy 9.534914 -76.558559) (xy 9.534398 -76.529946)
			(xy 9.534884 -76.502695) (xy 9.54264 -76.448747) (xy 9.557995 -76.396452) (xy 9.580637 -76.346875)
			(xy 9.610103 -76.301025) (xy 9.645794 -76.259834) (xy 9.686985 -76.224143) (xy 9.732835 -76.194677)
			(xy 9.782412 -76.172035) (xy 9.834707 -76.15668) (xy 9.888655 -76.148924) (xy 9.943157 -76.148924)
			(xy 9.997105 -76.15668) (xy 10.0494 -76.172035) (xy 10.098977 -76.194677) (xy 10.144827 -76.224143)
			(xy 10.186018 -76.259834) (xy 10.221709 -76.301025) (xy 10.251175 -76.346875) (xy 10.273817 -76.396452)
			(xy 10.289172 -76.448747) (xy 10.296928 -76.502695) (xy 10.297414 -76.529946) (xy 10.296883 -76.55856)
			(xy 10.288349 -76.615149) (xy 10.271449 -76.669825) (xy 10.246563 -76.721359) (xy 10.214251 -76.768593)
			(xy 10.17524 -76.810464) (xy 10.153142 -76.82865) (xy 10.141588 -76.838638) (xy 10.124398 -76.863859)
			(xy 10.115402 -76.893026) (xy 10.115398 -76.923548) (xy 10.124386 -76.952717) (xy 10.14157 -76.977943)
			(xy 10.153142 -76.987908) (xy 10.175205 -77.006133) (xy 10.21421 -77.048004) (xy 10.246522 -77.095231)
			(xy 10.271416 -77.146756) (xy 10.288334 -77.201421) (xy 10.296895 -77.258) (xy 10.297414 -77.286612)
			(xy 10.296928 -77.313863) (xy 10.289172 -77.367811) (xy 10.273817 -77.420106) (xy 10.251175 -77.469683)
			(xy 10.221709 -77.515533) (xy 10.186018 -77.556724) (xy 10.144827 -77.592415) (xy 10.098977 -77.621881)
			(xy 10.0494 -77.644523) (xy 9.997105 -77.659878) (xy 9.943157 -77.667634) (xy 9.888655 -77.667634)
			(xy 9.834707 -77.659878) (xy 9.782412 -77.644523) (xy 9.732835 -77.621881) (xy 9.686985 -77.592415)
			(xy 9.645794 -77.556724) (xy 9.610103 -77.515533) (xy 9.580637 -77.469683) (xy 9.557995 -77.420106)
			(xy 9.54264 -77.367811) (xy 9.534884 -77.313863) (xy 9.534398 -77.286612) (xy 8.154785 -77.286612)
			(xy 8.155945 -77.290726) (xy 8.163127 -77.342683) (xy 8.16356 -77.368908) (xy 8.163074 -77.396159)
			(xy 8.155318 -77.450107) (xy 8.139963 -77.502402) (xy 8.117321 -77.551979) (xy 8.087855 -77.597829)
			(xy 8.052164 -77.63902) (xy 8.010973 -77.674711) (xy 7.965123 -77.704177) (xy 7.915546 -77.726819)
			(xy 7.863251 -77.742174) (xy 7.809303 -77.74993) (xy 7.754801 -77.74993) (xy 7.700853 -77.742174)
			(xy 7.648558 -77.726819) (xy 7.598981 -77.704177) (xy 7.553131 -77.674711) (xy 7.51194 -77.63902)
			(xy 7.476249 -77.597829) (xy 7.446783 -77.551979) (xy 7.424141 -77.502402) (xy 7.408786 -77.450107)
			(xy 7.40103 -77.396159) (xy 7.400544 -77.368908) (xy 6.029605 -77.368908) (xy 6.029706 -77.375004)
			(xy 6.02922 -77.402255) (xy 6.021464 -77.456203) (xy 6.006109 -77.508498) (xy 5.983467 -77.558075)
			(xy 5.954001 -77.603925) (xy 5.91831 -77.645116) (xy 5.877119 -77.680807) (xy 5.831269 -77.710273)
			(xy 5.781692 -77.732915) (xy 5.729397 -77.74827) (xy 5.675449 -77.756026) (xy 5.620947 -77.756026)
			(xy 5.566999 -77.74827) (xy 5.514704 -77.732915) (xy 5.465127 -77.710273) (xy 5.419277 -77.680807)
			(xy 5.378086 -77.645116) (xy 5.342395 -77.603925) (xy 5.312929 -77.558075) (xy 5.290287 -77.508498)
			(xy 5.274932 -77.456203) (xy 5.267176 -77.402255) (xy 5.26669 -77.375004) (xy 3.866134 -77.375004)
			(xy 3.866134 -78.361032) (xy 5.76199 -80.256888)
		)
		(stroke
			(width 0)
			(type solid)
		)
		(fill yes)
		(layer "In7.Cu")
		(net "GND")
	)
	(gr_poly
		(pts
			(xy 19.724624 -100.8634) (xy 19.739256 -100.86293) (xy 19.767324 -100.854648) (xy 19.791888 -100.838742)
			(xy 19.810929 -100.81652) (xy 19.822883 -100.789809) (xy 19.826767 -100.760804) (xy 19.822262 -100.731889)
			(xy 19.809737 -100.705441) (xy 19.800316 -100.694236) (xy 19.783381 -100.674542) (xy 19.754806 -100.631172)
			(xy 19.73283 -100.584112) (xy 19.717921 -100.534359) (xy 19.710393 -100.482969) (xy 19.709892 -100.457)
			(xy 19.71039 -100.430351) (xy 19.718333 -100.377647) (xy 19.734043 -100.326717) (xy 19.757169 -100.278696)
			(xy 19.787193 -100.234659) (xy 19.823445 -100.195588) (xy 19.865116 -100.162357) (xy 19.911274 -100.135708)
			(xy 19.960888 -100.116236) (xy 20.01285 -100.104376) (xy 20.066 -100.100393) (xy 20.11915 -100.104376)
			(xy 20.171112 -100.116236) (xy 20.220726 -100.135708) (xy 20.239309 -100.146437) (xy 22.329142 -100.146437)
			(xy 22.329142 -100.094463) (xy 22.337272 -100.043128) (xy 22.353333 -99.993698) (xy 22.376929 -99.947388)
			(xy 22.407479 -99.90534) (xy 22.44423 -99.868589) (xy 22.486278 -99.838039) (xy 22.532588 -99.814443)
			(xy 22.582018 -99.798382) (xy 22.633353 -99.790252) (xy 22.685327 -99.790252) (xy 22.736662 -99.798382)
			(xy 22.786092 -99.814443) (xy 22.832402 -99.838039) (xy 22.87445 -99.868589) (xy 22.911201 -99.90534)
			(xy 22.941751 -99.947388) (xy 22.965347 -99.993698) (xy 22.981408 -100.043128) (xy 22.989538 -100.094463)
			(xy 22.990048 -100.12045) (xy 22.989538 -100.146437) (xy 23.129242 -100.146437) (xy 23.129242 -100.094463)
			(xy 23.137372 -100.043128) (xy 23.153433 -99.993698) (xy 23.177029 -99.947388) (xy 23.207579 -99.90534)
			(xy 23.24433 -99.868589) (xy 23.286378 -99.838039) (xy 23.332688 -99.814443) (xy 23.382118 -99.798382)
			(xy 23.433453 -99.790252) (xy 23.485427 -99.790252) (xy 23.536762 -99.798382) (xy 23.586192 -99.814443)
			(xy 23.632502 -99.838039) (xy 23.67455 -99.868589) (xy 23.711301 -99.90534) (xy 23.741851 -99.947388)
			(xy 23.765447 -99.993698) (xy 23.781508 -100.043128) (xy 23.789638 -100.094463) (xy 23.790148 -100.12045)
			(xy 23.789638 -100.146437) (xy 23.781508 -100.197772) (xy 23.765447 -100.247202) (xy 23.741851 -100.293512)
			(xy 23.711301 -100.33556) (xy 23.67455 -100.372311) (xy 23.632502 -100.402861) (xy 23.586192 -100.426457)
			(xy 23.536762 -100.442518) (xy 23.485427 -100.450648) (xy 23.433453 -100.450648) (xy 23.382118 -100.442518)
			(xy 23.332688 -100.426457) (xy 23.286378 -100.402861) (xy 23.24433 -100.372311) (xy 23.207579 -100.33556)
			(xy 23.177029 -100.293512) (xy 23.153433 -100.247202) (xy 23.137372 -100.197772) (xy 23.129242 -100.146437)
			(xy 22.989538 -100.146437) (xy 22.981408 -100.197772) (xy 22.965347 -100.247202) (xy 22.941751 -100.293512)
			(xy 22.911201 -100.33556) (xy 22.87445 -100.372311) (xy 22.832402 -100.402861) (xy 22.786092 -100.426457)
			(xy 22.736662 -100.442518) (xy 22.685327 -100.450648) (xy 22.633353 -100.450648) (xy 22.582018 -100.442518)
			(xy 22.532588 -100.426457) (xy 22.486278 -100.402861) (xy 22.44423 -100.372311) (xy 22.407479 -100.33556)
			(xy 22.376929 -100.293512) (xy 22.353333 -100.247202) (xy 22.337272 -100.197772) (xy 22.329142 -100.146437)
			(xy 20.239309 -100.146437) (xy 20.266884 -100.162357) (xy 20.308555 -100.195588) (xy 20.344807 -100.234659)
			(xy 20.374831 -100.278696) (xy 20.397957 -100.326717) (xy 20.413667 -100.377647) (xy 20.42161 -100.430351)
			(xy 20.422108 -100.457) (xy 20.421639 -100.482971) (xy 20.414102 -100.534362) (xy 20.399186 -100.584116)
			(xy 20.377209 -100.631179) (xy 20.348634 -100.674554) (xy 20.331684 -100.694236) (xy 20.322318 -100.705464)
			(xy 20.309849 -100.7319) (xy 20.305379 -100.760784) (xy 20.309274 -100.789752) (xy 20.321214 -100.816431)
			(xy 20.340222 -100.838634) (xy 20.364741 -100.854544) (xy 20.392762 -100.862857) (xy 20.407376 -100.8634)
			(xy 20.593812 -100.8634) (xy 20.607274 -100.833428) (xy 20.618959 -100.808687) (xy 20.648364 -100.762546)
			(xy 20.684059 -100.721079) (xy 20.725311 -100.685136) (xy 20.771276 -100.655455) (xy 20.821008 -100.632644)
			(xy 20.87349 -100.617172) (xy 20.927643 -100.609356) (xy 20.982357 -100.609356) (xy 21.03651 -100.617172)
			(xy 21.088992 -100.632644) (xy 21.138724 -100.655455) (xy 21.184689 -100.685136) (xy 21.225941 -100.721079)
			(xy 21.261636 -100.762546) (xy 21.291041 -100.808687) (xy 21.302726 -100.833428) (xy 21.316188 -100.8634)
			(xy 21.559012 -100.8634) (xy 21.572474 -100.833428) (xy 21.584159 -100.808687) (xy 21.613564 -100.762546)
			(xy 21.649259 -100.721079) (xy 21.690511 -100.685136) (xy 21.736476 -100.655455) (xy 21.786208 -100.632644)
			(xy 21.83869 -100.617172) (xy 21.892843 -100.609356) (xy 21.947557 -100.609356) (xy 22.00171 -100.617172)
			(xy 22.054192 -100.632644) (xy 22.103924 -100.655455) (xy 22.149889 -100.685136) (xy 22.191141 -100.721079)
			(xy 22.226836 -100.762546) (xy 22.256241 -100.808687) (xy 22.267926 -100.833428) (xy 22.281388 -100.8634)
			(xy 22.625812 -100.8634) (xy 22.639274 -100.833428) (xy 22.650959 -100.808687) (xy 22.680364 -100.762546)
			(xy 22.716059 -100.721079) (xy 22.757311 -100.685136) (xy 22.803276 -100.655455) (xy 22.853008 -100.632644)
			(xy 22.90549 -100.617172) (xy 22.959643 -100.609356) (xy 23.014357 -100.609356) (xy 23.06851 -100.617172)
			(xy 23.120992 -100.632644) (xy 23.170724 -100.655455) (xy 23.216689 -100.685136) (xy 23.257941 -100.721079)
			(xy 23.293636 -100.762546) (xy 23.323041 -100.808687) (xy 23.334726 -100.833428) (xy 23.348188 -100.8634)
			(xy 27.4828 -100.8634) (xy 27.94 -100.4062) (xy 27.94 -99.7204) (xy 27.4828 -99.2632) (xy 27.4828 -99.190302)
			(xy 27.346402 -99.054158) (xy 27.329634 -99.036716) (xy 27.301201 -98.997574) (xy 27.279241 -98.954466)
			(xy 27.264294 -98.908454) (xy 27.25673 -98.86067) (xy 27.256232 -98.83648) (xy 27.256232 -94.516956)
			(xy 27.252676 -94.507558) (xy 27.23936 -94.473668) (xy 27.220609 -94.403308) (xy 27.211127 -94.331113)
			(xy 27.210512 -94.294706) (xy 27.210512 -92.68714) (xy 27.211141 -92.650734) (xy 27.220642 -92.578544)
			(xy 27.239374 -92.508182) (xy 27.252676 -92.474288) (xy 27.256232 -92.46489) (xy 27.256232 -90.87612)
			(xy 27.256705 -90.851928) (xy 27.26427 -90.80414) (xy 27.279218 -90.758124) (xy 27.30118 -90.715013)
			(xy 27.329616 -90.675868) (xy 27.346402 -90.658442) (xy 27.530552 -90.474292) (xy 27.530552 -90.083132)
			(xy 27.52852 -90.07602) (xy 27.517625 -90.036914) (xy 27.505892 -89.956588) (xy 27.505152 -89.916)
			(xy 27.505152 -88.098376) (xy 25.59304 -86.18601) (xy 25.58281 -86.176414) (xy 25.558335 -86.162734)
			(xy 25.531063 -86.156222) (xy 25.503048 -86.157371) (xy 25.476401 -86.166092) (xy 25.453128 -86.18173)
			(xy 25.443688 -86.192106) (xy 25.42547 -86.212853) (xy 25.384081 -86.249396) (xy 25.337857 -86.27959)
			(xy 25.287763 -86.302805) (xy 25.234845 -86.318557) (xy 25.18021 -86.326517) (xy 25.152604 -86.32698)
			(xy 25.125352 -86.326517) (xy 25.071402 -86.31876) (xy 25.019105 -86.303404) (xy 24.969526 -86.280762)
			(xy 24.923675 -86.251293) (xy 24.882484 -86.215599) (xy 24.846792 -86.174406) (xy 24.817327 -86.128553)
			(xy 24.794687 -86.078972) (xy 24.779335 -86.026675) (xy 24.771581 -85.972724) (xy 24.771096 -85.945472)
			(xy 24.771548 -85.91901) (xy 24.77886 -85.866592) (xy 24.793339 -85.815687) (xy 24.803608 -85.791294)
			(xy 24.808956 -85.777884) (xy 24.812718 -85.749273) (xy 24.808326 -85.720753) (xy 24.796131 -85.694599)
			(xy 24.777107 -85.672901) (xy 24.752773 -85.657391) (xy 24.725072 -85.649307) (xy 24.710644 -85.6488)
			(xy 21.185632 -85.6488) (xy 21.178012 -85.69071) (xy 21.172889 -85.716808) (xy 21.156363 -85.767359)
			(xy 21.13297 -85.815122) (xy 21.103163 -85.859168) (xy 21.067522 -85.898643) (xy 21.026738 -85.932778)
			(xy 20.981605 -85.960912) (xy 20.932999 -85.982498) (xy 20.881863 -85.997116) (xy 20.829192 -86.004483)
			(xy 20.8026 -86.004908) (xy 20.776554 -86.004464) (xy 20.724947 -85.997374) (xy 20.674785 -85.983327)
			(xy 20.627002 -85.962583) (xy 20.582486 -85.935529) (xy 20.542067 -85.902668) (xy 20.506496 -85.864611)
			(xy 20.476436 -85.822068) (xy 20.464018 -85.799168) (xy 20.457425 -85.787414) (xy 20.439162 -85.767608)
			(xy 20.416359 -85.753261) (xy 20.3906 -85.74537) (xy 20.363674 -85.744483) (xy 20.337451 -85.750661)
			(xy 20.313753 -85.763476) (xy 20.303744 -85.772498) (xy 20.28234 -85.792159) (xy 20.234686 -85.825426)
			(xy 20.182537 -85.851079) (xy 20.1271 -85.868523) (xy 20.069658 -85.877355) (xy 20.0406 -85.877908)
			(xy 20.011112 -85.877351) (xy 19.95284 -85.868265) (xy 19.896659 -85.850324) (xy 19.843906 -85.823956)
			(xy 19.795837 -85.789788) (xy 19.753595 -85.748633) (xy 19.718185 -85.70147) (xy 19.703796 -85.675724)
			(xy 19.689572 -85.6488) (xy 17.4244 -85.6488) (xy 16.5608 -86.5124) (xy 17.829782 -86.5124) (xy 17.833853 -86.456778)
			(xy 17.845979 -86.402341) (xy 17.865902 -86.35025) (xy 17.893198 -86.301615) (xy 17.927284 -86.257472)
			(xy 17.967433 -86.218763) (xy 18.012791 -86.186312) (xy 18.062391 -86.160811) (xy 18.115175 -86.142804)
			(xy 18.170018 -86.132674) (xy 18.225752 -86.130637) (xy 18.281189 -86.136737) (xy 18.335146 -86.150843)
			(xy 18.386475 -86.172655) (xy 18.434081 -86.201709) (xy 18.476949 -86.237384) (xy 18.514166 -86.278921)
			(xy 18.544939 -86.325434) (xy 18.561143 -86.36) (xy 19.607782 -86.36) (xy 19.611853 -86.304378) (xy 19.623979 -86.249941)
			(xy 19.643902 -86.19785) (xy 19.671198 -86.149215) (xy 19.705284 -86.105072) (xy 19.745433 -86.066363)
			(xy 19.790791 -86.033912) (xy 19.840391 -86.008411) (xy 19.893175 -85.990404) (xy 19.948018 -85.980274)
			(xy 20.003752 -85.978237) (xy 20.059189 -85.984337) (xy 20.113146 -85.998443) (xy 20.164475 -86.020255)
			(xy 20.212081 -86.049309) (xy 20.254949 -86.084984) (xy 20.292166 -86.126521) (xy 20.322939 -86.173034)
			(xy 20.346611 -86.223531) (xy 20.362679 -86.276938) (xy 20.370799 -86.332114) (xy 20.371308 -86.36)
			(xy 20.370799 -86.387886) (xy 20.362679 -86.443062) (xy 20.346611 -86.496469) (xy 20.322939 -86.546966)
			(xy 20.292166 -86.593479) (xy 20.254949 -86.635016) (xy 20.212081 -86.670691) (xy 20.164475 -86.699745)
			(xy 20.113146 -86.721557) (xy 20.059189 -86.735663) (xy 20.003752 -86.741763) (xy 19.948018 -86.739726)
			(xy 19.893175 -86.729596) (xy 19.840391 -86.711589) (xy 19.790791 -86.686088) (xy 19.745433 -86.653637)
			(xy 19.705284 -86.614928) (xy 19.671198 -86.570785) (xy 19.643902 -86.52215) (xy 19.623979 -86.470059)
			(xy 19.611853 -86.415622) (xy 19.607782 -86.36) (xy 18.561143 -86.36) (xy 18.568611 -86.375931) (xy 18.584679 -86.429338)
			(xy 18.592799 -86.484514) (xy 18.593308 -86.5124) (xy 18.592799 -86.540286) (xy 18.584679 -86.595462)
			(xy 18.568611 -86.648869) (xy 18.544939 -86.699366) (xy 18.514166 -86.745879) (xy 18.476949 -86.787416)
			(xy 18.434081 -86.823091) (xy 18.386475 -86.852145) (xy 18.335146 -86.873957) (xy 18.281189 -86.888063)
			(xy 18.225752 -86.894163) (xy 18.170018 -86.892126) (xy 18.115175 -86.881996) (xy 18.062391 -86.863989)
			(xy 18.012791 -86.838488) (xy 17.967433 -86.806037) (xy 17.927284 -86.767328) (xy 17.893198 -86.723185)
			(xy 17.865902 -86.67455) (xy 17.845979 -86.622459) (xy 17.833853 -86.568022) (xy 17.829782 -86.5124)
			(xy 16.5608 -86.5124) (xy 16.108426 -86.964774) (xy 16.133572 -86.999826) (xy 16.148061 -87.020967)
			(xy 16.171031 -87.066781) (xy 16.186659 -87.11559) (xy 16.194571 -87.166225) (xy 16.19504 -87.19185)
			(xy 16.194561 -87.217843) (xy 16.186436 -87.269189) (xy 16.170378 -87.318632) (xy 16.146784 -87.364955)
			(xy 16.116233 -87.407016) (xy 16.079478 -87.44378) (xy 16.037425 -87.474341) (xy 15.991108 -87.497947)
			(xy 15.941669 -87.514017) (xy 15.890325 -87.522154) (xy 15.864332 -87.522558) (xy 15.838707 -87.522079)
			(xy 15.78807 -87.514176) (xy 15.739258 -87.498555) (xy 15.693441 -87.47559) (xy 15.672308 -87.46109)
			(xy 15.637256 -87.435944) (xy 15.4178 -87.6554) (xy 15.4178 -88.138) (xy 15.5956 -88.3158) (xy 16.9164 -88.3158)
			(xy 17.146016 -88.086184) (xy 17.140428 -88.05926) (xy 17.137203 -88.04262) (xy 17.133772 -88.008898)
			(xy 17.13357 -87.99195) (xy 17.134049 -87.965958) (xy 17.142174 -87.914612) (xy 17.158232 -87.865169)
			(xy 17.181827 -87.818847) (xy 17.212378 -87.776787) (xy 17.249132 -87.740024) (xy 17.291186 -87.709464)
			(xy 17.337502 -87.685859) (xy 17.386941 -87.669791) (xy 17.438286 -87.661655) (xy 17.464278 -87.661242)
			(xy 17.489932 -87.662258) (xy 17.5133 -87.664036) (xy 17.82699 -87.350092) (xy 20.355052 -87.350092)
			(xy 20.370253 -87.349521) (xy 20.399304 -87.34056) (xy 20.424433 -87.323447) (xy 20.443412 -87.299697)
			(xy 20.454563 -87.271414) (xy 20.456898 -87.241101) (xy 20.450209 -87.211444) (xy 20.44319 -87.197946)
			(xy 20.42829 -87.17075) (xy 20.407114 -87.112472) (xy 20.396371 -87.051403) (xy 20.395692 -87.0204)
			(xy 20.39619 -86.993751) (xy 20.404133 -86.941047) (xy 20.419843 -86.890117) (xy 20.442969 -86.842096)
			(xy 20.472993 -86.798059) (xy 20.509245 -86.758988) (xy 20.550916 -86.725757) (xy 20.597074 -86.699108)
			(xy 20.646688 -86.679636) (xy 20.69865 -86.667776) (xy 20.7518 -86.663793) (xy 20.80495 -86.667776)
			(xy 20.856912 -86.679636) (xy 20.906526 -86.699108) (xy 20.952684 -86.725757) (xy 20.994355 -86.758988)
			(xy 21.030607 -86.798059) (xy 21.060631 -86.842096) (xy 21.083757 -86.890117) (xy 21.099467 -86.941047)
			(xy 21.10741 -86.993751) (xy 21.107908 -87.0204) (xy 21.107209 -87.051399) (xy 21.096431 -87.112455)
			(xy 21.075269 -87.170731) (xy 21.06041 -87.197946) (xy 21.05333 -87.211417) (xy 21.04663 -87.241085)
			(xy 21.048964 -87.271411) (xy 21.060124 -87.299705) (xy 21.07912 -87.323459) (xy 21.104269 -87.340565)
			(xy 21.13334 -87.349508) (xy 21.148548 -87.350092) (xy 24.97201 -87.350092) (xy 25.048464 -87.4268)
			(xy 25.2222 -87.4268) (xy 25.446736 -87.651336) (xy 25.467564 -87.65159) (xy 25.493219 -87.652327)
			(xy 25.543843 -87.660755) (xy 25.592558 -87.676902) (xy 25.638195 -87.70038) (xy 25.679656 -87.730626)
			(xy 25.715948 -87.766913) (xy 25.746199 -87.808371) (xy 25.769683 -87.854004) (xy 25.785835 -87.902717)
			(xy 25.794269 -87.953341) (xy 25.79497 -87.978996) (xy 25.795224 -87.999824) (xy 25.873456 -88.078056)
			(xy 25.925018 -88.026494) (xy 25.924256 -88.004396) (xy 25.924002 -87.99195) (xy 25.924481 -87.965961)
			(xy 25.932605 -87.914621) (xy 25.94866 -87.865185) (xy 25.972251 -87.818868) (xy 26.002798 -87.776813)
			(xy 26.039547 -87.740054) (xy 26.081594 -87.709497) (xy 26.127904 -87.685893) (xy 26.177337 -87.669825)
			(xy 26.228674 -87.661688) (xy 26.280653 -87.661682) (xy 26.331992 -87.669808) (xy 26.381428 -87.685865)
			(xy 26.427743 -87.709458) (xy 26.469797 -87.740006) (xy 26.506555 -87.776757) (xy 26.53711 -87.818806)
			(xy 26.560712 -87.865117) (xy 26.576778 -87.91455) (xy 26.584913 -87.965888) (xy 26.584917 -88.017866)
			(xy 26.576789 -88.069205) (xy 26.56073 -88.11864) (xy 26.537135 -88.164954) (xy 26.506585 -88.207007)
			(xy 26.469833 -88.243763) (xy 26.427783 -88.274317) (xy 26.381471 -88.297917) (xy 26.332037 -88.313981)
			(xy 26.280699 -88.322114) (xy 26.25471 -88.322658) (xy 26.229767 -88.322203) (xy 26.180447 -88.314706)
			(xy 26.132814 -88.299881) (xy 26.087951 -88.278065) (xy 26.046877 -88.249753) (xy 26.028396 -88.232996)
			(xy 26.017258 -88.223227) (xy 25.990767 -88.209991) (xy 25.961594 -88.204903) (xy 25.932186 -88.20839)
			(xy 25.905012 -88.220158) (xy 25.88235 -88.239222) (xy 25.866103 -88.26398) (xy 25.857633 -88.292357)
			(xy 25.8572 -88.307164) (xy 25.8572 -88.476328) (xy 25.857719 -88.491216) (xy 25.866303 -88.519727)
			(xy 25.882735 -88.544557) (xy 25.905623 -88.563602) (xy 25.933027 -88.575248) (xy 25.962623 -88.578507)
			(xy 25.991904 -88.573103) (xy 26.018387 -88.559495) (xy 26.029412 -88.54948) (xy 26.04802 -88.532141)
			(xy 26.089568 -88.502807) (xy 26.135116 -88.480178) (xy 26.183592 -88.464788) (xy 26.233852 -88.457)
			(xy 26.259282 -88.456516) (xy 26.28527 -88.456998) (xy 26.336607 -88.465126) (xy 26.386041 -88.481186)
			(xy 26.432353 -88.504781) (xy 26.474404 -88.53533) (xy 26.511158 -88.572082) (xy 26.54171 -88.614132)
			(xy 26.565308 -88.660443) (xy 26.58137 -88.709875) (xy 26.589501 -88.761212) (xy 26.589501 -88.813188)
			(xy 26.588773 -88.817783) (xy 26.724358 -88.817783) (xy 26.724358 -88.765809) (xy 26.732488 -88.714474)
			(xy 26.748549 -88.665044) (xy 26.772145 -88.618734) (xy 26.802695 -88.576686) (xy 26.839446 -88.539935)
			(xy 26.881494 -88.509385) (xy 26.927804 -88.485789) (xy 26.977234 -88.469728) (xy 27.028569 -88.461598)
			(xy 27.080543 -88.461598) (xy 27.131878 -88.469728) (xy 27.181308 -88.485789) (xy 27.227618 -88.509385)
			(xy 27.269666 -88.539935) (xy 27.306417 -88.576686) (xy 27.336967 -88.618734) (xy 27.360563 -88.665044)
			(xy 27.376624 -88.714474) (xy 27.384754 -88.765809) (xy 27.385264 -88.791796) (xy 27.384754 -88.817783)
			(xy 27.376624 -88.869118) (xy 27.360563 -88.918548) (xy 27.336967 -88.964858) (xy 27.306417 -89.006906)
			(xy 27.269666 -89.043657) (xy 27.227618 -89.074207) (xy 27.181308 -89.097803) (xy 27.131878 -89.113864)
			(xy 27.080543 -89.121994) (xy 27.028569 -89.121994) (xy 26.977234 -89.113864) (xy 26.927804 -89.097803)
			(xy 26.881494 -89.074207) (xy 26.839446 -89.043657) (xy 26.802695 -89.006906) (xy 26.772145 -88.964858)
			(xy 26.748549 -88.918548) (xy 26.732488 -88.869118) (xy 26.724358 -88.817783) (xy 26.588773 -88.817783)
			(xy 26.58137 -88.864525) (xy 26.565308 -88.913957) (xy 26.54171 -88.960268) (xy 26.511158 -89.002318)
			(xy 26.474404 -89.03907) (xy 26.432353 -89.069619) (xy 26.386041 -89.093214) (xy 26.336607 -89.109274)
			(xy 26.28527 -89.117402) (xy 26.259282 -89.117932) (xy 26.233852 -89.117464) (xy 26.183592 -89.109672)
			(xy 26.135118 -89.094276) (xy 26.089574 -89.071639) (xy 26.048033 -89.042294) (xy 26.029412 -89.024968)
			(xy 26.018347 -89.014989) (xy 25.991875 -89.001343) (xy 25.962593 -88.995911) (xy 25.932988 -88.999155)
			(xy 25.905577 -89.0108) (xy 25.882689 -89.029855) (xy 25.86627 -89.054702) (xy 25.857714 -89.083228)
			(xy 25.8572 -89.09812) (xy 25.8572 -89.617883) (xy 26.724612 -89.617883) (xy 26.724612 -89.565909)
			(xy 26.732742 -89.514574) (xy 26.748803 -89.465144) (xy 26.772399 -89.418834) (xy 26.802949 -89.376786)
			(xy 26.8397 -89.340035) (xy 26.881748 -89.309485) (xy 26.928058 -89.285889) (xy 26.977488 -89.269828)
			(xy 27.028823 -89.261698) (xy 27.080797 -89.261698) (xy 27.132132 -89.269828) (xy 27.181562 -89.285889)
			(xy 27.227872 -89.309485) (xy 27.26992 -89.340035) (xy 27.306671 -89.376786) (xy 27.337221 -89.418834)
			(xy 27.360817 -89.465144) (xy 27.376878 -89.514574) (xy 27.385008 -89.565909) (xy 27.385518 -89.591896)
			(xy 27.385008 -89.617883) (xy 27.376878 -89.669218) (xy 27.360817 -89.718648) (xy 27.337221 -89.764958)
			(xy 27.306671 -89.807006) (xy 27.26992 -89.843757) (xy 27.227872 -89.874307) (xy 27.181562 -89.897903)
			(xy 27.132132 -89.913964) (xy 27.080797 -89.922094) (xy 27.028823 -89.922094) (xy 26.977488 -89.913964)
			(xy 26.928058 -89.897903) (xy 26.881748 -89.874307) (xy 26.8397 -89.843757) (xy 26.802949 -89.807006)
			(xy 26.772399 -89.764958) (xy 26.748803 -89.718648) (xy 26.732742 -89.669218) (xy 26.724612 -89.617883)
			(xy 25.8572 -89.617883) (xy 25.8572 -89.9414) (xy 25.665938 -90.132662) (xy 25.698704 -90.168476)
			(xy 25.714912 -90.186874) (xy 25.742279 -90.227556) (xy 25.763341 -90.271831) (xy 25.777636 -90.318731)
			(xy 25.784853 -90.367227) (xy 25.785318 -90.391742) (xy 25.784805 -90.417727) (xy 25.77667 -90.469057)
			(xy 25.760605 -90.518483) (xy 25.737007 -90.564787) (xy 25.706457 -90.606831) (xy 25.669706 -90.643578)
			(xy 25.62766 -90.674124) (xy 25.581353 -90.697717) (xy 25.531926 -90.713777) (xy 25.480595 -90.721908)
			(xy 25.45461 -90.72245) (xy 25.430094 -90.722008) (xy 25.381598 -90.714779) (xy 25.334697 -90.700479)
			(xy 25.290418 -90.679419) (xy 25.249728 -90.65206) (xy 25.231344 -90.635836) (xy 25.19553 -90.60307)
			(xy 24.4856 -91.313) (xy 24.164036 -91.313) (xy 24.149812 -91.34094) (xy 24.137621 -91.363987) (xy 24.107102 -91.406257)
			(xy 24.070327 -91.443214) (xy 24.028209 -91.473943) (xy 23.981791 -91.497681) (xy 23.932222 -91.513841)
			(xy 23.880732 -91.522022) (xy 23.828596 -91.522022) (xy 23.777106 -91.513841) (xy 23.727537 -91.497681)
			(xy 23.681119 -91.473943) (xy 23.639001 -91.443214) (xy 23.602226 -91.406257) (xy 23.571707 -91.363987)
			(xy 23.559516 -91.34094) (xy 23.545292 -91.313) (xy 23.363936 -91.313) (xy 23.349712 -91.34094) (xy 23.337516 -91.363982)
			(xy 23.306989 -91.406242) (xy 23.270212 -91.44319) (xy 23.228094 -91.473913) (xy 23.181679 -91.497648)
			(xy 23.132115 -91.51381) (xy 23.08063 -91.521997) (xy 23.054564 -91.52255) (xy 23.034351 -91.522235)
			(xy 22.994232 -91.517273) (xy 22.974554 -91.512644) (xy 22.946614 -91.505786) (xy 22.758908 -91.693746)
			(xy 22.758908 -92.38361) (xy 22.533102 -92.609416) (xy 22.549612 -92.642182) (xy 22.56088 -92.665495)
			(xy 22.576828 -92.714755) (xy 22.584901 -92.765899) (xy 22.585426 -92.791788) (xy 22.584916 -92.817775)
			(xy 22.724366 -92.817775) (xy 22.724366 -92.765801) (xy 22.732496 -92.714466) (xy 22.748557 -92.665036)
			(xy 22.772153 -92.618726) (xy 22.802703 -92.576678) (xy 22.839454 -92.539927) (xy 22.881502 -92.509377)
			(xy 22.927812 -92.485781) (xy 22.977242 -92.46972) (xy 23.028577 -92.46159) (xy 23.080551 -92.46159)
			(xy 23.131886 -92.46972) (xy 23.181316 -92.485781) (xy 23.227626 -92.509377) (xy 23.269674 -92.539927)
			(xy 23.306425 -92.576678) (xy 23.336975 -92.618726) (xy 23.360571 -92.665036) (xy 23.376632 -92.714466)
			(xy 23.384762 -92.765801) (xy 23.385272 -92.791788) (xy 23.384762 -92.817775) (xy 23.376632 -92.86911)
			(xy 23.360571 -92.91854) (xy 23.336975 -92.96485) (xy 23.306425 -93.006898) (xy 23.269674 -93.043649)
			(xy 23.227626 -93.074199) (xy 23.181316 -93.097795) (xy 23.131886 -93.113856) (xy 23.080551 -93.121986)
			(xy 23.028577 -93.121986) (xy 22.977242 -93.113856) (xy 22.927812 -93.097795) (xy 22.881502 -93.074199)
			(xy 22.839454 -93.043649) (xy 22.802703 -93.006898) (xy 22.772153 -92.96485) (xy 22.748557 -92.91854)
			(xy 22.732496 -92.86911) (xy 22.724366 -92.817775) (xy 22.584916 -92.817775) (xy 22.576786 -92.86911)
			(xy 22.560725 -92.91854) (xy 22.537129 -92.96485) (xy 22.506579 -93.006898) (xy 22.469828 -93.043649)
			(xy 22.42778 -93.074199) (xy 22.38147 -93.097795) (xy 22.33204 -93.113856) (xy 22.280705 -93.121986)
			(xy 22.228731 -93.121986) (xy 22.177396 -93.113856) (xy 22.127966 -93.097795) (xy 22.081656 -93.074199)
			(xy 22.039608 -93.043649) (xy 22.002857 -93.006898) (xy 21.972307 -92.96485) (xy 21.948711 -92.91854)
			(xy 21.93265 -92.86911) (xy 21.92452 -92.817775) (xy 21.92401 -92.791788) (xy 21.924589 -92.764118)
			(xy 21.933844 -92.709557) (xy 21.952061 -92.6573) (xy 21.964904 -92.632784) (xy 21.983192 -92.599256)
			(xy 20.827492 -91.44381) (xy 20.827492 -91.414346) (xy 20.7264 -91.313) (xy 20.173696 -91.313) (xy 20.159472 -91.34094)
			(xy 20.147277 -91.363985) (xy 20.116752 -91.40625) (xy 20.079976 -91.443206) (xy 20.037859 -91.473935)
			(xy 19.991444 -91.497679) (xy 19.941879 -91.51385) (xy 19.890392 -91.522046) (xy 19.864324 -91.52255)
			(xy 19.838833 -91.522096) (xy 19.788449 -91.514304) (xy 19.739859 -91.498872) (xy 19.694213 -91.476164)
			(xy 19.652594 -91.446719) (xy 19.633946 -91.429332) (xy 19.624186 -91.420471) (xy 19.601188 -91.407605)
			(xy 19.575665 -91.401047) (xy 19.549314 -91.401232) (xy 19.523885 -91.408147) (xy 19.50107 -91.421334)
			(xy 19.491452 -91.430348) (xy 19.3802 -91.5416) (xy 19.3802 -91.894152) (xy 19.382232 -91.90101)
			(xy 19.388194 -91.923398) (xy 19.394575 -91.969285) (xy 19.394932 -91.99245) (xy 19.394932 -92.013532)
			(xy 19.399334 -92.017929) (xy 20.333972 -92.017929) (xy 20.333972 -91.965955) (xy 20.342102 -91.91462)
			(xy 20.358163 -91.86519) (xy 20.381759 -91.81888) (xy 20.412309 -91.776832) (xy 20.44906 -91.740081)
			(xy 20.491108 -91.709531) (xy 20.537418 -91.685935) (xy 20.586848 -91.669874) (xy 20.638183 -91.661744)
			(xy 20.690157 -91.661744) (xy 20.741492 -91.669874) (xy 20.790922 -91.685935) (xy 20.837232 -91.709531)
			(xy 20.87928 -91.740081) (xy 20.916031 -91.776832) (xy 20.946581 -91.81888) (xy 20.970177 -91.86519)
			(xy 20.986238 -91.91462) (xy 20.994368 -91.965955) (xy 20.994878 -91.991942) (xy 20.994368 -92.017929)
			(xy 20.986238 -92.069264) (xy 20.970177 -92.118694) (xy 20.946581 -92.165004) (xy 20.916031 -92.207052)
			(xy 20.87928 -92.243803) (xy 20.837232 -92.274353) (xy 20.790922 -92.297949) (xy 20.741492 -92.31401)
			(xy 20.690157 -92.32214) (xy 20.638183 -92.32214) (xy 20.586848 -92.31401) (xy 20.537418 -92.297949)
			(xy 20.491108 -92.274353) (xy 20.44906 -92.243803) (xy 20.412309 -92.207052) (xy 20.381759 -92.165004)
			(xy 20.358163 -92.118694) (xy 20.342102 -92.069264) (xy 20.333972 -92.017929) (xy 19.399334 -92.017929)
			(xy 19.633946 -92.252292) (xy 20.01901 -92.252292) (xy 20.306284 -92.539566) (xy 20.317502 -92.550056)
			(xy 20.344673 -92.564346) (xy 20.374866 -92.569899) (xy 20.405343 -92.566212) (xy 20.43334 -92.55362)
			(xy 20.445222 -92.543884) (xy 20.463451 -92.528364) (xy 20.503538 -92.502191) (xy 20.546976 -92.482063)
			(xy 20.59286 -92.468401) (xy 20.640233 -92.461488) (xy 20.66417 -92.46108) (xy 20.690162 -92.461561)
			(xy 20.741506 -92.469689) (xy 20.790946 -92.485749) (xy 20.837265 -92.509346) (xy 20.879322 -92.539899)
			(xy 20.916082 -92.576655) (xy 20.946638 -92.618709) (xy 20.97024 -92.665026) (xy 20.986304 -92.714465)
			(xy 20.994437 -92.765808) (xy 20.994437 -92.817792) (xy 20.986304 -92.869135) (xy 20.97024 -92.918574)
			(xy 20.946638 -92.964891) (xy 20.916082 -93.006945) (xy 20.879322 -93.043701) (xy 20.837265 -93.074254)
			(xy 20.790946 -93.097851) (xy 20.741506 -93.113911) (xy 20.690162 -93.122039) (xy 20.66417 -93.122496)
			(xy 20.635188 -93.121869) (xy 20.578116 -93.111729) (xy 20.523678 -93.091817) (xy 20.498308 -93.077792)
			(xy 20.484842 -93.070671) (xy 20.455161 -93.063892) (xy 20.424801 -93.066158) (xy 20.396455 -93.077266)
			(xy 20.372639 -93.096232) (xy 20.355468 -93.121371) (xy 20.346464 -93.150454) (xy 20.345908 -93.165676)
			(xy 20.345908 -94.008448) (xy 20.346411 -94.023685) (xy 20.355387 -94.052806) (xy 20.372556 -94.077983)
			(xy 20.39639 -94.096972) (xy 20.424765 -94.108085) (xy 20.455156 -94.11033) (xy 20.484856 -94.103508)
			(xy 20.498308 -94.096332) (xy 20.523672 -94.082292) (xy 20.578107 -94.062361) (xy 20.635186 -94.052237)
			(xy 20.66417 -94.051628) (xy 20.690158 -94.052109) (xy 20.741495 -94.060235) (xy 20.790928 -94.076293)
			(xy 20.83724 -94.099887) (xy 20.879291 -94.130435) (xy 20.916045 -94.167186) (xy 20.946597 -94.209234)
			(xy 20.970195 -94.255544) (xy 20.986258 -94.304976) (xy 20.994389 -94.356312) (xy 20.994389 -94.408288)
			(xy 20.986258 -94.459624) (xy 20.970195 -94.509056) (xy 20.946597 -94.555366) (xy 20.916045 -94.597414)
			(xy 20.879291 -94.634165) (xy 20.83724 -94.664713) (xy 20.790928 -94.688307) (xy 20.741495 -94.704365)
			(xy 20.690158 -94.712491) (xy 20.66417 -94.713044) (xy 20.640163 -94.712612) (xy 20.592655 -94.705664)
			(xy 20.546652 -94.691916) (xy 20.503121 -94.67166) (xy 20.462977 -94.645321) (xy 20.444714 -94.629732)
			(xy 20.432844 -94.619882) (xy 20.404753 -94.607174) (xy 20.374152 -94.603409) (xy 20.343819 -94.608929)
			(xy 20.316507 -94.623234) (xy 20.305268 -94.633796) (xy 20.01901 -94.920308) (xy 19.6342 -94.920308)
			(xy 19.6342 -95.208169) (xy 20.333972 -95.208169) (xy 20.333972 -95.156195) (xy 20.342102 -95.10486)
			(xy 20.358163 -95.05543) (xy 20.381759 -95.00912) (xy 20.412309 -94.967072) (xy 20.44906 -94.930321)
			(xy 20.491108 -94.899771) (xy 20.537418 -94.876175) (xy 20.586848 -94.860114) (xy 20.638183 -94.851984)
			(xy 20.690157 -94.851984) (xy 20.741492 -94.860114) (xy 20.790922 -94.876175) (xy 20.837232 -94.899771)
			(xy 20.87928 -94.930321) (xy 20.916031 -94.967072) (xy 20.946581 -95.00912) (xy 20.970177 -95.05543)
			(xy 20.986238 -95.10486) (xy 20.994368 -95.156195) (xy 20.994878 -95.182182) (xy 20.994368 -95.208169)
			(xy 20.986238 -95.259504) (xy 20.970177 -95.308934) (xy 20.946581 -95.355244) (xy 20.916031 -95.397292)
			(xy 20.87928 -95.434043) (xy 20.837232 -95.464593) (xy 20.790922 -95.488189) (xy 20.741492 -95.50425)
			(xy 20.690157 -95.51238) (xy 20.638183 -95.51238) (xy 20.586848 -95.50425) (xy 20.537418 -95.488189)
			(xy 20.491108 -95.464593) (xy 20.44906 -95.434043) (xy 20.412309 -95.397292) (xy 20.381759 -95.355244)
			(xy 20.358163 -95.308934) (xy 20.342102 -95.259504) (xy 20.333972 -95.208169) (xy 19.6342 -95.208169)
			(xy 19.6342 -95.504) (xy 19.789394 -95.659194) (xy 19.814794 -95.655384) (xy 19.827101 -95.653616)
			(xy 19.851892 -95.651708) (xy 19.864324 -95.651574) (xy 19.886422 -95.651947) (xy 19.930224 -95.65783)
			(xy 19.972857 -95.669475) (xy 19.993356 -95.677736) (xy 20.002754 -95.6818) (xy 20.52574 -95.6818)
			(xy 20.535138 -95.677736) (xy 20.555624 -95.669437) (xy 20.598259 -95.657777) (xy 20.642069 -95.651919)
			(xy 20.66417 -95.651574) (xy 20.692078 -95.652132) (xy 20.747109 -95.661452) (xy 20.773644 -95.670116)
			(xy 20.803616 -95.680784) (xy 21.081492 -95.402654) (xy 21.081492 -95.32239) (xy 21.78939 -94.614492)
			(xy 21.84273 -94.614492) (xy 21.85636 -94.614062) (xy 21.882648 -94.606851) (xy 21.906083 -94.592928)
			(xy 21.924986 -94.573288) (xy 21.938005 -94.549338) (xy 21.944206 -94.522794) (xy 21.943146 -94.495556)
			(xy 21.939504 -94.482412) (xy 21.932255 -94.458031) (xy 21.924469 -94.407767) (xy 21.92401 -94.382336)
			(xy 21.92452 -94.356349) (xy 21.93265 -94.305014) (xy 21.948711 -94.255584) (xy 21.972307 -94.209274)
			(xy 22.002857 -94.167226) (xy 22.039608 -94.130475) (xy 22.081656 -94.099925) (xy 22.127966 -94.076329)
			(xy 22.177396 -94.060268) (xy 22.228731 -94.052138) (xy 22.280705 -94.052138) (xy 22.33204 -94.060268)
			(xy 22.38147 -94.076329) (xy 22.42778 -94.099925) (xy 22.469828 -94.130475) (xy 22.506579 -94.167226)
			(xy 22.537129 -94.209274) (xy 22.560725 -94.255584) (xy 22.576786 -94.305014) (xy 22.584916 -94.356349)
			(xy 22.585426 -94.382336) (xy 22.58488 -94.408323) (xy 22.724366 -94.408323) (xy 22.724366 -94.356349)
			(xy 22.732496 -94.305014) (xy 22.748557 -94.255584) (xy 22.772153 -94.209274) (xy 22.802703 -94.167226)
			(xy 22.839454 -94.130475) (xy 22.881502 -94.099925) (xy 22.927812 -94.076329) (xy 22.977242 -94.060268)
			(xy 23.028577 -94.052138) (xy 23.080551 -94.052138) (xy 23.131886 -94.060268) (xy 23.181316 -94.076329)
			(xy 23.227626 -94.099925) (xy 23.269674 -94.130475) (xy 23.306425 -94.167226) (xy 23.336975 -94.209274)
			(xy 23.360571 -94.255584) (xy 23.376632 -94.305014) (xy 23.384762 -94.356349) (xy 23.385272 -94.382336)
			(xy 23.384762 -94.408323) (xy 23.376632 -94.459658) (xy 23.360571 -94.509088) (xy 23.336975 -94.555398)
			(xy 23.306425 -94.597446) (xy 23.269674 -94.634197) (xy 23.227626 -94.664747) (xy 23.181316 -94.688343)
			(xy 23.131886 -94.704404) (xy 23.080551 -94.712534) (xy 23.028577 -94.712534) (xy 22.977242 -94.704404)
			(xy 22.927812 -94.688343) (xy 22.881502 -94.664747) (xy 22.839454 -94.634197) (xy 22.802703 -94.597446)
			(xy 22.772153 -94.555398) (xy 22.748557 -94.509088) (xy 22.732496 -94.459658) (xy 22.724366 -94.408323)
			(xy 22.58488 -94.408323) (xy 22.584829 -94.410771) (xy 22.575108 -94.466803) (xy 22.555974 -94.520357)
			(xy 22.5425 -94.545404) (xy 22.52345 -94.578932) (xy 22.987508 -95.04299) (xy 22.987508 -95.32239)
			(xy 23.446994 -95.781876) (xy 23.457357 -95.791602) (xy 23.482187 -95.805404) (xy 23.509863 -95.811815)
			(xy 23.538233 -95.810338) (xy 23.565093 -95.801087) (xy 23.588355 -95.784781) (xy 23.597616 -95.774002)
			(xy 23.613421 -95.755227) (xy 23.649631 -95.722102) (xy 23.690337 -95.694691) (xy 23.734646 -95.673594)
			(xy 23.781586 -95.659275) (xy 23.830126 -95.652048) (xy 23.854664 -95.651574) (xy 23.880656 -95.652054)
			(xy 23.932 -95.660181) (xy 23.98144 -95.67624) (xy 24.02776 -95.699835) (xy 24.069818 -95.730387)
			(xy 24.106578 -95.767141) (xy 24.137136 -95.809194) (xy 24.160739 -95.85551) (xy 24.176806 -95.904948)
			(xy 24.184941 -95.95629) (xy 24.185372 -95.982282) (xy 24.184922 -96.006818) (xy 24.177668 -96.055352)
			(xy 24.163332 -96.102284) (xy 24.142227 -96.146587) (xy 24.114816 -96.18729) (xy 24.081699 -96.223503)
			(xy 24.062944 -96.23933) (xy 24.052242 -96.24865) (xy 24.036018 -96.27192) (xy 24.026812 -96.298753)
			(xy 24.025332 -96.327082) (xy 24.031692 -96.354727) (xy 24.045403 -96.379562) (xy 24.05507 -96.389952)
			(xy 24.247094 -96.581976) (xy 24.257457 -96.591702) (xy 24.282287 -96.605504) (xy 24.309963 -96.611915)
			(xy 24.338333 -96.610438) (xy 24.365193 -96.601187) (xy 24.388455 -96.584881) (xy 24.397716 -96.574102)
			(xy 24.413521 -96.555327) (xy 24.449731 -96.522202) (xy 24.490437 -96.494791) (xy 24.534746 -96.473694)
			(xy 24.581686 -96.459375) (xy 24.630226 -96.452148) (xy 24.654764 -96.451674) (xy 24.680756 -96.452154)
			(xy 24.7321 -96.460281) (xy 24.78154 -96.47634) (xy 24.82786 -96.499935) (xy 24.869918 -96.530487)
			(xy 24.906678 -96.567241) (xy 24.937236 -96.609294) (xy 24.960839 -96.65561) (xy 24.976906 -96.705048)
			(xy 24.985041 -96.75639) (xy 24.985472 -96.782382) (xy 24.984993 -96.808278) (xy 24.984979 -96.808369)
			(xy 25.124412 -96.808369) (xy 25.124412 -96.756395) (xy 25.132542 -96.70506) (xy 25.148603 -96.65563)
			(xy 25.172199 -96.60932) (xy 25.202749 -96.567272) (xy 25.2395 -96.530521) (xy 25.281548 -96.499971)
			(xy 25.327858 -96.476375) (xy 25.377288 -96.460314) (xy 25.428623 -96.452184) (xy 25.480597 -96.452184)
			(xy 25.531932 -96.460314) (xy 25.581362 -96.476375) (xy 25.627672 -96.499971) (xy 25.66972 -96.530521)
			(xy 25.706471 -96.567272) (xy 25.737021 -96.60932) (xy 25.760617 -96.65563) (xy 25.776678 -96.70506)
			(xy 25.784808 -96.756395) (xy 25.785318 -96.782382) (xy 25.784808 -96.808369) (xy 25.776678 -96.859704)
			(xy 25.760617 -96.909134) (xy 25.737021 -96.955444) (xy 25.706471 -96.997492) (xy 25.66972 -97.034243)
			(xy 25.627672 -97.064793) (xy 25.581362 -97.088389) (xy 25.531932 -97.10445) (xy 25.480597 -97.11258)
			(xy 25.428623 -97.11258) (xy 25.377288 -97.10445) (xy 25.327858 -97.088389) (xy 25.281548 -97.064793)
			(xy 25.2395 -97.034243) (xy 25.202749 -96.997492) (xy 25.172199 -96.955444) (xy 25.148603 -96.909134)
			(xy 25.132542 -96.859704) (xy 25.124412 -96.808369) (xy 24.984979 -96.808369) (xy 24.976961 -96.859443)
			(xy 24.96947 -96.884236) (xy 24.959818 -96.913954) (xy 25.171908 -97.12579) (xy 25.171908 -97.189798)
			(xy 25.172365 -97.204361) (xy 25.180563 -97.232309) (xy 25.196321 -97.256803) (xy 25.218356 -97.27585)
			(xy 25.244873 -97.287897) (xy 25.273713 -97.291965) (xy 25.302527 -97.287721) (xy 25.315926 -97.282)
			(xy 25.337764 -97.272371) (xy 25.383517 -97.258789) (xy 25.430747 -97.251927) (xy 25.45461 -97.25152)
			(xy 25.480594 -97.25203) (xy 25.531923 -97.260161) (xy 25.581348 -97.276222) (xy 25.627653 -97.299816)
			(xy 25.669696 -97.330364) (xy 25.706443 -97.367112) (xy 25.736989 -97.409156) (xy 25.760582 -97.455461)
			(xy 25.776641 -97.504886) (xy 25.784771 -97.556216) (xy 25.784771 -97.608184) (xy 25.776641 -97.659514)
			(xy 25.760582 -97.708939) (xy 25.736989 -97.755244) (xy 25.706443 -97.797288) (xy 25.669696 -97.834036)
			(xy 25.627653 -97.864584) (xy 25.581348 -97.888178) (xy 25.531923 -97.904239) (xy 25.480594 -97.91237)
			(xy 25.45461 -97.912936) (xy 25.427567 -97.912421) (xy 25.374197 -97.90366) (xy 25.322966 -97.886323)
			(xy 25.275244 -97.860872) (xy 25.253442 -97.844864) (xy 25.245696 -97.839516) (xy 25.227628 -97.834302)
			(xy 25.208895 -97.83596) (xy 25.192022 -97.844265) (xy 25.179283 -97.858098) (xy 25.172392 -97.875596)
			(xy 25.171908 -97.884996) (xy 25.171908 -97.89541) (xy 25.146 -97.921064) (xy 25.146 -97.9424) (xy 24.914606 -98.173794)
			(xy 24.935688 -98.208084) (xy 24.947469 -98.22779) (xy 24.966071 -98.269764) (xy 24.978687 -98.313908)
			(xy 24.985075 -98.359373) (xy 24.985472 -98.382328) (xy 24.984987 -98.408315) (xy 25.124412 -98.408315)
			(xy 25.124412 -98.356341) (xy 25.132542 -98.305006) (xy 25.148603 -98.255576) (xy 25.172199 -98.209266)
			(xy 25.202749 -98.167218) (xy 25.2395 -98.130467) (xy 25.281548 -98.099917) (xy 25.327858 -98.076321)
			(xy 25.377288 -98.06026) (xy 25.428623 -98.05213) (xy 25.480597 -98.05213) (xy 25.531932 -98.06026)
			(xy 25.581362 -98.076321) (xy 25.627672 -98.099917) (xy 25.66972 -98.130467) (xy 25.706471 -98.167218)
			(xy 25.737021 -98.209266) (xy 25.760617 -98.255576) (xy 25.776678 -98.305006) (xy 25.784808 -98.356341)
			(xy 25.785318 -98.382328) (xy 25.784808 -98.408315) (xy 25.784084 -98.412887) (xy 25.929084 -98.412887)
			(xy 25.929084 -98.360913) (xy 25.937214 -98.309578) (xy 25.953275 -98.260148) (xy 25.976871 -98.213838)
			(xy 26.007421 -98.17179) (xy 26.044172 -98.135039) (xy 26.08622 -98.104489) (xy 26.13253 -98.080893)
			(xy 26.18196 -98.064832) (xy 26.233295 -98.056702) (xy 26.285269 -98.056702) (xy 26.336604 -98.064832)
			(xy 26.386034 -98.080893) (xy 26.432344 -98.104489) (xy 26.474392 -98.135039) (xy 26.511143 -98.17179)
			(xy 26.541693 -98.213838) (xy 26.565289 -98.260148) (xy 26.58135 -98.309578) (xy 26.58948 -98.360913)
			(xy 26.58999 -98.3869) (xy 26.58948 -98.412887) (xy 26.58135 -98.464222) (xy 26.565289 -98.513652)
			(xy 26.541693 -98.559962) (xy 26.511143 -98.60201) (xy 26.474392 -98.638761) (xy 26.432344 -98.669311)
			(xy 26.386034 -98.692907) (xy 26.336604 -98.708968) (xy 26.285269 -98.717098) (xy 26.233295 -98.717098)
			(xy 26.18196 -98.708968) (xy 26.13253 -98.692907) (xy 26.08622 -98.669311) (xy 26.044172 -98.638761)
			(xy 26.007421 -98.60201) (xy 25.976871 -98.559962) (xy 25.953275 -98.513652) (xy 25.937214 -98.464222)
			(xy 25.929084 -98.412887) (xy 25.784084 -98.412887) (xy 25.776678 -98.45965) (xy 25.760617 -98.50908)
			(xy 25.737021 -98.55539) (xy 25.706471 -98.597438) (xy 25.66972 -98.634189) (xy 25.627672 -98.664739)
			(xy 25.581362 -98.688335) (xy 25.531932 -98.704396) (xy 25.480597 -98.712526) (xy 25.428623 -98.712526)
			(xy 25.377288 -98.704396) (xy 25.327858 -98.688335) (xy 25.281548 -98.664739) (xy 25.2395 -98.634189)
			(xy 25.202749 -98.597438) (xy 25.172199 -98.55539) (xy 25.148603 -98.50908) (xy 25.132542 -98.45965)
			(xy 25.124412 -98.408315) (xy 24.984987 -98.408315) (xy 24.976852 -98.459648) (xy 24.960787 -98.509076)
			(xy 24.937187 -98.555383) (xy 24.906634 -98.597428) (xy 24.869879 -98.634175) (xy 24.827828 -98.66472)
			(xy 24.781517 -98.688311) (xy 24.732086 -98.704367) (xy 24.680751 -98.712492) (xy 24.654764 -98.713036)
			(xy 24.629181 -98.712562) (xy 24.578623 -98.70469) (xy 24.529882 -98.689123) (xy 24.484121 -98.666233)
			(xy 24.442433 -98.636567) (xy 24.405812 -98.600833) (xy 24.375133 -98.559884) (xy 24.351129 -98.514698)
			(xy 24.334372 -98.466353) (xy 24.32939 -98.441256) (xy 24.32177 -98.3996) (xy 24.187658 -98.3996)
			(xy 24.180038 -98.441256) (xy 24.175009 -98.46634) (xy 24.158248 -98.514674) (xy 24.134244 -98.55985)
			(xy 24.103568 -98.60079) (xy 24.066953 -98.636518) (xy 24.025272 -98.66618) (xy 23.979521 -98.689068)
			(xy 23.93079 -98.704638) (xy 23.880243 -98.712517) (xy 23.829085 -98.712517) (xy 23.778538 -98.704638)
			(xy 23.729807 -98.689068) (xy 23.684056 -98.66618) (xy 23.642375 -98.636518) (xy 23.60576 -98.60079)
			(xy 23.575084 -98.55985) (xy 23.55108 -98.514674) (xy 23.534319 -98.46634) (xy 23.52929 -98.441256)
			(xy 23.52167 -98.3996) (xy 23.387558 -98.3996) (xy 23.379938 -98.441256) (xy 23.374909 -98.46634)
			(xy 23.358148 -98.514674) (xy 23.334144 -98.55985) (xy 23.303468 -98.60079) (xy 23.266853 -98.636518)
			(xy 23.225172 -98.66618) (xy 23.179421 -98.689068) (xy 23.13069 -98.704638) (xy 23.080143 -98.712517)
			(xy 23.028985 -98.712517) (xy 22.978438 -98.704638) (xy 22.929707 -98.689068) (xy 22.883956 -98.66618)
			(xy 22.842275 -98.636518) (xy 22.80566 -98.60079) (xy 22.774984 -98.55985) (xy 22.75098 -98.514674)
			(xy 22.734219 -98.46634) (xy 22.72919 -98.441256) (xy 22.72157 -98.3996) (xy 22.587712 -98.3996)
			(xy 22.580092 -98.441256) (xy 22.575063 -98.46634) (xy 22.558302 -98.514674) (xy 22.534298 -98.55985)
			(xy 22.503622 -98.60079) (xy 22.467007 -98.636518) (xy 22.425326 -98.66618) (xy 22.379575 -98.689068)
			(xy 22.330844 -98.704638) (xy 22.280297 -98.712517) (xy 22.229139 -98.712517) (xy 22.178592 -98.704638)
			(xy 22.129861 -98.689068) (xy 22.08411 -98.66618) (xy 22.042429 -98.636518) (xy 22.005814 -98.60079)
			(xy 21.975138 -98.55985) (xy 21.951134 -98.514674) (xy 21.934373 -98.46634) (xy 21.929344 -98.441256)
			(xy 21.921724 -98.3996) (xy 20.997164 -98.3996) (xy 20.989544 -98.441256) (xy 20.984515 -98.46634)
			(xy 20.967754 -98.514674) (xy 20.94375 -98.55985) (xy 20.913074 -98.60079) (xy 20.876459 -98.636518)
			(xy 20.834778 -98.66618) (xy 20.789027 -98.689068) (xy 20.740296 -98.704638) (xy 20.689749 -98.712517)
			(xy 20.638591 -98.712517) (xy 20.588044 -98.704638) (xy 20.539313 -98.689068) (xy 20.493562 -98.66618)
			(xy 20.451881 -98.636518) (xy 20.415266 -98.60079) (xy 20.38459 -98.55985) (xy 20.360586 -98.514674)
			(xy 20.343825 -98.46634) (xy 20.338796 -98.441256) (xy 20.331176 -98.3996) (xy 19.5072 -98.3996)
			(xy 18.999708 -98.907346) (xy 18.999708 -98.96221) (xy 18.753757 -99.208161) (xy 21.92452 -99.208161)
			(xy 21.92452 -99.156187) (xy 21.93265 -99.104852) (xy 21.948711 -99.055422) (xy 21.972307 -99.009112)
			(xy 22.002857 -98.967064) (xy 22.039608 -98.930313) (xy 22.081656 -98.899763) (xy 22.127966 -98.876167)
			(xy 22.177396 -98.860106) (xy 22.228731 -98.851976) (xy 22.280705 -98.851976) (xy 22.33204 -98.860106)
			(xy 22.38147 -98.876167) (xy 22.42778 -98.899763) (xy 22.469828 -98.930313) (xy 22.506579 -98.967064)
			(xy 22.537129 -99.009112) (xy 22.560725 -99.055422) (xy 22.576786 -99.104852) (xy 22.584916 -99.156187)
			(xy 22.585426 -99.182174) (xy 22.584916 -99.208161) (xy 22.724366 -99.208161) (xy 22.724366 -99.156187)
			(xy 22.732496 -99.104852) (xy 22.748557 -99.055422) (xy 22.772153 -99.009112) (xy 22.802703 -98.967064)
			(xy 22.839454 -98.930313) (xy 22.881502 -98.899763) (xy 22.927812 -98.876167) (xy 22.977242 -98.860106)
			(xy 23.028577 -98.851976) (xy 23.080551 -98.851976) (xy 23.131886 -98.860106) (xy 23.181316 -98.876167)
			(xy 23.227626 -98.899763) (xy 23.269674 -98.930313) (xy 23.306425 -98.967064) (xy 23.336975 -99.009112)
			(xy 23.360571 -99.055422) (xy 23.376632 -99.104852) (xy 23.384762 -99.156187) (xy 23.385272 -99.182174)
			(xy 23.384762 -99.208161) (xy 23.376632 -99.259496) (xy 23.360571 -99.308926) (xy 23.336975 -99.355236)
			(xy 23.306425 -99.397284) (xy 23.269674 -99.434035) (xy 23.227626 -99.464585) (xy 23.181316 -99.488181)
			(xy 23.131886 -99.504242) (xy 23.080551 -99.512372) (xy 23.028577 -99.512372) (xy 22.977242 -99.504242)
			(xy 22.927812 -99.488181) (xy 22.881502 -99.464585) (xy 22.839454 -99.434035) (xy 22.802703 -99.397284)
			(xy 22.772153 -99.355236) (xy 22.748557 -99.308926) (xy 22.732496 -99.259496) (xy 22.724366 -99.208161)
			(xy 22.584916 -99.208161) (xy 22.576786 -99.259496) (xy 22.560725 -99.308926) (xy 22.537129 -99.355236)
			(xy 22.506579 -99.397284) (xy 22.469828 -99.434035) (xy 22.42778 -99.464585) (xy 22.38147 -99.488181)
			(xy 22.33204 -99.504242) (xy 22.280705 -99.512372) (xy 22.228731 -99.512372) (xy 22.177396 -99.504242)
			(xy 22.127966 -99.488181) (xy 22.081656 -99.464585) (xy 22.039608 -99.434035) (xy 22.002857 -99.397284)
			(xy 21.972307 -99.355236) (xy 21.948711 -99.308926) (xy 21.93265 -99.259496) (xy 21.92452 -99.208161)
			(xy 18.753757 -99.208161) (xy 18.59661 -99.365308) (xy 16.139668 -99.365308) (xy 16.12419 -99.387596)
			(xy 16.087171 -99.427267) (xy 16.044175 -99.460366) (xy 15.996355 -99.486005) (xy 15.944991 -99.503497)
			(xy 15.891462 -99.512373) (xy 15.864332 -99.512882) (xy 15.838342 -99.512401) (xy 15.787001 -99.504274)
			(xy 15.737564 -99.488214) (xy 15.691248 -99.464618) (xy 15.649194 -99.434066) (xy 15.612438 -99.39731)
			(xy 15.581886 -99.355257) (xy 15.558288 -99.308942) (xy 15.542228 -99.259505) (xy 15.534099 -99.208164)
			(xy 15.533624 -99.182174) (xy 15.533878 -99.166426) (xy 15.53407 -99.152712) (xy 15.528015 -99.125972)
			(xy 15.515067 -99.101805) (xy 15.496159 -99.081951) (xy 15.472652 -99.067841) (xy 15.446239 -99.06049)
			(xy 15.432532 -99.06) (xy 15.278608 -99.06) (xy 15.278608 -99.567238) (xy 15.278038 -99.595415) (xy 15.269191 -99.65107)
			(xy 15.251752 -99.704658) (xy 15.22615 -99.754861) (xy 15.193014 -99.800444) (xy 15.173452 -99.82073)
			(xy 14.790169 -100.204249) (xy 17.67839 -100.204249) (xy 17.67839 -100.150951) (xy 17.686333 -100.098247)
			(xy 17.702043 -100.047317) (xy 17.725169 -99.999296) (xy 17.755193 -99.955259) (xy 17.791445 -99.916188)
			(xy 17.833116 -99.882957) (xy 17.879274 -99.856308) (xy 17.928888 -99.836836) (xy 17.98085 -99.824976)
			(xy 18.034 -99.820993) (xy 18.08715 -99.824976) (xy 18.139112 -99.836836) (xy 18.188726 -99.856308)
			(xy 18.234884 -99.882957) (xy 18.276555 -99.916188) (xy 18.312807 -99.955259) (xy 18.342831 -99.999296)
			(xy 18.365957 -100.047317) (xy 18.381667 -100.098247) (xy 18.38961 -100.150951) (xy 18.390108 -100.1776)
			(xy 18.38961 -100.204249) (xy 18.381667 -100.256953) (xy 18.365957 -100.307883) (xy 18.342831 -100.355904)
			(xy 18.312807 -100.399941) (xy 18.276555 -100.439012) (xy 18.234884 -100.472243) (xy 18.188726 -100.498892)
			(xy 18.139112 -100.518364) (xy 18.08715 -100.530224) (xy 18.034 -100.534208) (xy 17.98085 -100.530224)
			(xy 17.928888 -100.518364) (xy 17.879274 -100.498892) (xy 17.833116 -100.472243) (xy 17.791445 -100.439012)
			(xy 17.755193 -100.399941) (xy 17.725169 -100.355904) (xy 17.702043 -100.307883) (xy 17.686333 -100.256953)
			(xy 17.67839 -100.204249) (xy 14.790169 -100.204249) (xy 14.760448 -100.233988) (xy 14.760448 -100.586794)
			(xy 15.0368 -100.8634)
		)
		(stroke
			(width 0)
			(type solid)
		)
		(fill yes)
		(layer "In7.Cu")
		(net "PVCCA_AUX_PLD")
	)
	(gr_poly
		(pts
			(xy 78.954376 -97.655888) (xy 78.969023 -97.65541) (xy 78.997115 -97.647103) (xy 79.021694 -97.631166)
			(xy 79.040741 -97.60891) (xy 79.052688 -97.582163) (xy 79.056555 -97.553125) (xy 79.052022 -97.524184)
			(xy 79.039462 -97.497719) (xy 79.030068 -97.48647) (xy 79.010272 -97.465043) (xy 78.976763 -97.417296)
			(xy 78.950919 -97.365002) (xy 78.933344 -97.30938) (xy 78.924447 -97.25173) (xy 78.923896 -97.222564)
			(xy 78.924382 -97.195313) (xy 78.932138 -97.141365) (xy 78.947493 -97.08907) (xy 78.970135 -97.039493)
			(xy 78.999601 -96.993643) (xy 79.035292 -96.952452) (xy 79.076483 -96.916761) (xy 79.122333 -96.887295)
			(xy 79.17191 -96.864653) (xy 79.224205 -96.849298) (xy 79.278153 -96.841542) (xy 79.332655 -96.841542)
			(xy 79.386603 -96.849298) (xy 79.438898 -96.864653) (xy 79.488475 -96.887295) (xy 79.534325 -96.916761)
			(xy 79.575516 -96.952452) (xy 79.611207 -96.993643) (xy 79.640673 -97.039493) (xy 79.663315 -97.08907)
			(xy 79.67867 -97.141365) (xy 79.686426 -97.195313) (xy 79.686912 -97.222564) (xy 79.686333 -97.251726)
			(xy 79.67741 -97.309364) (xy 79.659826 -97.364975) (xy 79.633992 -97.417266) (xy 79.600507 -97.465021)
			(xy 79.58074 -97.48647) (xy 79.571715 -97.497285) (xy 79.559439 -97.522626) (xy 79.554541 -97.550354)
			(xy 79.557395 -97.578367) (xy 79.567782 -97.604538) (xy 79.584916 -97.626883) (xy 79.607495 -97.643706)
			(xy 79.633808 -97.653731) (xy 79.647796 -97.65538) (xy 79.741522 -97.65538) (xy 80.426052 -96.971104)
			(xy 80.426052 -93.473016) (xy 80.425586 -93.459143) (xy 80.418122 -93.43242) (xy 80.403741 -93.408692)
			(xy 80.383504 -93.38971) (xy 80.358905 -93.376875) (xy 80.331759 -93.371135) (xy 80.30407 -93.372914)
			(xy 80.277882 -93.382079) (xy 80.266286 -93.389704) (xy 80.245975 -93.40532) (xy 80.201961 -93.431543)
			(xy 80.154833 -93.451638) (xy 80.105438 -93.465241) (xy 80.054667 -93.472107) (xy 80.02905 -93.472508)
			(xy 80.001937 -93.472034) (xy 79.948258 -93.464355) (xy 79.896209 -93.449144) (xy 79.846842 -93.42671)
			(xy 79.801153 -93.397505) (xy 79.760066 -93.362119) (xy 79.724408 -93.321266) (xy 79.709264 -93.298772)
			(xy 79.700744 -93.287752) (xy 79.67892 -93.270459) (xy 79.653236 -93.259703) (xy 79.625601 -93.256286)
			(xy 79.59807 -93.260459) (xy 79.57269 -93.271914) (xy 79.551348 -93.289799) (xy 79.543148 -93.301058)
			(xy 79.527817 -93.322531) (xy 79.492188 -93.361444) (xy 79.451536 -93.395076) (xy 79.406636 -93.422784)
			(xy 79.358347 -93.444039) (xy 79.307588 -93.458436) (xy 79.25533 -93.465701) (xy 79.22895 -93.466158)
			(xy 79.201698 -93.465669) (xy 79.147748 -93.457905) (xy 79.095453 -93.442544) (xy 79.045875 -93.419897)
			(xy 79.000025 -93.390425) (xy 78.958835 -93.354729) (xy 78.923145 -93.313535) (xy 78.893679 -93.267681)
			(xy 78.871039 -93.218101) (xy 78.855684 -93.165803) (xy 78.847928 -93.111853) (xy 78.847928 -93.057347)
			(xy 78.855684 -93.003397) (xy 78.871039 -92.951099) (xy 78.893679 -92.901519) (xy 78.923145 -92.855665)
			(xy 78.958835 -92.814471) (xy 79.000025 -92.778775) (xy 79.045875 -92.749303) (xy 79.095453 -92.726656)
			(xy 79.147748 -92.711295) (xy 79.201698 -92.703531) (xy 79.22895 -92.703142) (xy 79.256062 -92.703616)
			(xy 79.30974 -92.711296) (xy 79.361787 -92.726508) (xy 79.411152 -92.748944) (xy 79.456838 -92.778151)
			(xy 79.497923 -92.81354) (xy 79.533575 -92.854395) (xy 79.548736 -92.876878) (xy 79.557253 -92.887902)
			(xy 79.579075 -92.905204) (xy 79.604761 -92.915965) (xy 79.632399 -92.919385) (xy 79.659933 -92.915209)
			(xy 79.685314 -92.903748) (xy 79.706654 -92.885855) (xy 79.714852 -92.874592) (xy 79.730184 -92.853121)
			(xy 79.765816 -92.814213) (xy 79.806469 -92.780586) (xy 79.851369 -92.752881) (xy 79.899657 -92.731629)
			(xy 79.950414 -92.717233) (xy 80.002671 -92.70997) (xy 80.02905 -92.709492) (xy 80.054667 -92.709904)
			(xy 80.105441 -92.71676) (xy 80.154839 -92.730354) (xy 80.201971 -92.750443) (xy 80.245988 -92.776663)
			(xy 80.266286 -92.792296) (xy 80.277927 -92.799859) (xy 80.304111 -92.809043) (xy 80.331801 -92.810838)
			(xy 80.358951 -92.805112) (xy 80.383557 -92.792286) (xy 80.403801 -92.773309) (xy 80.418188 -92.749582)
			(xy 80.425655 -92.722858) (xy 80.426052 -92.708984) (xy 80.426052 -80.194658) (xy 79.321406 -79.090012)
			(xy 79.321406 -74.858626) (xy 79.277464 -74.852784) (xy 79.251289 -74.848794) (xy 79.200302 -74.834524)
			(xy 79.175864 -74.824336) (xy 79.173832 -74.824336) (xy 79.159665 -74.820579) (xy 79.130369 -74.820458)
			(xy 79.102246 -74.828666) (xy 79.077614 -74.844527) (xy 79.058504 -74.866732) (xy 79.046491 -74.893452)
			(xy 79.044038 -74.907902) (xy 79.041172 -74.936162) (xy 79.028139 -74.991446) (xy 79.007052 -75.044187)
			(xy 78.978377 -75.093218) (xy 78.942749 -75.137454) (xy 78.900954 -75.175918) (xy 78.853918 -75.207759)
			(xy 78.802681 -75.232273) (xy 78.748374 -75.248918) (xy 78.6922 -75.257326) (xy 78.6638 -75.257914)
			(xy 78.636549 -75.257428) (xy 78.582601 -75.249672) (xy 78.530305 -75.234317) (xy 78.480728 -75.211676)
			(xy 78.434877 -75.182209) (xy 78.393686 -75.146518) (xy 78.357994 -75.105328) (xy 78.328527 -75.059477)
			(xy 78.305885 -75.0099) (xy 78.29053 -74.957605) (xy 78.282772 -74.903657) (xy 78.282292 -74.876406)
			(xy 78.282767 -74.849304) (xy 78.290438 -74.795647) (xy 78.305626 -74.743615) (xy 78.328026 -74.694257)
			(xy 78.357186 -74.648566) (xy 78.39252 -74.607462) (xy 78.433316 -74.571773) (xy 78.478752 -74.542218)
			(xy 78.527914 -74.519391) (xy 78.579812 -74.503752) (xy 78.633402 -74.495616) (xy 78.660498 -74.494898)
			(xy 78.664054 -74.494898) (xy 78.687989 -74.495273) (xy 78.735485 -74.501258) (xy 78.781861 -74.513127)
			(xy 78.804262 -74.521568) (xy 78.80858 -74.523346) (xy 78.821008 -74.527997) (xy 78.847311 -74.53142)
			(xy 78.873607 -74.52794) (xy 78.898114 -74.517792) (xy 78.919173 -74.501664) (xy 78.935357 -74.480648)
			(xy 78.945569 -74.456167) (xy 78.947772 -74.443082) (xy 78.950665 -74.414479) (xy 78.963952 -74.358548)
			(xy 78.985479 -74.305242) (xy 79.014757 -74.255768) (xy 79.051124 -74.211245) (xy 79.093758 -74.17268)
			(xy 79.141695 -74.140946) (xy 79.193848 -74.116762) (xy 79.249039 -74.100673) (xy 79.277464 -74.096372)
			(xy 79.321406 -74.09053) (xy 79.321406 -73.695814) (xy 79.271876 -73.645522) (xy 79.252572 -73.644252)
			(xy 79.223901 -73.641896) (xy 79.167694 -73.629651) (xy 79.113962 -73.609107) (xy 79.063924 -73.580728)
			(xy 79.018713 -73.54516) (xy 78.979354 -73.503206) (xy 78.94674 -73.45582) (xy 78.921609 -73.404074)
			(xy 78.904532 -73.349142) (xy 78.895895 -73.292269) (xy 78.895448 -73.263506) (xy 78.895929 -73.235973)
			(xy 78.903836 -73.181478) (xy 78.919486 -73.128683) (xy 78.942556 -73.078682) (xy 78.972567 -73.032513)
			(xy 79.008897 -72.991132) (xy 79.02956 -72.97293) (xy 79.03958 -72.963422) (xy 79.054556 -72.940225)
			(xy 79.062749 -72.913858) (xy 79.063559 -72.88626) (xy 79.056925 -72.859458) (xy 79.043336 -72.835423)
			(xy 79.033878 -72.825356) (xy 78.964028 -72.755506) (xy 78.959202 -72.752458) (xy 78.936046 -72.737117)
			(xy 78.894019 -72.700801) (xy 78.8577 -72.658776) (xy 78.842362 -72.635618) (xy 78.839314 -72.630792)
			(xy 78.801468 -72.592946) (xy 77.394308 -72.592946) (xy 77.380986 -72.593341) (xy 77.355249 -72.600237)
			(xy 77.332176 -72.613562) (xy 77.313339 -72.632406) (xy 77.300023 -72.655484) (xy 77.293136 -72.681224)
			(xy 77.292708 -72.694546) (xy 77.292708 -72.6948) (xy 77.292222 -72.722051) (xy 77.284466 -72.775999)
			(xy 77.269111 -72.828294) (xy 77.246469 -72.877871) (xy 77.217003 -72.923721) (xy 77.181312 -72.964912)
			(xy 77.140121 -73.000603) (xy 77.094271 -73.030069) (xy 77.044694 -73.052711) (xy 76.992399 -73.068066)
			(xy 76.938451 -73.075822) (xy 76.9112 -73.076308) (xy 76.880028 -73.075709) (xy 76.818504 -73.065629)
			(xy 76.788772 -73.056242) (xy 76.780898 -73.053448) (xy 76.225146 -73.053448) (xy 76.19697 -73.052876)
			(xy 76.141318 -73.044026) (xy 76.087733 -73.026583) (xy 76.037535 -73.000976) (xy 75.991958 -72.967836)
			(xy 75.971654 -72.948292) (xy 75.3999 -72.376284) (xy 75.058016 -72.0344) (xy 73.48982 -72.0344)
			(xy 73.00722 -72.517) (xy 73.147428 -72.657208) (xy 73.162668 -72.660256) (xy 73.188401 -72.665718)
			(xy 73.238164 -72.682775) (xy 73.285112 -72.706505) (xy 73.328356 -72.73646) (xy 73.367075 -72.772071)
			(xy 73.400535 -72.812663) (xy 73.428102 -72.857466) (xy 73.449254 -72.905632) (xy 73.463589 -72.956246)
			(xy 73.470835 -73.00835) (xy 73.471278 -73.034652) (xy 73.470818 -73.061906) (xy 73.463066 -73.115861)
			(xy 73.447714 -73.168163) (xy 73.425074 -73.217747) (xy 73.395607 -73.263604) (xy 73.359913 -73.3048)
			(xy 73.318718 -73.340496) (xy 73.272863 -73.369965) (xy 73.22328 -73.392608) (xy 73.170978 -73.407963)
			(xy 73.117024 -73.415717) (xy 73.08977 -73.41616) (xy 73.063463 -73.415723) (xy 73.011349 -73.4085)
			(xy 72.960722 -73.394182) (xy 72.912543 -73.37304) (xy 72.867729 -73.345476) (xy 72.827129 -73.312013)
			(xy 72.791514 -73.273287) (xy 72.761561 -73.230032) (xy 72.737839 -73.183071) (xy 72.720797 -73.133295)
			(xy 72.715374 -73.10755) (xy 72.712326 -73.09231) (xy 72.572118 -72.952102) (xy 71.738998 -73.785222)
			(xy 71.738998 -75.6158) (xy 73.531982 -75.6158) (xy 73.536053 -75.560178) (xy 73.548179 -75.505741)
			(xy 73.568102 -75.45365) (xy 73.595398 -75.405015) (xy 73.629484 -75.360872) (xy 73.669633 -75.322163)
			(xy 73.714991 -75.289712) (xy 73.764591 -75.264211) (xy 73.817375 -75.246204) (xy 73.872218 -75.236074)
			(xy 73.927952 -75.234037) (xy 73.983389 -75.240137) (xy 74.037346 -75.254243) (xy 74.088675 -75.276055)
			(xy 74.136281 -75.305109) (xy 74.179149 -75.340784) (xy 74.216366 -75.382321) (xy 74.247139 -75.428834)
			(xy 74.270811 -75.479331) (xy 74.286879 -75.532738) (xy 74.292337 -75.569826) (xy 76.59954 -75.569826)
			(xy 76.603611 -75.514204) (xy 76.615737 -75.459767) (xy 76.63566 -75.407676) (xy 76.662956 -75.359041)
			(xy 76.697042 -75.314898) (xy 76.737191 -75.276189) (xy 76.782549 -75.243738) (xy 76.832149 -75.218237)
			(xy 76.884933 -75.20023) (xy 76.939776 -75.1901) (xy 76.99551 -75.188063) (xy 77.050947 -75.194163)
			(xy 77.104904 -75.208269) (xy 77.156233 -75.230081) (xy 77.203839 -75.259135) (xy 77.246707 -75.29481)
			(xy 77.283924 -75.336347) (xy 77.314697 -75.38286) (xy 77.338369 -75.433357) (xy 77.354437 -75.486764)
			(xy 77.362557 -75.54194) (xy 77.363066 -75.569826) (xy 77.362557 -75.597712) (xy 77.354437 -75.652888)
			(xy 77.338369 -75.706295) (xy 77.314697 -75.756792) (xy 77.283924 -75.803305) (xy 77.246707 -75.844842)
			(xy 77.203839 -75.880517) (xy 77.156233 -75.909571) (xy 77.104904 -75.931383) (xy 77.050947 -75.945489)
			(xy 76.99551 -75.951589) (xy 76.939776 -75.949552) (xy 76.884933 -75.939422) (xy 76.832149 -75.921415)
			(xy 76.782549 -75.895914) (xy 76.737191 -75.863463) (xy 76.697042 -75.824754) (xy 76.662956 -75.780611)
			(xy 76.63566 -75.731976) (xy 76.615737 -75.679885) (xy 76.603611 -75.625448) (xy 76.59954 -75.569826)
			(xy 74.292337 -75.569826) (xy 74.294999 -75.587914) (xy 74.295508 -75.6158) (xy 74.294999 -75.643686)
			(xy 74.286879 -75.698862) (xy 74.270811 -75.752269) (xy 74.247139 -75.802766) (xy 74.216366 -75.849279)
			(xy 74.179149 -75.890816) (xy 74.136281 -75.926491) (xy 74.088675 -75.955545) (xy 74.037346 -75.977357)
			(xy 73.983389 -75.991463) (xy 73.927952 -75.997563) (xy 73.872218 -75.995526) (xy 73.817375 -75.985396)
			(xy 73.764591 -75.967389) (xy 73.714991 -75.941888) (xy 73.669633 -75.909437) (xy 73.629484 -75.870728)
			(xy 73.595398 -75.826585) (xy 73.568102 -75.77795) (xy 73.548179 -75.725859) (xy 73.536053 -75.671422)
			(xy 73.531982 -75.6158) (xy 71.738998 -75.6158) (xy 71.738998 -76.605384) (xy 72.64476 -76.605384)
			(xy 72.648831 -76.549762) (xy 72.660957 -76.495325) (xy 72.68088 -76.443234) (xy 72.708176 -76.394599)
			(xy 72.742262 -76.350456) (xy 72.782411 -76.311747) (xy 72.827769 -76.279296) (xy 72.877369 -76.253795)
			(xy 72.930153 -76.235788) (xy 72.984996 -76.225658) (xy 73.04073 -76.223621) (xy 73.096167 -76.229721)
			(xy 73.150124 -76.243827) (xy 73.201453 -76.265639) (xy 73.249059 -76.294693) (xy 73.291927 -76.330368)
			(xy 73.329144 -76.371905) (xy 73.359917 -76.418418) (xy 73.383589 -76.468915) (xy 73.399657 -76.522322)
			(xy 73.407777 -76.577498) (xy 73.407841 -76.581) (xy 77.468982 -76.581) (xy 77.473053 -76.525378)
			(xy 77.485179 -76.470941) (xy 77.505102 -76.41885) (xy 77.532398 -76.370215) (xy 77.566484 -76.326072)
			(xy 77.606633 -76.287363) (xy 77.651991 -76.254912) (xy 77.701591 -76.229411) (xy 77.754375 -76.211404)
			(xy 77.809218 -76.201274) (xy 77.864952 -76.199237) (xy 77.920389 -76.205337) (xy 77.974346 -76.219443)
			(xy 78.025675 -76.241255) (xy 78.073281 -76.270309) (xy 78.116149 -76.305984) (xy 78.153366 -76.347521)
			(xy 78.184139 -76.394034) (xy 78.207811 -76.444531) (xy 78.223879 -76.497938) (xy 78.231999 -76.553114)
			(xy 78.232508 -76.581) (xy 78.231999 -76.608886) (xy 78.223879 -76.664062) (xy 78.207811 -76.717469)
			(xy 78.184139 -76.767966) (xy 78.153366 -76.814479) (xy 78.116149 -76.856016) (xy 78.073281 -76.891691)
			(xy 78.025675 -76.920745) (xy 77.974346 -76.942557) (xy 77.920389 -76.956663) (xy 77.864952 -76.962763)
			(xy 77.809218 -76.960726) (xy 77.754375 -76.950596) (xy 77.701591 -76.932589) (xy 77.651991 -76.907088)
			(xy 77.606633 -76.874637) (xy 77.566484 -76.835928) (xy 77.532398 -76.791785) (xy 77.505102 -76.74315)
			(xy 77.485179 -76.691059) (xy 77.473053 -76.636622) (xy 77.468982 -76.581) (xy 73.407841 -76.581)
			(xy 73.408286 -76.605384) (xy 73.407777 -76.63327) (xy 73.399657 -76.688446) (xy 73.383589 -76.741853)
			(xy 73.359917 -76.79235) (xy 73.329144 -76.838863) (xy 73.291927 -76.8804) (xy 73.249059 -76.916075)
			(xy 73.201453 -76.945129) (xy 73.150124 -76.966941) (xy 73.096167 -76.981047) (xy 73.04073 -76.987147)
			(xy 72.984996 -76.98511) (xy 72.930153 -76.97498) (xy 72.877369 -76.956973) (xy 72.827769 -76.931472)
			(xy 72.782411 -76.899021) (xy 72.742262 -76.860312) (xy 72.708176 -76.816169) (xy 72.68088 -76.767534)
			(xy 72.660957 -76.715443) (xy 72.648831 -76.661006) (xy 72.64476 -76.605384) (xy 71.738998 -76.605384)
			(xy 71.738998 -77.6859) (xy 72.528682 -77.6859) (xy 72.532753 -77.630278) (xy 72.544879 -77.575841)
			(xy 72.564802 -77.52375) (xy 72.592098 -77.475115) (xy 72.626184 -77.430972) (xy 72.666333 -77.392263)
			(xy 72.711691 -77.359812) (xy 72.761291 -77.334311) (xy 72.814075 -77.316304) (xy 72.868918 -77.306174)
			(xy 72.924652 -77.304137) (xy 72.980089 -77.310237) (xy 73.034046 -77.324343) (xy 73.085375 -77.346155)
			(xy 73.132981 -77.375209) (xy 73.175849 -77.410884) (xy 73.213066 -77.452421) (xy 73.224696 -77.47)
			(xy 76.833982 -77.47) (xy 76.838053 -77.414378) (xy 76.850179 -77.359941) (xy 76.870102 -77.30785)
			(xy 76.897398 -77.259215) (xy 76.931484 -77.215072) (xy 76.971633 -77.176363) (xy 77.016991 -77.143912)
			(xy 77.066591 -77.118411) (xy 77.119375 -77.100404) (xy 77.174218 -77.090274) (xy 77.229952 -77.088237)
			(xy 77.285389 -77.094337) (xy 77.339346 -77.108443) (xy 77.390675 -77.130255) (xy 77.438281 -77.159309)
			(xy 77.481149 -77.194984) (xy 77.518366 -77.236521) (xy 77.549139 -77.283034) (xy 77.572811 -77.333531)
			(xy 77.588879 -77.386938) (xy 77.596999 -77.442114) (xy 77.597508 -77.47) (xy 77.596999 -77.497886)
			(xy 77.588879 -77.553062) (xy 77.572811 -77.606469) (xy 77.549139 -77.656966) (xy 77.518366 -77.703479)
			(xy 77.481149 -77.745016) (xy 77.438281 -77.780691) (xy 77.390675 -77.809745) (xy 77.339346 -77.831557)
			(xy 77.285389 -77.845663) (xy 77.229952 -77.851763) (xy 77.174218 -77.849726) (xy 77.119375 -77.839596)
			(xy 77.066591 -77.821589) (xy 77.016991 -77.796088) (xy 76.971633 -77.763637) (xy 76.931484 -77.724928)
			(xy 76.897398 -77.680785) (xy 76.870102 -77.63215) (xy 76.850179 -77.580059) (xy 76.838053 -77.525622)
			(xy 76.833982 -77.47) (xy 73.224696 -77.47) (xy 73.243839 -77.498934) (xy 73.267511 -77.549431) (xy 73.283579 -77.602838)
			(xy 73.291699 -77.658014) (xy 73.292208 -77.6859) (xy 73.291699 -77.713786) (xy 73.283579 -77.768962)
			(xy 73.267511 -77.822369) (xy 73.243839 -77.872866) (xy 73.213066 -77.919379) (xy 73.175849 -77.960916)
			(xy 73.132981 -77.996591) (xy 73.085375 -78.025645) (xy 73.034046 -78.047457) (xy 72.980089 -78.061563)
			(xy 72.924652 -78.067663) (xy 72.868918 -78.065626) (xy 72.814075 -78.055496) (xy 72.761291 -78.037489)
			(xy 72.711691 -78.011988) (xy 72.666333 -77.979537) (xy 72.626184 -77.940828) (xy 72.592098 -77.896685)
			(xy 72.564802 -77.84805) (xy 72.544879 -77.795959) (xy 72.532753 -77.741522) (xy 72.528682 -77.6859)
			(xy 71.738998 -77.6859) (xy 71.738998 -78.186026) (xy 71.756392 -78.206902) (xy 71.78571 -78.252651)
			(xy 71.808235 -78.302099) (xy 71.82351 -78.354245) (xy 71.831226 -78.408031) (xy 71.831226 -78.462369)
			(xy 71.82565 -78.50124) (xy 73.262488 -78.50124) (xy 73.266559 -78.445618) (xy 73.278685 -78.391181)
			(xy 73.298608 -78.33909) (xy 73.325904 -78.290455) (xy 73.35999 -78.246312) (xy 73.400139 -78.207603)
			(xy 73.445497 -78.175152) (xy 73.495097 -78.149651) (xy 73.547881 -78.131644) (xy 73.602724 -78.121514)
			(xy 73.658458 -78.119477) (xy 73.713895 -78.125577) (xy 73.767852 -78.139683) (xy 73.819181 -78.161495)
			(xy 73.866787 -78.190549) (xy 73.909655 -78.226224) (xy 73.946872 -78.267761) (xy 73.977645 -78.314274)
			(xy 74.001317 -78.364771) (xy 74.017385 -78.418178) (xy 74.025505 -78.473354) (xy 74.026014 -78.50124)
			(xy 74.025505 -78.529126) (xy 74.020365 -78.564051) (xy 76.580978 -78.564051) (xy 76.580978 -78.509549)
			(xy 76.588734 -78.455601) (xy 76.604089 -78.403306) (xy 76.626731 -78.353729) (xy 76.656197 -78.307879)
			(xy 76.691888 -78.266688) (xy 76.733079 -78.230997) (xy 76.778929 -78.201531) (xy 76.828506 -78.178889)
			(xy 76.880801 -78.163534) (xy 76.934749 -78.155778) (xy 76.962 -78.155292) (xy 76.990237 -78.155808)
			(xy 77.046093 -78.164133) (xy 77.100111 -78.180602) (xy 77.151112 -78.204853) (xy 77.19798 -78.236358)
			(xy 77.239692 -78.274428) (xy 77.25791 -78.296008) (xy 77.267587 -78.307102) (xy 77.291906 -78.323672)
			(xy 77.319937 -78.332627) (xy 77.349358 -78.333224) (xy 77.37773 -78.325414) (xy 77.402701 -78.309844)
			(xy 77.422201 -78.287806) (xy 77.428852 -78.274672) (xy 77.440668 -78.250275) (xy 77.470198 -78.204816)
			(xy 77.505868 -78.163997) (xy 77.546959 -78.128641) (xy 77.592644 -78.099461) (xy 77.642 -78.077045)
			(xy 77.694034 -78.061846) (xy 77.747696 -78.054168) (xy 77.7748 -78.053692) (xy 77.802051 -78.054178)
			(xy 77.855999 -78.061934) (xy 77.908294 -78.077289) (xy 77.957871 -78.099931) (xy 78.003721 -78.129397)
			(xy 78.044912 -78.165088) (xy 78.080603 -78.206279) (xy 78.110069 -78.252129) (xy 78.132711 -78.301706)
			(xy 78.148066 -78.354001) (xy 78.155822 -78.407949) (xy 78.155822 -78.462451) (xy 78.148066 -78.516399)
			(xy 78.132711 -78.568694) (xy 78.110069 -78.618271) (xy 78.080603 -78.664121) (xy 78.044912 -78.705312)
			(xy 78.003721 -78.741003) (xy 77.957871 -78.770469) (xy 77.908294 -78.793111) (xy 77.855999 -78.808466)
			(xy 77.802051 -78.816222) (xy 77.7748 -78.816708) (xy 77.746563 -78.816192) (xy 77.690707 -78.807867)
			(xy 77.636689 -78.791398) (xy 77.585688 -78.767147) (xy 77.53882 -78.735642) (xy 77.497108 -78.697572)
			(xy 77.47889 -78.675992) (xy 77.469213 -78.664898) (xy 77.444894 -78.648328) (xy 77.416863 -78.639373)
			(xy 77.387442 -78.638776) (xy 77.35907 -78.646586) (xy 77.334099 -78.662156) (xy 77.314599 -78.684194)
			(xy 77.307948 -78.697328) (xy 77.296132 -78.721725) (xy 77.266602 -78.767184) (xy 77.230932 -78.808003)
			(xy 77.189841 -78.843359) (xy 77.144156 -78.872539) (xy 77.0948 -78.894955) (xy 77.042766 -78.910154)
			(xy 76.989104 -78.917832) (xy 76.962 -78.918308) (xy 76.934749 -78.917822) (xy 76.880801 -78.910066)
			(xy 76.828506 -78.894711) (xy 76.778929 -78.872069) (xy 76.733079 -78.842603) (xy 76.691888 -78.806912)
			(xy 76.656197 -78.765721) (xy 76.626731 -78.719871) (xy 76.604089 -78.670294) (xy 76.588734 -78.617999)
			(xy 76.580978 -78.564051) (xy 74.020365 -78.564051) (xy 74.017385 -78.584302) (xy 74.001317 -78.637709)
			(xy 73.977645 -78.688206) (xy 73.946872 -78.734719) (xy 73.909655 -78.776256) (xy 73.866787 -78.811931)
			(xy 73.819181 -78.840985) (xy 73.767852 -78.862797) (xy 73.713895 -78.876903) (xy 73.658458 -78.883003)
			(xy 73.602724 -78.880966) (xy 73.547881 -78.870836) (xy 73.495097 -78.852829) (xy 73.445497 -78.827328)
			(xy 73.400139 -78.794877) (xy 73.35999 -78.756168) (xy 73.325904 -78.712025) (xy 73.298608 -78.66339)
			(xy 73.278685 -78.611299) (xy 73.266559 -78.556862) (xy 73.262488 -78.50124) (xy 71.82565 -78.50124)
			(xy 71.82351 -78.516155) (xy 71.808235 -78.568301) (xy 71.78571 -78.617749) (xy 71.756392 -78.663498)
			(xy 71.738998 -78.684374) (xy 71.738998 -80.2386) (xy 73.608182 -80.2386) (xy 73.612253 -80.182978)
			(xy 73.624379 -80.128541) (xy 73.644302 -80.07645) (xy 73.671598 -80.027815) (xy 73.705684 -79.983672)
			(xy 73.745833 -79.944963) (xy 73.791191 -79.912512) (xy 73.840791 -79.887011) (xy 73.893575 -79.869004)
			(xy 73.948418 -79.858874) (xy 74.004152 -79.856837) (xy 74.059589 -79.862937) (xy 74.113546 -79.877043)
			(xy 74.164875 -79.898855) (xy 74.212481 -79.927909) (xy 74.255349 -79.963584) (xy 74.292566 -80.005121)
			(xy 74.295794 -80.01) (xy 78.230982 -80.01) (xy 78.235053 -79.954378) (xy 78.247179 -79.899941) (xy 78.267102 -79.84785)
			(xy 78.294398 -79.799215) (xy 78.328484 -79.755072) (xy 78.368633 -79.716363) (xy 78.413991 -79.683912)
			(xy 78.463591 -79.658411) (xy 78.516375 -79.640404) (xy 78.571218 -79.630274) (xy 78.626952 -79.628237)
			(xy 78.682389 -79.634337) (xy 78.736346 -79.648443) (xy 78.787675 -79.670255) (xy 78.835281 -79.699309)
			(xy 78.878149 -79.734984) (xy 78.915366 -79.776521) (xy 78.946139 -79.823034) (xy 78.969811 -79.873531)
			(xy 78.985879 -79.926938) (xy 78.993999 -79.982114) (xy 78.994508 -80.01) (xy 78.993999 -80.037886)
			(xy 78.985879 -80.093062) (xy 78.969811 -80.146469) (xy 78.946139 -80.196966) (xy 78.915366 -80.243479)
			(xy 78.878149 -80.285016) (xy 78.835281 -80.320691) (xy 78.787675 -80.349745) (xy 78.736346 -80.371557)
			(xy 78.682389 -80.385663) (xy 78.626952 -80.391763) (xy 78.571218 -80.389726) (xy 78.516375 -80.379596)
			(xy 78.463591 -80.361589) (xy 78.413991 -80.336088) (xy 78.368633 -80.303637) (xy 78.328484 -80.264928)
			(xy 78.294398 -80.220785) (xy 78.267102 -80.17215) (xy 78.247179 -80.120059) (xy 78.235053 -80.065622)
			(xy 78.230982 -80.01) (xy 74.295794 -80.01) (xy 74.323339 -80.051634) (xy 74.347011 -80.102131) (xy 74.363079 -80.155538)
			(xy 74.371199 -80.210714) (xy 74.371708 -80.2386) (xy 74.371199 -80.266486) (xy 74.363079 -80.321662)
			(xy 74.347011 -80.375069) (xy 74.323339 -80.425566) (xy 74.292566 -80.472079) (xy 74.255349 -80.513616)
			(xy 74.212481 -80.549291) (xy 74.164875 -80.578345) (xy 74.113546 -80.600157) (xy 74.059589 -80.614263)
			(xy 74.004152 -80.620363) (xy 73.948418 -80.618326) (xy 73.893575 -80.608196) (xy 73.840791 -80.590189)
			(xy 73.791191 -80.564688) (xy 73.745833 -80.532237) (xy 73.705684 -80.493528) (xy 73.671598 -80.449385)
			(xy 73.644302 -80.40075) (xy 73.624379 -80.348659) (xy 73.612253 -80.294222) (xy 73.608182 -80.2386)
			(xy 71.738998 -80.2386) (xy 71.738998 -81.4578) (xy 72.35647 -81.4578) (xy 72.360541 -81.402178)
			(xy 72.372667 -81.347741) (xy 72.39259 -81.29565) (xy 72.419886 -81.247015) (xy 72.453972 -81.202872)
			(xy 72.494121 -81.164163) (xy 72.539479 -81.131712) (xy 72.589079 -81.106211) (xy 72.641863 -81.088204)
			(xy 72.696706 -81.078074) (xy 72.75244 -81.076037) (xy 72.807877 -81.082137) (xy 72.861834 -81.096243)
			(xy 72.913163 -81.118055) (xy 72.960769 -81.147109) (xy 73.003637 -81.182784) (xy 73.040854 -81.224321)
			(xy 73.071627 -81.270834) (xy 73.095299 -81.321331) (xy 73.111367 -81.374738) (xy 73.116115 -81.407)
			(xy 78.611982 -81.407) (xy 78.616053 -81.351378) (xy 78.628179 -81.296941) (xy 78.648102 -81.24485)
			(xy 78.675398 -81.196215) (xy 78.709484 -81.152072) (xy 78.749633 -81.113363) (xy 78.794991 -81.080912)
			(xy 78.844591 -81.055411) (xy 78.897375 -81.037404) (xy 78.952218 -81.027274) (xy 79.007952 -81.025237)
			(xy 79.063389 -81.031337) (xy 79.117346 -81.045443) (xy 79.168675 -81.067255) (xy 79.216281 -81.096309)
			(xy 79.259149 -81.131984) (xy 79.296366 -81.173521) (xy 79.327139 -81.220034) (xy 79.350811 -81.270531)
			(xy 79.366879 -81.323938) (xy 79.374999 -81.379114) (xy 79.375508 -81.407) (xy 79.374999 -81.434886)
			(xy 79.366879 -81.490062) (xy 79.350811 -81.543469) (xy 79.327139 -81.593966) (xy 79.296366 -81.640479)
			(xy 79.259149 -81.682016) (xy 79.216281 -81.717691) (xy 79.168675 -81.746745) (xy 79.117346 -81.768557)
			(xy 79.063389 -81.782663) (xy 79.007952 -81.788763) (xy 78.952218 -81.786726) (xy 78.897375 -81.776596)
			(xy 78.844591 -81.758589) (xy 78.794991 -81.733088) (xy 78.749633 -81.700637) (xy 78.709484 -81.661928)
			(xy 78.675398 -81.617785) (xy 78.648102 -81.56915) (xy 78.628179 -81.517059) (xy 78.616053 -81.462622)
			(xy 78.611982 -81.407) (xy 73.116115 -81.407) (xy 73.119487 -81.429914) (xy 73.119996 -81.4578) (xy 73.119487 -81.485686)
			(xy 73.111367 -81.540862) (xy 73.095299 -81.594269) (xy 73.071627 -81.644766) (xy 73.040854 -81.691279)
			(xy 73.003637 -81.732816) (xy 72.960769 -81.768491) (xy 72.913163 -81.797545) (xy 72.861834 -81.819357)
			(xy 72.807877 -81.833463) (xy 72.75244 -81.839563) (xy 72.696706 -81.837526) (xy 72.641863 -81.827396)
			(xy 72.589079 -81.809389) (xy 72.539479 -81.783888) (xy 72.494121 -81.751437) (xy 72.453972 -81.712728)
			(xy 72.419886 -81.668585) (xy 72.39259 -81.61995) (xy 72.372667 -81.567859) (xy 72.360541 -81.513422)
			(xy 72.35647 -81.4578) (xy 71.738998 -81.4578) (xy 71.738998 -81.852262) (xy 73.176382 -81.852262)
			(xy 73.180453 -81.79664) (xy 73.192579 -81.742203) (xy 73.212502 -81.690112) (xy 73.239798 -81.641477)
			(xy 73.273884 -81.597334) (xy 73.314033 -81.558625) (xy 73.359391 -81.526174) (xy 73.408991 -81.500673)
			(xy 73.461775 -81.482666) (xy 73.516618 -81.472536) (xy 73.572352 -81.470499) (xy 73.627789 -81.476599)
			(xy 73.681746 -81.490705) (xy 73.733075 -81.512517) (xy 73.780681 -81.541571) (xy 73.823549 -81.577246)
			(xy 73.860766 -81.618783) (xy 73.891539 -81.665296) (xy 73.915211 -81.715793) (xy 73.931279 -81.7692)
			(xy 73.939399 -81.824376) (xy 73.939908 -81.852262) (xy 73.939399 -81.880148) (xy 73.931279 -81.935324)
			(xy 73.915211 -81.988731) (xy 73.891539 -82.039228) (xy 73.860766 -82.085741) (xy 73.823549 -82.127278)
			(xy 73.780681 -82.162953) (xy 73.733075 -82.192007) (xy 73.681746 -82.213819) (xy 73.627789 -82.227925)
			(xy 73.572352 -82.234025) (xy 73.516618 -82.231988) (xy 73.461775 -82.221858) (xy 73.408991 -82.203851)
			(xy 73.359391 -82.17835) (xy 73.314033 -82.145899) (xy 73.273884 -82.10719) (xy 73.239798 -82.063047)
			(xy 73.212502 -82.014412) (xy 73.192579 -81.962321) (xy 73.180453 -81.907884) (xy 73.176382 -81.852262)
			(xy 71.738998 -81.852262) (xy 71.738998 -82.999072) (xy 72.35647 -82.999072) (xy 72.360541 -82.94345)
			(xy 72.372667 -82.889013) (xy 72.39259 -82.836922) (xy 72.419886 -82.788287) (xy 72.453972 -82.744144)
			(xy 72.494121 -82.705435) (xy 72.539479 -82.672984) (xy 72.589079 -82.647483) (xy 72.641863 -82.629476)
			(xy 72.696706 -82.619346) (xy 72.75244 -82.617309) (xy 72.807877 -82.623409) (xy 72.861834 -82.637515)
			(xy 72.913163 -82.659327) (xy 72.960769 -82.688381) (xy 73.003637 -82.724056) (xy 73.006992 -82.7278)
			(xy 75.040234 -82.7278) (xy 75.044305 -82.672178) (xy 75.056431 -82.617741) (xy 75.076354 -82.56565)
			(xy 75.10365 -82.517015) (xy 75.137736 -82.472872) (xy 75.177885 -82.434163) (xy 75.223243 -82.401712)
			(xy 75.272843 -82.376211) (xy 75.325627 -82.358204) (xy 75.38047 -82.348074) (xy 75.436204 -82.346037)
			(xy 75.491641 -82.352137) (xy 75.545598 -82.366243) (xy 75.596927 -82.388055) (xy 75.644533 -82.417109)
			(xy 75.687401 -82.452784) (xy 75.724618 -82.494321) (xy 75.755391 -82.540834) (xy 75.779063 -82.591331)
			(xy 75.795131 -82.644738) (xy 75.803251 -82.699914) (xy 75.80376 -82.7278) (xy 75.803251 -82.755686)
			(xy 75.795131 -82.810862) (xy 75.779063 -82.864269) (xy 75.755391 -82.914766) (xy 75.744651 -82.931)
			(xy 76.198982 -82.931) (xy 76.203053 -82.875378) (xy 76.215179 -82.820941) (xy 76.235102 -82.76885)
			(xy 76.262398 -82.720215) (xy 76.296484 -82.676072) (xy 76.336633 -82.637363) (xy 76.381991 -82.604912)
			(xy 76.431591 -82.579411) (xy 76.484375 -82.561404) (xy 76.539218 -82.551274) (xy 76.594952 -82.549237)
			(xy 76.650389 -82.555337) (xy 76.704346 -82.569443) (xy 76.755675 -82.591255) (xy 76.803281 -82.620309)
			(xy 76.846149 -82.655984) (xy 76.883366 -82.697521) (xy 76.914139 -82.744034) (xy 76.937811 -82.794531)
			(xy 76.953879 -82.847938) (xy 76.961999 -82.903114) (xy 76.962508 -82.931) (xy 76.961999 -82.958886)
			(xy 76.953879 -83.014062) (xy 76.937811 -83.067469) (xy 76.914139 -83.117966) (xy 76.883366 -83.164479)
			(xy 76.846149 -83.206016) (xy 76.803281 -83.241691) (xy 76.755675 -83.270745) (xy 76.704346 -83.292557)
			(xy 76.650389 -83.306663) (xy 76.594952 -83.312763) (xy 76.539218 -83.310726) (xy 76.484375 -83.300596)
			(xy 76.431591 -83.282589) (xy 76.381991 -83.257088) (xy 76.336633 -83.224637) (xy 76.296484 -83.185928)
			(xy 76.262398 -83.141785) (xy 76.235102 -83.09315) (xy 76.215179 -83.041059) (xy 76.203053 -82.986622)
			(xy 76.198982 -82.931) (xy 75.744651 -82.931) (xy 75.724618 -82.961279) (xy 75.687401 -83.002816)
			(xy 75.644533 -83.038491) (xy 75.596927 -83.067545) (xy 75.545598 -83.089357) (xy 75.491641 -83.103463)
			(xy 75.436204 -83.109563) (xy 75.38047 -83.107526) (xy 75.325627 -83.097396) (xy 75.272843 -83.079389)
			(xy 75.223243 -83.053888) (xy 75.177885 -83.021437) (xy 75.137736 -82.982728) (xy 75.10365 -82.938585)
			(xy 75.076354 -82.88995) (xy 75.056431 -82.837859) (xy 75.044305 -82.783422) (xy 75.040234 -82.7278)
			(xy 73.006992 -82.7278) (xy 73.040854 -82.765593) (xy 73.071627 -82.812106) (xy 73.095299 -82.862603)
			(xy 73.111367 -82.91601) (xy 73.119487 -82.971186) (xy 73.119996 -82.999072) (xy 73.119487 -83.026958)
			(xy 73.111367 -83.082134) (xy 73.095299 -83.135541) (xy 73.071627 -83.186038) (xy 73.040854 -83.232551)
			(xy 73.003637 -83.274088) (xy 72.960769 -83.309763) (xy 72.913163 -83.338817) (xy 72.861834 -83.360629)
			(xy 72.807877 -83.374735) (xy 72.75244 -83.380835) (xy 72.696706 -83.378798) (xy 72.641863 -83.368668)
			(xy 72.589079 -83.350661) (xy 72.539479 -83.32516) (xy 72.494121 -83.292709) (xy 72.453972 -83.254)
			(xy 72.419886 -83.209857) (xy 72.39259 -83.161222) (xy 72.372667 -83.109131) (xy 72.360541 -83.054694)
			(xy 72.35647 -82.999072) (xy 71.738998 -82.999072) (xy 71.738998 -85.2424) (xy 73.277982 -85.2424)
			(xy 73.282053 -85.186778) (xy 73.294179 -85.132341) (xy 73.314102 -85.08025) (xy 73.341398 -85.031615)
			(xy 73.375484 -84.987472) (xy 73.415633 -84.948763) (xy 73.460991 -84.916312) (xy 73.510591 -84.890811)
			(xy 73.563375 -84.872804) (xy 73.618218 -84.862674) (xy 73.673952 -84.860637) (xy 73.729389 -84.866737)
			(xy 73.783346 -84.880843) (xy 73.834675 -84.902655) (xy 73.882281 -84.931709) (xy 73.925149 -84.967384)
			(xy 73.962366 -85.008921) (xy 73.993139 -85.055434) (xy 74.016811 -85.105931) (xy 74.032879 -85.159338)
			(xy 74.040999 -85.214514) (xy 74.041508 -85.2424) (xy 74.040999 -85.270286) (xy 74.032879 -85.325462)
			(xy 74.016811 -85.378869) (xy 73.993139 -85.429366) (xy 73.962366 -85.475879) (xy 73.925149 -85.517416)
			(xy 73.882281 -85.553091) (xy 73.834675 -85.582145) (xy 73.783346 -85.603957) (xy 73.729389 -85.618063)
			(xy 73.673952 -85.624163) (xy 73.618218 -85.622126) (xy 73.563375 -85.611996) (xy 73.510591 -85.593989)
			(xy 73.460991 -85.568488) (xy 73.415633 -85.536037) (xy 73.375484 -85.497328) (xy 73.341398 -85.453185)
			(xy 73.314102 -85.40455) (xy 73.294179 -85.352459) (xy 73.282053 -85.298022) (xy 73.277982 -85.2424)
			(xy 71.738998 -85.2424) (xy 71.738998 -86.19998) (xy 73.308462 -86.19998) (xy 73.312533 -86.144358)
			(xy 73.324659 -86.089921) (xy 73.344582 -86.03783) (xy 73.371878 -85.989195) (xy 73.405964 -85.945052)
			(xy 73.446113 -85.906343) (xy 73.491471 -85.873892) (xy 73.541071 -85.848391) (xy 73.593855 -85.830384)
			(xy 73.648698 -85.820254) (xy 73.704432 -85.818217) (xy 73.759869 -85.824317) (xy 73.813826 -85.838423)
			(xy 73.865155 -85.860235) (xy 73.912761 -85.889289) (xy 73.955629 -85.924964) (xy 73.992846 -85.966501)
			(xy 74.023619 -86.013014) (xy 74.047291 -86.063511) (xy 74.063359 -86.116918) (xy 74.071479 -86.172094)
			(xy 74.071988 -86.19998) (xy 74.071479 -86.227866) (xy 74.063359 -86.283042) (xy 74.047291 -86.336449)
			(xy 74.023619 -86.386946) (xy 73.992846 -86.433459) (xy 73.955629 -86.474996) (xy 73.912761 -86.510671)
			(xy 73.865155 -86.539725) (xy 73.813826 -86.561537) (xy 73.759869 -86.575643) (xy 73.704432 -86.581743)
			(xy 73.648698 -86.579706) (xy 73.593855 -86.569576) (xy 73.541071 -86.551569) (xy 73.491471 -86.526068)
			(xy 73.446113 -86.493617) (xy 73.405964 -86.454908) (xy 73.371878 -86.410765) (xy 73.344582 -86.36213)
			(xy 73.324659 -86.310039) (xy 73.312533 -86.255602) (xy 73.308462 -86.19998) (xy 71.738998 -86.19998)
			(xy 71.738998 -86.6902) (xy 75.995782 -86.6902) (xy 75.999853 -86.634578) (xy 76.011979 -86.580141)
			(xy 76.031902 -86.52805) (xy 76.059198 -86.479415) (xy 76.093284 -86.435272) (xy 76.133433 -86.396563)
			(xy 76.178791 -86.364112) (xy 76.228391 -86.338611) (xy 76.281175 -86.320604) (xy 76.336018 -86.310474)
			(xy 76.391752 -86.308437) (xy 76.447189 -86.314537) (xy 76.501146 -86.328643) (xy 76.552475 -86.350455)
			(xy 76.600081 -86.379509) (xy 76.642949 -86.415184) (xy 76.680166 -86.456721) (xy 76.710939 -86.503234)
			(xy 76.727143 -86.5378) (xy 78.942182 -86.5378) (xy 78.946253 -86.482178) (xy 78.958379 -86.427741)
			(xy 78.978302 -86.37565) (xy 79.005598 -86.327015) (xy 79.039684 -86.282872) (xy 79.079833 -86.244163)
			(xy 79.125191 -86.211712) (xy 79.174791 -86.186211) (xy 79.227575 -86.168204) (xy 79.282418 -86.158074)
			(xy 79.338152 -86.156037) (xy 79.393589 -86.162137) (xy 79.447546 -86.176243) (xy 79.498875 -86.198055)
			(xy 79.546481 -86.227109) (xy 79.589349 -86.262784) (xy 79.626566 -86.304321) (xy 79.657339 -86.350834)
			(xy 79.681011 -86.401331) (xy 79.697079 -86.454738) (xy 79.705199 -86.509914) (xy 79.705708 -86.5378)
			(xy 79.705199 -86.565686) (xy 79.697079 -86.620862) (xy 79.681011 -86.674269) (xy 79.657339 -86.724766)
			(xy 79.626566 -86.771279) (xy 79.589349 -86.812816) (xy 79.546481 -86.848491) (xy 79.498875 -86.877545)
			(xy 79.447546 -86.899357) (xy 79.393589 -86.913463) (xy 79.338152 -86.919563) (xy 79.282418 -86.917526)
			(xy 79.227575 -86.907396) (xy 79.174791 -86.889389) (xy 79.125191 -86.863888) (xy 79.079833 -86.831437)
			(xy 79.039684 -86.792728) (xy 79.005598 -86.748585) (xy 78.978302 -86.69995) (xy 78.958379 -86.647859)
			(xy 78.946253 -86.593422) (xy 78.942182 -86.5378) (xy 76.727143 -86.5378) (xy 76.734611 -86.553731)
			(xy 76.750679 -86.607138) (xy 76.758799 -86.662314) (xy 76.759308 -86.6902) (xy 76.758799 -86.718086)
			(xy 76.750679 -86.773262) (xy 76.734611 -86.826669) (xy 76.710939 -86.877166) (xy 76.680166 -86.923679)
			(xy 76.642949 -86.965216) (xy 76.600081 -87.000891) (xy 76.552475 -87.029945) (xy 76.501146 -87.051757)
			(xy 76.447189 -87.065863) (xy 76.391752 -87.071963) (xy 76.336018 -87.069926) (xy 76.281175 -87.059796)
			(xy 76.228391 -87.041789) (xy 76.178791 -87.016288) (xy 76.133433 -86.983837) (xy 76.093284 -86.945128)
			(xy 76.059198 -86.900985) (xy 76.031902 -86.85235) (xy 76.011979 -86.800259) (xy 75.999853 -86.745822)
			(xy 75.995782 -86.6902) (xy 71.738998 -86.6902) (xy 71.738998 -90.14968) (xy 74.674982 -90.14968)
			(xy 74.679053 -90.094058) (xy 74.691179 -90.039621) (xy 74.711102 -89.98753) (xy 74.738398 -89.938895)
			(xy 74.772484 -89.894752) (xy 74.812633 -89.856043) (xy 74.857991 -89.823592) (xy 74.907591 -89.798091)
			(xy 74.960375 -89.780084) (xy 75.015218 -89.769954) (xy 75.070952 -89.767917) (xy 75.126389 -89.774017)
			(xy 75.180346 -89.788123) (xy 75.231675 -89.809935) (xy 75.279281 -89.838989) (xy 75.322149 -89.874664)
			(xy 75.359366 -89.916201) (xy 75.390139 -89.962714) (xy 75.413811 -90.013211) (xy 75.429879 -90.066618)
			(xy 75.437999 -90.121794) (xy 75.438508 -90.14968) (xy 75.437999 -90.177566) (xy 75.429879 -90.232742)
			(xy 75.413811 -90.286149) (xy 75.390139 -90.336646) (xy 75.359366 -90.383159) (xy 75.322149 -90.424696)
			(xy 75.279281 -90.460371) (xy 75.231675 -90.489425) (xy 75.180346 -90.511237) (xy 75.126389 -90.525343)
			(xy 75.070952 -90.531443) (xy 75.015218 -90.529406) (xy 74.960375 -90.519276) (xy 74.907591 -90.501269)
			(xy 74.857991 -90.475768) (xy 74.812633 -90.443317) (xy 74.772484 -90.404608) (xy 74.738398 -90.360465)
			(xy 74.711102 -90.31183) (xy 74.691179 -90.259739) (xy 74.679053 -90.205302) (xy 74.674982 -90.14968)
			(xy 71.738998 -90.14968) (xy 71.738998 -92.19438) (xy 71.739252 -92.208604) (xy 71.739252 -92.322142)
			(xy 72.700642 -92.322142) (xy 72.701128 -92.294891) (xy 72.708884 -92.240943) (xy 72.724239 -92.188648)
			(xy 72.746881 -92.139071) (xy 72.776347 -92.093221) (xy 72.812038 -92.05203) (xy 72.853229 -92.016339)
			(xy 72.899079 -91.986873) (xy 72.948656 -91.964231) (xy 73.000951 -91.948876) (xy 73.054899 -91.94112)
			(xy 73.109401 -91.94112) (xy 73.163349 -91.948876) (xy 73.215644 -91.964231) (xy 73.265221 -91.986873)
			(xy 73.311071 -92.016339) (xy 73.352262 -92.05203) (xy 73.387953 -92.093221) (xy 73.398606 -92.109798)
			(xy 78.080106 -92.109798) (xy 78.084177 -92.054176) (xy 78.096303 -91.999739) (xy 78.116226 -91.947648)
			(xy 78.143522 -91.899013) (xy 78.177608 -91.85487) (xy 78.217757 -91.816161) (xy 78.263115 -91.78371)
			(xy 78.312715 -91.758209) (xy 78.365499 -91.740202) (xy 78.420342 -91.730072) (xy 78.476076 -91.728035)
			(xy 78.531513 -91.734135) (xy 78.58547 -91.748241) (xy 78.636799 -91.770053) (xy 78.684405 -91.799107)
			(xy 78.727273 -91.834782) (xy 78.76449 -91.876319) (xy 78.795263 -91.922832) (xy 78.818935 -91.973329)
			(xy 78.835003 -92.026736) (xy 78.843123 -92.081912) (xy 78.843632 -92.109798) (xy 78.843123 -92.137684)
			(xy 78.835003 -92.19286) (xy 78.818935 -92.246267) (xy 78.795263 -92.296764) (xy 78.76449 -92.343277)
			(xy 78.727273 -92.384814) (xy 78.684405 -92.420489) (xy 78.636799 -92.449543) (xy 78.58547 -92.471355)
			(xy 78.531513 -92.485461) (xy 78.476076 -92.491561) (xy 78.420342 -92.489524) (xy 78.365499 -92.479394)
			(xy 78.312715 -92.461387) (xy 78.263115 -92.435886) (xy 78.217757 -92.403435) (xy 78.177608 -92.364726)
			(xy 78.143522 -92.320583) (xy 78.116226 -92.271948) (xy 78.096303 -92.219857) (xy 78.084177 -92.16542)
			(xy 78.080106 -92.109798) (xy 73.398606 -92.109798) (xy 73.417419 -92.139071) (xy 73.440061 -92.188648)
			(xy 73.455416 -92.240943) (xy 73.463172 -92.294891) (xy 73.463658 -92.322142) (xy 73.463118 -92.352159)
			(xy 73.453698 -92.411448) (xy 73.435112 -92.468533) (xy 73.40782 -92.522004) (xy 73.372494 -92.570543)
			(xy 73.351644 -92.592144) (xy 73.342373 -92.602021) (xy 73.328987 -92.625562) (xy 73.322248 -92.651791)
			(xy 73.32263 -92.678869) (xy 73.330106 -92.704898) (xy 73.344152 -92.728052) (xy 73.353676 -92.737686)
			(xy 73.37214 -92.755788) (xy 73.404544 -92.79608) (xy 73.431202 -92.840383) (xy 73.451626 -92.887884)
			(xy 73.46544 -92.93771) (xy 73.472391 -92.988947) (xy 73.472802 -93.0148) (xy 73.472316 -93.042051)
			(xy 73.46456 -93.095999) (xy 73.449205 -93.148294) (xy 73.426563 -93.197871) (xy 73.397097 -93.243721)
			(xy 73.361406 -93.284912) (xy 73.320215 -93.320603) (xy 73.274365 -93.350069) (xy 73.224788 -93.372711)
			(xy 73.172493 -93.388066) (xy 73.118545 -93.395822) (xy 73.064043 -93.395822) (xy 73.010095 -93.388066)
			(xy 72.9578 -93.372711) (xy 72.908223 -93.350069) (xy 72.862373 -93.320603) (xy 72.821182 -93.284912)
			(xy 72.785491 -93.243721) (xy 72.756025 -93.197871) (xy 72.733383 -93.148294) (xy 72.718028 -93.095999)
			(xy 72.710272 -93.042051) (xy 72.709786 -93.0148) (xy 72.71034 -92.984784) (xy 72.719755 -92.925494)
			(xy 72.738336 -92.868409) (xy 72.765626 -92.814938) (xy 72.800951 -92.766399) (xy 72.8218 -92.744798)
			(xy 72.831034 -92.734887) (xy 72.84443 -92.711358) (xy 72.851179 -92.685136) (xy 72.850804 -92.658063)
			(xy 72.843334 -92.632038) (xy 72.829291 -92.608887) (xy 72.819768 -92.599256) (xy 72.801285 -92.581173)
			(xy 72.768881 -92.540878) (xy 72.742224 -92.496571) (xy 72.721803 -92.449066) (xy 72.707994 -92.399236)
			(xy 72.70105 -92.347996) (xy 72.700642 -92.322142) (xy 71.739252 -92.322142) (xy 71.739252 -94.361)
			(xy 75.000102 -94.361) (xy 75.004173 -94.305378) (xy 75.016299 -94.250941) (xy 75.036222 -94.19885)
			(xy 75.063518 -94.150215) (xy 75.097604 -94.106072) (xy 75.137753 -94.067363) (xy 75.183111 -94.034912)
			(xy 75.232711 -94.009411) (xy 75.285495 -93.991404) (xy 75.340338 -93.981274) (xy 75.396072 -93.979237)
			(xy 75.451509 -93.985337) (xy 75.505466 -93.999443) (xy 75.556795 -94.021255) (xy 75.604401 -94.050309)
			(xy 75.647269 -94.085984) (xy 75.684486 -94.127521) (xy 75.715259 -94.174034) (xy 75.738931 -94.224531)
			(xy 75.754999 -94.277938) (xy 75.763119 -94.333114) (xy 75.763628 -94.361) (xy 75.763119 -94.388886)
			(xy 75.754999 -94.444062) (xy 75.738931 -94.497469) (xy 75.715259 -94.547966) (xy 75.684486 -94.594479)
			(xy 75.647269 -94.636016) (xy 75.604401 -94.671691) (xy 75.556795 -94.700745) (xy 75.505466 -94.722557)
			(xy 75.451509 -94.736663) (xy 75.396072 -94.742763) (xy 75.340338 -94.740726) (xy 75.285495 -94.730596)
			(xy 75.232711 -94.712589) (xy 75.183111 -94.687088) (xy 75.137753 -94.654637) (xy 75.097604 -94.615928)
			(xy 75.063518 -94.571785) (xy 75.036222 -94.52315) (xy 75.016299 -94.471059) (xy 75.004173 -94.416622)
			(xy 75.000102 -94.361) (xy 71.739252 -94.361) (xy 71.739252 -94.817184) (xy 79.460342 -94.817184)
			(xy 79.464413 -94.761562) (xy 79.476539 -94.707125) (xy 79.496462 -94.655034) (xy 79.523758 -94.606399)
			(xy 79.557844 -94.562256) (xy 79.597993 -94.523547) (xy 79.643351 -94.491096) (xy 79.692951 -94.465595)
			(xy 79.745735 -94.447588) (xy 79.800578 -94.437458) (xy 79.856312 -94.435421) (xy 79.911749 -94.441521)
			(xy 79.965706 -94.455627) (xy 80.017035 -94.477439) (xy 80.064641 -94.506493) (xy 80.107509 -94.542168)
			(xy 80.144726 -94.583705) (xy 80.175499 -94.630218) (xy 80.199171 -94.680715) (xy 80.215239 -94.734122)
			(xy 80.223359 -94.789298) (xy 80.223868 -94.817184) (xy 80.223359 -94.84507) (xy 80.215239 -94.900246)
			(xy 80.199171 -94.953653) (xy 80.175499 -95.00415) (xy 80.144726 -95.050663) (xy 80.107509 -95.0922)
			(xy 80.064641 -95.127875) (xy 80.017035 -95.156929) (xy 79.965706 -95.178741) (xy 79.911749 -95.192847)
			(xy 79.856312 -95.198947) (xy 79.800578 -95.19691) (xy 79.745735 -95.18678) (xy 79.692951 -95.168773)
			(xy 79.643351 -95.143272) (xy 79.597993 -95.110821) (xy 79.557844 -95.072112) (xy 79.523758 -95.027969)
			(xy 79.496462 -94.979334) (xy 79.476539 -94.927243) (xy 79.464413 -94.872806) (xy 79.460342 -94.817184)
			(xy 71.739252 -94.817184) (xy 71.739252 -95.7834) (xy 71.769478 -95.813372) (xy 71.77786 -95.822262)
			(xy 71.891398 -95.9358) (xy 72.5678 -95.9358) (xy 72.611996 -95.979996) (xy 72.69226 -95.91929) (xy 72.68067 -95.897824)
			(xy 72.662431 -95.852579) (xy 72.650104 -95.805378) (xy 72.643889 -95.756992) (xy 72.643492 -95.7326)
			(xy 72.643978 -95.705349) (xy 72.651734 -95.651401) (xy 72.667089 -95.599106) (xy 72.689731 -95.549529)
			(xy 72.719197 -95.503679) (xy 72.754888 -95.462488) (xy 72.796079 -95.426797) (xy 72.841929 -95.397331)
			(xy 72.891506 -95.374689) (xy 72.943801 -95.359334) (xy 72.997749 -95.351578) (xy 73.052251 -95.351578)
			(xy 73.106199 -95.359334) (xy 73.158494 -95.374689) (xy 73.208071 -95.397331) (xy 73.253921 -95.426797)
			(xy 73.295112 -95.462488) (xy 73.330803 -95.503679) (xy 73.360269 -95.549529) (xy 73.382911 -95.599106)
			(xy 73.398266 -95.651401) (xy 73.406022 -95.705349) (xy 73.406022 -95.759851) (xy 73.398266 -95.813799)
			(xy 73.382911 -95.866094) (xy 73.360269 -95.915671) (xy 73.330803 -95.961521) (xy 73.295112 -96.002712)
			(xy 73.253921 -96.038403) (xy 73.208071 -96.067869) (xy 73.158494 -96.090511) (xy 73.106199 -96.105866)
			(xy 73.052251 -96.113622) (xy 73.025 -96.114108) (xy 72.993384 -96.113431) (xy 72.931022 -96.102974)
			(xy 72.871231 -96.082395) (xy 72.843136 -96.06788) (xy 72.829671 -96.061488) (xy 72.800389 -96.055997)
			(xy 72.770768 -96.059187) (xy 72.743325 -96.070785) (xy 72.720395 -96.089806) (xy 72.703926 -96.114632)
			(xy 72.695318 -96.143154) (xy 72.6948 -96.15805) (xy 72.6948 -97.0534) (xy 77.976982 -97.0534) (xy 77.981053 -96.997778)
			(xy 77.993179 -96.943341) (xy 78.013102 -96.89125) (xy 78.040398 -96.842615) (xy 78.074484 -96.798472)
			(xy 78.114633 -96.759763) (xy 78.159991 -96.727312) (xy 78.209591 -96.701811) (xy 78.262375 -96.683804)
			(xy 78.317218 -96.673674) (xy 78.372952 -96.671637) (xy 78.428389 -96.677737) (xy 78.482346 -96.691843)
			(xy 78.533675 -96.713655) (xy 78.581281 -96.742709) (xy 78.624149 -96.778384) (xy 78.661366 -96.819921)
			(xy 78.692139 -96.866434) (xy 78.715811 -96.916931) (xy 78.731879 -96.970338) (xy 78.739999 -97.025514)
			(xy 78.740508 -97.0534) (xy 78.739999 -97.081286) (xy 78.731879 -97.136462) (xy 78.715811 -97.189869)
			(xy 78.692139 -97.240366) (xy 78.661366 -97.286879) (xy 78.624149 -97.328416) (xy 78.581281 -97.364091)
			(xy 78.533675 -97.393145) (xy 78.482346 -97.414957) (xy 78.428389 -97.429063) (xy 78.372952 -97.435163)
			(xy 78.317218 -97.433126) (xy 78.262375 -97.422996) (xy 78.209591 -97.404989) (xy 78.159991 -97.379488)
			(xy 78.114633 -97.347037) (xy 78.074484 -97.308328) (xy 78.040398 -97.264185) (xy 78.013102 -97.21555)
			(xy 77.993179 -97.163459) (xy 77.981053 -97.109022) (xy 77.976982 -97.0534) (xy 72.6948 -97.0534)
			(xy 72.6948 -97.325688) (xy 73.025 -97.655888)
		)
		(stroke
			(width 0)
			(type solid)
		)
		(fill yes)
		(layer "In7.Cu")
		(net "P1V8_AUX")
	)
	(gr_poly
		(pts
			(xy 50.60061 -65.331086) (xy 50.607412 -65.303304) (xy 50.628205 -65.250022) (xy 50.656719 -65.20044)
			(xy 50.692313 -65.155669) (xy 50.734191 -65.116712) (xy 50.781414 -65.084442) (xy 50.832924 -65.059582)
			(xy 50.887569 -65.042688) (xy 50.944122 -65.03414) (xy 50.97272 -65.033652) (xy 50.984658 -65.033906)
			(xy 50.998269 -65.03392) (xy 51.024732 -65.027598) (xy 51.048583 -65.014507) (xy 51.068127 -64.995578)
			(xy 51.081974 -64.972158) (xy 51.08914 -64.94591) (xy 51.08956 -64.932306) (xy 51.08956 -64.287146)
			(xy 48.930814 -62.1284) (xy 48.930814 -60.464954) (xy 48.930268 -60.449452) (xy 48.920965 -60.419877)
			(xy 48.903201 -60.394466) (xy 48.878621 -60.375569) (xy 48.849498 -60.364935) (xy 48.83404 -60.363608)
			(xy 48.811258 -60.373219) (xy 48.763709 -60.38678) (xy 48.714744 -60.393656) (xy 48.690022 -60.394088)
			(xy 48.677576 -60.393834) (xy 48.66513 -60.394088) (xy 48.664622 -60.394088) (xy 48.637971 -60.393616)
			(xy 48.585265 -60.385675) (xy 48.534331 -60.369967) (xy 48.486307 -60.346842) (xy 48.442266 -60.316818)
			(xy 48.403192 -60.280565) (xy 48.369958 -60.238894) (xy 48.343306 -60.192734) (xy 48.323833 -60.143117)
			(xy 48.311971 -60.091152) (xy 48.307988 -60.038) (xy 48.311971 -59.984848) (xy 48.323833 -59.932883)
			(xy 48.343306 -59.883266) (xy 48.369958 -59.837106) (xy 48.403192 -59.795435) (xy 48.442266 -59.759182)
			(xy 48.486307 -59.729158) (xy 48.534331 -59.706033) (xy 48.585265 -59.690325) (xy 48.637971 -59.682384)
			(xy 48.664622 -59.681872) (xy 48.678084 -59.682126) (xy 48.690022 -59.681872) (xy 48.701198 -59.682126)
			(xy 48.715428 -59.680198) (xy 48.742059 -59.669487) (xy 48.764659 -59.651791) (xy 48.781444 -59.628506)
			(xy 48.791089 -59.601471) (xy 48.792833 -59.57282) (xy 48.786539 -59.544815) (xy 48.772702 -59.519667)
			(xy 48.76292 -59.509152) (xy 48.562006 -59.308238) (xy 48.562006 -56.996838) (xy 48.561465 -56.981771)
			(xy 48.55267 -56.952951) (xy 48.535836 -56.927959) (xy 48.512434 -56.908977) (xy 48.484506 -56.897663)
			(xy 48.46955 -56.895746) (xy 48.445213 -56.893073) (xy 48.397651 -56.881468) (xy 48.352319 -56.862975)
			(xy 48.31021 -56.838) (xy 48.272245 -56.807089) (xy 48.239253 -56.770916) (xy 48.211956 -56.730274)
			(xy 48.190951 -56.686051) (xy 48.176696 -56.639214) (xy 48.169505 -56.590787) (xy 48.169068 -56.566308)
			(xy 48.169577 -56.54032) (xy 48.177706 -56.488983) (xy 48.193766 -56.43955) (xy 48.217361 -56.393237)
			(xy 48.247911 -56.351186) (xy 48.284662 -56.314431) (xy 48.32671 -56.283878) (xy 48.37302 -56.260279)
			(xy 48.422452 -56.244214) (xy 48.473788 -56.236079) (xy 48.499776 -56.2356) (xy 48.518093 -56.235861)
			(xy 48.554499 -56.239934) (xy 48.57242 -56.243728) (xy 48.599598 -56.249824) (xy 48.699674 -56.149494)
			(xy 48.70637 -56.142058) (xy 48.713959 -56.123566) (xy 48.713908 -56.103577) (xy 48.706224 -56.085124)
			(xy 48.692072 -56.071006) (xy 48.673601 -56.063367) (xy 48.663606 -56.06288) (xy 48.646842 -56.06288)
			(xy 48.636682 -56.067452) (xy 48.615084 -56.076812) (xy 48.569905 -56.090028) (xy 48.523312 -56.096722)
			(xy 48.499776 -56.09717) (xy 48.494442 -56.09717) (xy 48.468726 -56.096272) (xy 48.418026 -56.087496)
			(xy 48.369298 -56.070973) (xy 48.323716 -56.047104) (xy 48.28238 -56.016462) (xy 48.24629 -55.979789)
			(xy 48.216314 -55.937968) (xy 48.193177 -55.89201) (xy 48.177437 -55.843023) (xy 48.169474 -55.792189)
			(xy 48.169068 -55.766462) (xy 48.16958 -55.740476) (xy 48.177715 -55.689145) (xy 48.19378 -55.639718)
			(xy 48.217377 -55.593412) (xy 48.247927 -55.551367) (xy 48.284678 -55.514618) (xy 48.326724 -55.48407)
			(xy 48.373031 -55.460474) (xy 48.422458 -55.444412) (xy 48.47379 -55.436279) (xy 48.499776 -55.435754)
			(xy 48.512526 -55.435844) (xy 48.537955 -55.437747) (xy 48.550576 -55.439564) (xy 48.57595 -55.443997)
			(xy 48.62501 -55.459689) (xy 48.671042 -55.482799) (xy 48.712934 -55.512767) (xy 48.749673 -55.548869)
			(xy 48.780368 -55.590231) (xy 48.804279 -55.635853) (xy 48.820825 -55.684631) (xy 48.829607 -55.735385)
			(xy 48.830484 -55.761128) (xy 48.830484 -55.763922) (xy 48.830484 -55.766462) (xy 48.830073 -55.79061)
			(xy 48.823049 -55.838391) (xy 48.809132 -55.884637) (xy 48.799242 -55.90667) (xy 48.794416 -55.917084)
			(xy 48.794416 -55.97906) (xy 48.8823 -55.97906) (xy 48.897757 -55.978531) (xy 48.927263 -55.969307)
			(xy 48.952655 -55.951675) (xy 48.971605 -55.927252) (xy 48.982377 -55.898275) (xy 48.983982 -55.867404)
			(xy 48.980598 -55.852314) (xy 48.975366 -55.831621) (xy 48.969636 -55.789325) (xy 48.969168 -55.767986)
			(xy 48.969168 -55.763414) (xy 48.969904 -55.737584) (xy 48.97841 -55.686616) (xy 48.99474 -55.637592)
			(xy 49.018495 -55.591704) (xy 49.049098 -55.550069) (xy 49.085803 -55.5137) (xy 49.127719 -55.483482)
			(xy 49.173824 -55.460151) (xy 49.222996 -55.444274) (xy 49.27404 -55.436238) (xy 49.325712 -55.436238)
			(xy 49.376756 -55.444274) (xy 49.425928 -55.460151) (xy 49.472033 -55.483482) (xy 49.513949 -55.5137)
			(xy 49.550654 -55.550069) (xy 49.581257 -55.591704) (xy 49.605012 -55.637592) (xy 49.621342 -55.686616)
			(xy 49.629848 -55.737584) (xy 49.630584 -55.763414) (xy 49.630584 -55.766716) (xy 49.630232 -55.788303)
			(xy 49.624623 -55.83111) (xy 49.619408 -55.85206) (xy 49.619154 -55.852822) (xy 49.6189 -55.853838)
			(xy 49.61584 -55.868843) (xy 49.617844 -55.899389) (xy 49.628801 -55.927971) (xy 49.647729 -55.952028)
			(xy 49.672932 -55.969403) (xy 49.702148 -55.978537) (xy 49.717452 -55.97906) (xy 49.805082 -55.97906)
			(xy 49.805082 -55.917084) (xy 49.800256 -55.90667) (xy 49.790422 -55.884616) (xy 49.776527 -55.838374)
			(xy 49.769485 -55.790604) (xy 49.769014 -55.766462) (xy 49.769014 -55.761382) (xy 49.769895 -55.735653)
			(xy 49.778641 -55.684924) (xy 49.795143 -55.636162) (xy 49.819 -55.590546) (xy 49.849637 -55.549178)
			(xy 49.886314 -55.513056) (xy 49.928144 -55.483053) (xy 49.974119 -55.459893) (xy 50.023126 -55.444137)
			(xy 50.073983 -55.436164) (xy 50.099722 -55.435754) (xy 50.125709 -55.436265) (xy 50.177043 -55.444398)
			(xy 50.226473 -55.460461) (xy 50.272782 -55.484057) (xy 50.314831 -55.514607) (xy 50.351583 -55.551357)
			(xy 50.382135 -55.593404) (xy 50.405733 -55.639712) (xy 50.421798 -55.689141) (xy 50.429934 -55.740475)
			(xy 50.43043 -55.766462) (xy 50.430314 -55.779022) (xy 50.42841 -55.804068) (xy 50.42662 -55.8165)
			(xy 50.42281 -55.8419) (xy 50.476912 -55.896002) (xy 50.570384 -55.80253) (xy 50.569368 -55.780178)
			(xy 50.569114 -55.766462) (xy 50.569626 -55.740477) (xy 50.577762 -55.689149) (xy 50.593826 -55.639725)
			(xy 50.617425 -55.593422) (xy 50.647975 -55.551381) (xy 50.684727 -55.514636) (xy 50.726773 -55.484093)
			(xy 50.77308 -55.460503) (xy 50.822507 -55.444448) (xy 50.873837 -55.436322) (xy 50.899822 -55.435754)
			(xy 50.913538 -55.436008) (xy 50.93589 -55.437024) (xy 51.34102 -55.03164) (xy 52.23002 -55.03164)
			(xy 52.645564 -54.615842) (xy 52.645564 -53.711348) (xy 52.709826 -53.64734) (xy 52.709826 -53.647086)
			(xy 52.778152 -53.57876) (xy 52.89677 -53.460396) (xy 52.912518 -53.460396) (xy 52.97043 -53.402484)
			(xy 52.969414 -53.380132) (xy 52.96916 -53.366416) (xy 52.969668 -53.340427) (xy 52.977797 -53.289089)
			(xy 52.993856 -53.239654) (xy 53.01745 -53.19334) (xy 53.047999 -53.151287) (xy 53.08475 -53.114531)
			(xy 53.126799 -53.083975) (xy 53.17311 -53.060374) (xy 53.222542 -53.044308) (xy 53.273879 -53.036172)
			(xy 53.299868 -53.035708) (xy 53.325096 -53.036189) (xy 53.374965 -53.043861) (xy 53.42309 -53.059018)
			(xy 53.468356 -53.081308) (xy 53.509711 -53.110214) (xy 53.546197 -53.145064) (xy 53.561996 -53.16474)
			(xy 53.837586 -53.16474) (xy 53.853349 -53.145033) (xy 53.889839 -53.110177) (xy 53.9312 -53.081268)
			(xy 53.976473 -53.058978) (xy 54.024606 -53.043825) (xy 54.074483 -53.036159) (xy 54.124945 -53.036159)
			(xy 54.174822 -53.043825) (xy 54.222955 -53.058978) (xy 54.268228 -53.081268) (xy 54.309589 -53.110177)
			(xy 54.346079 -53.145033) (xy 54.361842 -53.16474) (xy 55.1434 -53.16474) (xy 55.480966 -52.827174)
			(xy 55.447692 -52.79136) (xy 55.431221 -52.77291) (xy 55.40338 -52.732034) (xy 55.381939 -52.687467)
			(xy 55.367374 -52.640204) (xy 55.360012 -52.591298) (xy 55.359554 -52.56657) (xy 55.360066 -52.540583)
			(xy 55.3682 -52.48925) (xy 55.384263 -52.439821) (xy 55.40786 -52.393513) (xy 55.438409 -52.351466)
			(xy 55.47516 -52.314715) (xy 55.517206 -52.284164) (xy 55.563514 -52.260566) (xy 55.612942 -52.244502)
			(xy 55.664275 -52.236366) (xy 55.690262 -52.235862) (xy 55.703461 -52.235966) (xy 55.729781 -52.238001)
			(xy 55.74284 -52.239926) (xy 55.749698 -52.241196) (xy 55.772682 -52.245809) (xy 55.817142 -52.260666)
			(xy 55.859055 -52.281662) (xy 55.897576 -52.308375) (xy 55.915052 -52.324) (xy 55.950866 -52.357274)
			(xy 57.089802 -51.218338) (xy 59.28487 -51.218338) (xy 59.298872 -51.217899) (xy 59.325823 -51.210296)
			(xy 59.349694 -51.195655) (xy 59.368686 -51.175076) (xy 59.381371 -51.150111) (xy 59.386793 -51.122638)
			(xy 59.384544 -51.094725) (xy 59.38012 -51.081432) (xy 59.378596 -51.077368) (xy 59.369743 -51.050803)
			(xy 59.360168 -50.995635) (xy 59.359546 -50.96764) (xy 59.359546 -50.962306) (xy 59.360359 -50.936531)
			(xy 59.368993 -50.885692) (xy 59.385415 -50.836811) (xy 59.409225 -50.79107) (xy 59.439847 -50.74958)
			(xy 59.476538 -50.713347) (xy 59.518409 -50.683248) (xy 59.564444 -50.660013) (xy 59.613528 -50.644206)
			(xy 59.664471 -50.63621) (xy 59.690254 -50.635662) (xy 59.716246 -50.636142) (xy 59.767592 -50.644267)
			(xy 59.817035 -50.660325) (xy 59.863357 -50.68392) (xy 59.905417 -50.714471) (xy 59.94218 -50.751225)
			(xy 59.972741 -50.793278) (xy 59.996346 -50.839595) (xy 60.012415 -50.889034) (xy 60.020552 -50.940378)
			(xy 60.020962 -50.96637) (xy 60.020708 -50.980086) (xy 60.020546 -50.993647) (xy 60.026546 -51.020086)
			(xy 60.039301 -51.044008) (xy 60.05791 -51.063724) (xy 60.081056 -51.07784) (xy 60.107104 -51.085356)
			(xy 60.134212 -51.085743) (xy 60.160464 -51.078973) (xy 60.184003 -51.065524) (xy 60.193936 -51.056286)
			(xy 60.976002 -50.27422) (xy 60.969144 -50.24628) (xy 60.965632 -50.231378) (xy 60.961055 -50.201102)
			(xy 60.96 -50.185828) (xy 60.959492 -50.166524) (xy 60.959984 -50.140738) (xy 60.967985 -50.089792)
			(xy 60.983798 -50.040705) (xy 61.007039 -49.994668) (xy 61.037144 -49.952796) (xy 61.073385 -49.916105)
			(xy 61.114881 -49.885485) (xy 61.160627 -49.861677) (xy 61.209515 -49.845258) (xy 61.260359 -49.836628)
			(xy 61.286136 -49.835816) (xy 61.290454 -49.835816) (xy 61.318978 -49.836438) (xy 61.375172 -49.846277)
			(xy 61.402214 -49.855374) (xy 61.410596 -49.858422) (xy 61.96076 -49.858422) (xy 61.978032 -49.855374)
			(xy 62.004148 -49.846535) (xy 62.058393 -49.83668) (xy 62.11352 -49.835955) (xy 62.140846 -49.839626)
			(xy 62.154732 -49.841966) (xy 62.182074 -49.848704) (xy 62.195456 -49.853088) (xy 62.202568 -49.855374)
			(xy 62.210696 -49.858422) (xy 62.760606 -49.858422) (xy 62.777878 -49.855374) (xy 62.803995 -49.846539)
			(xy 62.858238 -49.836691) (xy 62.913364 -49.835973) (xy 62.940692 -49.839626) (xy 62.954577 -49.841967)
			(xy 62.981919 -49.84871) (xy 62.995302 -49.853088) (xy 63.002414 -49.855374) (xy 63.010542 -49.858422)
			(xy 63.560706 -49.858422) (xy 63.577978 -49.855374) (xy 63.604095 -49.846539) (xy 63.658338 -49.836691)
			(xy 63.713464 -49.835973) (xy 63.740792 -49.839626) (xy 63.754677 -49.841967) (xy 63.782019 -49.84871)
			(xy 63.795402 -49.853088) (xy 63.802514 -49.855374) (xy 63.810642 -49.858422) (xy 64.360552 -49.858422)
			(xy 64.377824 -49.855374) (xy 64.40394 -49.846535) (xy 64.458185 -49.836678) (xy 64.513312 -49.835951)
			(xy 64.540638 -49.839626) (xy 64.554524 -49.841965) (xy 64.581867 -49.848703) (xy 64.595248 -49.853088)
			(xy 64.60236 -49.855374) (xy 64.610488 -49.858422) (xy 65.160652 -49.858422) (xy 65.177924 -49.855374)
			(xy 65.20404 -49.846535) (xy 65.258285 -49.836678) (xy 65.313412 -49.835951) (xy 65.340738 -49.839626)
			(xy 65.354624 -49.841965) (xy 65.381967 -49.848703) (xy 65.395348 -49.853088) (xy 65.40246 -49.855374)
			(xy 65.410588 -49.858422) (xy 70.215506 -49.858422) (xy 70.227444 -49.87036) (xy 70.24497 -49.87036)
			(xy 70.689803 -50.315193) (xy 72.340472 -50.315193) (xy 72.340472 -50.263219) (xy 72.348602 -50.211884)
			(xy 72.364663 -50.162454) (xy 72.388259 -50.116144) (xy 72.418809 -50.074096) (xy 72.45556 -50.037345)
			(xy 72.497608 -50.006795) (xy 72.543918 -49.983199) (xy 72.593348 -49.967138) (xy 72.644683 -49.959008)
			(xy 72.696657 -49.959008) (xy 72.747992 -49.967138) (xy 72.797422 -49.983199) (xy 72.843732 -50.006795)
			(xy 72.88578 -50.037345) (xy 72.922531 -50.074096) (xy 72.953081 -50.116144) (xy 72.976677 -50.162454)
			(xy 72.992738 -50.211884) (xy 73.000868 -50.263219) (xy 73.001378 -50.289206) (xy 73.000868 -50.315193)
			(xy 73.140318 -50.315193) (xy 73.140318 -50.263219) (xy 73.148448 -50.211884) (xy 73.164509 -50.162454)
			(xy 73.188105 -50.116144) (xy 73.218655 -50.074096) (xy 73.255406 -50.037345) (xy 73.297454 -50.006795)
			(xy 73.343764 -49.983199) (xy 73.393194 -49.967138) (xy 73.444529 -49.959008) (xy 73.496503 -49.959008)
			(xy 73.547838 -49.967138) (xy 73.597268 -49.983199) (xy 73.643578 -50.006795) (xy 73.685626 -50.037345)
			(xy 73.722377 -50.074096) (xy 73.752927 -50.116144) (xy 73.776523 -50.162454) (xy 73.792584 -50.211884)
			(xy 73.800714 -50.263219) (xy 73.801129 -50.28438) (xy 73.928986 -50.28438) (xy 73.929491 -50.258728)
			(xy 73.937397 -50.208037) (xy 73.953032 -50.159174) (xy 73.976022 -50.11331) (xy 74.005815 -50.071544)
			(xy 74.041698 -50.034877) (xy 74.08281 -50.004187) (xy 74.105262 -49.991772) (xy 74.117132 -49.985107)
			(xy 74.13698 -49.966482) (xy 74.151193 -49.94327) (xy 74.158761 -49.917126) (xy 74.159143 -49.889911)
			(xy 74.152312 -49.863564) (xy 74.138755 -49.839963) (xy 74.119438 -49.820788) (xy 74.107802 -49.813718)
			(xy 74.086275 -49.801057) (xy 74.047014 -49.770189) (xy 74.012835 -49.733775) (xy 73.984512 -49.692641)
			(xy 73.962688 -49.647719) (xy 73.947859 -49.600029) (xy 73.940361 -49.550653) (xy 73.939908 -49.525682)
			(xy 73.940418 -49.499695) (xy 73.948548 -49.44836) (xy 73.964609 -49.39893) (xy 73.988205 -49.35262)
			(xy 74.018755 -49.310572) (xy 74.055506 -49.273821) (xy 74.097554 -49.243271) (xy 74.143864 -49.219675)
			(xy 74.193294 -49.203614) (xy 74.244629 -49.195484) (xy 74.296603 -49.195484) (xy 74.347938 -49.203614)
			(xy 74.397368 -49.219675) (xy 74.443678 -49.243271) (xy 74.485726 -49.273821) (xy 74.522477 -49.310572)
			(xy 74.553027 -49.35262) (xy 74.576623 -49.39893) (xy 74.592684 -49.44836) (xy 74.595023 -49.463131)
			(xy 74.703833 -49.463131) (xy 74.711962 -49.411785) (xy 74.728024 -49.362342) (xy 74.751622 -49.31602)
			(xy 74.782177 -49.27396) (xy 74.818935 -49.237199) (xy 74.860991 -49.20664) (xy 74.90731 -49.183037)
			(xy 74.956751 -49.16697) (xy 75.008098 -49.158836) (xy 75.060084 -49.158835) (xy 75.11143 -49.166966)
			(xy 75.160873 -49.18303) (xy 75.207193 -49.20663) (xy 75.249251 -49.237187) (xy 75.286011 -49.273946)
			(xy 75.316568 -49.316004) (xy 75.340169 -49.362324) (xy 75.356233 -49.411766) (xy 75.364365 -49.463113)
			(xy 75.364848 -49.489106) (xy 75.36434 -49.507648) (xy 75.364093 -49.522781) (xy 75.371249 -49.552164)
			(xy 75.386704 -49.578159) (xy 75.409101 -49.598481) (xy 75.436471 -49.611344) (xy 75.46641 -49.615618)
			(xy 75.481434 -49.61382) (xy 75.494114 -49.611934) (xy 75.51967 -49.609897) (xy 75.532488 -49.609756)
			(xy 75.558479 -49.610262) (xy 75.609821 -49.618392) (xy 75.65926 -49.634454) (xy 75.705576 -49.658053)
			(xy 75.718083 -49.667139) (xy 76.227168 -49.667139) (xy 76.227168 -49.613841) (xy 76.235111 -49.561137)
			(xy 76.250821 -49.510207) (xy 76.273947 -49.462186) (xy 76.303971 -49.418149) (xy 76.340223 -49.379078)
			(xy 76.381894 -49.345847) (xy 76.428052 -49.319198) (xy 76.477666 -49.299726) (xy 76.529628 -49.287866)
			(xy 76.582778 -49.283883) (xy 76.635928 -49.287866) (xy 76.68789 -49.299726) (xy 76.737504 -49.319198)
			(xy 76.783662 -49.345847) (xy 76.825333 -49.379078) (xy 76.861585 -49.418149) (xy 76.891609 -49.462186)
			(xy 76.914735 -49.510207) (xy 76.916242 -49.515093) (xy 77.903834 -49.515093) (xy 77.903834 -49.463119)
			(xy 77.911964 -49.411784) (xy 77.928025 -49.362354) (xy 77.951621 -49.316044) (xy 77.982171 -49.273996)
			(xy 78.018922 -49.237245) (xy 78.06097 -49.206695) (xy 78.10728 -49.183099) (xy 78.15671 -49.167038)
			(xy 78.208045 -49.158908) (xy 78.260019 -49.158908) (xy 78.311354 -49.167038) (xy 78.360784 -49.183099)
			(xy 78.407094 -49.206695) (xy 78.449142 -49.237245) (xy 78.485893 -49.273996) (xy 78.516443 -49.316044)
			(xy 78.540039 -49.362354) (xy 78.5561 -49.411784) (xy 78.56423 -49.463119) (xy 78.56474 -49.489106)
			(xy 78.56423 -49.515093) (xy 78.703934 -49.515093) (xy 78.703934 -49.463119) (xy 78.712064 -49.411784)
			(xy 78.728125 -49.362354) (xy 78.751721 -49.316044) (xy 78.782271 -49.273996) (xy 78.819022 -49.237245)
			(xy 78.86107 -49.206695) (xy 78.90738 -49.183099) (xy 78.95681 -49.167038) (xy 79.008145 -49.158908)
			(xy 79.060119 -49.158908) (xy 79.111454 -49.167038) (xy 79.160884 -49.183099) (xy 79.207194 -49.206695)
			(xy 79.249242 -49.237245) (xy 79.285993 -49.273996) (xy 79.316543 -49.316044) (xy 79.340139 -49.362354)
			(xy 79.3562 -49.411784) (xy 79.36433 -49.463119) (xy 79.36484 -49.489106) (xy 79.36433 -49.515093)
			(xy 79.50378 -49.515093) (xy 79.50378 -49.463119) (xy 79.51191 -49.411784) (xy 79.527971 -49.362354)
			(xy 79.551567 -49.316044) (xy 79.582117 -49.273996) (xy 79.618868 -49.237245) (xy 79.660916 -49.206695)
			(xy 79.707226 -49.183099) (xy 79.756656 -49.167038) (xy 79.807991 -49.158908) (xy 79.859965 -49.158908)
			(xy 79.9113 -49.167038) (xy 79.96073 -49.183099) (xy 80.00704 -49.206695) (xy 80.049088 -49.237245)
			(xy 80.085839 -49.273996) (xy 80.116389 -49.316044) (xy 80.139985 -49.362354) (xy 80.156046 -49.411784)
			(xy 80.164176 -49.463119) (xy 80.164686 -49.489106) (xy 80.164176 -49.515093) (xy 80.156046 -49.566428)
			(xy 80.15443 -49.571402) (xy 80.911698 -49.571402) (xy 80.915769 -49.51578) (xy 80.927895 -49.461343)
			(xy 80.947818 -49.409252) (xy 80.975114 -49.360617) (xy 81.0092 -49.316474) (xy 81.049349 -49.277765)
			(xy 81.094707 -49.245314) (xy 81.144307 -49.219813) (xy 81.197091 -49.201806) (xy 81.251934 -49.191676)
			(xy 81.307668 -49.189639) (xy 81.363105 -49.195739) (xy 81.417062 -49.209845) (xy 81.468391 -49.231657)
			(xy 81.515997 -49.260711) (xy 81.558865 -49.296386) (xy 81.596082 -49.337923) (xy 81.626855 -49.384436)
			(xy 81.650527 -49.434933) (xy 81.666595 -49.48834) (xy 81.674715 -49.543516) (xy 81.675224 -49.571402)
			(xy 81.674715 -49.599288) (xy 81.666595 -49.654464) (xy 81.650527 -49.707871) (xy 81.626855 -49.758368)
			(xy 81.596082 -49.804881) (xy 81.558865 -49.846418) (xy 81.515997 -49.882093) (xy 81.468391 -49.911147)
			(xy 81.417062 -49.932959) (xy 81.363105 -49.947065) (xy 81.307668 -49.953165) (xy 81.251934 -49.951128)
			(xy 81.197091 -49.940998) (xy 81.144307 -49.922991) (xy 81.094707 -49.89749) (xy 81.049349 -49.865039)
			(xy 81.0092 -49.82633) (xy 80.975114 -49.782187) (xy 80.947818 -49.733552) (xy 80.927895 -49.681461)
			(xy 80.915769 -49.627024) (xy 80.911698 -49.571402) (xy 80.15443 -49.571402) (xy 80.139985 -49.615858)
			(xy 80.116389 -49.662168) (xy 80.085839 -49.704216) (xy 80.049088 -49.740967) (xy 80.00704 -49.771517)
			(xy 79.96073 -49.795113) (xy 79.9113 -49.811174) (xy 79.859965 -49.819304) (xy 79.807991 -49.819304)
			(xy 79.756656 -49.811174) (xy 79.707226 -49.795113) (xy 79.660916 -49.771517) (xy 79.618868 -49.740967)
			(xy 79.582117 -49.704216) (xy 79.551567 -49.662168) (xy 79.527971 -49.615858) (xy 79.51191 -49.566428)
			(xy 79.50378 -49.515093) (xy 79.36433 -49.515093) (xy 79.3562 -49.566428) (xy 79.340139 -49.615858)
			(xy 79.316543 -49.662168) (xy 79.285993 -49.704216) (xy 79.249242 -49.740967) (xy 79.207194 -49.771517)
			(xy 79.160884 -49.795113) (xy 79.111454 -49.811174) (xy 79.060119 -49.819304) (xy 79.008145 -49.819304)
			(xy 78.95681 -49.811174) (xy 78.90738 -49.795113) (xy 78.86107 -49.771517) (xy 78.819022 -49.740967)
			(xy 78.782271 -49.704216) (xy 78.751721 -49.662168) (xy 78.728125 -49.615858) (xy 78.712064 -49.566428)
			(xy 78.703934 -49.515093) (xy 78.56423 -49.515093) (xy 78.5561 -49.566428) (xy 78.540039 -49.615858)
			(xy 78.516443 -49.662168) (xy 78.485893 -49.704216) (xy 78.449142 -49.740967) (xy 78.407094 -49.771517)
			(xy 78.360784 -49.795113) (xy 78.311354 -49.811174) (xy 78.260019 -49.819304) (xy 78.208045 -49.819304)
			(xy 78.15671 -49.811174) (xy 78.10728 -49.795113) (xy 78.06097 -49.771517) (xy 78.018922 -49.740967)
			(xy 77.982171 -49.704216) (xy 77.951621 -49.662168) (xy 77.928025 -49.615858) (xy 77.911964 -49.566428)
			(xy 77.903834 -49.515093) (xy 76.916242 -49.515093) (xy 76.930445 -49.561137) (xy 76.938388 -49.613841)
			(xy 76.938886 -49.64049) (xy 76.938388 -49.667139) (xy 76.930445 -49.719843) (xy 76.914735 -49.770773)
			(xy 76.891609 -49.818794) (xy 76.861585 -49.862831) (xy 76.825333 -49.901902) (xy 76.783662 -49.935133)
			(xy 76.737504 -49.961782) (xy 76.68789 -49.981254) (xy 76.635928 -49.993114) (xy 76.582778 -49.997098)
			(xy 76.529628 -49.993114) (xy 76.477666 -49.981254) (xy 76.428052 -49.961782) (xy 76.381894 -49.935133)
			(xy 76.340223 -49.901902) (xy 76.303971 -49.862831) (xy 76.273947 -49.818794) (xy 76.250821 -49.770773)
			(xy 76.235111 -49.719843) (xy 76.227168 -49.667139) (xy 75.718083 -49.667139) (xy 75.747631 -49.688606)
			(xy 75.784388 -49.725363) (xy 75.814943 -49.767417) (xy 75.838542 -49.813733) (xy 75.854606 -49.863171)
			(xy 75.862737 -49.914513) (xy 75.862736 -49.966495) (xy 75.854604 -50.017837) (xy 75.838539 -50.067274)
			(xy 75.814939 -50.11359) (xy 75.784383 -50.155643) (xy 75.747625 -50.192399) (xy 75.70557 -50.222951)
			(xy 75.659252 -50.246549) (xy 75.609814 -50.262609) (xy 75.558471 -50.270738) (xy 75.506489 -50.270735)
			(xy 75.455148 -50.2626) (xy 75.405711 -50.246533) (xy 75.359396 -50.22293) (xy 75.317344 -50.192373)
			(xy 75.280591 -50.155613) (xy 75.25004 -50.113556) (xy 75.226445 -50.067237) (xy 75.210387 -50.017798)
			(xy 75.20226 -49.966455) (xy 75.20178 -49.940464) (xy 75.202288 -49.921922) (xy 75.202645 -49.906786)
			(xy 75.195475 -49.877387) (xy 75.18 -49.851382) (xy 75.15758 -49.831058) (xy 75.130186 -49.818201)
			(xy 75.100226 -49.813942) (xy 75.085194 -49.81575) (xy 75.072515 -49.817644) (xy 75.046959 -49.819676)
			(xy 75.03414 -49.819814) (xy 75.008147 -49.819368) (xy 74.9568 -49.811241) (xy 74.907356 -49.795182)
			(xy 74.861033 -49.771586) (xy 74.818972 -49.741033) (xy 74.782209 -49.704277) (xy 74.751648 -49.662222)
			(xy 74.728043 -49.615904) (xy 74.711974 -49.566463) (xy 74.703837 -49.515118) (xy 74.703833 -49.463131)
			(xy 74.595023 -49.463131) (xy 74.600814 -49.499695) (xy 74.601324 -49.525682) (xy 74.600864 -49.551335)
			(xy 74.592949 -49.602028) (xy 74.577305 -49.650892) (xy 74.554308 -49.696756) (xy 74.524508 -49.738521)
			(xy 74.48862 -49.775187) (xy 74.447503 -49.805876) (xy 74.425048 -49.81829) (xy 74.413211 -49.825009)
			(xy 74.393365 -49.843624) (xy 74.37915 -49.866825) (xy 74.37158 -49.892961) (xy 74.371193 -49.920168)
			(xy 74.378017 -49.946508) (xy 74.391567 -49.970104) (xy 74.410876 -49.989275) (xy 74.422508 -49.996344)
			(xy 74.444021 -50.009028) (xy 74.483281 -50.039893) (xy 74.517461 -50.076303) (xy 74.545785 -50.117433)
			(xy 74.56761 -50.162351) (xy 74.582443 -50.210037) (xy 74.589946 -50.25941) (xy 74.590402 -50.28438)
			(xy 74.589892 -50.310367) (xy 74.583335 -50.351769) (xy 77.903834 -50.351769) (xy 77.903834 -50.299795)
			(xy 77.911964 -50.24846) (xy 77.928025 -50.19903) (xy 77.951621 -50.15272) (xy 77.982171 -50.110672)
			(xy 78.018922 -50.073921) (xy 78.06097 -50.043371) (xy 78.10728 -50.019775) (xy 78.15671 -50.003714)
			(xy 78.208045 -49.995584) (xy 78.260019 -49.995584) (xy 78.311354 -50.003714) (xy 78.360784 -50.019775)
			(xy 78.407094 -50.043371) (xy 78.449142 -50.073921) (xy 78.485893 -50.110672) (xy 78.516443 -50.15272)
			(xy 78.540039 -50.19903) (xy 78.5561 -50.24846) (xy 78.56423 -50.299795) (xy 78.564532 -50.315193)
			(xy 78.703934 -50.315193) (xy 78.703934 -50.263219) (xy 78.712064 -50.211884) (xy 78.728125 -50.162454)
			(xy 78.751721 -50.116144) (xy 78.782271 -50.074096) (xy 78.819022 -50.037345) (xy 78.86107 -50.006795)
			(xy 78.90738 -49.983199) (xy 78.95681 -49.967138) (xy 79.008145 -49.959008) (xy 79.060119 -49.959008)
			(xy 79.111454 -49.967138) (xy 79.160884 -49.983199) (xy 79.207194 -50.006795) (xy 79.249242 -50.037345)
			(xy 79.285993 -50.074096) (xy 79.316543 -50.116144) (xy 79.340139 -50.162454) (xy 79.3562 -50.211884)
			(xy 79.36433 -50.263219) (xy 79.36484 -50.289206) (xy 79.36433 -50.315193) (xy 79.50378 -50.315193)
			(xy 79.50378 -50.263219) (xy 79.51191 -50.211884) (xy 79.527971 -50.162454) (xy 79.551567 -50.116144)
			(xy 79.582117 -50.074096) (xy 79.618868 -50.037345) (xy 79.660916 -50.006795) (xy 79.707226 -49.983199)
			(xy 79.756656 -49.967138) (xy 79.807991 -49.959008) (xy 79.859965 -49.959008) (xy 79.9113 -49.967138)
			(xy 79.96073 -49.983199) (xy 80.00704 -50.006795) (xy 80.049088 -50.037345) (xy 80.049743 -50.038)
			(xy 85.237064 -50.038) (xy 85.241135 -49.982378) (xy 85.253261 -49.927941) (xy 85.273184 -49.87585)
			(xy 85.30048 -49.827215) (xy 85.334566 -49.783072) (xy 85.374715 -49.744363) (xy 85.420073 -49.711912)
			(xy 85.469673 -49.686411) (xy 85.522457 -49.668404) (xy 85.5773 -49.658274) (xy 85.633034 -49.656237)
			(xy 85.688471 -49.662337) (xy 85.742428 -49.676443) (xy 85.793757 -49.698255) (xy 85.841363 -49.727309)
			(xy 85.884231 -49.762984) (xy 85.921448 -49.804521) (xy 85.952221 -49.851034) (xy 85.975893 -49.901531)
			(xy 85.991961 -49.954938) (xy 86.000081 -50.010114) (xy 86.00059 -50.038) (xy 86.000081 -50.065886)
			(xy 85.991961 -50.121062) (xy 85.975893 -50.174469) (xy 85.952221 -50.224966) (xy 85.921448 -50.271479)
			(xy 85.884231 -50.313016) (xy 85.841363 -50.348691) (xy 85.793757 -50.377745) (xy 85.742428 -50.399557)
			(xy 85.688471 -50.413663) (xy 85.633034 -50.419763) (xy 85.5773 -50.417726) (xy 85.522457 -50.407596)
			(xy 85.469673 -50.389589) (xy 85.420073 -50.364088) (xy 85.374715 -50.331637) (xy 85.334566 -50.292928)
			(xy 85.30048 -50.248785) (xy 85.273184 -50.20015) (xy 85.253261 -50.148059) (xy 85.241135 -50.093622)
			(xy 85.237064 -50.038) (xy 80.049743 -50.038) (xy 80.085839 -50.074096) (xy 80.116389 -50.116144)
			(xy 80.139985 -50.162454) (xy 80.156046 -50.211884) (xy 80.164176 -50.263219) (xy 80.164686 -50.289206)
			(xy 80.164176 -50.315193) (xy 80.156046 -50.366528) (xy 80.139985 -50.415958) (xy 80.116389 -50.462268)
			(xy 80.085839 -50.504316) (xy 80.049088 -50.541067) (xy 80.00704 -50.571617) (xy 79.96073 -50.595213)
			(xy 79.9113 -50.611274) (xy 79.859965 -50.619404) (xy 79.807991 -50.619404) (xy 79.756656 -50.611274)
			(xy 79.707226 -50.595213) (xy 79.660916 -50.571617) (xy 79.618868 -50.541067) (xy 79.582117 -50.504316)
			(xy 79.551567 -50.462268) (xy 79.527971 -50.415958) (xy 79.51191 -50.366528) (xy 79.50378 -50.315193)
			(xy 79.36433 -50.315193) (xy 79.3562 -50.366528) (xy 79.340139 -50.415958) (xy 79.316543 -50.462268)
			(xy 79.285993 -50.504316) (xy 79.249242 -50.541067) (xy 79.207194 -50.571617) (xy 79.160884 -50.595213)
			(xy 79.111454 -50.611274) (xy 79.060119 -50.619404) (xy 79.008145 -50.619404) (xy 78.95681 -50.611274)
			(xy 78.90738 -50.595213) (xy 78.86107 -50.571617) (xy 78.819022 -50.541067) (xy 78.782271 -50.504316)
			(xy 78.751721 -50.462268) (xy 78.728125 -50.415958) (xy 78.712064 -50.366528) (xy 78.703934 -50.315193)
			(xy 78.564532 -50.315193) (xy 78.56474 -50.325782) (xy 78.56423 -50.351769) (xy 78.5561 -50.403104)
			(xy 78.540039 -50.452534) (xy 78.516443 -50.498844) (xy 78.485893 -50.540892) (xy 78.449142 -50.577643)
			(xy 78.407094 -50.608193) (xy 78.360784 -50.631789) (xy 78.311354 -50.64785) (xy 78.260019 -50.65598)
			(xy 78.208045 -50.65598) (xy 78.15671 -50.64785) (xy 78.10728 -50.631789) (xy 78.06097 -50.608193)
			(xy 78.018922 -50.577643) (xy 77.982171 -50.540892) (xy 77.951621 -50.498844) (xy 77.928025 -50.452534)
			(xy 77.911964 -50.403104) (xy 77.903834 -50.351769) (xy 74.583335 -50.351769) (xy 74.581762 -50.361702)
			(xy 74.565701 -50.411132) (xy 74.542105 -50.457442) (xy 74.511555 -50.49949) (xy 74.474804 -50.536241)
			(xy 74.432756 -50.566791) (xy 74.386446 -50.590387) (xy 74.337016 -50.606448) (xy 74.285681 -50.614578)
			(xy 74.233707 -50.614578) (xy 74.182372 -50.606448) (xy 74.132942 -50.590387) (xy 74.086632 -50.566791)
			(xy 74.044584 -50.536241) (xy 74.007833 -50.49949) (xy 73.977283 -50.457442) (xy 73.953687 -50.411132)
			(xy 73.937626 -50.361702) (xy 73.929496 -50.310367) (xy 73.928986 -50.28438) (xy 73.801129 -50.28438)
			(xy 73.801224 -50.289206) (xy 73.800714 -50.315193) (xy 73.792584 -50.366528) (xy 73.776523 -50.415958)
			(xy 73.752927 -50.462268) (xy 73.722377 -50.504316) (xy 73.685626 -50.541067) (xy 73.643578 -50.571617)
			(xy 73.597268 -50.595213) (xy 73.547838 -50.611274) (xy 73.496503 -50.619404) (xy 73.444529 -50.619404)
			(xy 73.393194 -50.611274) (xy 73.343764 -50.595213) (xy 73.297454 -50.571617) (xy 73.255406 -50.541067)
			(xy 73.218655 -50.504316) (xy 73.188105 -50.462268) (xy 73.164509 -50.415958) (xy 73.148448 -50.366528)
			(xy 73.140318 -50.315193) (xy 73.000868 -50.315193) (xy 72.992738 -50.366528) (xy 72.976677 -50.415958)
			(xy 72.953081 -50.462268) (xy 72.922531 -50.504316) (xy 72.88578 -50.541067) (xy 72.843732 -50.571617)
			(xy 72.797422 -50.595213) (xy 72.747992 -50.611274) (xy 72.696657 -50.619404) (xy 72.644683 -50.619404)
			(xy 72.593348 -50.611274) (xy 72.543918 -50.595213) (xy 72.497608 -50.571617) (xy 72.45556 -50.541067)
			(xy 72.418809 -50.504316) (xy 72.388259 -50.462268) (xy 72.364663 -50.415958) (xy 72.348602 -50.366528)
			(xy 72.340472 -50.315193) (xy 70.689803 -50.315193) (xy 71.489903 -51.115293) (xy 72.340472 -51.115293)
			(xy 72.340472 -51.063319) (xy 72.348602 -51.011984) (xy 72.364663 -50.962554) (xy 72.388259 -50.916244)
			(xy 72.418809 -50.874196) (xy 72.45556 -50.837445) (xy 72.497608 -50.806895) (xy 72.543918 -50.783299)
			(xy 72.593348 -50.767238) (xy 72.644683 -50.759108) (xy 72.696657 -50.759108) (xy 72.747992 -50.767238)
			(xy 72.797422 -50.783299) (xy 72.843732 -50.806895) (xy 72.88578 -50.837445) (xy 72.922531 -50.874196)
			(xy 72.953081 -50.916244) (xy 72.976677 -50.962554) (xy 72.992738 -51.011984) (xy 73.000868 -51.063319)
			(xy 73.001378 -51.089306) (xy 73.000868 -51.115293) (xy 73.140318 -51.115293) (xy 73.140318 -51.063319)
			(xy 73.148448 -51.011984) (xy 73.164509 -50.962554) (xy 73.188105 -50.916244) (xy 73.218655 -50.874196)
			(xy 73.255406 -50.837445) (xy 73.297454 -50.806895) (xy 73.343764 -50.783299) (xy 73.393194 -50.767238)
			(xy 73.444529 -50.759108) (xy 73.496503 -50.759108) (xy 73.547838 -50.767238) (xy 73.597268 -50.783299)
			(xy 73.643578 -50.806895) (xy 73.685626 -50.837445) (xy 73.722377 -50.874196) (xy 73.752927 -50.916244)
			(xy 73.776523 -50.962554) (xy 73.792584 -51.011984) (xy 73.800714 -51.063319) (xy 73.801224 -51.089306)
			(xy 73.800714 -51.115293) (xy 73.794962 -51.151615) (xy 73.940418 -51.151615) (xy 73.940418 -51.099641)
			(xy 73.948548 -51.048306) (xy 73.964609 -50.998876) (xy 73.988205 -50.952566) (xy 74.018755 -50.910518)
			(xy 74.055506 -50.873767) (xy 74.097554 -50.843217) (xy 74.143864 -50.819621) (xy 74.193294 -50.80356)
			(xy 74.244629 -50.79543) (xy 74.296603 -50.79543) (xy 74.347938 -50.80356) (xy 74.397368 -50.819621)
			(xy 74.443678 -50.843217) (xy 74.485726 -50.873767) (xy 74.522477 -50.910518) (xy 74.553027 -50.952566)
			(xy 74.576623 -50.998876) (xy 74.592684 -51.048306) (xy 74.600814 -51.099641) (xy 74.601324 -51.125628)
			(xy 74.600814 -51.151615) (xy 74.598722 -51.164823) (xy 75.78522 -51.164823) (xy 75.78522 -51.112849)
			(xy 75.79335 -51.061514) (xy 75.809411 -51.012084) (xy 75.833007 -50.965774) (xy 75.863557 -50.923726)
			(xy 75.900308 -50.886975) (xy 75.942356 -50.856425) (xy 75.988666 -50.832829) (xy 76.038096 -50.816768)
			(xy 76.089431 -50.808638) (xy 76.141405 -50.808638) (xy 76.19274 -50.816768) (xy 76.24217 -50.832829)
			(xy 76.28848 -50.856425) (xy 76.330528 -50.886975) (xy 76.367279 -50.923726) (xy 76.397829 -50.965774)
			(xy 76.421425 -51.012084) (xy 76.437486 -51.061514) (xy 76.445616 -51.112849) (xy 76.445664 -51.115293)
			(xy 78.703934 -51.115293) (xy 78.703934 -51.063319) (xy 78.712064 -51.011984) (xy 78.728125 -50.962554)
			(xy 78.751721 -50.916244) (xy 78.782271 -50.874196) (xy 78.819022 -50.837445) (xy 78.86107 -50.806895)
			(xy 78.90738 -50.783299) (xy 78.95681 -50.767238) (xy 79.008145 -50.759108) (xy 79.060119 -50.759108)
			(xy 79.111454 -50.767238) (xy 79.160884 -50.783299) (xy 79.207194 -50.806895) (xy 79.249242 -50.837445)
			(xy 79.285993 -50.874196) (xy 79.316543 -50.916244) (xy 79.340139 -50.962554) (xy 79.3562 -51.011984)
			(xy 79.36433 -51.063319) (xy 79.36484 -51.089306) (xy 79.36433 -51.115293) (xy 79.50378 -51.115293)
			(xy 79.50378 -51.063319) (xy 79.51191 -51.011984) (xy 79.527971 -50.962554) (xy 79.551567 -50.916244)
			(xy 79.582117 -50.874196) (xy 79.618868 -50.837445) (xy 79.660916 -50.806895) (xy 79.707226 -50.783299)
			(xy 79.756656 -50.767238) (xy 79.807991 -50.759108) (xy 79.859965 -50.759108) (xy 79.9113 -50.767238)
			(xy 79.96073 -50.783299) (xy 80.00704 -50.806895) (xy 80.049088 -50.837445) (xy 80.085839 -50.874196)
			(xy 80.116389 -50.916244) (xy 80.139985 -50.962554) (xy 80.156046 -51.011984) (xy 80.164176 -51.063319)
			(xy 80.164686 -51.089306) (xy 80.164681 -51.08956) (xy 80.797146 -51.08956) (xy 80.797615 -51.060789)
			(xy 80.806243 -51.003898) (xy 80.823313 -50.948946) (xy 80.848438 -50.89718) (xy 80.881048 -50.849771)
			(xy 80.920405 -50.807794) (xy 80.942688 -50.789586) (xy 80.953994 -50.780153) (xy 80.97103 -50.756151)
			(xy 80.980494 -50.72828) (xy 80.981595 -50.698867) (xy 80.974243 -50.670367) (xy 80.967072 -50.657506)
			(xy 80.954061 -50.635105) (xy 80.933544 -50.587537) (xy 80.919652 -50.537631) (xy 80.912642 -50.486304)
			(xy 80.912208 -50.460402) (xy 80.912694 -50.433151) (xy 80.92045 -50.379203) (xy 80.935805 -50.326908)
			(xy 80.958447 -50.277331) (xy 80.987913 -50.231481) (xy 81.023604 -50.19029) (xy 81.064795 -50.154599)
			(xy 81.110645 -50.125133) (xy 81.160222 -50.102491) (xy 81.212517 -50.087136) (xy 81.266465 -50.07938)
			(xy 81.320967 -50.07938) (xy 81.374915 -50.087136) (xy 81.42721 -50.102491) (xy 81.476787 -50.125133)
			(xy 81.522637 -50.154599) (xy 81.563828 -50.19029) (xy 81.599519 -50.231481) (xy 81.628985 -50.277331)
			(xy 81.651627 -50.326908) (xy 81.666982 -50.379203) (xy 81.674738 -50.433151) (xy 81.675224 -50.460402)
			(xy 81.674701 -50.489171) (xy 81.666081 -50.546058) (xy 81.64902 -50.601007) (xy 81.623905 -50.652774)
			(xy 81.591305 -50.700184) (xy 81.551959 -50.742165) (xy 81.529682 -50.760376) (xy 81.518405 -50.76984)
			(xy 81.501371 -50.793834) (xy 81.491905 -50.821695) (xy 81.490795 -50.8511) (xy 81.498134 -50.879595)
			(xy 81.505298 -50.892456) (xy 81.518291 -50.914867) (xy 81.538813 -50.962431) (xy 81.55271 -51.012334)
			(xy 81.559725 -51.063659) (xy 81.560162 -51.08956) (xy 81.559676 -51.116811) (xy 81.55192 -51.170759)
			(xy 81.550032 -51.17719) (xy 82.608164 -51.17719) (xy 82.612235 -51.121568) (xy 82.624361 -51.067131)
			(xy 82.644284 -51.01504) (xy 82.67158 -50.966405) (xy 82.705666 -50.922262) (xy 82.745815 -50.883553)
			(xy 82.791173 -50.851102) (xy 82.840773 -50.825601) (xy 82.893557 -50.807594) (xy 82.9484 -50.797464)
			(xy 83.004134 -50.795427) (xy 83.059571 -50.801527) (xy 83.113528 -50.815633) (xy 83.164857 -50.837445)
			(xy 83.212463 -50.866499) (xy 83.255331 -50.902174) (xy 83.292548 -50.943711) (xy 83.323321 -50.990224)
			(xy 83.346993 -51.040721) (xy 83.363061 -51.094128) (xy 83.371181 -51.149304) (xy 83.37169 -51.17719)
			(xy 83.371181 -51.205076) (xy 83.363061 -51.260252) (xy 83.346993 -51.313659) (xy 83.336191 -51.336702)
			(xy 85.216998 -51.336702) (xy 85.221069 -51.28108) (xy 85.233195 -51.226643) (xy 85.253118 -51.174552)
			(xy 85.280414 -51.125917) (xy 85.3145 -51.081774) (xy 85.354649 -51.043065) (xy 85.400007 -51.010614)
			(xy 85.449607 -50.985113) (xy 85.502391 -50.967106) (xy 85.557234 -50.956976) (xy 85.612968 -50.954939)
			(xy 85.668405 -50.961039) (xy 85.722362 -50.975145) (xy 85.773691 -50.996957) (xy 85.821297 -51.026011)
			(xy 85.864165 -51.061686) (xy 85.901382 -51.103223) (xy 85.932155 -51.149736) (xy 85.955827 -51.200233)
			(xy 85.971895 -51.25364) (xy 85.980015 -51.308816) (xy 85.980524 -51.336702) (xy 85.980015 -51.364588)
			(xy 85.971895 -51.419764) (xy 85.955827 -51.473171) (xy 85.932155 -51.523668) (xy 85.901382 -51.570181)
			(xy 85.864165 -51.611718) (xy 85.821297 -51.647393) (xy 85.773691 -51.676447) (xy 85.722362 -51.698259)
			(xy 85.668405 -51.712365) (xy 85.612968 -51.718465) (xy 85.557234 -51.716428) (xy 85.502391 -51.706298)
			(xy 85.449607 -51.688291) (xy 85.400007 -51.66279) (xy 85.354649 -51.630339) (xy 85.3145 -51.59163)
			(xy 85.280414 -51.547487) (xy 85.253118 -51.498852) (xy 85.233195 -51.446761) (xy 85.221069 -51.392324)
			(xy 85.216998 -51.336702) (xy 83.336191 -51.336702) (xy 83.323321 -51.364156) (xy 83.292548 -51.410669)
			(xy 83.255331 -51.452206) (xy 83.212463 -51.487881) (xy 83.164857 -51.516935) (xy 83.113528 -51.538747)
			(xy 83.059571 -51.552853) (xy 83.004134 -51.558953) (xy 82.9484 -51.556916) (xy 82.893557 -51.546786)
			(xy 82.840773 -51.528779) (xy 82.791173 -51.503278) (xy 82.745815 -51.470827) (xy 82.705666 -51.432118)
			(xy 82.67158 -51.387975) (xy 82.644284 -51.33934) (xy 82.624361 -51.287249) (xy 82.612235 -51.232812)
			(xy 82.608164 -51.17719) (xy 81.550032 -51.17719) (xy 81.536565 -51.223054) (xy 81.513923 -51.272631)
			(xy 81.484457 -51.318481) (xy 81.448766 -51.359672) (xy 81.407575 -51.395363) (xy 81.361725 -51.424829)
			(xy 81.312148 -51.447471) (xy 81.259853 -51.462826) (xy 81.205905 -51.470582) (xy 81.151403 -51.470582)
			(xy 81.097455 -51.462826) (xy 81.04516 -51.447471) (xy 80.995583 -51.424829) (xy 80.949733 -51.395363)
			(xy 80.908542 -51.359672) (xy 80.872851 -51.318481) (xy 80.843385 -51.272631) (xy 80.820743 -51.223054)
			(xy 80.805388 -51.170759) (xy 80.797632 -51.116811) (xy 80.797146 -51.08956) (xy 80.164681 -51.08956)
			(xy 80.164176 -51.115293) (xy 80.156046 -51.166628) (xy 80.139985 -51.216058) (xy 80.116389 -51.262368)
			(xy 80.085839 -51.304416) (xy 80.049088 -51.341167) (xy 80.00704 -51.371717) (xy 79.96073 -51.395313)
			(xy 79.9113 -51.411374) (xy 79.859965 -51.419504) (xy 79.807991 -51.419504) (xy 79.756656 -51.411374)
			(xy 79.707226 -51.395313) (xy 79.660916 -51.371717) (xy 79.618868 -51.341167) (xy 79.582117 -51.304416)
			(xy 79.551567 -51.262368) (xy 79.527971 -51.216058) (xy 79.51191 -51.166628) (xy 79.50378 -51.115293)
			(xy 79.36433 -51.115293) (xy 79.3562 -51.166628) (xy 79.340139 -51.216058) (xy 79.316543 -51.262368)
			(xy 79.285993 -51.304416) (xy 79.249242 -51.341167) (xy 79.207194 -51.371717) (xy 79.160884 -51.395313)
			(xy 79.111454 -51.411374) (xy 79.060119 -51.419504) (xy 79.008145 -51.419504) (xy 78.95681 -51.411374)
			(xy 78.90738 -51.395313) (xy 78.86107 -51.371717) (xy 78.819022 -51.341167) (xy 78.782271 -51.304416)
			(xy 78.751721 -51.262368) (xy 78.728125 -51.216058) (xy 78.712064 -51.166628) (xy 78.703934 -51.115293)
			(xy 76.445664 -51.115293) (xy 76.446126 -51.138836) (xy 76.445616 -51.164823) (xy 76.437486 -51.216158)
			(xy 76.421425 -51.265588) (xy 76.397829 -51.311898) (xy 76.367279 -51.353946) (xy 76.330528 -51.390697)
			(xy 76.28848 -51.421247) (xy 76.24217 -51.444843) (xy 76.19274 -51.460904) (xy 76.141405 -51.469034)
			(xy 76.089431 -51.469034) (xy 76.038096 -51.460904) (xy 75.988666 -51.444843) (xy 75.942356 -51.421247)
			(xy 75.900308 -51.390697) (xy 75.863557 -51.353946) (xy 75.833007 -51.311898) (xy 75.809411 -51.265588)
			(xy 75.79335 -51.216158) (xy 75.78522 -51.164823) (xy 74.598722 -51.164823) (xy 74.592684 -51.20295)
			(xy 74.576623 -51.25238) (xy 74.553027 -51.29869) (xy 74.522477 -51.340738) (xy 74.485726 -51.377489)
			(xy 74.443678 -51.408039) (xy 74.397368 -51.431635) (xy 74.347938 -51.447696) (xy 74.296603 -51.455826)
			(xy 74.244629 -51.455826) (xy 74.193294 -51.447696) (xy 74.143864 -51.431635) (xy 74.097554 -51.408039)
			(xy 74.055506 -51.377489) (xy 74.018755 -51.340738) (xy 73.988205 -51.29869) (xy 73.964609 -51.25238)
			(xy 73.948548 -51.20295) (xy 73.940418 -51.151615) (xy 73.794962 -51.151615) (xy 73.792584 -51.166628)
			(xy 73.776523 -51.216058) (xy 73.752927 -51.262368) (xy 73.722377 -51.304416) (xy 73.685626 -51.341167)
			(xy 73.643578 -51.371717) (xy 73.597268 -51.395313) (xy 73.547838 -51.411374) (xy 73.496503 -51.419504)
			(xy 73.444529 -51.419504) (xy 73.393194 -51.411374) (xy 73.343764 -51.395313) (xy 73.297454 -51.371717)
			(xy 73.255406 -51.341167) (xy 73.218655 -51.304416) (xy 73.188105 -51.262368) (xy 73.164509 -51.216058)
			(xy 73.148448 -51.166628) (xy 73.140318 -51.115293) (xy 73.000868 -51.115293) (xy 72.992738 -51.166628)
			(xy 72.976677 -51.216058) (xy 72.953081 -51.262368) (xy 72.922531 -51.304416) (xy 72.88578 -51.341167)
			(xy 72.843732 -51.371717) (xy 72.797422 -51.395313) (xy 72.747992 -51.411374) (xy 72.696657 -51.419504)
			(xy 72.644683 -51.419504) (xy 72.593348 -51.411374) (xy 72.543918 -51.395313) (xy 72.497608 -51.371717)
			(xy 72.45556 -51.341167) (xy 72.418809 -51.304416) (xy 72.388259 -51.262368) (xy 72.364663 -51.216058)
			(xy 72.348602 -51.166628) (xy 72.340472 -51.115293) (xy 71.489903 -51.115293) (xy 72.191372 -51.816762)
			(xy 72.202086 -51.826798) (xy 72.227875 -51.840802) (xy 72.256582 -51.846892) (xy 72.285835 -51.844566)
			(xy 72.313219 -51.834017) (xy 72.336471 -51.816114) (xy 72.353671 -51.792338) (xy 72.359012 -51.778662)
			(xy 72.367952 -51.754842) (xy 72.392094 -51.710057) (xy 72.422808 -51.669498) (xy 72.45937 -51.634118)
			(xy 72.500918 -51.604754) (xy 72.546472 -51.582098) (xy 72.594958 -51.566683) (xy 72.645232 -51.558874)
			(xy 72.67067 -51.558444) (xy 72.696306 -51.558932) (xy 72.746962 -51.566857) (xy 72.795787 -51.582506)
			(xy 72.841612 -51.605504) (xy 72.883338 -51.6353) (xy 72.919964 -51.67118) (xy 72.950613 -51.712283)
			(xy 72.963024 -51.73472) (xy 72.969768 -51.746568) (xy 72.988409 -51.766449) (xy 73.011645 -51.78069)
			(xy 73.03782 -51.788276) (xy 73.06507 -51.788668) (xy 73.091453 -51.781837) (xy 73.115089 -51.76827)
			(xy 73.134293 -51.748934) (xy 73.141332 -51.73726) (xy 73.154016 -51.715765) (xy 73.184839 -51.676512)
			(xy 73.221207 -51.642334) (xy 73.262296 -51.614006) (xy 73.307174 -51.59217) (xy 73.354822 -51.577321)
			(xy 73.40416 -51.569798) (xy 73.429114 -51.569366) (xy 73.455103 -51.569877) (xy 73.506439 -51.57801)
			(xy 73.555872 -51.594073) (xy 73.602183 -51.617672) (xy 73.644233 -51.648224) (xy 73.680985 -51.684978)
			(xy 73.711536 -51.727029) (xy 73.735132 -51.773341) (xy 73.751194 -51.822774) (xy 73.759324 -51.874111)
			(xy 73.759324 -51.926089) (xy 73.755266 -51.951715) (xy 77.14031 -51.951715) (xy 77.14031 -51.899741)
			(xy 77.14844 -51.848406) (xy 77.164501 -51.798976) (xy 77.188097 -51.752666) (xy 77.218647 -51.710618)
			(xy 77.255398 -51.673867) (xy 77.297446 -51.643317) (xy 77.343756 -51.619721) (xy 77.393186 -51.60366)
			(xy 77.444521 -51.59553) (xy 77.496495 -51.59553) (xy 77.54783 -51.60366) (xy 77.59726 -51.619721)
			(xy 77.64357 -51.643317) (xy 77.685618 -51.673867) (xy 77.722369 -51.710618) (xy 77.752919 -51.752666)
			(xy 77.776515 -51.798976) (xy 77.792576 -51.848406) (xy 77.800706 -51.899741) (xy 77.801216 -51.925728)
			(xy 77.800706 -51.951715) (xy 77.94041 -51.951715) (xy 77.94041 -51.899741) (xy 77.94854 -51.848406)
			(xy 77.964601 -51.798976) (xy 77.988197 -51.752666) (xy 78.018747 -51.710618) (xy 78.055498 -51.673867)
			(xy 78.097546 -51.643317) (xy 78.143856 -51.619721) (xy 78.193286 -51.60366) (xy 78.244621 -51.59553)
			(xy 78.296595 -51.59553) (xy 78.34793 -51.60366) (xy 78.39736 -51.619721) (xy 78.44367 -51.643317)
			(xy 78.485718 -51.673867) (xy 78.522469 -51.710618) (xy 78.553019 -51.752666) (xy 78.576615 -51.798976)
			(xy 78.592676 -51.848406) (xy 78.600806 -51.899741) (xy 78.601108 -51.915139) (xy 78.703934 -51.915139)
			(xy 78.703934 -51.863165) (xy 78.712064 -51.81183) (xy 78.728125 -51.7624) (xy 78.751721 -51.71609)
			(xy 78.782271 -51.674042) (xy 78.819022 -51.637291) (xy 78.86107 -51.606741) (xy 78.90738 -51.583145)
			(xy 78.95681 -51.567084) (xy 79.008145 -51.558954) (xy 79.060119 -51.558954) (xy 79.111454 -51.567084)
			(xy 79.160884 -51.583145) (xy 79.207194 -51.606741) (xy 79.249242 -51.637291) (xy 79.285993 -51.674042)
			(xy 79.316543 -51.71609) (xy 79.340139 -51.7624) (xy 79.3562 -51.81183) (xy 79.36433 -51.863165)
			(xy 79.36484 -51.889152) (xy 79.36433 -51.915139) (xy 79.50378 -51.915139) (xy 79.50378 -51.863165)
			(xy 79.51191 -51.81183) (xy 79.527971 -51.7624) (xy 79.551567 -51.71609) (xy 79.582117 -51.674042)
			(xy 79.618868 -51.637291) (xy 79.660916 -51.606741) (xy 79.707226 -51.583145) (xy 79.756656 -51.567084)
			(xy 79.807991 -51.558954) (xy 79.859965 -51.558954) (xy 79.9113 -51.567084) (xy 79.96073 -51.583145)
			(xy 80.00704 -51.606741) (xy 80.049088 -51.637291) (xy 80.085839 -51.674042) (xy 80.116389 -51.71609)
			(xy 80.139985 -51.7624) (xy 80.156046 -51.81183) (xy 80.164176 -51.863165) (xy 80.164686 -51.889152)
			(xy 80.164176 -51.915139) (xy 80.156046 -51.966474) (xy 80.139985 -52.015904) (xy 80.116389 -52.062214)
			(xy 80.085839 -52.104262) (xy 80.049088 -52.141013) (xy 80.00704 -52.171563) (xy 79.96073 -52.195159)
			(xy 79.9113 -52.21122) (xy 79.859965 -52.21935) (xy 79.807991 -52.21935) (xy 79.756656 -52.21122)
			(xy 79.707226 -52.195159) (xy 79.660916 -52.171563) (xy 79.618868 -52.141013) (xy 79.582117 -52.104262)
			(xy 79.551567 -52.062214) (xy 79.527971 -52.015904) (xy 79.51191 -51.966474) (xy 79.50378 -51.915139)
			(xy 79.36433 -51.915139) (xy 79.3562 -51.966474) (xy 79.340139 -52.015904) (xy 79.316543 -52.062214)
			(xy 79.285993 -52.104262) (xy 79.249242 -52.141013) (xy 79.207194 -52.171563) (xy 79.160884 -52.195159)
			(xy 79.111454 -52.21122) (xy 79.060119 -52.21935) (xy 79.008145 -52.21935) (xy 78.95681 -52.21122)
			(xy 78.90738 -52.195159) (xy 78.86107 -52.171563) (xy 78.819022 -52.141013) (xy 78.782271 -52.104262)
			(xy 78.751721 -52.062214) (xy 78.728125 -52.015904) (xy 78.712064 -51.966474) (xy 78.703934 -51.915139)
			(xy 78.601108 -51.915139) (xy 78.601316 -51.925728) (xy 78.600806 -51.951715) (xy 78.592676 -52.00305)
			(xy 78.576615 -52.05248) (xy 78.553019 -52.09879) (xy 78.522469 -52.140838) (xy 78.485718 -52.177589)
			(xy 78.44367 -52.208139) (xy 78.39736 -52.231735) (xy 78.359644 -52.24399) (xy 82.65871 -52.24399)
			(xy 82.662781 -52.188368) (xy 82.674907 -52.133931) (xy 82.69483 -52.08184) (xy 82.722126 -52.033205)
			(xy 82.756212 -51.989062) (xy 82.796361 -51.950353) (xy 82.841719 -51.917902) (xy 82.891319 -51.892401)
			(xy 82.944103 -51.874394) (xy 82.998946 -51.864264) (xy 83.05468 -51.862227) (xy 83.110117 -51.868327)
			(xy 83.164074 -51.882433) (xy 83.215403 -51.904245) (xy 83.263009 -51.933299) (xy 83.305877 -51.968974)
			(xy 83.343094 -52.010511) (xy 83.373867 -52.057024) (xy 83.397539 -52.107521) (xy 83.413607 -52.160928)
			(xy 83.421727 -52.216104) (xy 83.422236 -52.24399) (xy 83.421727 -52.271876) (xy 83.413607 -52.327052)
			(xy 83.40589 -52.352702) (xy 85.216998 -52.352702) (xy 85.221069 -52.29708) (xy 85.233195 -52.242643)
			(xy 85.253118 -52.190552) (xy 85.280414 -52.141917) (xy 85.3145 -52.097774) (xy 85.354649 -52.059065)
			(xy 85.400007 -52.026614) (xy 85.449607 -52.001113) (xy 85.502391 -51.983106) (xy 85.557234 -51.972976)
			(xy 85.612968 -51.970939) (xy 85.668405 -51.977039) (xy 85.722362 -51.991145) (xy 85.773691 -52.012957)
			(xy 85.821297 -52.042011) (xy 85.864165 -52.077686) (xy 85.901382 -52.119223) (xy 85.932155 -52.165736)
			(xy 85.955827 -52.216233) (xy 85.971895 -52.26964) (xy 85.980015 -52.324816) (xy 85.980524 -52.352702)
			(xy 85.980015 -52.380588) (xy 85.971895 -52.435764) (xy 85.955827 -52.489171) (xy 85.932155 -52.539668)
			(xy 85.901382 -52.586181) (xy 85.864165 -52.627718) (xy 85.821297 -52.663393) (xy 85.773691 -52.692447)
			(xy 85.722362 -52.714259) (xy 85.668405 -52.728365) (xy 85.612968 -52.734465) (xy 85.557234 -52.732428)
			(xy 85.502391 -52.722298) (xy 85.449607 -52.704291) (xy 85.400007 -52.67879) (xy 85.354649 -52.646339)
			(xy 85.3145 -52.60763) (xy 85.280414 -52.563487) (xy 85.253118 -52.514852) (xy 85.233195 -52.462761)
			(xy 85.221069 -52.408324) (xy 85.216998 -52.352702) (xy 83.40589 -52.352702) (xy 83.397539 -52.380459)
			(xy 83.373867 -52.430956) (xy 83.343094 -52.477469) (xy 83.305877 -52.519006) (xy 83.263009 -52.554681)
			(xy 83.215403 -52.583735) (xy 83.164074 -52.605547) (xy 83.110117 -52.619653) (xy 83.05468 -52.625753)
			(xy 82.998946 -52.623716) (xy 82.944103 -52.613586) (xy 82.891319 -52.595579) (xy 82.841719 -52.570078)
			(xy 82.796361 -52.537627) (xy 82.756212 -52.498918) (xy 82.722126 -52.454775) (xy 82.69483 -52.40614)
			(xy 82.674907 -52.354049) (xy 82.662781 -52.299612) (xy 82.65871 -52.24399) (xy 78.359644 -52.24399)
			(xy 78.34793 -52.247796) (xy 78.296595 -52.255926) (xy 78.244621 -52.255926) (xy 78.193286 -52.247796)
			(xy 78.143856 -52.231735) (xy 78.097546 -52.208139) (xy 78.055498 -52.177589) (xy 78.018747 -52.140838)
			(xy 77.988197 -52.09879) (xy 77.964601 -52.05248) (xy 77.94854 -52.00305) (xy 77.94041 -51.951715)
			(xy 77.800706 -51.951715) (xy 77.792576 -52.00305) (xy 77.776515 -52.05248) (xy 77.752919 -52.09879)
			(xy 77.722369 -52.140838) (xy 77.685618 -52.177589) (xy 77.64357 -52.208139) (xy 77.59726 -52.231735)
			(xy 77.54783 -52.247796) (xy 77.496495 -52.255926) (xy 77.444521 -52.255926) (xy 77.393186 -52.247796)
			(xy 77.343756 -52.231735) (xy 77.297446 -52.208139) (xy 77.255398 -52.177589) (xy 77.218647 -52.140838)
			(xy 77.188097 -52.09879) (xy 77.164501 -52.05248) (xy 77.14844 -52.00305) (xy 77.14031 -51.951715)
			(xy 73.755266 -51.951715) (xy 73.751194 -51.977426) (xy 73.735132 -52.026859) (xy 73.711536 -52.073171)
			(xy 73.680985 -52.115222) (xy 73.644233 -52.151976) (xy 73.602183 -52.182528) (xy 73.555872 -52.206127)
			(xy 73.506439 -52.22219) (xy 73.455103 -52.230323) (xy 73.429114 -52.230782) (xy 73.403478 -52.230293)
			(xy 73.352823 -52.222367) (xy 73.303998 -52.206716) (xy 73.258174 -52.183718) (xy 73.216449 -52.153923)
			(xy 73.179822 -52.118044) (xy 73.149172 -52.076943) (xy 73.13676 -52.054506) (xy 73.130018 -52.042657)
			(xy 73.11138 -52.022776) (xy 73.088146 -52.008535) (xy 73.061971 -52.000949) (xy 73.034723 -52.000559)
			(xy 73.008342 -52.007393) (xy 72.98471 -52.020964) (xy 72.965511 -52.040304) (xy 72.958452 -52.051966)
			(xy 72.946449 -52.07236) (xy 72.917514 -52.109805) (xy 72.883537 -52.142743) (xy 72.845213 -52.170502)
			(xy 72.803323 -52.192516) (xy 72.78116 -52.20081) (xy 72.767485 -52.206149) (xy 72.743727 -52.22337)
			(xy 72.725836 -52.246629) (xy 72.715288 -52.274012) (xy 72.71295 -52.303262) (xy 72.719015 -52.331972)
			(xy 72.732984 -52.357778) (xy 72.74306 -52.36845) (xy 73.089849 -52.715239) (xy 77.903834 -52.715239)
			(xy 77.903834 -52.663265) (xy 77.911964 -52.61193) (xy 77.928025 -52.5625) (xy 77.951621 -52.51619)
			(xy 77.982171 -52.474142) (xy 78.018922 -52.437391) (xy 78.06097 -52.406841) (xy 78.10728 -52.383245)
			(xy 78.15671 -52.367184) (xy 78.208045 -52.359054) (xy 78.260019 -52.359054) (xy 78.311354 -52.367184)
			(xy 78.360784 -52.383245) (xy 78.407094 -52.406841) (xy 78.449142 -52.437391) (xy 78.485893 -52.474142)
			(xy 78.516443 -52.51619) (xy 78.540039 -52.5625) (xy 78.5561 -52.61193) (xy 78.56423 -52.663265)
			(xy 78.56474 -52.689252) (xy 78.56423 -52.715239) (xy 79.50378 -52.715239) (xy 79.50378 -52.663265)
			(xy 79.51191 -52.61193) (xy 79.527971 -52.5625) (xy 79.551567 -52.51619) (xy 79.582117 -52.474142)
			(xy 79.618868 -52.437391) (xy 79.660916 -52.406841) (xy 79.707226 -52.383245) (xy 79.756656 -52.367184)
			(xy 79.807991 -52.359054) (xy 79.859965 -52.359054) (xy 79.9113 -52.367184) (xy 79.96073 -52.383245)
			(xy 80.00704 -52.406841) (xy 80.049088 -52.437391) (xy 80.085839 -52.474142) (xy 80.116389 -52.51619)
			(xy 80.139985 -52.5625) (xy 80.156046 -52.61193) (xy 80.164176 -52.663265) (xy 80.164686 -52.689252)
			(xy 80.164176 -52.715239) (xy 80.156046 -52.766574) (xy 80.139985 -52.816004) (xy 80.116389 -52.862314)
			(xy 80.085839 -52.904362) (xy 80.049088 -52.941113) (xy 80.00704 -52.971663) (xy 79.96073 -52.995259)
			(xy 79.9113 -53.01132) (xy 79.859965 -53.01945) (xy 79.807991 -53.01945) (xy 79.756656 -53.01132)
			(xy 79.707226 -52.995259) (xy 79.660916 -52.971663) (xy 79.618868 -52.941113) (xy 79.582117 -52.904362)
			(xy 79.551567 -52.862314) (xy 79.527971 -52.816004) (xy 79.51191 -52.766574) (xy 79.50378 -52.715239)
			(xy 78.56423 -52.715239) (xy 78.5561 -52.766574) (xy 78.540039 -52.816004) (xy 78.516443 -52.862314)
			(xy 78.485893 -52.904362) (xy 78.449142 -52.941113) (xy 78.407094 -52.971663) (xy 78.360784 -52.995259)
			(xy 78.311354 -53.01132) (xy 78.260019 -53.01945) (xy 78.208045 -53.01945) (xy 78.15671 -53.01132)
			(xy 78.10728 -52.995259) (xy 78.06097 -52.971663) (xy 78.018922 -52.941113) (xy 77.982171 -52.904362)
			(xy 77.951621 -52.862314) (xy 77.928025 -52.816004) (xy 77.911964 -52.766574) (xy 77.903834 -52.715239)
			(xy 73.089849 -52.715239) (xy 73.540112 -53.165502) (xy 73.553574 -53.169058) (xy 73.577767 -53.175821)
			(xy 73.62392 -53.195651) (xy 73.666543 -53.222234) (xy 73.704654 -53.254959) (xy 73.737376 -53.293071)
			(xy 73.763957 -53.335695) (xy 73.783785 -53.381849) (xy 73.790556 -53.40604) (xy 73.794112 -53.419502)
			(xy 73.891648 -53.517038) (xy 73.940162 -53.468524) (xy 73.942194 -53.450998) (xy 73.945794 -53.424488)
			(xy 73.960442 -53.373034) (xy 73.983178 -53.324609) (xy 74.01341 -53.280472) (xy 74.05035 -53.241776)
			(xy 74.093036 -53.209528) (xy 74.140354 -53.184568) (xy 74.191072 -53.167548) (xy 74.243867 -53.15891)
			(xy 74.270616 -53.15839) (xy 74.296602 -53.158901) (xy 74.347935 -53.167033) (xy 74.397364 -53.183096)
			(xy 74.443671 -53.206692) (xy 74.485717 -53.237242) (xy 74.522467 -53.273993) (xy 74.553015 -53.316041)
			(xy 74.57661 -53.362349) (xy 74.59267 -53.411779) (xy 74.6008 -53.463112) (xy 74.601324 -53.489098)
			(xy 74.600831 -53.515085) (xy 74.703942 -53.515085) (xy 74.703942 -53.463111) (xy 74.712072 -53.411776)
			(xy 74.728133 -53.362346) (xy 74.751729 -53.316036) (xy 74.782279 -53.273988) (xy 74.81903 -53.237237)
			(xy 74.861078 -53.206687) (xy 74.907388 -53.183091) (xy 74.956818 -53.16703) (xy 75.008153 -53.1589)
			(xy 75.060127 -53.1589) (xy 75.111462 -53.16703) (xy 75.160892 -53.183091) (xy 75.207202 -53.206687)
			(xy 75.24925 -53.237237) (xy 75.286001 -53.273988) (xy 75.316551 -53.316036) (xy 75.340147 -53.362346)
			(xy 75.356208 -53.411776) (xy 75.364338 -53.463111) (xy 75.36481 -53.487145) (xy 75.543158 -53.487145)
			(xy 75.543158 -53.435171) (xy 75.551288 -53.383836) (xy 75.567349 -53.334406) (xy 75.590945 -53.288096)
			(xy 75.621495 -53.246048) (xy 75.658246 -53.209297) (xy 75.700294 -53.178747) (xy 75.746604 -53.155151)
			(xy 75.796034 -53.13909) (xy 75.847369 -53.13096) (xy 75.899343 -53.13096) (xy 75.950678 -53.13909)
			(xy 76.000108 -53.155151) (xy 76.046418 -53.178747) (xy 76.088466 -53.209297) (xy 76.125217 -53.246048)
			(xy 76.155767 -53.288096) (xy 76.179363 -53.334406) (xy 76.195424 -53.383836) (xy 76.203554 -53.435171)
			(xy 76.204064 -53.461158) (xy 76.203554 -53.487145) (xy 76.195424 -53.53848) (xy 76.179363 -53.58791)
			(xy 76.155767 -53.63422) (xy 76.125217 -53.676268) (xy 76.088466 -53.713019) (xy 76.046418 -53.743569)
			(xy 76.000108 -53.767165) (xy 75.950678 -53.783226) (xy 75.899343 -53.791356) (xy 75.847369 -53.791356)
			(xy 75.796034 -53.783226) (xy 75.746604 -53.767165) (xy 75.700294 -53.743569) (xy 75.658246 -53.713019)
			(xy 75.621495 -53.676268) (xy 75.590945 -53.63422) (xy 75.567349 -53.58791) (xy 75.551288 -53.53848)
			(xy 75.543158 -53.487145) (xy 75.36481 -53.487145) (xy 75.364848 -53.489098) (xy 75.364338 -53.515085)
			(xy 75.356208 -53.56642) (xy 75.340147 -53.61585) (xy 75.316551 -53.66216) (xy 75.286001 -53.704208)
			(xy 75.24925 -53.740959) (xy 75.207202 -53.771509) (xy 75.160892 -53.795105) (xy 75.111462 -53.811166)
			(xy 75.060127 -53.819296) (xy 75.008153 -53.819296) (xy 74.956818 -53.811166) (xy 74.907388 -53.795105)
			(xy 74.861078 -53.771509) (xy 74.81903 -53.740959) (xy 74.782279 -53.704208) (xy 74.751729 -53.66216)
			(xy 74.728133 -53.61585) (xy 74.712072 -53.56642) (xy 74.703942 -53.515085) (xy 74.600831 -53.515085)
			(xy 74.600816 -53.515853) (xy 74.592213 -53.568666) (xy 74.575214 -53.619404) (xy 74.550264 -53.666741)
			(xy 74.518015 -53.70944) (xy 74.479309 -53.746387) (xy 74.435156 -53.776616) (xy 74.38671 -53.799338)
			(xy 74.335237 -53.81396) (xy 74.308716 -53.81752) (xy 74.29119 -53.819552) (xy 74.242676 -53.868066)
			(xy 74.340212 -53.965602) (xy 74.353674 -53.969158) (xy 74.377867 -53.975921) (xy 74.42402 -53.995751)
			(xy 74.457539 -54.016656) (xy 76.870052 -54.016656) (xy 76.870531 -53.991269) (xy 76.878298 -53.941092)
			(xy 76.893642 -53.892691) (xy 76.916203 -53.847205) (xy 76.94545 -53.8057) (xy 76.980698 -53.769153)
			(xy 77.021116 -53.738423) (xy 77.065757 -53.714231) (xy 77.089508 -53.705252) (xy 77.103819 -53.699596)
			(xy 77.128401 -53.681108) (xy 77.146379 -53.656149) (xy 77.156127 -53.626975) (xy 77.156765 -53.596223)
			(xy 77.153008 -53.5813) (xy 77.146853 -53.558747) (xy 77.140222 -53.512472) (xy 77.1398 -53.489098)
			(xy 77.14031 -53.463111) (xy 77.14844 -53.411776) (xy 77.164501 -53.362346) (xy 77.188097 -53.316036)
			(xy 77.218647 -53.273988) (xy 77.255398 -53.237237) (xy 77.297446 -53.206687) (xy 77.343756 -53.183091)
			(xy 77.393186 -53.16703) (xy 77.444521 -53.1589) (xy 77.496495 -53.1589) (xy 77.54783 -53.16703)
			(xy 77.59726 -53.183091) (xy 77.64357 -53.206687) (xy 77.685618 -53.237237) (xy 77.722369 -53.273988)
			(xy 77.752919 -53.316036) (xy 77.776515 -53.362346) (xy 77.792576 -53.411776) (xy 77.800706 -53.463111)
			(xy 77.801216 -53.489098) (xy 77.800805 -53.514488) (xy 77.795045 -53.551661) (xy 77.903834 -53.551661)
			(xy 77.903834 -53.499687) (xy 77.911964 -53.448352) (xy 77.928025 -53.398922) (xy 77.951621 -53.352612)
			(xy 77.982171 -53.310564) (xy 78.018922 -53.273813) (xy 78.06097 -53.243263) (xy 78.10728 -53.219667)
			(xy 78.15671 -53.203606) (xy 78.208045 -53.195476) (xy 78.260019 -53.195476) (xy 78.311354 -53.203606)
			(xy 78.360784 -53.219667) (xy 78.407094 -53.243263) (xy 78.449142 -53.273813) (xy 78.485893 -53.310564)
			(xy 78.516443 -53.352612) (xy 78.540039 -53.398922) (xy 78.5561 -53.448352) (xy 78.56423 -53.499687)
			(xy 78.564532 -53.515085) (xy 78.703934 -53.515085) (xy 78.703934 -53.463111) (xy 78.712064 -53.411776)
			(xy 78.728125 -53.362346) (xy 78.751721 -53.316036) (xy 78.782271 -53.273988) (xy 78.819022 -53.237237)
			(xy 78.86107 -53.206687) (xy 78.90738 -53.183091) (xy 78.95681 -53.16703) (xy 79.008145 -53.1589)
			(xy 79.060119 -53.1589) (xy 79.111454 -53.16703) (xy 79.160884 -53.183091) (xy 79.207194 -53.206687)
			(xy 79.249242 -53.237237) (xy 79.285993 -53.273988) (xy 79.316543 -53.316036) (xy 79.340139 -53.362346)
			(xy 79.3562 -53.411776) (xy 79.36433 -53.463111) (xy 79.36484 -53.489098) (xy 79.36433 -53.515085)
			(xy 79.50378 -53.515085) (xy 79.50378 -53.463111) (xy 79.51191 -53.411776) (xy 79.527971 -53.362346)
			(xy 79.551567 -53.316036) (xy 79.582117 -53.273988) (xy 79.618868 -53.237237) (xy 79.660916 -53.206687)
			(xy 79.707226 -53.183091) (xy 79.756656 -53.16703) (xy 79.807991 -53.1589) (xy 79.859965 -53.1589)
			(xy 79.9113 -53.16703) (xy 79.96073 -53.183091) (xy 80.00704 -53.206687) (xy 80.049088 -53.237237)
			(xy 80.085839 -53.273988) (xy 80.116389 -53.316036) (xy 80.139985 -53.362346) (xy 80.156046 -53.411776)
			(xy 80.164176 -53.463111) (xy 80.164686 -53.489098) (xy 80.164176 -53.515085) (xy 80.156046 -53.56642)
			(xy 80.139985 -53.61585) (xy 80.116389 -53.66216) (xy 80.085839 -53.704208) (xy 80.049088 -53.740959)
			(xy 80.00704 -53.771509) (xy 79.96073 -53.795105) (xy 79.9113 -53.811166) (xy 79.859965 -53.819296)
			(xy 79.807991 -53.819296) (xy 79.756656 -53.811166) (xy 79.707226 -53.795105) (xy 79.660916 -53.771509)
			(xy 79.618868 -53.740959) (xy 79.582117 -53.704208) (xy 79.551567 -53.66216) (xy 79.527971 -53.61585)
			(xy 79.51191 -53.56642) (xy 79.50378 -53.515085) (xy 79.36433 -53.515085) (xy 79.3562 -53.56642)
			(xy 79.340139 -53.61585) (xy 79.316543 -53.66216) (xy 79.285993 -53.704208) (xy 79.249242 -53.740959)
			(xy 79.207194 -53.771509) (xy 79.160884 -53.795105) (xy 79.111454 -53.811166) (xy 79.060119 -53.819296)
			(xy 79.008145 -53.819296) (xy 78.95681 -53.811166) (xy 78.90738 -53.795105) (xy 78.86107 -53.771509)
			(xy 78.819022 -53.740959) (xy 78.782271 -53.704208) (xy 78.751721 -53.66216) (xy 78.728125 -53.61585)
			(xy 78.712064 -53.56642) (xy 78.703934 -53.515085) (xy 78.564532 -53.515085) (xy 78.56474 -53.525674)
			(xy 78.56423 -53.551661) (xy 78.5561 -53.602996) (xy 78.540039 -53.652426) (xy 78.516443 -53.698736)
			(xy 78.485893 -53.740784) (xy 78.449142 -53.777535) (xy 78.407094 -53.808085) (xy 78.360784 -53.831681)
			(xy 78.311354 -53.847742) (xy 78.260019 -53.855872) (xy 78.208045 -53.855872) (xy 78.15671 -53.847742)
			(xy 78.10728 -53.831681) (xy 78.06097 -53.808085) (xy 78.018922 -53.777535) (xy 77.982171 -53.740784)
			(xy 77.951621 -53.698736) (xy 77.928025 -53.652426) (xy 77.911964 -53.602996) (xy 77.903834 -53.551661)
			(xy 77.795045 -53.551661) (xy 77.793029 -53.564669) (xy 77.777676 -53.613072) (xy 77.755105 -53.65856)
			(xy 77.725848 -53.700065) (xy 77.690591 -53.73661) (xy 77.650164 -53.767338) (xy 77.605515 -53.791526)
			(xy 77.58176 -53.800502) (xy 77.567465 -53.806192) (xy 77.54289 -53.824676) (xy 77.524914 -53.849626)
			(xy 77.515161 -53.878789) (xy 77.514511 -53.909533) (xy 77.51826 -53.924454) (xy 77.524428 -53.947004)
			(xy 77.53105 -53.993282) (xy 77.531468 -54.016656) (xy 77.530958 -54.042643) (xy 77.522828 -54.093978)
			(xy 77.506767 -54.143408) (xy 77.483171 -54.189718) (xy 77.452621 -54.231766) (xy 77.41587 -54.268517)
			(xy 77.373822 -54.299067) (xy 77.327512 -54.322663) (xy 77.278082 -54.338724) (xy 77.226747 -54.346854)
			(xy 77.174773 -54.346854) (xy 77.123438 -54.338724) (xy 77.074008 -54.322663) (xy 77.027698 -54.299067)
			(xy 76.98565 -54.268517) (xy 76.948899 -54.231766) (xy 76.918349 -54.189718) (xy 76.894753 -54.143408)
			(xy 76.878692 -54.093978) (xy 76.870562 -54.042643) (xy 76.870052 -54.016656) (xy 74.457539 -54.016656)
			(xy 74.466643 -54.022334) (xy 74.504754 -54.055059) (xy 74.537476 -54.093171) (xy 74.564057 -54.135795)
			(xy 74.583885 -54.181949) (xy 74.590656 -54.20614) (xy 74.594212 -54.219602) (xy 74.8018 -54.42719)
			(xy 78.018587 -54.42719) (xy 78.018587 -54.37521) (xy 78.026719 -54.323869) (xy 78.042784 -54.274433)
			(xy 78.066384 -54.228119) (xy 78.096939 -54.186067) (xy 78.133697 -54.149313) (xy 78.175753 -54.118763)
			(xy 78.22207 -54.095168) (xy 78.271508 -54.07911) (xy 78.32285 -54.070984) (xy 78.34884 -54.070504)
			(xy 78.374341 -54.070995) (xy 78.424738 -54.07883) (xy 78.473335 -54.094307) (xy 78.518981 -54.11706)
			(xy 78.560593 -54.14655) (xy 78.579218 -54.163976) (xy 78.589257 -54.173111) (xy 78.612999 -54.18624)
			(xy 78.639364 -54.192639) (xy 78.666483 -54.191853) (xy 78.692434 -54.183939) (xy 78.715376 -54.169458)
			(xy 78.733683 -54.149435) (xy 78.740254 -54.13756) (xy 78.752522 -54.114782) (xy 78.783117 -54.073063)
			(xy 78.819836 -54.036616) (xy 78.861781 -54.006333) (xy 78.907931 -53.98295) (xy 78.957159 -53.967039)
			(xy 79.008264 -53.958988) (xy 79.034132 -53.95849) (xy 79.060117 -53.959006) (xy 79.111448 -53.96714)
			(xy 79.160874 -53.983204) (xy 79.207178 -54.006802) (xy 79.249222 -54.037352) (xy 79.285969 -54.074102)
			(xy 79.316515 -54.116149) (xy 79.340108 -54.162456) (xy 79.356167 -54.211883) (xy 79.364297 -54.263215)
			(xy 79.364297 -54.315185) (xy 79.50378 -54.315185) (xy 79.50378 -54.263211) (xy 79.51191 -54.211876)
			(xy 79.527971 -54.162446) (xy 79.551567 -54.116136) (xy 79.582117 -54.074088) (xy 79.618868 -54.037337)
			(xy 79.660916 -54.006787) (xy 79.707226 -53.983191) (xy 79.756656 -53.96713) (xy 79.807991 -53.959)
			(xy 79.859965 -53.959) (xy 79.9113 -53.96713) (xy 79.96073 -53.983191) (xy 80.00704 -54.006787) (xy 80.049088 -54.037337)
			(xy 80.085839 -54.074088) (xy 80.116389 -54.116136) (xy 80.139985 -54.162446) (xy 80.156046 -54.211876)
			(xy 80.164176 -54.263211) (xy 80.164686 -54.289198) (xy 80.164176 -54.315185) (xy 80.156046 -54.36652)
			(xy 80.139985 -54.41595) (xy 80.116389 -54.46226) (xy 80.085839 -54.504308) (xy 80.049088 -54.541059)
			(xy 80.00704 -54.571609) (xy 79.96073 -54.595205) (xy 79.9113 -54.611266) (xy 79.859965 -54.619396)
			(xy 79.807991 -54.619396) (xy 79.756656 -54.611266) (xy 79.707226 -54.595205) (xy 79.660916 -54.571609)
			(xy 79.618868 -54.541059) (xy 79.582117 -54.504308) (xy 79.551567 -54.46226) (xy 79.527971 -54.41595)
			(xy 79.51191 -54.36652) (xy 79.50378 -54.315185) (xy 79.364297 -54.315185) (xy 79.356167 -54.366517)
			(xy 79.340108 -54.415944) (xy 79.316515 -54.462251) (xy 79.285969 -54.504298) (xy 79.249222 -54.541048)
			(xy 79.207178 -54.571598) (xy 79.160874 -54.595196) (xy 79.111448 -54.61126) (xy 79.060117 -54.619394)
			(xy 79.034132 -54.619906) (xy 79.00863 -54.61943) (xy 78.958233 -54.611591) (xy 78.909636 -54.59611)
			(xy 78.86399 -54.573354) (xy 78.822378 -54.543861) (xy 78.803754 -54.526434) (xy 78.793744 -54.517264)
			(xy 78.769994 -54.504135) (xy 78.743622 -54.497739) (xy 78.716496 -54.498529) (xy 78.690541 -54.50645)
			(xy 78.667595 -54.520939) (xy 78.649287 -54.54097) (xy 78.642718 -54.55285) (xy 78.630433 -54.575619)
			(xy 78.599845 -54.617343) (xy 78.563131 -54.653793) (xy 78.521188 -54.68408) (xy 78.47504 -54.707464)
			(xy 78.47246 -54.708298) (xy 81.134966 -54.708298) (xy 81.135452 -54.680186) (xy 81.143699 -54.624571)
			(xy 81.160014 -54.570767) (xy 81.184044 -54.519937) (xy 81.21527 -54.473182) (xy 81.233772 -54.452012)
			(xy 81.243406 -54.440574) (xy 81.256184 -54.413552) (xy 81.260605 -54.38399) (xy 81.256294 -54.354412)
			(xy 81.243617 -54.327342) (xy 81.234026 -54.315868) (xy 81.215747 -54.29477) (xy 81.184922 -54.24823)
			(xy 81.161208 -54.197695) (xy 81.145112 -54.144243) (xy 81.136976 -54.089017) (xy 81.13649 -54.061106)
			(xy 81.137063 -54.030994) (xy 81.14649 -53.971512) (xy 81.165145 -53.914249) (xy 81.192562 -53.860628)
			(xy 81.228062 -53.811979) (xy 81.249012 -53.790342) (xy 81.259378 -53.779209) (xy 81.273685 -53.752386)
			(xy 81.279476 -53.722542) (xy 81.276238 -53.692315) (xy 81.264258 -53.664375) (xy 81.254854 -53.65242)
			(xy 81.237752 -53.631651) (xy 81.208993 -53.586182) (xy 81.186909 -53.537122) (xy 81.17194 -53.485446)
			(xy 81.164382 -53.432178) (xy 81.163922 -53.405278) (xy 81.164408 -53.378027) (xy 81.172164 -53.324079)
			(xy 81.187519 -53.271784) (xy 81.210161 -53.222207) (xy 81.239627 -53.176357) (xy 81.275318 -53.135166)
			(xy 81.316509 -53.099475) (xy 81.362359 -53.070009) (xy 81.411936 -53.047367) (xy 81.464231 -53.032012)
			(xy 81.518179 -53.024256) (xy 81.572681 -53.024256) (xy 81.626629 -53.032012) (xy 81.678924 -53.047367)
			(xy 81.728501 -53.070009) (xy 81.774351 -53.099475) (xy 81.815542 -53.135166) (xy 81.851233 -53.176357)
			(xy 81.880699 -53.222207) (xy 81.903341 -53.271784) (xy 81.914794 -53.31079) (xy 82.608164 -53.31079)
			(xy 82.612235 -53.255168) (xy 82.624361 -53.200731) (xy 82.644284 -53.14864) (xy 82.67158 -53.100005)
			(xy 82.705666 -53.055862) (xy 82.745815 -53.017153) (xy 82.791173 -52.984702) (xy 82.840773 -52.959201)
			(xy 82.893557 -52.941194) (xy 82.9484 -52.931064) (xy 83.004134 -52.929027) (xy 83.059571 -52.935127)
			(xy 83.113528 -52.949233) (xy 83.164857 -52.971045) (xy 83.212463 -53.000099) (xy 83.255331 -53.035774)
			(xy 83.292548 -53.077311) (xy 83.323321 -53.123824) (xy 83.346993 -53.174321) (xy 83.363061 -53.227728)
			(xy 83.371181 -53.282904) (xy 83.37169 -53.31079) (xy 83.371181 -53.338676) (xy 83.366762 -53.368702)
			(xy 85.216998 -53.368702) (xy 85.221069 -53.31308) (xy 85.233195 -53.258643) (xy 85.253118 -53.206552)
			(xy 85.280414 -53.157917) (xy 85.3145 -53.113774) (xy 85.354649 -53.075065) (xy 85.400007 -53.042614)
			(xy 85.449607 -53.017113) (xy 85.502391 -52.999106) (xy 85.557234 -52.988976) (xy 85.612968 -52.986939)
			(xy 85.668405 -52.993039) (xy 85.722362 -53.007145) (xy 85.773691 -53.028957) (xy 85.821297 -53.058011)
			(xy 85.864165 -53.093686) (xy 85.901382 -53.135223) (xy 85.932155 -53.181736) (xy 85.955827 -53.232233)
			(xy 85.971895 -53.28564) (xy 85.980015 -53.340816) (xy 85.980524 -53.368702) (xy 85.980015 -53.396588)
			(xy 85.971895 -53.451764) (xy 85.955827 -53.505171) (xy 85.932155 -53.555668) (xy 85.901382 -53.602181)
			(xy 85.864165 -53.643718) (xy 85.821297 -53.679393) (xy 85.773691 -53.708447) (xy 85.722362 -53.730259)
			(xy 85.668405 -53.744365) (xy 85.612968 -53.750465) (xy 85.557234 -53.748428) (xy 85.502391 -53.738298)
			(xy 85.449607 -53.720291) (xy 85.400007 -53.69479) (xy 85.354649 -53.662339) (xy 85.3145 -53.62363)
			(xy 85.280414 -53.579487) (xy 85.253118 -53.530852) (xy 85.233195 -53.478761) (xy 85.221069 -53.424324)
			(xy 85.216998 -53.368702) (xy 83.366762 -53.368702) (xy 83.363061 -53.393852) (xy 83.346993 -53.447259)
			(xy 83.323321 -53.497756) (xy 83.292548 -53.544269) (xy 83.255331 -53.585806) (xy 83.212463 -53.621481)
			(xy 83.164857 -53.650535) (xy 83.113528 -53.672347) (xy 83.059571 -53.686453) (xy 83.004134 -53.692553)
			(xy 82.9484 -53.690516) (xy 82.893557 -53.680386) (xy 82.840773 -53.662379) (xy 82.791173 -53.636878)
			(xy 82.745815 -53.604427) (xy 82.705666 -53.565718) (xy 82.67158 -53.521575) (xy 82.644284 -53.47294)
			(xy 82.624361 -53.420849) (xy 82.612235 -53.366412) (xy 82.608164 -53.31079) (xy 81.914794 -53.31079)
			(xy 81.918696 -53.324079) (xy 81.926452 -53.378027) (xy 81.926938 -53.405278) (xy 81.926411 -53.435392)
			(xy 81.916971 -53.494876) (xy 81.898305 -53.552138) (xy 81.870878 -53.605759) (xy 81.83537 -53.654406)
			(xy 81.814416 -53.676042) (xy 81.804065 -53.687188) (xy 81.789752 -53.714006) (xy 81.783957 -53.743846)
			(xy 81.787192 -53.774072) (xy 81.799171 -53.80201) (xy 81.808574 -53.813964) (xy 81.825673 -53.834735)
			(xy 81.854432 -53.880204) (xy 81.876515 -53.929263) (xy 81.891485 -53.980939) (xy 81.899045 -54.034206)
			(xy 81.899506 -54.061106) (xy 81.89903 -54.089218) (xy 81.890782 -54.144834) (xy 81.874465 -54.198639)
			(xy 81.850432 -54.249468) (xy 81.838995 -54.266592) (xy 82.607656 -54.266592) (xy 82.611727 -54.21097)
			(xy 82.623853 -54.156533) (xy 82.643776 -54.104442) (xy 82.671072 -54.055807) (xy 82.705158 -54.011664)
			(xy 82.745307 -53.972955) (xy 82.790665 -53.940504) (xy 82.840265 -53.915003) (xy 82.893049 -53.896996)
			(xy 82.947892 -53.886866) (xy 83.003626 -53.884829) (xy 83.059063 -53.890929) (xy 83.11302 -53.905035)
			(xy 83.164349 -53.926847) (xy 83.211955 -53.955901) (xy 83.254823 -53.991576) (xy 83.29204 -54.033113)
			(xy 83.322813 -54.079626) (xy 83.346485 -54.130123) (xy 83.362553 -54.18353) (xy 83.370673 -54.238706)
			(xy 83.371182 -54.266592) (xy 83.370673 -54.294478) (xy 83.362553 -54.349654) (xy 83.346485 -54.403061)
			(xy 83.322813 -54.453558) (xy 83.29204 -54.500071) (xy 83.254823 -54.541608) (xy 83.211955 -54.577283)
			(xy 83.164349 -54.606337) (xy 83.11302 -54.628149) (xy 83.059063 -54.642255) (xy 83.003626 -54.648355)
			(xy 82.947892 -54.646318) (xy 82.893049 -54.636188) (xy 82.840265 -54.618181) (xy 82.790665 -54.59268)
			(xy 82.745307 -54.560229) (xy 82.705158 -54.52152) (xy 82.671072 -54.477377) (xy 82.643776 -54.428742)
			(xy 82.623853 -54.376651) (xy 82.611727 -54.322214) (xy 82.607656 -54.266592) (xy 81.838995 -54.266592)
			(xy 81.819204 -54.296222) (xy 81.8007 -54.317392) (xy 81.791064 -54.328828) (xy 81.778291 -54.355851)
			(xy 81.773871 -54.385413) (xy 81.778183 -54.414991) (xy 81.790857 -54.442061) (xy 81.800446 -54.453536)
			(xy 81.818722 -54.474637) (xy 81.849549 -54.521175) (xy 81.873263 -54.57171) (xy 81.88936 -54.625161)
			(xy 81.897496 -54.680387) (xy 81.897982 -54.708298) (xy 81.897496 -54.735549) (xy 81.88974 -54.789497)
			(xy 81.874385 -54.841792) (xy 81.851743 -54.891369) (xy 81.822277 -54.937219) (xy 81.786586 -54.97841)
			(xy 81.745395 -55.014101) (xy 81.699545 -55.043567) (xy 81.649968 -55.066209) (xy 81.597673 -55.081564)
			(xy 81.543725 -55.08932) (xy 81.489223 -55.08932) (xy 81.435275 -55.081564) (xy 81.38298 -55.066209)
			(xy 81.333403 -55.043567) (xy 81.287553 -55.014101) (xy 81.246362 -54.97841) (xy 81.210671 -54.937219)
			(xy 81.181205 -54.891369) (xy 81.158563 -54.841792) (xy 81.143208 -54.789497) (xy 81.135452 -54.735549)
			(xy 81.134966 -54.708298) (xy 78.47246 -54.708298) (xy 78.425812 -54.723375) (xy 78.374708 -54.731424)
			(xy 78.34884 -54.73192) (xy 78.32285 -54.731416) (xy 78.271508 -54.72329) (xy 78.22207 -54.707232)
			(xy 78.175753 -54.683637) (xy 78.133697 -54.653087) (xy 78.096939 -54.616333) (xy 78.066384 -54.574281)
			(xy 78.042784 -54.527967) (xy 78.026719 -54.478531) (xy 78.018587 -54.42719) (xy 74.8018 -54.42719)
			(xy 76.527406 -56.152796) (xy 79.6671 -56.152796) (xy 79.688001 -56.140758) (xy 79.732346 -56.121782)
			(xy 79.778833 -56.108922) (xy 79.826625 -56.102409) (xy 79.850742 -56.101996) (xy 79.85252 -56.101996)
			(xy 80.201516 -56.101996) (xy 80.216471 -56.101469) (xy 80.245102 -56.09281) (xy 80.270003 -56.076238)
			(xy 80.289044 -56.053171) (xy 80.300597 -56.025581) (xy 80.303673 -55.995828) (xy 80.298009 -55.966458)
			(xy 80.28409 -55.939983) (xy 80.273906 -55.929022) (xy 80.253516 -55.907481) (xy 80.218977 -55.859263)
			(xy 80.192316 -55.806281) (xy 80.174174 -55.749812) (xy 80.164987 -55.691216) (xy 80.164432 -55.66156)
			(xy 80.164918 -55.634309) (xy 80.172674 -55.580361) (xy 80.188029 -55.528066) (xy 80.210671 -55.478489)
			(xy 80.240137 -55.432639) (xy 80.275828 -55.391448) (xy 80.317019 -55.355757) (xy 80.362869 -55.326291)
			(xy 80.412446 -55.303649) (xy 80.464741 -55.288294) (xy 80.518689 -55.280538) (xy 80.573191 -55.280538)
			(xy 80.627139 -55.288294) (xy 80.679434 -55.303649) (xy 80.729011 -55.326291) (xy 80.774861 -55.355757)
			(xy 80.816052 -55.391448) (xy 80.851743 -55.432639) (xy 80.881209 -55.478489) (xy 80.903851 -55.528066)
			(xy 80.919206 -55.580361) (xy 80.926962 -55.634309) (xy 80.927448 -55.66156) (xy 80.926888 -55.691217)
			(xy 80.917713 -55.749817) (xy 80.899578 -55.80629) (xy 80.872921 -55.859276) (xy 80.838383 -55.907497)
			(xy 80.817974 -55.929022) (xy 80.807843 -55.940037) (xy 80.793896 -55.966501) (xy 80.78821 -55.995869)
			(xy 80.791272 -56.025625) (xy 80.802819 -56.05322) (xy 80.821862 -56.076289) (xy 80.84677 -56.092855)
			(xy 80.875407 -56.101499) (xy 80.890364 -56.101996) (xy 86.274402 -56.101996) (xy 87.101934 -55.274464)
			(xy 87.101934 -37.43579) (xy 86.352126 -36.685982) (xy 81.11363 -36.685982) (xy 81.09966 -36.714938)
			(xy 81.087655 -36.738896) (xy 81.057932 -36.783484) (xy 81.022261 -36.823474) (xy 80.981345 -36.858078)
			(xy 80.935989 -36.886616) (xy 80.887086 -36.908526) (xy 80.835597 -36.923377) (xy 80.782538 -36.930876)
			(xy 80.72895 -36.930876) (xy 80.675891 -36.923377) (xy 80.624402 -36.908526) (xy 80.575499 -36.886616)
			(xy 80.530143 -36.858078) (xy 80.489227 -36.823474) (xy 80.453556 -36.783484) (xy 80.423833 -36.738896)
			(xy 80.411828 -36.714938) (xy 80.397858 -36.685982) (xy 80.09763 -36.685982) (xy 80.08366 -36.714938)
			(xy 80.071655 -36.738896) (xy 80.041932 -36.783484) (xy 80.006261 -36.823474) (xy 79.965345 -36.858078)
			(xy 79.919989 -36.886616) (xy 79.871086 -36.908526) (xy 79.819597 -36.923377) (xy 79.766538 -36.930876)
			(xy 79.71295 -36.930876) (xy 79.659891 -36.923377) (xy 79.608402 -36.908526) (xy 79.559499 -36.886616)
			(xy 79.514143 -36.858078) (xy 79.473227 -36.823474) (xy 79.437556 -36.783484) (xy 79.407833 -36.738896)
			(xy 79.395828 -36.714938) (xy 79.381858 -36.685982) (xy 79.08163 -36.685982) (xy 79.06766 -36.714938)
			(xy 79.055655 -36.738896) (xy 79.025932 -36.783484) (xy 78.990261 -36.823474) (xy 78.949345 -36.858078)
			(xy 78.903989 -36.886616) (xy 78.855086 -36.908526) (xy 78.803597 -36.923377) (xy 78.750538 -36.930876)
			(xy 78.69695 -36.930876) (xy 78.643891 -36.923377) (xy 78.592402 -36.908526) (xy 78.543499 -36.886616)
			(xy 78.498143 -36.858078) (xy 78.457227 -36.823474) (xy 78.421556 -36.783484) (xy 78.391833 -36.738896)
			(xy 78.379828 -36.714938) (xy 78.365858 -36.685982) (xy 78.06563 -36.685982) (xy 78.05166 -36.714938)
			(xy 78.039655 -36.738896) (xy 78.009932 -36.783484) (xy 77.974261 -36.823474) (xy 77.933345 -36.858078)
			(xy 77.887989 -36.886616) (xy 77.839086 -36.908526) (xy 77.787597 -36.923377) (xy 77.734538 -36.930876)
			(xy 77.68095 -36.930876) (xy 77.627891 -36.923377) (xy 77.576402 -36.908526) (xy 77.527499 -36.886616)
			(xy 77.482143 -36.858078) (xy 77.441227 -36.823474) (xy 77.405556 -36.783484) (xy 77.375833 -36.738896)
			(xy 77.363828 -36.714938) (xy 77.349858 -36.685982) (xy 77.04963 -36.685982) (xy 77.03566 -36.714938)
			(xy 77.023655 -36.738896) (xy 76.993932 -36.783484) (xy 76.958261 -36.823474) (xy 76.917345 -36.858078)
			(xy 76.871989 -36.886616) (xy 76.823086 -36.908526) (xy 76.771597 -36.923377) (xy 76.718538 -36.930876)
			(xy 76.66495 -36.930876) (xy 76.611891 -36.923377) (xy 76.560402 -36.908526) (xy 76.511499 -36.886616)
			(xy 76.466143 -36.858078) (xy 76.425227 -36.823474) (xy 76.389556 -36.783484) (xy 76.359833 -36.738896)
			(xy 76.347828 -36.714938) (xy 76.333858 -36.685982) (xy 75.937364 -36.685982) (xy 75.527916 -37.095684)
			(xy 75.527916 -38.37305) (xy 80.958688 -38.37305) (xy 80.962759 -38.317428) (xy 80.974885 -38.262991)
			(xy 80.994808 -38.2109) (xy 81.022104 -38.162265) (xy 81.05619 -38.118122) (xy 81.096339 -38.079413)
			(xy 81.141697 -38.046962) (xy 81.191297 -38.021461) (xy 81.244081 -38.003454) (xy 81.298924 -37.993324)
			(xy 81.354658 -37.991287) (xy 81.410095 -37.997387) (xy 81.464052 -38.011493) (xy 81.515381 -38.033305)
			(xy 81.562987 -38.062359) (xy 81.605855 -38.098034) (xy 81.643072 -38.139571) (xy 81.673845 -38.186084)
			(xy 81.697517 -38.236581) (xy 81.713585 -38.289988) (xy 81.721705 -38.345164) (xy 81.722214 -38.37305)
			(xy 81.721964 -38.386766) (xy 84.270594 -38.386766) (xy 84.274665 -38.331144) (xy 84.286791 -38.276707)
			(xy 84.306714 -38.224616) (xy 84.33401 -38.175981) (xy 84.368096 -38.131838) (xy 84.408245 -38.093129)
			(xy 84.453603 -38.060678) (xy 84.503203 -38.035177) (xy 84.555987 -38.01717) (xy 84.61083 -38.00704)
			(xy 84.666564 -38.005003) (xy 84.722001 -38.011103) (xy 84.775958 -38.025209) (xy 84.827287 -38.047021)
			(xy 84.874893 -38.076075) (xy 84.917761 -38.11175) (xy 84.954978 -38.153287) (xy 84.985751 -38.1998)
			(xy 85.009423 -38.250297) (xy 85.025491 -38.303704) (xy 85.033611 -38.35888) (xy 85.03412 -38.386766)
			(xy 85.033611 -38.414652) (xy 85.025491 -38.469828) (xy 85.009423 -38.523235) (xy 84.985751 -38.573732)
			(xy 84.971146 -38.595808) (xy 85.818218 -38.595808) (xy 85.818704 -38.568557) (xy 85.82646 -38.514609)
			(xy 85.841815 -38.462314) (xy 85.864457 -38.412737) (xy 85.893923 -38.366887) (xy 85.929614 -38.325696)
			(xy 85.970805 -38.290005) (xy 86.016655 -38.260539) (xy 86.066232 -38.237897) (xy 86.118527 -38.222542)
			(xy 86.172475 -38.214786) (xy 86.226977 -38.214786) (xy 86.280925 -38.222542) (xy 86.33322 -38.237897)
			(xy 86.382797 -38.260539) (xy 86.428647 -38.290005) (xy 86.469838 -38.325696) (xy 86.505529 -38.366887)
			(xy 86.534995 -38.412737) (xy 86.557637 -38.462314) (xy 86.572992 -38.514609) (xy 86.580748 -38.568557)
			(xy 86.581234 -38.595808) (xy 86.580698 -38.62482) (xy 86.571929 -38.682177) (xy 86.554577 -38.737546)
			(xy 86.529044 -38.78965) (xy 86.495918 -38.837288) (xy 86.476332 -38.858698) (xy 86.466117 -38.87017)
			(xy 86.452538 -38.897709) (xy 86.447757 -38.92804) (xy 86.452205 -38.958421) (xy 86.465482 -38.986107)
			(xy 86.486386 -39.008597) (xy 86.499446 -39.016686) (xy 86.523989 -39.031368) (xy 86.568745 -39.066975)
			(xy 86.607685 -39.108862) (xy 86.639939 -39.15609) (xy 86.664783 -39.207604) (xy 86.681662 -39.262247)
			(xy 86.690198 -39.318798) (xy 86.690708 -39.347394) (xy 86.690222 -39.374645) (xy 86.682466 -39.428593)
			(xy 86.667111 -39.480888) (xy 86.644469 -39.530465) (xy 86.615003 -39.576315) (xy 86.579312 -39.617506)
			(xy 86.538121 -39.653197) (xy 86.492271 -39.682663) (xy 86.442694 -39.705305) (xy 86.390399 -39.72066)
			(xy 86.336451 -39.728416) (xy 86.281949 -39.728416) (xy 86.228001 -39.72066) (xy 86.175706 -39.705305)
			(xy 86.126129 -39.682663) (xy 86.080279 -39.653197) (xy 86.039088 -39.617506) (xy 86.003397 -39.576315)
			(xy 85.973931 -39.530465) (xy 85.951289 -39.480888) (xy 85.935934 -39.428593) (xy 85.928178 -39.374645)
			(xy 85.927692 -39.347394) (xy 85.928222 -39.318382) (xy 85.936992 -39.261024) (xy 85.954344 -39.205655)
			(xy 85.979879 -39.153551) (xy 86.013007 -39.105913) (xy 86.032594 -39.084504) (xy 86.042799 -39.073025)
			(xy 86.056374 -39.045488) (xy 86.061154 -39.01516) (xy 86.056707 -38.984782) (xy 86.043435 -38.957098)
			(xy 86.022537 -38.934607) (xy 86.00948 -38.926516) (xy 85.984943 -38.911823) (xy 85.940187 -38.876219)
			(xy 85.901245 -38.834335) (xy 85.86899 -38.787108) (xy 85.844145 -38.735596) (xy 85.827265 -38.680953)
			(xy 85.818728 -38.624403) (xy 85.818218 -38.595808) (xy 84.971146 -38.595808) (xy 84.954978 -38.620245)
			(xy 84.917761 -38.661782) (xy 84.874893 -38.697457) (xy 84.827287 -38.726511) (xy 84.775958 -38.748323)
			(xy 84.722001 -38.762429) (xy 84.666564 -38.768529) (xy 84.61083 -38.766492) (xy 84.555987 -38.756362)
			(xy 84.503203 -38.738355) (xy 84.453603 -38.712854) (xy 84.408245 -38.680403) (xy 84.368096 -38.641694)
			(xy 84.33401 -38.597551) (xy 84.306714 -38.548916) (xy 84.286791 -38.496825) (xy 84.274665 -38.442388)
			(xy 84.270594 -38.386766) (xy 81.721964 -38.386766) (xy 81.721705 -38.400936) (xy 81.713585 -38.456112)
			(xy 81.697517 -38.509519) (xy 81.673845 -38.560016) (xy 81.643072 -38.606529) (xy 81.605855 -38.648066)
			(xy 81.562987 -38.683741) (xy 81.515381 -38.712795) (xy 81.464052 -38.734607) (xy 81.410095 -38.748713)
			(xy 81.354658 -38.754813) (xy 81.298924 -38.752776) (xy 81.244081 -38.742646) (xy 81.191297 -38.724639)
			(xy 81.141697 -38.699138) (xy 81.096339 -38.666687) (xy 81.05619 -38.627978) (xy 81.022104 -38.583835)
			(xy 80.994808 -38.5352) (xy 80.974885 -38.483109) (xy 80.962759 -38.428672) (xy 80.958688 -38.37305)
			(xy 75.527916 -38.37305) (xy 75.527916 -38.957758) (xy 81.789268 -38.957758) (xy 81.793339 -38.902136)
			(xy 81.805465 -38.847699) (xy 81.825388 -38.795608) (xy 81.852684 -38.746973) (xy 81.88677 -38.70283)
			(xy 81.926919 -38.664121) (xy 81.972277 -38.63167) (xy 82.021877 -38.606169) (xy 82.074661 -38.588162)
			(xy 82.129504 -38.578032) (xy 82.185238 -38.575995) (xy 82.240675 -38.582095) (xy 82.294632 -38.596201)
			(xy 82.345961 -38.618013) (xy 82.393567 -38.647067) (xy 82.436435 -38.682742) (xy 82.473652 -38.724279)
			(xy 82.504425 -38.770792) (xy 82.519118 -38.802136) (xy 83.186307 -38.802136) (xy 83.186309 -38.747639)
			(xy 83.194066 -38.693697) (xy 83.209421 -38.641409) (xy 83.232061 -38.591837) (xy 83.261525 -38.545992)
			(xy 83.297213 -38.504807) (xy 83.338399 -38.46912) (xy 83.384244 -38.439657) (xy 83.433816 -38.417018)
			(xy 83.486105 -38.401665) (xy 83.540047 -38.393908) (xy 83.594544 -38.393908) (xy 83.648486 -38.401663)
			(xy 83.700775 -38.417015) (xy 83.750347 -38.439652) (xy 83.796194 -38.469114) (xy 83.837381 -38.504801)
			(xy 83.87307 -38.545985) (xy 83.902535 -38.591829) (xy 83.925176 -38.6414) (xy 83.940532 -38.693688)
			(xy 83.94829 -38.74763) (xy 83.948778 -38.774878) (xy 83.948506 -38.796791) (xy 83.943536 -38.840333)
			(xy 83.938872 -38.861746) (xy 83.936034 -38.876692) (xy 83.9381 -38.907019) (xy 83.94901 -38.93539)
			(xy 83.967797 -38.959287) (xy 83.992791 -38.976587) (xy 84.021773 -38.985754) (xy 84.052169 -38.985974)
			(xy 84.066888 -38.982142) (xy 84.093755 -38.974582) (xy 84.148965 -38.966418) (xy 84.17687 -38.965886)
			(xy 84.204122 -38.966383) (xy 84.258071 -38.974136) (xy 84.310368 -38.989488) (xy 84.359948 -39.012126)
			(xy 84.405801 -39.041591) (xy 84.446994 -39.077281) (xy 84.482688 -39.11847) (xy 84.512156 -39.164321)
			(xy 84.5348 -39.213898) (xy 84.550156 -39.266194) (xy 84.557914 -39.320142) (xy 84.558378 -39.347394)
			(xy 84.557914 -39.374764) (xy 84.550096 -39.428944) (xy 84.534607 -39.481447) (xy 84.511765 -39.531194)
			(xy 84.48204 -39.577161) (xy 84.464398 -39.598092) (xy 84.455167 -39.609424) (xy 84.442989 -39.63598)
			(xy 84.438816 -39.664895) (xy 84.442987 -39.693811) (xy 84.455162 -39.720369) (xy 84.464398 -39.731696)
			(xy 84.482032 -39.752634) (xy 84.511755 -39.798601) (xy 84.534599 -39.848347) (xy 84.550095 -39.900848)
			(xy 84.557923 -39.955025) (xy 84.557924 -40.009766) (xy 84.550097 -40.063943) (xy 84.534602 -40.116444)
			(xy 84.511759 -40.166191) (xy 84.482037 -40.212159) (xy 84.464398 -40.233092) (xy 84.455167 -40.244424)
			(xy 84.442989 -40.27098) (xy 84.438816 -40.299895) (xy 84.442987 -40.328811) (xy 84.455162 -40.355369)
			(xy 84.464398 -40.366696) (xy 84.482048 -40.387619) (xy 84.511759 -40.433594) (xy 84.534592 -40.483344)
			(xy 84.550081 -40.535847) (xy 84.557906 -40.590024) (xy 84.558378 -40.617394) (xy 84.557892 -40.644645)
			(xy 84.550136 -40.698593) (xy 84.534781 -40.750888) (xy 84.512139 -40.800465) (xy 84.482673 -40.846315)
			(xy 84.446982 -40.887506) (xy 84.405791 -40.923197) (xy 84.359941 -40.952663) (xy 84.310364 -40.975305)
			(xy 84.258069 -40.99066) (xy 84.204121 -40.998416) (xy 84.149619 -40.998416) (xy 84.095671 -40.99066)
			(xy 84.043376 -40.975305) (xy 83.993799 -40.952663) (xy 83.947949 -40.923197) (xy 83.906758 -40.887506)
			(xy 83.871067 -40.846315) (xy 83.841601 -40.800465) (xy 83.818959 -40.750888) (xy 83.803604 -40.698593)
			(xy 83.795848 -40.644645) (xy 83.795362 -40.617394) (xy 83.795809 -40.590023) (xy 83.803629 -40.535842)
			(xy 83.819122 -40.483339) (xy 83.841968 -40.433592) (xy 83.871698 -40.387626) (xy 83.889342 -40.366696)
			(xy 83.898581 -40.355372) (xy 83.910753 -40.328812) (xy 83.914922 -40.299895) (xy 83.91075 -40.270979)
			(xy 83.898576 -40.244421) (xy 83.889342 -40.233092) (xy 83.871695 -40.212164) (xy 83.841969 -40.166196)
			(xy 83.819123 -40.116449) (xy 83.803627 -40.063946) (xy 83.795798 -40.009767) (xy 83.795799 -39.955024)
			(xy 83.803629 -39.900845) (xy 83.819126 -39.848343) (xy 83.841973 -39.798596) (xy 83.8717 -39.752628)
			(xy 83.889342 -39.731696) (xy 83.898581 -39.720372) (xy 83.910753 -39.693812) (xy 83.914922 -39.664895)
			(xy 83.91075 -39.635979) (xy 83.898576 -39.609421) (xy 83.889342 -39.598092) (xy 83.871692 -39.577168)
			(xy 83.841981 -39.531194) (xy 83.819146 -39.481444) (xy 83.803658 -39.428942) (xy 83.795833 -39.374764)
			(xy 83.795362 -39.347394) (xy 83.795645 -39.325481) (xy 83.800607 -39.281939) (xy 83.805268 -39.260526)
			(xy 83.808212 -39.245596) (xy 83.806139 -39.215251) (xy 83.795215 -39.186865) (xy 83.77641 -39.162959)
			(xy 83.751396 -39.145657) (xy 83.722392 -39.136496) (xy 83.691978 -39.136289) (xy 83.677252 -39.14013)
			(xy 83.650389 -39.147704) (xy 83.595176 -39.155859) (xy 83.56727 -39.156386) (xy 83.540022 -39.15589)
			(xy 83.48608 -39.14813) (xy 83.433792 -39.132773) (xy 83.384222 -39.110131) (xy 83.338379 -39.080665)
			(xy 83.297195 -39.044975) (xy 83.261509 -39.003787) (xy 83.232049 -38.95794) (xy 83.209412 -38.908368)
			(xy 83.194061 -38.856078) (xy 83.186307 -38.802136) (xy 82.519118 -38.802136) (xy 82.528097 -38.821289)
			(xy 82.544165 -38.874696) (xy 82.552285 -38.929872) (xy 82.552794 -38.957758) (xy 82.552285 -38.985644)
			(xy 82.544165 -39.04082) (xy 82.528097 -39.094227) (xy 82.504425 -39.144724) (xy 82.473652 -39.191237)
			(xy 82.436435 -39.232774) (xy 82.393567 -39.268449) (xy 82.345961 -39.297503) (xy 82.294632 -39.319315)
			(xy 82.240675 -39.333421) (xy 82.185238 -39.339521) (xy 82.129504 -39.337484) (xy 82.074661 -39.327354)
			(xy 82.021877 -39.309347) (xy 81.972277 -39.283846) (xy 81.926919 -39.251395) (xy 81.88677 -39.212686)
			(xy 81.852684 -39.168543) (xy 81.825388 -39.119908) (xy 81.805465 -39.067817) (xy 81.793339 -39.01338)
			(xy 81.789268 -38.957758) (xy 75.527916 -38.957758) (xy 75.527916 -39.43096) (xy 75.527261 -39.460964)
			(xy 75.517744 -39.520214) (xy 75.49908 -39.577248) (xy 75.471727 -39.630662) (xy 75.45451 -39.655242)
			(xy 75.45451 -39.655496) (xy 75.444858 -39.668958) (xy 75.444858 -39.786052) (xy 75.256898 -39.974012)
			(xy 81.757518 -39.974012) (xy 81.761589 -39.91839) (xy 81.773715 -39.863953) (xy 81.793638 -39.811862)
			(xy 81.820934 -39.763227) (xy 81.85502 -39.719084) (xy 81.895169 -39.680375) (xy 81.940527 -39.647924)
			(xy 81.990127 -39.622423) (xy 82.042911 -39.604416) (xy 82.097754 -39.594286) (xy 82.153488 -39.592249)
			(xy 82.208925 -39.598349) (xy 82.262882 -39.612455) (xy 82.314211 -39.634267) (xy 82.361817 -39.663321)
			(xy 82.404685 -39.698996) (xy 82.441902 -39.740533) (xy 82.472675 -39.787046) (xy 82.496347 -39.837543)
			(xy 82.512415 -39.89095) (xy 82.520535 -39.946126) (xy 82.521044 -39.974012) (xy 82.520535 -40.001898)
			(xy 82.512415 -40.057074) (xy 82.496347 -40.110481) (xy 82.472675 -40.160978) (xy 82.441902 -40.207491)
			(xy 82.404685 -40.249028) (xy 82.361817 -40.284703) (xy 82.314211 -40.313757) (xy 82.262882 -40.335569)
			(xy 82.208925 -40.349675) (xy 82.153488 -40.355775) (xy 82.097754 -40.353738) (xy 82.042911 -40.343608)
			(xy 81.990127 -40.325601) (xy 81.940527 -40.3001) (xy 81.895169 -40.267649) (xy 81.85502 -40.22894)
			(xy 81.820934 -40.184797) (xy 81.793638 -40.136162) (xy 81.773715 -40.084071) (xy 81.761589 -40.029634)
			(xy 81.757518 -39.974012) (xy 75.256898 -39.974012) (xy 74.66965 -40.56126) (xy 72.061832 -40.56126)
			(xy 71.633138 -40.990012) (xy 81.757518 -40.990012) (xy 81.761589 -40.93439) (xy 81.773715 -40.879953)
			(xy 81.793638 -40.827862) (xy 81.820934 -40.779227) (xy 81.85502 -40.735084) (xy 81.895169 -40.696375)
			(xy 81.940527 -40.663924) (xy 81.990127 -40.638423) (xy 82.042911 -40.620416) (xy 82.097754 -40.610286)
			(xy 82.153488 -40.608249) (xy 82.208925 -40.614349) (xy 82.262882 -40.628455) (xy 82.314211 -40.650267)
			(xy 82.361817 -40.679321) (xy 82.404685 -40.714996) (xy 82.441902 -40.756533) (xy 82.472675 -40.803046)
			(xy 82.496347 -40.853543) (xy 82.512415 -40.90695) (xy 82.520535 -40.962126) (xy 82.521044 -40.990012)
			(xy 82.520535 -41.017898) (xy 82.512415 -41.073074) (xy 82.496347 -41.126481) (xy 82.472675 -41.176978)
			(xy 82.441902 -41.223491) (xy 82.404685 -41.265028) (xy 82.361817 -41.300703) (xy 82.314211 -41.329757)
			(xy 82.262882 -41.351569) (xy 82.208925 -41.365675) (xy 82.153488 -41.371775) (xy 82.097754 -41.369738)
			(xy 82.042911 -41.359608) (xy 81.990127 -41.341601) (xy 81.940527 -41.3161) (xy 81.895169 -41.283649)
			(xy 81.85502 -41.24494) (xy 81.820934 -41.200797) (xy 81.793638 -41.152162) (xy 81.773715 -41.100071)
			(xy 81.761589 -41.045634) (xy 81.757518 -40.990012) (xy 71.633138 -40.990012) (xy 71.07154 -41.551685)
			(xy 72.308722 -41.551685) (xy 72.308722 -41.499711) (xy 72.316852 -41.448376) (xy 72.332913 -41.398946)
			(xy 72.356509 -41.352636) (xy 72.387059 -41.310588) (xy 72.42381 -41.273837) (xy 72.465858 -41.243287)
			(xy 72.512168 -41.219691) (xy 72.561598 -41.20363) (xy 72.612933 -41.1955) (xy 72.664907 -41.1955)
			(xy 72.716242 -41.20363) (xy 72.765672 -41.219691) (xy 72.811982 -41.243287) (xy 72.85403 -41.273837)
			(xy 72.890781 -41.310588) (xy 72.921331 -41.352636) (xy 72.944927 -41.398946) (xy 72.960988 -41.448376)
			(xy 72.969118 -41.499711) (xy 72.969628 -41.525698) (xy 72.969118 -41.551685) (xy 73.103742 -41.551685)
			(xy 73.103742 -41.499711) (xy 73.111872 -41.448376) (xy 73.127933 -41.398946) (xy 73.151529 -41.352636)
			(xy 73.182079 -41.310588) (xy 73.21883 -41.273837) (xy 73.260878 -41.243287) (xy 73.307188 -41.219691)
			(xy 73.356618 -41.20363) (xy 73.407953 -41.1955) (xy 73.459927 -41.1955) (xy 73.511262 -41.20363)
			(xy 73.560692 -41.219691) (xy 73.607002 -41.243287) (xy 73.64905 -41.273837) (xy 73.685801 -41.310588)
			(xy 73.716351 -41.352636) (xy 73.739947 -41.398946) (xy 73.756008 -41.448376) (xy 73.764138 -41.499711)
			(xy 73.764648 -41.525698) (xy 73.764138 -41.551685) (xy 73.903842 -41.551685) (xy 73.903842 -41.499711)
			(xy 73.911972 -41.448376) (xy 73.928033 -41.398946) (xy 73.951629 -41.352636) (xy 73.982179 -41.310588)
			(xy 74.01893 -41.273837) (xy 74.060978 -41.243287) (xy 74.107288 -41.219691) (xy 74.156718 -41.20363)
			(xy 74.208053 -41.1955) (xy 74.260027 -41.1955) (xy 74.311362 -41.20363) (xy 74.360792 -41.219691)
			(xy 74.407102 -41.243287) (xy 74.44915 -41.273837) (xy 74.485901 -41.310588) (xy 74.516451 -41.352636)
			(xy 74.540047 -41.398946) (xy 74.556108 -41.448376) (xy 74.564238 -41.499711) (xy 74.564748 -41.525698)
			(xy 74.564238 -41.551685) (xy 77.903834 -41.551685) (xy 77.903834 -41.499711) (xy 77.911964 -41.448376)
			(xy 77.928025 -41.398946) (xy 77.951621 -41.352636) (xy 77.982171 -41.310588) (xy 78.018922 -41.273837)
			(xy 78.06097 -41.243287) (xy 78.10728 -41.219691) (xy 78.15671 -41.20363) (xy 78.208045 -41.1955)
			(xy 78.260019 -41.1955) (xy 78.311354 -41.20363) (xy 78.360784 -41.219691) (xy 78.407094 -41.243287)
			(xy 78.449142 -41.273837) (xy 78.485893 -41.310588) (xy 78.516443 -41.352636) (xy 78.540039 -41.398946)
			(xy 78.5561 -41.448376) (xy 78.56423 -41.499711) (xy 78.56474 -41.525698) (xy 78.56423 -41.551685)
			(xy 78.703934 -41.551685) (xy 78.703934 -41.499711) (xy 78.712064 -41.448376) (xy 78.728125 -41.398946)
			(xy 78.751721 -41.352636) (xy 78.782271 -41.310588) (xy 78.819022 -41.273837) (xy 78.86107 -41.243287)
			(xy 78.90738 -41.219691) (xy 78.95681 -41.20363) (xy 79.008145 -41.1955) (xy 79.060119 -41.1955)
			(xy 79.111454 -41.20363) (xy 79.160884 -41.219691) (xy 79.207194 -41.243287) (xy 79.249242 -41.273837)
			(xy 79.285993 -41.310588) (xy 79.316543 -41.352636) (xy 79.340139 -41.398946) (xy 79.3562 -41.448376)
			(xy 79.36433 -41.499711) (xy 79.36484 -41.525698) (xy 79.36433 -41.551685) (xy 79.50378 -41.551685)
			(xy 79.50378 -41.499711) (xy 79.51191 -41.448376) (xy 79.527971 -41.398946) (xy 79.551567 -41.352636)
			(xy 79.582117 -41.310588) (xy 79.618868 -41.273837) (xy 79.660916 -41.243287) (xy 79.707226 -41.219691)
			(xy 79.756656 -41.20363) (xy 79.807991 -41.1955) (xy 79.859965 -41.1955) (xy 79.9113 -41.20363) (xy 79.96073 -41.219691)
			(xy 80.00704 -41.243287) (xy 80.049088 -41.273837) (xy 80.085839 -41.310588) (xy 80.116389 -41.352636)
			(xy 80.139985 -41.398946) (xy 80.156046 -41.448376) (xy 80.164176 -41.499711) (xy 80.164686 -41.525698)
			(xy 80.164176 -41.551685) (xy 80.156046 -41.60302) (xy 80.139985 -41.65245) (xy 80.116389 -41.69876)
			(xy 80.085839 -41.740808) (xy 80.049088 -41.777559) (xy 80.00704 -41.808109) (xy 79.96073 -41.831705)
			(xy 79.9113 -41.847766) (xy 79.859965 -41.855896) (xy 79.807991 -41.855896) (xy 79.756656 -41.847766)
			(xy 79.707226 -41.831705) (xy 79.660916 -41.808109) (xy 79.618868 -41.777559) (xy 79.582117 -41.740808)
			(xy 79.551567 -41.69876) (xy 79.527971 -41.65245) (xy 79.51191 -41.60302) (xy 79.50378 -41.551685)
			(xy 79.36433 -41.551685) (xy 79.3562 -41.60302) (xy 79.340139 -41.65245) (xy 79.316543 -41.69876)
			(xy 79.285993 -41.740808) (xy 79.249242 -41.777559) (xy 79.207194 -41.808109) (xy 79.160884 -41.831705)
			(xy 79.111454 -41.847766) (xy 79.060119 -41.855896) (xy 79.008145 -41.855896) (xy 78.95681 -41.847766)
			(xy 78.90738 -41.831705) (xy 78.86107 -41.808109) (xy 78.819022 -41.777559) (xy 78.782271 -41.740808)
			(xy 78.751721 -41.69876) (xy 78.728125 -41.65245) (xy 78.712064 -41.60302) (xy 78.703934 -41.551685)
			(xy 78.56423 -41.551685) (xy 78.5561 -41.60302) (xy 78.540039 -41.65245) (xy 78.516443 -41.69876)
			(xy 78.485893 -41.740808) (xy 78.449142 -41.777559) (xy 78.407094 -41.808109) (xy 78.360784 -41.831705)
			(xy 78.311354 -41.847766) (xy 78.260019 -41.855896) (xy 78.208045 -41.855896) (xy 78.15671 -41.847766)
			(xy 78.10728 -41.831705) (xy 78.06097 -41.808109) (xy 78.018922 -41.777559) (xy 77.982171 -41.740808)
			(xy 77.951621 -41.69876) (xy 77.928025 -41.65245) (xy 77.911964 -41.60302) (xy 77.903834 -41.551685)
			(xy 74.564238 -41.551685) (xy 74.556108 -41.60302) (xy 74.540047 -41.65245) (xy 74.516451 -41.69876)
			(xy 74.485901 -41.740808) (xy 74.44915 -41.777559) (xy 74.407102 -41.808109) (xy 74.360792 -41.831705)
			(xy 74.311362 -41.847766) (xy 74.260027 -41.855896) (xy 74.208053 -41.855896) (xy 74.156718 -41.847766)
			(xy 74.107288 -41.831705) (xy 74.060978 -41.808109) (xy 74.01893 -41.777559) (xy 73.982179 -41.740808)
			(xy 73.951629 -41.69876) (xy 73.928033 -41.65245) (xy 73.911972 -41.60302) (xy 73.903842 -41.551685)
			(xy 73.764138 -41.551685) (xy 73.756008 -41.60302) (xy 73.739947 -41.65245) (xy 73.716351 -41.69876)
			(xy 73.685801 -41.740808) (xy 73.64905 -41.777559) (xy 73.607002 -41.808109) (xy 73.560692 -41.831705)
			(xy 73.511262 -41.847766) (xy 73.459927 -41.855896) (xy 73.407953 -41.855896) (xy 73.356618 -41.847766)
			(xy 73.307188 -41.831705) (xy 73.260878 -41.808109) (xy 73.21883 -41.777559) (xy 73.182079 -41.740808)
			(xy 73.151529 -41.69876) (xy 73.127933 -41.65245) (xy 73.111872 -41.60302) (xy 73.103742 -41.551685)
			(xy 72.969118 -41.551685) (xy 72.960988 -41.60302) (xy 72.944927 -41.65245) (xy 72.921331 -41.69876)
			(xy 72.890781 -41.740808) (xy 72.85403 -41.777559) (xy 72.811982 -41.808109) (xy 72.765672 -41.831705)
			(xy 72.716242 -41.847766) (xy 72.664907 -41.855896) (xy 72.612933 -41.855896) (xy 72.561598 -41.847766)
			(xy 72.512168 -41.831705) (xy 72.465858 -41.808109) (xy 72.42381 -41.777559) (xy 72.387059 -41.740808)
			(xy 72.356509 -41.69876) (xy 72.332913 -41.65245) (xy 72.316852 -41.60302) (xy 72.308722 -41.551685)
			(xy 71.07154 -41.551685) (xy 70.271548 -42.351785) (xy 77.903834 -42.351785) (xy 77.903834 -42.299811)
			(xy 77.911964 -42.248476) (xy 77.928025 -42.199046) (xy 77.951621 -42.152736) (xy 77.982171 -42.110688)
			(xy 78.018922 -42.073937) (xy 78.06097 -42.043387) (xy 78.10728 -42.019791) (xy 78.15671 -42.00373)
			(xy 78.208045 -41.9956) (xy 78.260019 -41.9956) (xy 78.311354 -42.00373) (xy 78.318377 -42.006012)
			(xy 81.757518 -42.006012) (xy 81.761589 -41.95039) (xy 81.773715 -41.895953) (xy 81.793638 -41.843862)
			(xy 81.820934 -41.795227) (xy 81.85502 -41.751084) (xy 81.895169 -41.712375) (xy 81.940527 -41.679924)
			(xy 81.990127 -41.654423) (xy 82.042911 -41.636416) (xy 82.097754 -41.626286) (xy 82.153488 -41.624249)
			(xy 82.208925 -41.630349) (xy 82.262882 -41.644455) (xy 82.314211 -41.666267) (xy 82.361817 -41.695321)
			(xy 82.404685 -41.730996) (xy 82.441902 -41.772533) (xy 82.472675 -41.819046) (xy 82.496347 -41.869543)
			(xy 82.512415 -41.92295) (xy 82.520535 -41.978126) (xy 82.521044 -42.006012) (xy 82.520535 -42.033898)
			(xy 82.512415 -42.089074) (xy 82.496347 -42.142481) (xy 82.472675 -42.192978) (xy 82.441902 -42.239491)
			(xy 82.404685 -42.281028) (xy 82.361817 -42.316703) (xy 82.314211 -42.345757) (xy 82.262882 -42.367569)
			(xy 82.208925 -42.381675) (xy 82.153488 -42.387775) (xy 82.097754 -42.385738) (xy 82.042911 -42.375608)
			(xy 81.990127 -42.357601) (xy 81.940527 -42.3321) (xy 81.895169 -42.299649) (xy 81.85502 -42.26094)
			(xy 81.820934 -42.216797) (xy 81.793638 -42.168162) (xy 81.773715 -42.116071) (xy 81.761589 -42.061634)
			(xy 81.757518 -42.006012) (xy 78.318377 -42.006012) (xy 78.360784 -42.019791) (xy 78.407094 -42.043387)
			(xy 78.449142 -42.073937) (xy 78.485893 -42.110688) (xy 78.516443 -42.152736) (xy 78.540039 -42.199046)
			(xy 78.5561 -42.248476) (xy 78.56423 -42.299811) (xy 78.56474 -42.325798) (xy 78.56423 -42.351785)
			(xy 78.5561 -42.40312) (xy 78.540039 -42.45255) (xy 78.516443 -42.49886) (xy 78.485893 -42.540908)
			(xy 78.449142 -42.577659) (xy 78.407094 -42.608209) (xy 78.360784 -42.631805) (xy 78.311354 -42.647866)
			(xy 78.260019 -42.655996) (xy 78.208045 -42.655996) (xy 78.15671 -42.647866) (xy 78.10728 -42.631805)
			(xy 78.06097 -42.608209) (xy 78.018922 -42.577659) (xy 77.982171 -42.540908) (xy 77.951621 -42.49886)
			(xy 77.928025 -42.45255) (xy 77.911964 -42.40312) (xy 77.903834 -42.351785) (xy 70.271548 -42.351785)
			(xy 70.174612 -42.448734) (xy 70.174612 -42.456862) (xy 69.907529 -42.723895) (xy 72.18223 -42.723895)
			(xy 72.18223 -42.671921) (xy 72.19036 -42.620586) (xy 72.206421 -42.571156) (xy 72.230017 -42.524846)
			(xy 72.260567 -42.482798) (xy 72.297318 -42.446047) (xy 72.339366 -42.415497) (xy 72.385676 -42.391901)
			(xy 72.435106 -42.37584) (xy 72.486441 -42.36771) (xy 72.538415 -42.36771) (xy 72.58975 -42.37584)
			(xy 72.63918 -42.391901) (xy 72.68549 -42.415497) (xy 72.727538 -42.446047) (xy 72.764289 -42.482798)
			(xy 72.794839 -42.524846) (xy 72.818435 -42.571156) (xy 72.834496 -42.620586) (xy 72.842626 -42.671921)
			(xy 72.843136 -42.697908) (xy 72.842626 -42.723895) (xy 72.841097 -42.733547) (xy 79.662022 -42.733547)
			(xy 79.662022 -42.681573) (xy 79.670152 -42.630238) (xy 79.686213 -42.580808) (xy 79.709809 -42.534498)
			(xy 79.740359 -42.49245) (xy 79.77711 -42.455699) (xy 79.819158 -42.425149) (xy 79.865468 -42.401553)
			(xy 79.914898 -42.385492) (xy 79.966233 -42.377362) (xy 80.018207 -42.377362) (xy 80.069542 -42.385492)
			(xy 80.118972 -42.401553) (xy 80.165282 -42.425149) (xy 80.20733 -42.455699) (xy 80.244081 -42.49245)
			(xy 80.274631 -42.534498) (xy 80.298227 -42.580808) (xy 80.314288 -42.630238) (xy 80.322418 -42.681573)
			(xy 80.322928 -42.70756) (xy 80.322418 -42.733547) (xy 80.314288 -42.784882) (xy 80.298227 -42.834312)
			(xy 80.274631 -42.880622) (xy 80.244081 -42.92267) (xy 80.20733 -42.959421) (xy 80.165282 -42.989971)
			(xy 80.118972 -43.013567) (xy 80.092981 -43.022012) (xy 81.757518 -43.022012) (xy 81.761589 -42.96639)
			(xy 81.773715 -42.911953) (xy 81.793638 -42.859862) (xy 81.820934 -42.811227) (xy 81.85502 -42.767084)
			(xy 81.895169 -42.728375) (xy 81.940527 -42.695924) (xy 81.990127 -42.670423) (xy 82.042911 -42.652416)
			(xy 82.097754 -42.642286) (xy 82.153488 -42.640249) (xy 82.208925 -42.646349) (xy 82.262882 -42.660455)
			(xy 82.314211 -42.682267) (xy 82.361817 -42.711321) (xy 82.404685 -42.746996) (xy 82.441902 -42.788533)
			(xy 82.472675 -42.835046) (xy 82.496347 -42.885543) (xy 82.512415 -42.93895) (xy 82.520535 -42.994126)
			(xy 82.521044 -43.022012) (xy 82.520535 -43.049898) (xy 82.512415 -43.105074) (xy 82.496347 -43.158481)
			(xy 82.472675 -43.208978) (xy 82.441902 -43.255491) (xy 82.404685 -43.297028) (xy 82.361817 -43.332703)
			(xy 82.314211 -43.361757) (xy 82.262882 -43.383569) (xy 82.208925 -43.397675) (xy 82.153488 -43.403775)
			(xy 82.097754 -43.401738) (xy 82.042911 -43.391608) (xy 81.990127 -43.373601) (xy 81.940527 -43.3481)
			(xy 81.895169 -43.315649) (xy 81.85502 -43.27694) (xy 81.820934 -43.232797) (xy 81.793638 -43.184162)
			(xy 81.773715 -43.132071) (xy 81.761589 -43.077634) (xy 81.757518 -43.022012) (xy 80.092981 -43.022012)
			(xy 80.069542 -43.029628) (xy 80.018207 -43.037758) (xy 79.966233 -43.037758) (xy 79.914898 -43.029628)
			(xy 79.865468 -43.013567) (xy 79.819158 -42.989971) (xy 79.77711 -42.959421) (xy 79.740359 -42.92267)
			(xy 79.709809 -42.880622) (xy 79.686213 -42.834312) (xy 79.670152 -42.784882) (xy 79.662022 -42.733547)
			(xy 72.841097 -42.733547) (xy 72.834496 -42.77523) (xy 72.818435 -42.82466) (xy 72.794839 -42.87097)
			(xy 72.764289 -42.913018) (xy 72.727538 -42.949769) (xy 72.68549 -42.980319) (xy 72.63918 -43.003915)
			(xy 72.58975 -43.019976) (xy 72.538415 -43.028106) (xy 72.486441 -43.028106) (xy 72.435106 -43.019976)
			(xy 72.385676 -43.003915) (xy 72.339366 -42.980319) (xy 72.297318 -42.949769) (xy 72.260567 -42.913018)
			(xy 72.230017 -42.87097) (xy 72.206421 -42.82466) (xy 72.19036 -42.77523) (xy 72.18223 -42.723895)
			(xy 69.907529 -42.723895) (xy 69.516041 -43.115309) (xy 73.903842 -43.115309) (xy 73.903842 -43.063335)
			(xy 73.911972 -43.012) (xy 73.928033 -42.96257) (xy 73.951629 -42.91626) (xy 73.982179 -42.874212)
			(xy 74.01893 -42.837461) (xy 74.060978 -42.806911) (xy 74.107288 -42.783315) (xy 74.156718 -42.767254)
			(xy 74.208053 -42.759124) (xy 74.260027 -42.759124) (xy 74.311362 -42.767254) (xy 74.360792 -42.783315)
			(xy 74.407102 -42.806911) (xy 74.44915 -42.837461) (xy 74.485901 -42.874212) (xy 74.516451 -42.91626)
			(xy 74.540047 -42.96257) (xy 74.556108 -43.012) (xy 74.564238 -43.063335) (xy 74.564748 -43.089322)
			(xy 74.564238 -43.115309) (xy 74.558486 -43.151631) (xy 74.703942 -43.151631) (xy 74.703942 -43.099657)
			(xy 74.712072 -43.048322) (xy 74.728133 -42.998892) (xy 74.751729 -42.952582) (xy 74.782279 -42.910534)
			(xy 74.81903 -42.873783) (xy 74.861078 -42.843233) (xy 74.907388 -42.819637) (xy 74.956818 -42.803576)
			(xy 75.008153 -42.795446) (xy 75.060127 -42.795446) (xy 75.111462 -42.803576) (xy 75.160892 -42.819637)
			(xy 75.207202 -42.843233) (xy 75.24925 -42.873783) (xy 75.286001 -42.910534) (xy 75.316551 -42.952582)
			(xy 75.340147 -42.998892) (xy 75.356208 -43.048322) (xy 75.364338 -43.099657) (xy 75.364848 -43.125644)
			(xy 75.364338 -43.151631) (xy 77.14031 -43.151631) (xy 77.14031 -43.099657) (xy 77.14844 -43.048322)
			(xy 77.164501 -42.998892) (xy 77.188097 -42.952582) (xy 77.218647 -42.910534) (xy 77.255398 -42.873783)
			(xy 77.297446 -42.843233) (xy 77.343756 -42.819637) (xy 77.393186 -42.803576) (xy 77.444521 -42.795446)
			(xy 77.496495 -42.795446) (xy 77.54783 -42.803576) (xy 77.59726 -42.819637) (xy 77.64357 -42.843233)
			(xy 77.685618 -42.873783) (xy 77.722369 -42.910534) (xy 77.752919 -42.952582) (xy 77.776515 -42.998892)
			(xy 77.792576 -43.048322) (xy 77.800706 -43.099657) (xy 77.801216 -43.125644) (xy 77.800706 -43.151631)
			(xy 77.94041 -43.151631) (xy 77.94041 -43.099657) (xy 77.94854 -43.048322) (xy 77.964601 -42.998892)
			(xy 77.988197 -42.952582) (xy 78.018747 -42.910534) (xy 78.055498 -42.873783) (xy 78.097546 -42.843233)
			(xy 78.143856 -42.819637) (xy 78.193286 -42.803576) (xy 78.244621 -42.795446) (xy 78.296595 -42.795446)
			(xy 78.34793 -42.803576) (xy 78.39736 -42.819637) (xy 78.44367 -42.843233) (xy 78.485718 -42.873783)
			(xy 78.522469 -42.910534) (xy 78.553019 -42.952582) (xy 78.576615 -42.998892) (xy 78.592676 -43.048322)
			(xy 78.600806 -43.099657) (xy 78.601113 -43.115309) (xy 78.703934 -43.115309) (xy 78.703934 -43.063335)
			(xy 78.712064 -43.012) (xy 78.728125 -42.96257) (xy 78.751721 -42.91626) (xy 78.782271 -42.874212)
			(xy 78.819022 -42.837461) (xy 78.86107 -42.806911) (xy 78.90738 -42.783315) (xy 78.95681 -42.767254)
			(xy 79.008145 -42.759124) (xy 79.060119 -42.759124) (xy 79.111454 -42.767254) (xy 79.160884 -42.783315)
			(xy 79.207194 -42.806911) (xy 79.249242 -42.837461) (xy 79.285993 -42.874212) (xy 79.316543 -42.91626)
			(xy 79.340139 -42.96257) (xy 79.3562 -43.012) (xy 79.36433 -43.063335) (xy 79.36484 -43.089322) (xy 79.36433 -43.115309)
			(xy 79.3562 -43.166644) (xy 79.340139 -43.216074) (xy 79.316543 -43.262384) (xy 79.285993 -43.304432)
			(xy 79.249242 -43.341183) (xy 79.207194 -43.371733) (xy 79.160884 -43.395329) (xy 79.111454 -43.41139)
			(xy 79.060119 -43.41952) (xy 79.008145 -43.41952) (xy 78.95681 -43.41139) (xy 78.90738 -43.395329)
			(xy 78.86107 -43.371733) (xy 78.819022 -43.341183) (xy 78.782271 -43.304432) (xy 78.751721 -43.262384)
			(xy 78.728125 -43.216074) (xy 78.712064 -43.166644) (xy 78.703934 -43.115309) (xy 78.601113 -43.115309)
			(xy 78.601316 -43.125644) (xy 78.600806 -43.151631) (xy 78.592676 -43.202966) (xy 78.576615 -43.252396)
			(xy 78.553019 -43.298706) (xy 78.522469 -43.340754) (xy 78.485718 -43.377505) (xy 78.44367 -43.408055)
			(xy 78.39736 -43.431651) (xy 78.34793 -43.447712) (xy 78.296595 -43.455842) (xy 78.244621 -43.455842)
			(xy 78.193286 -43.447712) (xy 78.143856 -43.431651) (xy 78.097546 -43.408055) (xy 78.055498 -43.377505)
			(xy 78.018747 -43.340754) (xy 77.988197 -43.298706) (xy 77.964601 -43.252396) (xy 77.94854 -43.202966)
			(xy 77.94041 -43.151631) (xy 77.800706 -43.151631) (xy 77.792576 -43.202966) (xy 77.776515 -43.252396)
			(xy 77.752919 -43.298706) (xy 77.722369 -43.340754) (xy 77.685618 -43.377505) (xy 77.64357 -43.408055)
			(xy 77.59726 -43.431651) (xy 77.54783 -43.447712) (xy 77.496495 -43.455842) (xy 77.444521 -43.455842)
			(xy 77.393186 -43.447712) (xy 77.343756 -43.431651) (xy 77.297446 -43.408055) (xy 77.255398 -43.377505)
			(xy 77.218647 -43.340754) (xy 77.188097 -43.298706) (xy 77.164501 -43.252396) (xy 77.14844 -43.202966)
			(xy 77.14031 -43.151631) (xy 75.364338 -43.151631) (xy 75.356208 -43.202966) (xy 75.340147 -43.252396)
			(xy 75.316551 -43.298706) (xy 75.286001 -43.340754) (xy 75.24925 -43.377505) (xy 75.207202 -43.408055)
			(xy 75.160892 -43.431651) (xy 75.111462 -43.447712) (xy 75.060127 -43.455842) (xy 75.008153 -43.455842)
			(xy 74.956818 -43.447712) (xy 74.907388 -43.431651) (xy 74.861078 -43.408055) (xy 74.81903 -43.377505)
			(xy 74.782279 -43.340754) (xy 74.751729 -43.298706) (xy 74.728133 -43.252396) (xy 74.712072 -43.202966)
			(xy 74.703942 -43.151631) (xy 74.558486 -43.151631) (xy 74.556108 -43.166644) (xy 74.540047 -43.216074)
			(xy 74.516451 -43.262384) (xy 74.485901 -43.304432) (xy 74.44915 -43.341183) (xy 74.407102 -43.371733)
			(xy 74.360792 -43.395329) (xy 74.311362 -43.41139) (xy 74.260027 -43.41952) (xy 74.208053 -43.41952)
			(xy 74.156718 -43.41139) (xy 74.107288 -43.395329) (xy 74.060978 -43.371733) (xy 74.01893 -43.341183)
			(xy 73.982179 -43.304432) (xy 73.951629 -43.262384) (xy 73.928033 -43.216074) (xy 73.911972 -43.166644)
			(xy 73.903842 -43.115309) (xy 69.516041 -43.115309) (xy 69.116502 -43.514772) (xy 70.60006 -43.514772)
			(xy 70.604131 -43.45915) (xy 70.616257 -43.404713) (xy 70.63618 -43.352622) (xy 70.663476 -43.303987)
			(xy 70.697562 -43.259844) (xy 70.737711 -43.221135) (xy 70.783069 -43.188684) (xy 70.832669 -43.163183)
			(xy 70.885453 -43.145176) (xy 70.940296 -43.135046) (xy 70.99603 -43.133009) (xy 71.051467 -43.139109)
			(xy 71.105424 -43.153215) (xy 71.156753 -43.175027) (xy 71.204359 -43.204081) (xy 71.247227 -43.239756)
			(xy 71.284444 -43.281293) (xy 71.315217 -43.327806) (xy 71.338889 -43.378303) (xy 71.354957 -43.43171)
			(xy 71.363077 -43.486886) (xy 71.363586 -43.514772) (xy 71.363246 -43.533393) (xy 79.662022 -43.533393)
			(xy 79.662022 -43.481419) (xy 79.670152 -43.430084) (xy 79.686213 -43.380654) (xy 79.709809 -43.334344)
			(xy 79.740359 -43.292296) (xy 79.77711 -43.255545) (xy 79.819158 -43.224995) (xy 79.865468 -43.201399)
			(xy 79.914898 -43.185338) (xy 79.966233 -43.177208) (xy 80.018207 -43.177208) (xy 80.069542 -43.185338)
			(xy 80.118972 -43.201399) (xy 80.165282 -43.224995) (xy 80.20733 -43.255545) (xy 80.244081 -43.292296)
			(xy 80.274631 -43.334344) (xy 80.298227 -43.380654) (xy 80.314288 -43.430084) (xy 80.322418 -43.481419)
			(xy 80.322928 -43.507406) (xy 80.322418 -43.533393) (xy 80.314288 -43.584728) (xy 80.298227 -43.634158)
			(xy 80.274631 -43.680468) (xy 80.244081 -43.722516) (xy 80.20733 -43.759267) (xy 80.165282 -43.789817)
			(xy 80.118972 -43.813413) (xy 80.069542 -43.829474) (xy 80.018207 -43.837604) (xy 79.966233 -43.837604)
			(xy 79.914898 -43.829474) (xy 79.865468 -43.813413) (xy 79.819158 -43.789817) (xy 79.77711 -43.759267)
			(xy 79.740359 -43.722516) (xy 79.709809 -43.680468) (xy 79.686213 -43.634158) (xy 79.670152 -43.584728)
			(xy 79.662022 -43.533393) (xy 71.363246 -43.533393) (xy 71.363077 -43.542658) (xy 71.354957 -43.597834)
			(xy 71.338889 -43.651241) (xy 71.315217 -43.701738) (xy 71.284444 -43.748251) (xy 71.247227 -43.789788)
			(xy 71.204359 -43.825463) (xy 71.156753 -43.854517) (xy 71.105424 -43.876329) (xy 71.051467 -43.890435)
			(xy 70.99603 -43.896535) (xy 70.940296 -43.894498) (xy 70.885453 -43.884368) (xy 70.832669 -43.866361)
			(xy 70.783069 -43.84086) (xy 70.737711 -43.808409) (xy 70.697562 -43.7697) (xy 70.663476 -43.725557)
			(xy 70.63618 -43.676922) (xy 70.616257 -43.624831) (xy 70.604131 -43.570394) (xy 70.60006 -43.514772)
			(xy 69.116502 -43.514772) (xy 68.832222 -43.798998) (xy 68.340938 -44.290467) (xy 69.149966 -44.290467)
			(xy 69.149966 -44.237169) (xy 69.157909 -44.184465) (xy 69.173619 -44.133535) (xy 69.196745 -44.085514)
			(xy 69.226769 -44.041477) (xy 69.263021 -44.002406) (xy 69.304692 -43.969175) (xy 69.35085 -43.942526)
			(xy 69.400464 -43.923054) (xy 69.452426 -43.911194) (xy 69.505576 -43.907211) (xy 69.558726 -43.911194)
			(xy 69.610688 -43.923054) (xy 69.660302 -43.942526) (xy 69.693404 -43.961637) (xy 71.545452 -43.961637)
			(xy 71.545452 -43.909663) (xy 71.553582 -43.858328) (xy 71.569643 -43.808898) (xy 71.593239 -43.762588)
			(xy 71.623789 -43.72054) (xy 71.66054 -43.683789) (xy 71.702588 -43.653239) (xy 71.748898 -43.629643)
			(xy 71.798328 -43.613582) (xy 71.849663 -43.605452) (xy 71.901637 -43.605452) (xy 71.952972 -43.613582)
			(xy 72.002402 -43.629643) (xy 72.048712 -43.653239) (xy 72.09076 -43.683789) (xy 72.127511 -43.72054)
			(xy 72.158061 -43.762588) (xy 72.181657 -43.808898) (xy 72.197718 -43.858328) (xy 72.205848 -43.909663)
			(xy 72.206358 -43.93565) (xy 72.206042 -43.951731) (xy 72.340472 -43.951731) (xy 72.340472 -43.899757)
			(xy 72.348602 -43.848422) (xy 72.364663 -43.798992) (xy 72.388259 -43.752682) (xy 72.418809 -43.710634)
			(xy 72.45556 -43.673883) (xy 72.497608 -43.643333) (xy 72.543918 -43.619737) (xy 72.593348 -43.603676)
			(xy 72.644683 -43.595546) (xy 72.696657 -43.595546) (xy 72.747992 -43.603676) (xy 72.797422 -43.619737)
			(xy 72.843732 -43.643333) (xy 72.88578 -43.673883) (xy 72.922531 -43.710634) (xy 72.953081 -43.752682)
			(xy 72.976677 -43.798992) (xy 72.992738 -43.848422) (xy 73.000868 -43.899757) (xy 73.00117 -43.915155)
			(xy 73.140318 -43.915155) (xy 73.140318 -43.863181) (xy 73.148448 -43.811846) (xy 73.164509 -43.762416)
			(xy 73.188105 -43.716106) (xy 73.218655 -43.674058) (xy 73.255406 -43.637307) (xy 73.297454 -43.606757)
			(xy 73.343764 -43.583161) (xy 73.393194 -43.5671) (xy 73.444529 -43.55897) (xy 73.496503 -43.55897)
			(xy 73.547838 -43.5671) (xy 73.597268 -43.583161) (xy 73.643578 -43.606757) (xy 73.685626 -43.637307)
			(xy 73.722377 -43.674058) (xy 73.752927 -43.716106) (xy 73.776523 -43.762416) (xy 73.792584 -43.811846)
			(xy 73.800714 -43.863181) (xy 73.801224 -43.889168) (xy 73.800714 -43.915155) (xy 73.794921 -43.951731)
			(xy 73.935338 -43.951731) (xy 73.935338 -43.899757) (xy 73.943468 -43.848422) (xy 73.959529 -43.798992)
			(xy 73.983125 -43.752682) (xy 74.013675 -43.710634) (xy 74.050426 -43.673883) (xy 74.092474 -43.643333)
			(xy 74.138784 -43.619737) (xy 74.188214 -43.603676) (xy 74.239549 -43.595546) (xy 74.291523 -43.595546)
			(xy 74.342858 -43.603676) (xy 74.392288 -43.619737) (xy 74.438598 -43.643333) (xy 74.480646 -43.673883)
			(xy 74.517397 -43.710634) (xy 74.547947 -43.752682) (xy 74.571543 -43.798992) (xy 74.587604 -43.848422)
			(xy 74.595734 -43.899757) (xy 74.596244 -43.925744) (xy 74.595734 -43.951731) (xy 74.703942 -43.951731)
			(xy 74.703942 -43.899757) (xy 74.712072 -43.848422) (xy 74.728133 -43.798992) (xy 74.751729 -43.752682)
			(xy 74.782279 -43.710634) (xy 74.81903 -43.673883) (xy 74.861078 -43.643333) (xy 74.907388 -43.619737)
			(xy 74.956818 -43.603676) (xy 75.008153 -43.595546) (xy 75.060127 -43.595546) (xy 75.111462 -43.603676)
			(xy 75.160892 -43.619737) (xy 75.207202 -43.643333) (xy 75.24925 -43.673883) (xy 75.286001 -43.710634)
			(xy 75.316551 -43.752682) (xy 75.340147 -43.798992) (xy 75.356208 -43.848422) (xy 75.364338 -43.899757)
			(xy 75.364848 -43.925744) (xy 75.364338 -43.951731) (xy 77.14031 -43.951731) (xy 77.14031 -43.899757)
			(xy 77.14844 -43.848422) (xy 77.164501 -43.798992) (xy 77.188097 -43.752682) (xy 77.218647 -43.710634)
			(xy 77.255398 -43.673883) (xy 77.297446 -43.643333) (xy 77.343756 -43.619737) (xy 77.393186 -43.603676)
			(xy 77.444521 -43.595546) (xy 77.496495 -43.595546) (xy 77.54783 -43.603676) (xy 77.59726 -43.619737)
			(xy 77.64357 -43.643333) (xy 77.685618 -43.673883) (xy 77.722369 -43.710634) (xy 77.752919 -43.752682)
			(xy 77.776515 -43.798992) (xy 77.792576 -43.848422) (xy 77.800706 -43.899757) (xy 77.801216 -43.925744)
			(xy 77.800706 -43.951731) (xy 77.94041 -43.951731) (xy 77.94041 -43.899757) (xy 77.94854 -43.848422)
			(xy 77.964601 -43.798992) (xy 77.988197 -43.752682) (xy 78.018747 -43.710634) (xy 78.055498 -43.673883)
			(xy 78.097546 -43.643333) (xy 78.143856 -43.619737) (xy 78.193286 -43.603676) (xy 78.244621 -43.595546)
			(xy 78.296595 -43.595546) (xy 78.34793 -43.603676) (xy 78.39736 -43.619737) (xy 78.44367 -43.643333)
			(xy 78.485718 -43.673883) (xy 78.522469 -43.710634) (xy 78.553019 -43.752682) (xy 78.576615 -43.798992)
			(xy 78.592676 -43.848422) (xy 78.600806 -43.899757) (xy 78.601316 -43.925744) (xy 78.600806 -43.951731)
			(xy 78.592676 -44.003066) (xy 78.576615 -44.052496) (xy 78.553019 -44.098806) (xy 78.522469 -44.140854)
			(xy 78.485718 -44.177605) (xy 78.44367 -44.208155) (xy 78.39736 -44.231751) (xy 78.34793 -44.247812)
			(xy 78.296595 -44.255942) (xy 78.244621 -44.255942) (xy 78.193286 -44.247812) (xy 78.143856 -44.231751)
			(xy 78.097546 -44.208155) (xy 78.055498 -44.177605) (xy 78.018747 -44.140854) (xy 77.988197 -44.098806)
			(xy 77.964601 -44.052496) (xy 77.94854 -44.003066) (xy 77.94041 -43.951731) (xy 77.800706 -43.951731)
			(xy 77.792576 -44.003066) (xy 77.776515 -44.052496) (xy 77.752919 -44.098806) (xy 77.722369 -44.140854)
			(xy 77.685618 -44.177605) (xy 77.64357 -44.208155) (xy 77.59726 -44.231751) (xy 77.54783 -44.247812)
			(xy 77.496495 -44.255942) (xy 77.444521 -44.255942) (xy 77.393186 -44.247812) (xy 77.343756 -44.231751)
			(xy 77.297446 -44.208155) (xy 77.255398 -44.177605) (xy 77.218647 -44.140854) (xy 77.188097 -44.098806)
			(xy 77.164501 -44.052496) (xy 77.14844 -44.003066) (xy 77.14031 -43.951731) (xy 75.364338 -43.951731)
			(xy 75.356208 -44.003066) (xy 75.340147 -44.052496) (xy 75.316551 -44.098806) (xy 75.286001 -44.140854)
			(xy 75.24925 -44.177605) (xy 75.207202 -44.208155) (xy 75.160892 -44.231751) (xy 75.111462 -44.247812)
			(xy 75.060127 -44.255942) (xy 75.008153 -44.255942) (xy 74.956818 -44.247812) (xy 74.907388 -44.231751)
			(xy 74.861078 -44.208155) (xy 74.81903 -44.177605) (xy 74.782279 -44.140854) (xy 74.751729 -44.098806)
			(xy 74.728133 -44.052496) (xy 74.712072 -44.003066) (xy 74.703942 -43.951731) (xy 74.595734 -43.951731)
			(xy 74.587604 -44.003066) (xy 74.571543 -44.052496) (xy 74.547947 -44.098806) (xy 74.517397 -44.140854)
			(xy 74.480646 -44.177605) (xy 74.438598 -44.208155) (xy 74.392288 -44.231751) (xy 74.342858 -44.247812)
			(xy 74.291523 -44.255942) (xy 74.239549 -44.255942) (xy 74.188214 -44.247812) (xy 74.138784 -44.231751)
			(xy 74.092474 -44.208155) (xy 74.050426 -44.177605) (xy 74.013675 -44.140854) (xy 73.983125 -44.098806)
			(xy 73.959529 -44.052496) (xy 73.943468 -44.003066) (xy 73.935338 -43.951731) (xy 73.794921 -43.951731)
			(xy 73.792584 -43.96649) (xy 73.776523 -44.01592) (xy 73.752927 -44.06223) (xy 73.722377 -44.104278)
			(xy 73.685626 -44.141029) (xy 73.643578 -44.171579) (xy 73.597268 -44.195175) (xy 73.547838 -44.211236)
			(xy 73.496503 -44.219366) (xy 73.444529 -44.219366) (xy 73.393194 -44.211236) (xy 73.343764 -44.195175)
			(xy 73.297454 -44.171579) (xy 73.255406 -44.141029) (xy 73.218655 -44.104278) (xy 73.188105 -44.06223)
			(xy 73.164509 -44.01592) (xy 73.148448 -43.96649) (xy 73.140318 -43.915155) (xy 73.00117 -43.915155)
			(xy 73.001378 -43.925744) (xy 73.000868 -43.951731) (xy 72.992738 -44.003066) (xy 72.976677 -44.052496)
			(xy 72.953081 -44.098806) (xy 72.922531 -44.140854) (xy 72.88578 -44.177605) (xy 72.843732 -44.208155)
			(xy 72.797422 -44.231751) (xy 72.747992 -44.247812) (xy 72.696657 -44.255942) (xy 72.644683 -44.255942)
			(xy 72.593348 -44.247812) (xy 72.543918 -44.231751) (xy 72.497608 -44.208155) (xy 72.45556 -44.177605)
			(xy 72.418809 -44.140854) (xy 72.388259 -44.098806) (xy 72.364663 -44.052496) (xy 72.348602 -44.003066)
			(xy 72.340472 -43.951731) (xy 72.206042 -43.951731) (xy 72.205848 -43.961637) (xy 72.197718 -44.012972)
			(xy 72.181657 -44.062402) (xy 72.158061 -44.108712) (xy 72.127511 -44.15076) (xy 72.09076 -44.187511)
			(xy 72.048712 -44.218061) (xy 72.002402 -44.241657) (xy 71.952972 -44.257718) (xy 71.901637 -44.265848)
			(xy 71.849663 -44.265848) (xy 71.798328 -44.257718) (xy 71.748898 -44.241657) (xy 71.702588 -44.218061)
			(xy 71.66054 -44.187511) (xy 71.623789 -44.15076) (xy 71.593239 -44.108712) (xy 71.569643 -44.062402)
			(xy 71.553582 -44.012972) (xy 71.545452 -43.961637) (xy 69.693404 -43.961637) (xy 69.70646 -43.969175)
			(xy 69.748131 -44.002406) (xy 69.784383 -44.041477) (xy 69.814407 -44.085514) (xy 69.837533 -44.133535)
			(xy 69.853243 -44.184465) (xy 69.861186 -44.237169) (xy 69.861684 -44.263818) (xy 69.861186 -44.290467)
			(xy 69.854702 -44.333493) (xy 79.662022 -44.333493) (xy 79.662022 -44.281519) (xy 79.670152 -44.230184)
			(xy 79.686213 -44.180754) (xy 79.709809 -44.134444) (xy 79.740359 -44.092396) (xy 79.77711 -44.055645)
			(xy 79.819158 -44.025095) (xy 79.865468 -44.001499) (xy 79.914898 -43.985438) (xy 79.966233 -43.977308)
			(xy 80.018207 -43.977308) (xy 80.069542 -43.985438) (xy 80.118972 -44.001499) (xy 80.165282 -44.025095)
			(xy 80.183061 -44.038012) (xy 81.757518 -44.038012) (xy 81.761589 -43.98239) (xy 81.773715 -43.927953)
			(xy 81.793638 -43.875862) (xy 81.820934 -43.827227) (xy 81.85502 -43.783084) (xy 81.895169 -43.744375)
			(xy 81.940527 -43.711924) (xy 81.990127 -43.686423) (xy 82.042911 -43.668416) (xy 82.097754 -43.658286)
			(xy 82.153488 -43.656249) (xy 82.208925 -43.662349) (xy 82.262882 -43.676455) (xy 82.314211 -43.698267)
			(xy 82.361817 -43.727321) (xy 82.404685 -43.762996) (xy 82.441902 -43.804533) (xy 82.472675 -43.851046)
			(xy 82.496347 -43.901543) (xy 82.512415 -43.95495) (xy 82.520535 -44.010126) (xy 82.521044 -44.038012)
			(xy 82.520535 -44.065898) (xy 82.512415 -44.121074) (xy 82.496347 -44.174481) (xy 82.472675 -44.224978)
			(xy 82.441902 -44.271491) (xy 82.404685 -44.313028) (xy 82.361817 -44.348703) (xy 82.314211 -44.377757)
			(xy 82.262882 -44.399569) (xy 82.208925 -44.413675) (xy 82.153488 -44.419775) (xy 82.097754 -44.417738)
			(xy 82.042911 -44.407608) (xy 81.990127 -44.389601) (xy 81.940527 -44.3641) (xy 81.895169 -44.331649)
			(xy 81.85502 -44.29294) (xy 81.820934 -44.248797) (xy 81.793638 -44.200162) (xy 81.773715 -44.148071)
			(xy 81.761589 -44.093634) (xy 81.757518 -44.038012) (xy 80.183061 -44.038012) (xy 80.20733 -44.055645)
			(xy 80.244081 -44.092396) (xy 80.274631 -44.134444) (xy 80.298227 -44.180754) (xy 80.314288 -44.230184)
			(xy 80.322418 -44.281519) (xy 80.322928 -44.307506) (xy 80.322418 -44.333493) (xy 80.314288 -44.384828)
			(xy 80.298227 -44.434258) (xy 80.274631 -44.480568) (xy 80.244081 -44.522616) (xy 80.20733 -44.559367)
			(xy 80.165282 -44.589917) (xy 80.118972 -44.613513) (xy 80.069542 -44.629574) (xy 80.018207 -44.637704)
			(xy 79.966233 -44.637704) (xy 79.914898 -44.629574) (xy 79.865468 -44.613513) (xy 79.819158 -44.589917)
			(xy 79.77711 -44.559367) (xy 79.740359 -44.522616) (xy 79.709809 -44.480568) (xy 79.686213 -44.434258)
			(xy 79.670152 -44.384828) (xy 79.662022 -44.333493) (xy 69.854702 -44.333493) (xy 69.853243 -44.343171)
			(xy 69.837533 -44.394101) (xy 69.814407 -44.442122) (xy 69.784383 -44.486159) (xy 69.748131 -44.52523)
			(xy 69.70646 -44.558461) (xy 69.660302 -44.58511) (xy 69.610688 -44.604582) (xy 69.558726 -44.616442)
			(xy 69.505576 -44.620426) (xy 69.452426 -44.616442) (xy 69.400464 -44.604582) (xy 69.35085 -44.58511)
			(xy 69.304692 -44.558461) (xy 69.263021 -44.52523) (xy 69.226769 -44.486159) (xy 69.196745 -44.442122)
			(xy 69.173619 -44.394101) (xy 69.157909 -44.343171) (xy 69.149966 -44.290467) (xy 68.340938 -44.290467)
			(xy 68.156328 -44.475146) (xy 68.150798 -44.487588) (xy 68.145872 -44.514356) (xy 68.148227 -44.541471)
			(xy 68.152518 -44.554394) (xy 68.177812 -44.565861) (xy 68.225066 -44.595033) (xy 68.267594 -44.630746)
			(xy 68.304497 -44.672244) (xy 68.334997 -44.718653) (xy 68.338229 -44.72559) (xy 70.269352 -44.72559)
			(xy 70.273423 -44.669968) (xy 70.285549 -44.615531) (xy 70.305472 -44.56344) (xy 70.332768 -44.514805)
			(xy 70.366854 -44.470662) (xy 70.407003 -44.431953) (xy 70.452361 -44.399502) (xy 70.501961 -44.374001)
			(xy 70.554745 -44.355994) (xy 70.609588 -44.345864) (xy 70.665322 -44.343827) (xy 70.720759 -44.349927)
			(xy 70.774716 -44.364033) (xy 70.826045 -44.385845) (xy 70.873651 -44.414899) (xy 70.916519 -44.450574)
			(xy 70.953736 -44.492111) (xy 70.984509 -44.538624) (xy 71.008181 -44.589121) (xy 71.024249 -44.642528)
			(xy 71.032369 -44.697704) (xy 71.032878 -44.72559) (xy 71.032404 -44.751577) (xy 72.340472 -44.751577)
			(xy 72.340472 -44.699603) (xy 72.348602 -44.648268) (xy 72.364663 -44.598838) (xy 72.388259 -44.552528)
			(xy 72.418809 -44.51048) (xy 72.45556 -44.473729) (xy 72.497608 -44.443179) (xy 72.543918 -44.419583)
			(xy 72.593348 -44.403522) (xy 72.644683 -44.395392) (xy 72.696657 -44.395392) (xy 72.747992 -44.403522)
			(xy 72.797422 -44.419583) (xy 72.843732 -44.443179) (xy 72.88578 -44.473729) (xy 72.922531 -44.51048)
			(xy 72.953081 -44.552528) (xy 72.976677 -44.598838) (xy 72.992738 -44.648268) (xy 73.000868 -44.699603)
			(xy 73.001378 -44.72559) (xy 73.000868 -44.751577) (xy 73.140318 -44.751577) (xy 73.140318 -44.699603)
			(xy 73.148448 -44.648268) (xy 73.164509 -44.598838) (xy 73.188105 -44.552528) (xy 73.218655 -44.51048)
			(xy 73.255406 -44.473729) (xy 73.297454 -44.443179) (xy 73.343764 -44.419583) (xy 73.393194 -44.403522)
			(xy 73.444529 -44.395392) (xy 73.496503 -44.395392) (xy 73.547838 -44.403522) (xy 73.597268 -44.419583)
			(xy 73.643578 -44.443179) (xy 73.685626 -44.473729) (xy 73.722377 -44.51048) (xy 73.752927 -44.552528)
			(xy 73.776523 -44.598838) (xy 73.792584 -44.648268) (xy 73.800714 -44.699603) (xy 73.801224 -44.72559)
			(xy 73.800714 -44.751577) (xy 73.940418 -44.751577) (xy 73.940418 -44.699603) (xy 73.948548 -44.648268)
			(xy 73.964609 -44.598838) (xy 73.988205 -44.552528) (xy 74.018755 -44.51048) (xy 74.055506 -44.473729)
			(xy 74.097554 -44.443179) (xy 74.143864 -44.419583) (xy 74.193294 -44.403522) (xy 74.244629 -44.395392)
			(xy 74.296603 -44.395392) (xy 74.347938 -44.403522) (xy 74.397368 -44.419583) (xy 74.443678 -44.443179)
			(xy 74.485726 -44.473729) (xy 74.522477 -44.51048) (xy 74.553027 -44.552528) (xy 74.576623 -44.598838)
			(xy 74.592684 -44.648268) (xy 74.600814 -44.699603) (xy 74.601324 -44.72559) (xy 74.600814 -44.751577)
			(xy 77.14031 -44.751577) (xy 77.14031 -44.699603) (xy 77.14844 -44.648268) (xy 77.164501 -44.598838)
			(xy 77.188097 -44.552528) (xy 77.218647 -44.51048) (xy 77.255398 -44.473729) (xy 77.297446 -44.443179)
			(xy 77.343756 -44.419583) (xy 77.393186 -44.403522) (xy 77.444521 -44.395392) (xy 77.496495 -44.395392)
			(xy 77.54783 -44.403522) (xy 77.59726 -44.419583) (xy 77.64357 -44.443179) (xy 77.685618 -44.473729)
			(xy 77.722369 -44.51048) (xy 77.752919 -44.552528) (xy 77.776515 -44.598838) (xy 77.792576 -44.648268)
			(xy 77.800706 -44.699603) (xy 77.801216 -44.72559) (xy 77.800706 -44.751577) (xy 77.94041 -44.751577)
			(xy 77.94041 -44.699603) (xy 77.94854 -44.648268) (xy 77.964601 -44.598838) (xy 77.988197 -44.552528)
			(xy 78.018747 -44.51048) (xy 78.055498 -44.473729) (xy 78.097546 -44.443179) (xy 78.143856 -44.419583)
			(xy 78.193286 -44.403522) (xy 78.244621 -44.395392) (xy 78.296595 -44.395392) (xy 78.34793 -44.403522)
			(xy 78.39736 -44.419583) (xy 78.44367 -44.443179) (xy 78.485718 -44.473729) (xy 78.522469 -44.51048)
			(xy 78.553019 -44.552528) (xy 78.576615 -44.598838) (xy 78.592676 -44.648268) (xy 78.600806 -44.699603)
			(xy 78.601316 -44.72559) (xy 78.600806 -44.751577) (xy 78.592676 -44.802912) (xy 78.576615 -44.852342)
			(xy 78.553019 -44.898652) (xy 78.522469 -44.9407) (xy 78.485718 -44.977451) (xy 78.44367 -45.008001)
			(xy 78.39736 -45.031597) (xy 78.34793 -45.047658) (xy 78.296595 -45.055788) (xy 78.244621 -45.055788)
			(xy 78.193286 -45.047658) (xy 78.143856 -45.031597) (xy 78.097546 -45.008001) (xy 78.055498 -44.977451)
			(xy 78.018747 -44.9407) (xy 77.988197 -44.898652) (xy 77.964601 -44.852342) (xy 77.94854 -44.802912)
			(xy 77.94041 -44.751577) (xy 77.800706 -44.751577) (xy 77.792576 -44.802912) (xy 77.776515 -44.852342)
			(xy 77.752919 -44.898652) (xy 77.722369 -44.9407) (xy 77.685618 -44.977451) (xy 77.64357 -45.008001)
			(xy 77.59726 -45.031597) (xy 77.54783 -45.047658) (xy 77.496495 -45.055788) (xy 77.444521 -45.055788)
			(xy 77.393186 -45.047658) (xy 77.343756 -45.031597) (xy 77.297446 -45.008001) (xy 77.255398 -44.977451)
			(xy 77.218647 -44.9407) (xy 77.188097 -44.898652) (xy 77.164501 -44.852342) (xy 77.14844 -44.802912)
			(xy 77.14031 -44.751577) (xy 74.600814 -44.751577) (xy 74.592684 -44.802912) (xy 74.576623 -44.852342)
			(xy 74.553027 -44.898652) (xy 74.522477 -44.9407) (xy 74.485726 -44.977451) (xy 74.443678 -45.008001)
			(xy 74.397368 -45.031597) (xy 74.347938 -45.047658) (xy 74.296603 -45.055788) (xy 74.244629 -45.055788)
			(xy 74.193294 -45.047658) (xy 74.143864 -45.031597) (xy 74.097554 -45.008001) (xy 74.055506 -44.977451)
			(xy 74.018755 -44.9407) (xy 73.988205 -44.898652) (xy 73.964609 -44.852342) (xy 73.948548 -44.802912)
			(xy 73.940418 -44.751577) (xy 73.800714 -44.751577) (xy 73.792584 -44.802912) (xy 73.776523 -44.852342)
			(xy 73.752927 -44.898652) (xy 73.722377 -44.9407) (xy 73.685626 -44.977451) (xy 73.643578 -45.008001)
			(xy 73.597268 -45.031597) (xy 73.547838 -45.047658) (xy 73.496503 -45.055788) (xy 73.444529 -45.055788)
			(xy 73.393194 -45.047658) (xy 73.343764 -45.031597) (xy 73.297454 -45.008001) (xy 73.255406 -44.977451)
			(xy 73.218655 -44.9407) (xy 73.188105 -44.898652) (xy 73.164509 -44.852342) (xy 73.148448 -44.802912)
			(xy 73.140318 -44.751577) (xy 73.000868 -44.751577) (xy 72.992738 -44.802912) (xy 72.976677 -44.852342)
			(xy 72.953081 -44.898652) (xy 72.922531 -44.9407) (xy 72.88578 -44.977451) (xy 72.843732 -45.008001)
			(xy 72.797422 -45.031597) (xy 72.747992 -45.047658) (xy 72.696657 -45.055788) (xy 72.644683 -45.055788)
			(xy 72.593348 -45.047658) (xy 72.543918 -45.031597) (xy 72.497608 -45.008001) (xy 72.45556 -44.977451)
			(xy 72.418809 -44.9407) (xy 72.388259 -44.898652) (xy 72.364663 -44.852342) (xy 72.348602 -44.802912)
			(xy 72.340472 -44.751577) (xy 71.032404 -44.751577) (xy 71.032369 -44.753476) (xy 71.024249 -44.808652)
			(xy 71.008181 -44.862059) (xy 70.984509 -44.912556) (xy 70.953736 -44.959069) (xy 70.916519 -45.000606)
			(xy 70.873651 -45.036281) (xy 70.826045 -45.065335) (xy 70.774716 -45.087147) (xy 70.720759 -45.101253)
			(xy 70.665322 -45.107353) (xy 70.609588 -45.105316) (xy 70.554745 -45.095186) (xy 70.501961 -45.077179)
			(xy 70.452361 -45.051678) (xy 70.407003 -45.019227) (xy 70.366854 -44.980518) (xy 70.332768 -44.936375)
			(xy 70.305472 -44.88774) (xy 70.285549 -44.835649) (xy 70.273423 -44.781212) (xy 70.269352 -44.72559)
			(xy 68.338229 -44.72559) (xy 68.35845 -44.768991) (xy 68.37436 -44.822197) (xy 68.382391 -44.877147)
			(xy 68.382896 -44.904914) (xy 68.382428 -44.932118) (xy 68.374733 -44.985979) (xy 68.359471 -45.038203)
			(xy 68.336951 -45.087732) (xy 68.322698 -45.110908) (xy 68.326476 -45.124473) (xy 68.340351 -45.148964)
			(xy 68.360368 -45.168754) (xy 68.372482 -45.175932) (xy 68.373498 -45.17644) (xy 68.380102 -45.18025)
			(xy 68.418456 -45.202602) (xy 68.426076 -45.19295) (xy 68.439687 -45.192962) (xy 68.466151 -45.186637)
			(xy 68.490003 -45.173546) (xy 68.50955 -45.154619) (xy 68.523403 -45.131201) (xy 68.530578 -45.104955)
			(xy 68.530978 -45.09135) (xy 68.530978 -45.091096) (xy 68.531484 -45.064015) (xy 68.539686 -45.010476)
			(xy 68.555901 -44.958798) (xy 68.579755 -44.910171) (xy 68.610697 -44.865716) (xy 68.648014 -44.82646)
			(xy 68.690845 -44.793307) (xy 68.738203 -44.767023) (xy 68.788995 -44.748213) (xy 68.842049 -44.737311)
			(xy 68.896142 -44.734569) (xy 68.950027 -44.740049) (xy 69.00246 -44.753627) (xy 69.052233 -44.774987)
			(xy 69.098198 -44.803638) (xy 69.139293 -44.83892) (xy 69.174572 -44.880017) (xy 69.203221 -44.925983)
			(xy 69.224579 -44.975757) (xy 69.238154 -45.028191) (xy 69.243632 -45.082076) (xy 69.241031 -45.133339)
			(xy 79.662022 -45.133339) (xy 79.662022 -45.081365) (xy 79.670152 -45.03003) (xy 79.686213 -44.9806)
			(xy 79.709809 -44.93429) (xy 79.740359 -44.892242) (xy 79.77711 -44.855491) (xy 79.819158 -44.824941)
			(xy 79.865468 -44.801345) (xy 79.914898 -44.785284) (xy 79.966233 -44.777154) (xy 80.018207 -44.777154)
			(xy 80.069542 -44.785284) (xy 80.118972 -44.801345) (xy 80.165282 -44.824941) (xy 80.20733 -44.855491)
			(xy 80.244081 -44.892242) (xy 80.274631 -44.93429) (xy 80.298227 -44.9806) (xy 80.314288 -45.03003)
			(xy 80.318086 -45.054012) (xy 81.757518 -45.054012) (xy 81.761589 -44.99839) (xy 81.773715 -44.943953)
			(xy 81.793638 -44.891862) (xy 81.820934 -44.843227) (xy 81.85502 -44.799084) (xy 81.895169 -44.760375)
			(xy 81.940527 -44.727924) (xy 81.990127 -44.702423) (xy 82.042911 -44.684416) (xy 82.097754 -44.674286)
			(xy 82.153488 -44.672249) (xy 82.208925 -44.678349) (xy 82.262882 -44.692455) (xy 82.314211 -44.714267)
			(xy 82.361817 -44.743321) (xy 82.404685 -44.778996) (xy 82.441902 -44.820533) (xy 82.472675 -44.867046)
			(xy 82.496347 -44.917543) (xy 82.512415 -44.97095) (xy 82.520535 -45.026126) (xy 82.521044 -45.054012)
			(xy 82.520535 -45.081898) (xy 82.512415 -45.137074) (xy 82.496347 -45.190481) (xy 82.472675 -45.240978)
			(xy 82.441902 -45.287491) (xy 82.404685 -45.329028) (xy 82.361817 -45.364703) (xy 82.314211 -45.393757)
			(xy 82.262882 -45.415569) (xy 82.208925 -45.429675) (xy 82.153488 -45.435775) (xy 82.097754 -45.433738)
			(xy 82.042911 -45.423608) (xy 81.990127 -45.405601) (xy 81.940527 -45.3801) (xy 81.895169 -45.347649)
			(xy 81.85502 -45.30894) (xy 81.820934 -45.264797) (xy 81.793638 -45.216162) (xy 81.773715 -45.164071)
			(xy 81.761589 -45.109634) (xy 81.757518 -45.054012) (xy 80.318086 -45.054012) (xy 80.322418 -45.081365)
			(xy 80.322928 -45.107352) (xy 80.322418 -45.133339) (xy 80.314288 -45.184674) (xy 80.298227 -45.234104)
			(xy 80.274631 -45.280414) (xy 80.244081 -45.322462) (xy 80.20733 -45.359213) (xy 80.165282 -45.389763)
			(xy 80.118972 -45.413359) (xy 80.069542 -45.42942) (xy 80.018207 -45.43755) (xy 79.966233 -45.43755)
			(xy 79.914898 -45.42942) (xy 79.865468 -45.413359) (xy 79.819158 -45.389763) (xy 79.77711 -45.359213)
			(xy 79.740359 -45.322462) (xy 79.709809 -45.280414) (xy 79.686213 -45.234104) (xy 79.670152 -45.184674)
			(xy 79.662022 -45.133339) (xy 69.241031 -45.133339) (xy 69.240887 -45.136169) (xy 69.229982 -45.189223)
			(xy 69.21117 -45.240013) (xy 69.184883 -45.28737) (xy 69.151728 -45.330199) (xy 69.11247 -45.367514)
			(xy 69.068014 -45.398454) (xy 69.019385 -45.422305) (xy 68.967706 -45.438518) (xy 68.914167 -45.446717)
			(xy 68.887086 -45.447204) (xy 68.856138 -45.446539) (xy 68.795174 -45.435842) (xy 68.736975 -45.414773)
			(xy 68.709794 -45.39996) (xy 68.696318 -45.392876) (xy 68.666638 -45.386168) (xy 68.636298 -45.388496)
			(xy 68.607989 -45.399653) (xy 68.584219 -45.41865) (xy 68.567095 -45.443804) (xy 68.558136 -45.472884)
			(xy 68.557648 -45.488098) (xy 68.557648 -45.488352) (xy 68.55715 -45.515001) (xy 68.551623 -45.551677)
			(xy 73.103996 -45.551677) (xy 73.103996 -45.499703) (xy 73.112126 -45.448368) (xy 73.128187 -45.398938)
			(xy 73.151783 -45.352628) (xy 73.182333 -45.31058) (xy 73.219084 -45.273829) (xy 73.261132 -45.243279)
			(xy 73.307442 -45.219683) (xy 73.356872 -45.203622) (xy 73.408207 -45.195492) (xy 73.460181 -45.195492)
			(xy 73.511516 -45.203622) (xy 73.560946 -45.219683) (xy 73.607256 -45.243279) (xy 73.649304 -45.273829)
			(xy 73.686055 -45.31058) (xy 73.716605 -45.352628) (xy 73.740201 -45.398938) (xy 73.756262 -45.448368)
			(xy 73.764392 -45.499703) (xy 73.764902 -45.52569) (xy 73.764392 -45.551677) (xy 73.903842 -45.551677)
			(xy 73.903842 -45.499703) (xy 73.911972 -45.448368) (xy 73.928033 -45.398938) (xy 73.951629 -45.352628)
			(xy 73.982179 -45.31058) (xy 74.01893 -45.273829) (xy 74.060978 -45.243279) (xy 74.107288 -45.219683)
			(xy 74.156718 -45.203622) (xy 74.208053 -45.195492) (xy 74.260027 -45.195492) (xy 74.311362 -45.203622)
			(xy 74.360792 -45.219683) (xy 74.407102 -45.243279) (xy 74.44915 -45.273829) (xy 74.485901 -45.31058)
			(xy 74.516451 -45.352628) (xy 74.540047 -45.398938) (xy 74.556108 -45.448368) (xy 74.564238 -45.499703)
			(xy 74.564748 -45.52569) (xy 74.564238 -45.551677) (xy 74.703942 -45.551677) (xy 74.703942 -45.499703)
			(xy 74.712072 -45.448368) (xy 74.728133 -45.398938) (xy 74.751729 -45.352628) (xy 74.782279 -45.31058)
			(xy 74.81903 -45.273829) (xy 74.861078 -45.243279) (xy 74.907388 -45.219683) (xy 74.956818 -45.203622)
			(xy 75.008153 -45.195492) (xy 75.060127 -45.195492) (xy 75.111462 -45.203622) (xy 75.160892 -45.219683)
			(xy 75.207202 -45.243279) (xy 75.24925 -45.273829) (xy 75.286001 -45.31058) (xy 75.316551 -45.352628)
			(xy 75.340147 -45.398938) (xy 75.356208 -45.448368) (xy 75.364338 -45.499703) (xy 75.364848 -45.52569)
			(xy 75.364338 -45.551677) (xy 77.14031 -45.551677) (xy 77.14031 -45.499703) (xy 77.14844 -45.448368)
			(xy 77.164501 -45.398938) (xy 77.188097 -45.352628) (xy 77.218647 -45.31058) (xy 77.255398 -45.273829)
			(xy 77.297446 -45.243279) (xy 77.343756 -45.219683) (xy 77.393186 -45.203622) (xy 77.444521 -45.195492)
			(xy 77.496495 -45.195492) (xy 77.54783 -45.203622) (xy 77.59726 -45.219683) (xy 77.64357 -45.243279)
			(xy 77.685618 -45.273829) (xy 77.722369 -45.31058) (xy 77.752919 -45.352628) (xy 77.776515 -45.398938)
			(xy 77.792576 -45.448368) (xy 77.800706 -45.499703) (xy 77.801216 -45.52569) (xy 77.800706 -45.551677)
			(xy 77.94041 -45.551677) (xy 77.94041 -45.499703) (xy 77.94854 -45.448368) (xy 77.964601 -45.398938)
			(xy 77.988197 -45.352628) (xy 78.018747 -45.31058) (xy 78.055498 -45.273829) (xy 78.097546 -45.243279)
			(xy 78.143856 -45.219683) (xy 78.193286 -45.203622) (xy 78.244621 -45.195492) (xy 78.296595 -45.195492)
			(xy 78.34793 -45.203622) (xy 78.39736 -45.219683) (xy 78.44367 -45.243279) (xy 78.485718 -45.273829)
			(xy 78.522469 -45.31058) (xy 78.553019 -45.352628) (xy 78.576615 -45.398938) (xy 78.592676 -45.448368)
			(xy 78.600806 -45.499703) (xy 78.601316 -45.52569) (xy 78.600806 -45.551677) (xy 78.592676 -45.603012)
			(xy 78.576615 -45.652442) (xy 78.553019 -45.698752) (xy 78.522469 -45.7408) (xy 78.485718 -45.777551)
			(xy 78.44367 -45.808101) (xy 78.39736 -45.831697) (xy 78.34793 -45.847758) (xy 78.296595 -45.855888)
			(xy 78.244621 -45.855888) (xy 78.193286 -45.847758) (xy 78.143856 -45.831697) (xy 78.097546 -45.808101)
			(xy 78.055498 -45.777551) (xy 78.018747 -45.7408) (xy 77.988197 -45.698752) (xy 77.964601 -45.652442)
			(xy 77.94854 -45.603012) (xy 77.94041 -45.551677) (xy 77.800706 -45.551677) (xy 77.792576 -45.603012)
			(xy 77.776515 -45.652442) (xy 77.752919 -45.698752) (xy 77.722369 -45.7408) (xy 77.685618 -45.777551)
			(xy 77.64357 -45.808101) (xy 77.59726 -45.831697) (xy 77.54783 -45.847758) (xy 77.496495 -45.855888)
			(xy 77.444521 -45.855888) (xy 77.393186 -45.847758) (xy 77.343756 -45.831697) (xy 77.297446 -45.808101)
			(xy 77.255398 -45.777551) (xy 77.218647 -45.7408) (xy 77.188097 -45.698752) (xy 77.164501 -45.652442)
			(xy 77.14844 -45.603012) (xy 77.14031 -45.551677) (xy 75.364338 -45.551677) (xy 75.356208 -45.603012)
			(xy 75.340147 -45.652442) (xy 75.316551 -45.698752) (xy 75.286001 -45.7408) (xy 75.24925 -45.777551)
			(xy 75.207202 -45.808101) (xy 75.160892 -45.831697) (xy 75.111462 -45.847758) (xy 75.060127 -45.855888)
			(xy 75.008153 -45.855888) (xy 74.956818 -45.847758) (xy 74.907388 -45.831697) (xy 74.861078 -45.808101)
			(xy 74.81903 -45.777551) (xy 74.782279 -45.7408) (xy 74.751729 -45.698752) (xy 74.728133 -45.652442)
			(xy 74.712072 -45.603012) (xy 74.703942 -45.551677) (xy 74.564238 -45.551677) (xy 74.556108 -45.603012)
			(xy 74.540047 -45.652442) (xy 74.516451 -45.698752) (xy 74.485901 -45.7408) (xy 74.44915 -45.777551)
			(xy 74.407102 -45.808101) (xy 74.360792 -45.831697) (xy 74.311362 -45.847758) (xy 74.260027 -45.855888)
			(xy 74.208053 -45.855888) (xy 74.156718 -45.847758) (xy 74.107288 -45.831697) (xy 74.060978 -45.808101)
			(xy 74.01893 -45.777551) (xy 73.982179 -45.7408) (xy 73.951629 -45.698752) (xy 73.928033 -45.652442)
			(xy 73.911972 -45.603012) (xy 73.903842 -45.551677) (xy 73.764392 -45.551677) (xy 73.756262 -45.603012)
			(xy 73.740201 -45.652442) (xy 73.716605 -45.698752) (xy 73.686055 -45.7408) (xy 73.649304 -45.777551)
			(xy 73.607256 -45.808101) (xy 73.560946 -45.831697) (xy 73.511516 -45.847758) (xy 73.460181 -45.855888)
			(xy 73.408207 -45.855888) (xy 73.356872 -45.847758) (xy 73.307442 -45.831697) (xy 73.261132 -45.808101)
			(xy 73.219084 -45.777551) (xy 73.182333 -45.7408) (xy 73.151783 -45.698752) (xy 73.128187 -45.652442)
			(xy 73.112126 -45.603012) (xy 73.103996 -45.551677) (xy 68.551623 -45.551677) (xy 68.549207 -45.567705)
			(xy 68.533497 -45.618635) (xy 68.510371 -45.666656) (xy 68.480347 -45.710693) (xy 68.444095 -45.749764)
			(xy 68.402424 -45.782995) (xy 68.356266 -45.809644) (xy 68.306652 -45.829116) (xy 68.25469 -45.840976)
			(xy 68.20154 -45.84496) (xy 68.14839 -45.840976) (xy 68.096428 -45.829116) (xy 68.046814 -45.809644)
			(xy 68.000656 -45.782995) (xy 67.958985 -45.749764) (xy 67.922733 -45.710693) (xy 67.892709 -45.666656)
			(xy 67.869583 -45.618635) (xy 67.853873 -45.567705) (xy 67.84593 -45.515001) (xy 67.845432 -45.488352)
			(xy 67.845696 -45.468693) (xy 67.850028 -45.429615) (xy 67.854068 -45.410374) (xy 67.856819 -45.395442)
			(xy 67.854421 -45.36519) (xy 67.843243 -45.336977) (xy 67.824271 -45.313292) (xy 67.799179 -45.296225)
			(xy 67.770181 -45.28728) (xy 67.755008 -45.286676) (xy 67.344798 -45.286676) (xy 67.125088 -45.506386)
			(xy 67.122294 -45.522134) (xy 67.117058 -45.54883) (xy 67.099565 -45.60034) (xy 67.074444 -45.648591)
			(xy 67.042278 -45.692461) (xy 67.003816 -45.730931) (xy 66.959952 -45.763106) (xy 66.911706 -45.788237)
			(xy 66.8602 -45.80574) (xy 66.833496 -45.810932) (xy 66.817748 -45.813726) (xy 66.698015 -45.933439)
			(xy 79.662022 -45.933439) (xy 79.662022 -45.881465) (xy 79.670152 -45.83013) (xy 79.686213 -45.7807)
			(xy 79.709809 -45.73439) (xy 79.740359 -45.692342) (xy 79.77711 -45.655591) (xy 79.819158 -45.625041)
			(xy 79.865468 -45.601445) (xy 79.914898 -45.585384) (xy 79.966233 -45.577254) (xy 80.018207 -45.577254)
			(xy 80.069542 -45.585384) (xy 80.118972 -45.601445) (xy 80.165282 -45.625041) (xy 80.20733 -45.655591)
			(xy 80.244081 -45.692342) (xy 80.274631 -45.73439) (xy 80.298227 -45.7807) (xy 80.314288 -45.83013)
			(xy 80.322418 -45.881465) (xy 80.322928 -45.907452) (xy 80.322418 -45.933439) (xy 80.314288 -45.984774)
			(xy 80.298227 -46.034204) (xy 80.274631 -46.080514) (xy 80.244081 -46.122562) (xy 80.20733 -46.159313)
			(xy 80.165282 -46.189863) (xy 80.118972 -46.213459) (xy 80.069542 -46.22952) (xy 80.018207 -46.23765)
			(xy 79.966233 -46.23765) (xy 79.914898 -46.22952) (xy 79.865468 -46.213459) (xy 79.819158 -46.189863)
			(xy 79.77711 -46.159313) (xy 79.740359 -46.122562) (xy 79.709809 -46.080514) (xy 79.686213 -46.034204)
			(xy 79.670152 -45.984774) (xy 79.662022 -45.933439) (xy 66.698015 -45.933439) (xy 66.279608 -46.351777)
			(xy 72.340472 -46.351777) (xy 72.340472 -46.299803) (xy 72.348602 -46.248468) (xy 72.364663 -46.199038)
			(xy 72.388259 -46.152728) (xy 72.418809 -46.11068) (xy 72.45556 -46.073929) (xy 72.497608 -46.043379)
			(xy 72.543918 -46.019783) (xy 72.593348 -46.003722) (xy 72.644683 -45.995592) (xy 72.696657 -45.995592)
			(xy 72.747992 -46.003722) (xy 72.797422 -46.019783) (xy 72.843732 -46.043379) (xy 72.88578 -46.073929)
			(xy 72.922531 -46.11068) (xy 72.953081 -46.152728) (xy 72.976677 -46.199038) (xy 72.992738 -46.248468)
			(xy 73.000868 -46.299803) (xy 73.001378 -46.32579) (xy 73.000868 -46.351777) (xy 73.140318 -46.351777)
			(xy 73.140318 -46.299803) (xy 73.148448 -46.248468) (xy 73.164509 -46.199038) (xy 73.188105 -46.152728)
			(xy 73.218655 -46.11068) (xy 73.255406 -46.073929) (xy 73.297454 -46.043379) (xy 73.343764 -46.019783)
			(xy 73.393194 -46.003722) (xy 73.444529 -45.995592) (xy 73.496503 -45.995592) (xy 73.547838 -46.003722)
			(xy 73.597268 -46.019783) (xy 73.643578 -46.043379) (xy 73.685626 -46.073929) (xy 73.722377 -46.11068)
			(xy 73.752927 -46.152728) (xy 73.776523 -46.199038) (xy 73.792584 -46.248468) (xy 73.800714 -46.299803)
			(xy 73.801224 -46.32579) (xy 73.800714 -46.351777) (xy 77.94041 -46.351777) (xy 77.94041 -46.299803)
			(xy 77.94854 -46.248468) (xy 77.964601 -46.199038) (xy 77.988197 -46.152728) (xy 78.018747 -46.11068)
			(xy 78.055498 -46.073929) (xy 78.097546 -46.043379) (xy 78.143856 -46.019783) (xy 78.193286 -46.003722)
			(xy 78.244621 -45.995592) (xy 78.296595 -45.995592) (xy 78.34793 -46.003722) (xy 78.39736 -46.019783)
			(xy 78.44367 -46.043379) (xy 78.485718 -46.073929) (xy 78.522469 -46.11068) (xy 78.553019 -46.152728)
			(xy 78.576615 -46.199038) (xy 78.592676 -46.248468) (xy 78.600806 -46.299803) (xy 78.601316 -46.32579)
			(xy 78.600806 -46.351777) (xy 78.740256 -46.351777) (xy 78.740256 -46.299803) (xy 78.748386 -46.248468)
			(xy 78.764447 -46.199038) (xy 78.788043 -46.152728) (xy 78.818593 -46.11068) (xy 78.855344 -46.073929)
			(xy 78.897392 -46.043379) (xy 78.943702 -46.019783) (xy 78.993132 -46.003722) (xy 79.044467 -45.995592)
			(xy 79.096441 -45.995592) (xy 79.147776 -46.003722) (xy 79.197206 -46.019783) (xy 79.243516 -46.043379)
			(xy 79.285564 -46.073929) (xy 79.322315 -46.11068) (xy 79.352865 -46.152728) (xy 79.376461 -46.199038)
			(xy 79.392522 -46.248468) (xy 79.400652 -46.299803) (xy 79.401162 -46.32579) (xy 79.400652 -46.351777)
			(xy 79.392522 -46.403112) (xy 79.376461 -46.452542) (xy 79.371028 -46.463204) (xy 83.795362 -46.463204)
			(xy 83.795913 -46.434108) (xy 83.804744 -46.376589) (xy 83.822216 -46.321081) (xy 83.847923 -46.268875)
			(xy 83.881267 -46.221182) (xy 83.921474 -46.179114) (xy 83.944206 -46.160944) (xy 83.954557 -46.152525)
			(xy 83.970815 -46.13138) (xy 83.981036 -46.106743) (xy 83.984523 -46.080299) (xy 83.981036 -46.053856)
			(xy 83.970814 -46.029219) (xy 83.954556 -46.008074) (xy 83.944206 -45.999654) (xy 83.921451 -45.981513)
			(xy 83.881258 -45.93943) (xy 83.847923 -45.891729) (xy 83.822221 -45.839518) (xy 83.804748 -45.78401)
			(xy 83.79591 -45.726491) (xy 83.795362 -45.697394) (xy 83.795809 -45.670023) (xy 83.803629 -45.615842)
			(xy 83.819122 -45.563339) (xy 83.841968 -45.513592) (xy 83.871698 -45.467626) (xy 83.889342 -45.446696)
			(xy 83.898581 -45.435372) (xy 83.910753 -45.408812) (xy 83.914922 -45.379895) (xy 83.91075 -45.350979)
			(xy 83.898576 -45.324421) (xy 83.889342 -45.313092) (xy 83.871695 -45.292164) (xy 83.841969 -45.246196)
			(xy 83.819123 -45.196449) (xy 83.803627 -45.143946) (xy 83.795798 -45.089767) (xy 83.795799 -45.035024)
			(xy 83.803629 -44.980845) (xy 83.819126 -44.928343) (xy 83.841973 -44.878596) (xy 83.8717 -44.832628)
			(xy 83.889342 -44.811696) (xy 83.898581 -44.800372) (xy 83.910753 -44.773812) (xy 83.914922 -44.744895)
			(xy 83.91075 -44.715979) (xy 83.898576 -44.689421) (xy 83.889342 -44.678092) (xy 83.871695 -44.657164)
			(xy 83.841969 -44.611196) (xy 83.819123 -44.561449) (xy 83.803627 -44.508946) (xy 83.795798 -44.454767)
			(xy 83.795799 -44.400024) (xy 83.803629 -44.345845) (xy 83.819126 -44.293343) (xy 83.841973 -44.243596)
			(xy 83.8717 -44.197628) (xy 83.889342 -44.176696) (xy 83.898581 -44.165372) (xy 83.910753 -44.138812)
			(xy 83.914922 -44.109895) (xy 83.91075 -44.080979) (xy 83.898576 -44.054421) (xy 83.889342 -44.043092)
			(xy 83.871695 -44.022164) (xy 83.841969 -43.976196) (xy 83.819123 -43.926449) (xy 83.803627 -43.873946)
			(xy 83.795798 -43.819767) (xy 83.795799 -43.765024) (xy 83.803629 -43.710845) (xy 83.819126 -43.658343)
			(xy 83.841973 -43.608596) (xy 83.8717 -43.562628) (xy 83.889342 -43.541696) (xy 83.898581 -43.530372)
			(xy 83.910753 -43.503812) (xy 83.914922 -43.474895) (xy 83.91075 -43.445979) (xy 83.898576 -43.419421)
			(xy 83.889342 -43.408092) (xy 83.871695 -43.387164) (xy 83.841969 -43.341196) (xy 83.819123 -43.291449)
			(xy 83.803627 -43.238946) (xy 83.795798 -43.184767) (xy 83.795799 -43.130024) (xy 83.803629 -43.075845)
			(xy 83.819126 -43.023343) (xy 83.841973 -42.973596) (xy 83.8717 -42.927628) (xy 83.889342 -42.906696)
			(xy 83.898581 -42.895372) (xy 83.910753 -42.868812) (xy 83.914922 -42.839895) (xy 83.91075 -42.810979)
			(xy 83.898576 -42.784421) (xy 83.889342 -42.773092) (xy 83.871695 -42.752164) (xy 83.841969 -42.706196)
			(xy 83.819123 -42.656449) (xy 83.803627 -42.603946) (xy 83.795798 -42.549767) (xy 83.795799 -42.495024)
			(xy 83.803629 -42.440845) (xy 83.819126 -42.388343) (xy 83.841973 -42.338596) (xy 83.8717 -42.292628)
			(xy 83.889342 -42.271696) (xy 83.898581 -42.260372) (xy 83.910753 -42.233812) (xy 83.914922 -42.204895)
			(xy 83.91075 -42.175979) (xy 83.898576 -42.149421) (xy 83.889342 -42.138092) (xy 83.871692 -42.117168)
			(xy 83.841981 -42.071194) (xy 83.819146 -42.021444) (xy 83.803658 -41.968942) (xy 83.795833 -41.914764)
			(xy 83.795362 -41.887394) (xy 83.795848 -41.860143) (xy 83.803604 -41.806195) (xy 83.818959 -41.7539)
			(xy 83.841601 -41.704323) (xy 83.871067 -41.658473) (xy 83.906758 -41.617282) (xy 83.947949 -41.581591)
			(xy 83.993799 -41.552125) (xy 84.043376 -41.529483) (xy 84.095671 -41.514128) (xy 84.149619 -41.506372)
			(xy 84.204121 -41.506372) (xy 84.258069 -41.514128) (xy 84.310364 -41.529483) (xy 84.359941 -41.552125)
			(xy 84.405791 -41.581591) (xy 84.446982 -41.617282) (xy 84.482673 -41.658473) (xy 84.512139 -41.704323)
			(xy 84.534781 -41.7539) (xy 84.550136 -41.806195) (xy 84.557892 -41.860143) (xy 84.558378 -41.887394)
			(xy 84.557914 -41.914764) (xy 84.550096 -41.968944) (xy 84.534607 -42.021447) (xy 84.511765 -42.071194)
			(xy 84.48204 -42.117161) (xy 84.464398 -42.138092) (xy 84.461708 -42.141394) (xy 85.927692 -42.141394)
			(xy 85.928185 -42.115331) (xy 85.935294 -42.063692) (xy 85.949364 -42.013501) (xy 85.970135 -41.965692)
			(xy 85.997218 -41.921154) (xy 86.030112 -41.880717) (xy 86.068202 -41.845133) (xy 86.089236 -41.829736)
			(xy 86.101497 -41.820341) (xy 86.12022 -41.795794) (xy 86.130772 -41.766781) (xy 86.132194 -41.735942)
			(xy 86.124357 -41.706081) (xy 86.107973 -41.679915) (xy 86.096602 -41.669462) (xy 86.076035 -41.651247)
			(xy 86.039844 -41.609914) (xy 86.00995 -41.56382) (xy 85.986973 -41.513918) (xy 85.971386 -41.461237)
			(xy 85.963512 -41.406865) (xy 85.963512 -41.351927) (xy 85.971388 -41.297556) (xy 85.986976 -41.244875)
			(xy 86.009954 -41.194973) (xy 86.039848 -41.14888) (xy 86.076041 -41.107548) (xy 86.096602 -41.089326)
			(xy 86.107956 -41.078837) (xy 86.124402 -41.05269) (xy 86.13228 -41.022822) (xy 86.130871 -40.991965)
			(xy 86.120303 -40.962939) (xy 86.101543 -40.9384) (xy 86.089236 -40.929052) (xy 86.068199 -40.913653)
			(xy 86.030084 -40.878085) (xy 85.997169 -40.837656) (xy 85.97007 -40.793119) (xy 85.94929 -40.745306)
			(xy 85.935219 -40.695108) (xy 85.928117 -40.643461) (xy 85.927692 -40.617394) (xy 85.928178 -40.590143)
			(xy 85.935934 -40.536195) (xy 85.951289 -40.4839) (xy 85.973931 -40.434323) (xy 86.003397 -40.388473)
			(xy 86.039088 -40.347282) (xy 86.080279 -40.311591) (xy 86.126129 -40.282125) (xy 86.175706 -40.259483)
			(xy 86.228001 -40.244128) (xy 86.281949 -40.236372) (xy 86.336451 -40.236372) (xy 86.390399 -40.244128)
			(xy 86.442694 -40.259483) (xy 86.492271 -40.282125) (xy 86.538121 -40.311591) (xy 86.579312 -40.347282)
			(xy 86.615003 -40.388473) (xy 86.644469 -40.434323) (xy 86.667111 -40.4839) (xy 86.682466 -40.536195)
			(xy 86.690222 -40.590143) (xy 86.690708 -40.617394) (xy 86.690218 -40.644863) (xy 86.682332 -40.699234)
			(xy 86.666737 -40.751913) (xy 86.643754 -40.801814) (xy 86.613857 -40.847907) (xy 86.577665 -40.88924)
			(xy 86.557104 -40.907462) (xy 86.545657 -40.917858) (xy 86.529214 -40.944032) (xy 86.521345 -40.973924)
			(xy 86.522772 -41.004802) (xy 86.533363 -41.033842) (xy 86.55215 -41.058389) (xy 86.56447 -41.067736)
			(xy 86.587112 -41.084338) (xy 86.62774 -41.123086) (xy 86.662251 -41.16737) (xy 86.689897 -41.216234)
			(xy 86.710083 -41.268623) (xy 86.722371 -41.323405) (xy 86.726498 -41.379397) (xy 86.722372 -41.435388)
			(xy 86.710085 -41.49017) (xy 86.6899 -41.542559) (xy 86.662254 -41.591424) (xy 86.627745 -41.635709)
			(xy 86.587117 -41.674458) (xy 86.56447 -41.691052) (xy 86.55222 -41.700461) (xy 86.533496 -41.725004)
			(xy 86.522942 -41.754013) (xy 86.521518 -41.78485) (xy 86.529353 -41.814709) (xy 86.545734 -41.840874)
			(xy 86.557104 -41.851326) (xy 86.577652 -41.869565) (xy 86.613859 -41.910886) (xy 86.643766 -41.956973)
			(xy 86.666754 -42.006872) (xy 86.68235 -42.059552) (xy 86.690229 -42.113924) (xy 86.690708 -42.141394)
			(xy 86.690222 -42.168645) (xy 86.682466 -42.222593) (xy 86.667111 -42.274888) (xy 86.644469 -42.324465)
			(xy 86.615003 -42.370315) (xy 86.579312 -42.411506) (xy 86.538121 -42.447197) (xy 86.492271 -42.476663)
			(xy 86.442694 -42.499305) (xy 86.390399 -42.51466) (xy 86.336451 -42.522416) (xy 86.281949 -42.522416)
			(xy 86.228001 -42.51466) (xy 86.175706 -42.499305) (xy 86.126129 -42.476663) (xy 86.080279 -42.447197)
			(xy 86.039088 -42.411506) (xy 86.003397 -42.370315) (xy 85.973931 -42.324465) (xy 85.951289 -42.274888)
			(xy 85.935934 -42.222593) (xy 85.928178 -42.168645) (xy 85.927692 -42.141394) (xy 84.461708 -42.141394)
			(xy 84.455167 -42.149424) (xy 84.442989 -42.17598) (xy 84.438816 -42.204895) (xy 84.442987 -42.233811)
			(xy 84.455162 -42.260369) (xy 84.464398 -42.271696) (xy 84.482032 -42.292634) (xy 84.511755 -42.338601)
			(xy 84.534599 -42.388347) (xy 84.550095 -42.440848) (xy 84.557923 -42.495025) (xy 84.557924 -42.549766)
			(xy 84.550097 -42.603943) (xy 84.534602 -42.656444) (xy 84.511759 -42.706191) (xy 84.482037 -42.752159)
			(xy 84.464398 -42.773092) (xy 84.455167 -42.784424) (xy 84.442989 -42.81098) (xy 84.438816 -42.839895)
			(xy 84.442987 -42.868811) (xy 84.455162 -42.895369) (xy 84.464398 -42.906696) (xy 84.482032 -42.927634)
			(xy 84.511755 -42.973601) (xy 84.534599 -43.023347) (xy 84.550095 -43.075848) (xy 84.557923 -43.130025)
			(xy 84.557923 -43.157394) (xy 85.927182 -43.157394) (xy 85.931253 -43.101772) (xy 85.943379 -43.047335)
			(xy 85.963302 -42.995244) (xy 85.990598 -42.946609) (xy 86.024684 -42.902466) (xy 86.064833 -42.863757)
			(xy 86.110191 -42.831306) (xy 86.159791 -42.805805) (xy 86.212575 -42.787798) (xy 86.267418 -42.777668)
			(xy 86.323152 -42.775631) (xy 86.378589 -42.781731) (xy 86.432546 -42.795837) (xy 86.483875 -42.817649)
			(xy 86.531481 -42.846703) (xy 86.574349 -42.882378) (xy 86.611566 -42.923915) (xy 86.642339 -42.970428)
			(xy 86.666011 -43.020925) (xy 86.682079 -43.074332) (xy 86.690199 -43.129508) (xy 86.690708 -43.157394)
			(xy 86.690199 -43.18528) (xy 86.682079 -43.240456) (xy 86.666011 -43.293863) (xy 86.642339 -43.34436)
			(xy 86.611566 -43.390873) (xy 86.574349 -43.43241) (xy 86.531481 -43.468085) (xy 86.483875 -43.497139)
			(xy 86.432546 -43.518951) (xy 86.378589 -43.533057) (xy 86.323152 -43.539157) (xy 86.267418 -43.53712)
			(xy 86.212575 -43.52699) (xy 86.159791 -43.508983) (xy 86.110191 -43.483482) (xy 86.064833 -43.451031)
			(xy 86.024684 -43.412322) (xy 85.990598 -43.368179) (xy 85.963302 -43.319544) (xy 85.943379 -43.267453)
			(xy 85.931253 -43.213016) (xy 85.927182 -43.157394) (xy 84.557923 -43.157394) (xy 84.557924 -43.184766)
			(xy 84.550097 -43.238943) (xy 84.534602 -43.291444) (xy 84.511759 -43.341191) (xy 84.482037 -43.387159)
			(xy 84.464398 -43.408092) (xy 84.455167 -43.419424) (xy 84.442989 -43.44598) (xy 84.438816 -43.474895)
			(xy 84.442987 -43.503811) (xy 84.455162 -43.530369) (xy 84.464398 -43.541696) (xy 84.482032 -43.562634)
			(xy 84.511755 -43.608601) (xy 84.534599 -43.658347) (xy 84.550095 -43.710848) (xy 84.557923 -43.765025)
			(xy 84.557924 -43.819766) (xy 84.550097 -43.873943) (xy 84.534602 -43.926444) (xy 84.511759 -43.976191)
			(xy 84.482037 -44.022159) (xy 84.468251 -44.03852) (xy 85.93023 -44.03852) (xy 85.934301 -43.982898)
			(xy 85.946427 -43.928461) (xy 85.96635 -43.87637) (xy 85.993646 -43.827735) (xy 86.027732 -43.783592)
			(xy 86.067881 -43.744883) (xy 86.113239 -43.712432) (xy 86.162839 -43.686931) (xy 86.215623 -43.668924)
			(xy 86.270466 -43.658794) (xy 86.3262 -43.656757) (xy 86.381637 -43.662857) (xy 86.435594 -43.676963)
			(xy 86.486923 -43.698775) (xy 86.534529 -43.727829) (xy 86.577397 -43.763504) (xy 86.614614 -43.805041)
			(xy 86.645387 -43.851554) (xy 86.669059 -43.902051) (xy 86.685127 -43.955458) (xy 86.693247 -44.010634)
			(xy 86.693756 -44.03852) (xy 86.693247 -44.066406) (xy 86.685127 -44.121582) (xy 86.669059 -44.174989)
			(xy 86.645387 -44.225486) (xy 86.614614 -44.271999) (xy 86.577397 -44.313536) (xy 86.534529 -44.349211)
			(xy 86.486923 -44.378265) (xy 86.435594 -44.400077) (xy 86.381637 -44.414183) (xy 86.3262 -44.420283)
			(xy 86.270466 -44.418246) (xy 86.215623 -44.408116) (xy 86.162839 -44.390109) (xy 86.113239 -44.364608)
			(xy 86.067881 -44.332157) (xy 86.027732 -44.293448) (xy 85.993646 -44.249305) (xy 85.96635 -44.20067)
			(xy 85.946427 -44.148579) (xy 85.934301 -44.094142) (xy 85.93023 -44.03852) (xy 84.468251 -44.03852)
			(xy 84.464398 -44.043092) (xy 84.455167 -44.054424) (xy 84.442989 -44.08098) (xy 84.438816 -44.109895)
			(xy 84.442987 -44.138811) (xy 84.455162 -44.165369) (xy 84.464398 -44.176696) (xy 84.482032 -44.197634)
			(xy 84.511755 -44.243601) (xy 84.534599 -44.293347) (xy 84.550095 -44.345848) (xy 84.557923 -44.400025)
			(xy 84.557924 -44.454766) (xy 84.550097 -44.508943) (xy 84.534602 -44.561444) (xy 84.511759 -44.611191)
			(xy 84.482037 -44.657159) (xy 84.464398 -44.678092) (xy 84.455167 -44.689424) (xy 84.442989 -44.71598)
			(xy 84.438816 -44.744895) (xy 84.442987 -44.773811) (xy 84.455162 -44.800369) (xy 84.464398 -44.811696)
			(xy 84.482032 -44.832634) (xy 84.511755 -44.878601) (xy 84.534599 -44.928347) (xy 84.550095 -44.980848)
			(xy 84.557923 -45.035025) (xy 84.557924 -45.089766) (xy 84.550097 -45.143943) (xy 84.534602 -45.196444)
			(xy 84.511759 -45.246191) (xy 84.482037 -45.292159) (xy 84.464398 -45.313092) (xy 84.455167 -45.324424)
			(xy 84.442989 -45.35098) (xy 84.438816 -45.379895) (xy 84.442987 -45.408811) (xy 84.455162 -45.435369)
			(xy 84.464398 -45.446696) (xy 84.482048 -45.467619) (xy 84.511759 -45.513594) (xy 84.534592 -45.563344)
			(xy 84.550081 -45.615847) (xy 84.557906 -45.670024) (xy 84.558378 -45.697394) (xy 84.55781 -45.72649)
			(xy 84.54898 -45.784007) (xy 84.531511 -45.839513) (xy 84.505807 -45.89172) (xy 84.472467 -45.939412)
			(xy 84.432264 -45.981483) (xy 84.409534 -45.999654) (xy 84.399261 -46.008131) (xy 84.383097 -46.029289)
			(xy 84.37294 -46.053901) (xy 84.369476 -46.080299) (xy 84.37294 -46.106698) (xy 84.383097 -46.13131)
			(xy 84.39926 -46.152468) (xy 84.409534 -46.160944) (xy 84.432275 -46.179102) (xy 84.472472 -46.22118)
			(xy 84.50581 -46.268877) (xy 84.531514 -46.321084) (xy 84.54899 -46.376591) (xy 84.557829 -46.434108)
			(xy 84.558378 -46.463204) (xy 84.557892 -46.490455) (xy 84.550136 -46.544403) (xy 84.534781 -46.596698)
			(xy 84.512139 -46.646275) (xy 84.482673 -46.692125) (xy 84.446982 -46.733316) (xy 84.405791 -46.769007)
			(xy 84.359941 -46.798473) (xy 84.310364 -46.821115) (xy 84.258069 -46.83647) (xy 84.204121 -46.844226)
			(xy 84.149619 -46.844226) (xy 84.095671 -46.83647) (xy 84.043376 -46.821115) (xy 83.993799 -46.798473)
			(xy 83.947949 -46.769007) (xy 83.906758 -46.733316) (xy 83.871067 -46.692125) (xy 83.841601 -46.646275)
			(xy 83.818959 -46.596698) (xy 83.803604 -46.544403) (xy 83.795848 -46.490455) (xy 83.795362 -46.463204)
			(xy 79.371028 -46.463204) (xy 79.352865 -46.498852) (xy 79.322315 -46.5409) (xy 79.285564 -46.577651)
			(xy 79.243516 -46.608201) (xy 79.197206 -46.631797) (xy 79.147776 -46.647858) (xy 79.096441 -46.655988)
			(xy 79.044467 -46.655988) (xy 78.993132 -46.647858) (xy 78.943702 -46.631797) (xy 78.897392 -46.608201)
			(xy 78.855344 -46.577651) (xy 78.818593 -46.5409) (xy 78.788043 -46.498852) (xy 78.764447 -46.452542)
			(xy 78.748386 -46.403112) (xy 78.740256 -46.351777) (xy 78.600806 -46.351777) (xy 78.592676 -46.403112)
			(xy 78.576615 -46.452542) (xy 78.553019 -46.498852) (xy 78.522469 -46.5409) (xy 78.485718 -46.577651)
			(xy 78.44367 -46.608201) (xy 78.39736 -46.631797) (xy 78.34793 -46.647858) (xy 78.296595 -46.655988)
			(xy 78.244621 -46.655988) (xy 78.193286 -46.647858) (xy 78.143856 -46.631797) (xy 78.097546 -46.608201)
			(xy 78.055498 -46.577651) (xy 78.018747 -46.5409) (xy 77.988197 -46.498852) (xy 77.964601 -46.452542)
			(xy 77.94854 -46.403112) (xy 77.94041 -46.351777) (xy 73.800714 -46.351777) (xy 73.792584 -46.403112)
			(xy 73.776523 -46.452542) (xy 73.752927 -46.498852) (xy 73.722377 -46.5409) (xy 73.685626 -46.577651)
			(xy 73.643578 -46.608201) (xy 73.597268 -46.631797) (xy 73.547838 -46.647858) (xy 73.496503 -46.655988)
			(xy 73.444529 -46.655988) (xy 73.393194 -46.647858) (xy 73.343764 -46.631797) (xy 73.297454 -46.608201)
			(xy 73.255406 -46.577651) (xy 73.218655 -46.5409) (xy 73.188105 -46.498852) (xy 73.164509 -46.452542)
			(xy 73.148448 -46.403112) (xy 73.140318 -46.351777) (xy 73.000868 -46.351777) (xy 72.992738 -46.403112)
			(xy 72.976677 -46.452542) (xy 72.953081 -46.498852) (xy 72.922531 -46.5409) (xy 72.88578 -46.577651)
			(xy 72.843732 -46.608201) (xy 72.797422 -46.631797) (xy 72.747992 -46.647858) (xy 72.696657 -46.655988)
			(xy 72.644683 -46.655988) (xy 72.593348 -46.647858) (xy 72.543918 -46.631797) (xy 72.497608 -46.608201)
			(xy 72.45556 -46.577651) (xy 72.418809 -46.5409) (xy 72.388259 -46.498852) (xy 72.364663 -46.452542)
			(xy 72.348602 -46.403112) (xy 72.340472 -46.351777) (xy 66.279608 -46.351777) (xy 65.479629 -47.151623)
			(xy 72.340472 -47.151623) (xy 72.340472 -47.099649) (xy 72.348602 -47.048314) (xy 72.364663 -46.998884)
			(xy 72.388259 -46.952574) (xy 72.418809 -46.910526) (xy 72.45556 -46.873775) (xy 72.497608 -46.843225)
			(xy 72.543918 -46.819629) (xy 72.593348 -46.803568) (xy 72.644683 -46.795438) (xy 72.696657 -46.795438)
			(xy 72.747992 -46.803568) (xy 72.797422 -46.819629) (xy 72.843732 -46.843225) (xy 72.88578 -46.873775)
			(xy 72.922531 -46.910526) (xy 72.953081 -46.952574) (xy 72.976677 -46.998884) (xy 72.992738 -47.048314)
			(xy 73.000868 -47.099649) (xy 73.001378 -47.125636) (xy 73.000868 -47.151623) (xy 73.140318 -47.151623)
			(xy 73.140318 -47.099649) (xy 73.148448 -47.048314) (xy 73.164509 -46.998884) (xy 73.188105 -46.952574)
			(xy 73.218655 -46.910526) (xy 73.255406 -46.873775) (xy 73.297454 -46.843225) (xy 73.343764 -46.819629)
			(xy 73.393194 -46.803568) (xy 73.444529 -46.795438) (xy 73.496503 -46.795438) (xy 73.547838 -46.803568)
			(xy 73.597268 -46.819629) (xy 73.643578 -46.843225) (xy 73.685626 -46.873775) (xy 73.722377 -46.910526)
			(xy 73.752927 -46.952574) (xy 73.776523 -46.998884) (xy 73.792584 -47.048314) (xy 73.800714 -47.099649)
			(xy 73.801224 -47.125636) (xy 73.800714 -47.151623) (xy 73.940418 -47.151623) (xy 73.940418 -47.099649)
			(xy 73.948548 -47.048314) (xy 73.964609 -46.998884) (xy 73.988205 -46.952574) (xy 74.018755 -46.910526)
			(xy 74.055506 -46.873775) (xy 74.097554 -46.843225) (xy 74.143864 -46.819629) (xy 74.193294 -46.803568)
			(xy 74.244629 -46.795438) (xy 74.296603 -46.795438) (xy 74.347938 -46.803568) (xy 74.397368 -46.819629)
			(xy 74.443678 -46.843225) (xy 74.485726 -46.873775) (xy 74.522477 -46.910526) (xy 74.553027 -46.952574)
			(xy 74.576623 -46.998884) (xy 74.592684 -47.048314) (xy 74.600814 -47.099649) (xy 74.601324 -47.125636)
			(xy 74.600814 -47.151623) (xy 74.704196 -47.151623) (xy 74.704196 -47.099649) (xy 74.712326 -47.048314)
			(xy 74.728387 -46.998884) (xy 74.751983 -46.952574) (xy 74.782533 -46.910526) (xy 74.819284 -46.873775)
			(xy 74.861332 -46.843225) (xy 74.907642 -46.819629) (xy 74.957072 -46.803568) (xy 75.008407 -46.795438)
			(xy 75.060381 -46.795438) (xy 75.111716 -46.803568) (xy 75.161146 -46.819629) (xy 75.207456 -46.843225)
			(xy 75.249504 -46.873775) (xy 75.286255 -46.910526) (xy 75.316805 -46.952574) (xy 75.340401 -46.998884)
			(xy 75.356462 -47.048314) (xy 75.364592 -47.099649) (xy 75.364899 -47.115301) (xy 77.903834 -47.115301)
			(xy 77.903834 -47.063327) (xy 77.911964 -47.011992) (xy 77.928025 -46.962562) (xy 77.951621 -46.916252)
			(xy 77.982171 -46.874204) (xy 78.018922 -46.837453) (xy 78.06097 -46.806903) (xy 78.10728 -46.783307)
			(xy 78.15671 -46.767246) (xy 78.208045 -46.759116) (xy 78.260019 -46.759116) (xy 78.311354 -46.767246)
			(xy 78.360784 -46.783307) (xy 78.407094 -46.806903) (xy 78.449142 -46.837453) (xy 78.485893 -46.874204)
			(xy 78.516443 -46.916252) (xy 78.540039 -46.962562) (xy 78.5561 -47.011992) (xy 78.56423 -47.063327)
			(xy 78.56474 -47.089314) (xy 78.56423 -47.115301) (xy 78.558478 -47.151623) (xy 78.703934 -47.151623)
			(xy 78.703934 -47.099649) (xy 78.712064 -47.048314) (xy 78.728125 -46.998884) (xy 78.751721 -46.952574)
			(xy 78.782271 -46.910526) (xy 78.819022 -46.873775) (xy 78.86107 -46.843225) (xy 78.90738 -46.819629)
			(xy 78.95681 -46.803568) (xy 79.008145 -46.795438) (xy 79.060119 -46.795438) (xy 79.111454 -46.803568)
			(xy 79.160884 -46.819629) (xy 79.207194 -46.843225) (xy 79.249242 -46.873775) (xy 79.285993 -46.910526)
			(xy 79.316543 -46.952574) (xy 79.340139 -46.998884) (xy 79.3562 -47.048314) (xy 79.36433 -47.099649)
			(xy 79.36484 -47.125636) (xy 79.36433 -47.151623) (xy 79.50378 -47.151623) (xy 79.50378 -47.099649)
			(xy 79.51191 -47.048314) (xy 79.527971 -46.998884) (xy 79.551567 -46.952574) (xy 79.582117 -46.910526)
			(xy 79.618868 -46.873775) (xy 79.660916 -46.843225) (xy 79.707226 -46.819629) (xy 79.756656 -46.803568)
			(xy 79.807991 -46.795438) (xy 79.859965 -46.795438) (xy 79.9113 -46.803568) (xy 79.96073 -46.819629)
			(xy 80.00704 -46.843225) (xy 80.049088 -46.873775) (xy 80.085839 -46.910526) (xy 80.116389 -46.952574)
			(xy 80.139985 -46.998884) (xy 80.156046 -47.048314) (xy 80.164176 -47.099649) (xy 80.164686 -47.125636)
			(xy 80.164176 -47.151623) (xy 80.156046 -47.202958) (xy 80.139985 -47.252388) (xy 80.116389 -47.298698)
			(xy 80.085839 -47.340746) (xy 80.049088 -47.377497) (xy 80.00704 -47.408047) (xy 79.96073 -47.431643)
			(xy 79.9113 -47.447704) (xy 79.859965 -47.455834) (xy 79.807991 -47.455834) (xy 79.756656 -47.447704)
			(xy 79.707226 -47.431643) (xy 79.660916 -47.408047) (xy 79.618868 -47.377497) (xy 79.582117 -47.340746)
			(xy 79.551567 -47.298698) (xy 79.527971 -47.252388) (xy 79.51191 -47.202958) (xy 79.50378 -47.151623)
			(xy 79.36433 -47.151623) (xy 79.3562 -47.202958) (xy 79.340139 -47.252388) (xy 79.316543 -47.298698)
			(xy 79.285993 -47.340746) (xy 79.249242 -47.377497) (xy 79.207194 -47.408047) (xy 79.160884 -47.431643)
			(xy 79.111454 -47.447704) (xy 79.060119 -47.455834) (xy 79.008145 -47.455834) (xy 78.95681 -47.447704)
			(xy 78.90738 -47.431643) (xy 78.86107 -47.408047) (xy 78.819022 -47.377497) (xy 78.782271 -47.340746)
			(xy 78.751721 -47.298698) (xy 78.728125 -47.252388) (xy 78.712064 -47.202958) (xy 78.703934 -47.151623)
			(xy 78.558478 -47.151623) (xy 78.5561 -47.166636) (xy 78.540039 -47.216066) (xy 78.516443 -47.262376)
			(xy 78.485893 -47.304424) (xy 78.449142 -47.341175) (xy 78.407094 -47.371725) (xy 78.360784 -47.395321)
			(xy 78.311354 -47.411382) (xy 78.260019 -47.419512) (xy 78.208045 -47.419512) (xy 78.15671 -47.411382)
			(xy 78.10728 -47.395321) (xy 78.06097 -47.371725) (xy 78.018922 -47.341175) (xy 77.982171 -47.304424)
			(xy 77.951621 -47.262376) (xy 77.928025 -47.216066) (xy 77.911964 -47.166636) (xy 77.903834 -47.115301)
			(xy 75.364899 -47.115301) (xy 75.365102 -47.125636) (xy 75.364592 -47.151623) (xy 75.356462 -47.202958)
			(xy 75.340401 -47.252388) (xy 75.316805 -47.298698) (xy 75.286255 -47.340746) (xy 75.249504 -47.377497)
			(xy 75.207456 -47.408047) (xy 75.161146 -47.431643) (xy 75.111716 -47.447704) (xy 75.060381 -47.455834)
			(xy 75.008407 -47.455834) (xy 74.957072 -47.447704) (xy 74.907642 -47.431643) (xy 74.861332 -47.408047)
			(xy 74.819284 -47.377497) (xy 74.782533 -47.340746) (xy 74.751983 -47.298698) (xy 74.728387 -47.252388)
			(xy 74.712326 -47.202958) (xy 74.704196 -47.151623) (xy 74.600814 -47.151623) (xy 74.592684 -47.202958)
			(xy 74.576623 -47.252388) (xy 74.553027 -47.298698) (xy 74.522477 -47.340746) (xy 74.485726 -47.377497)
			(xy 74.443678 -47.408047) (xy 74.397368 -47.431643) (xy 74.347938 -47.447704) (xy 74.296603 -47.455834)
			(xy 74.244629 -47.455834) (xy 74.193294 -47.447704) (xy 74.143864 -47.431643) (xy 74.097554 -47.408047)
			(xy 74.055506 -47.377497) (xy 74.018755 -47.340746) (xy 73.988205 -47.298698) (xy 73.964609 -47.252388)
			(xy 73.948548 -47.202958) (xy 73.940418 -47.151623) (xy 73.800714 -47.151623) (xy 73.792584 -47.202958)
			(xy 73.776523 -47.252388) (xy 73.752927 -47.298698) (xy 73.722377 -47.340746) (xy 73.685626 -47.377497)
			(xy 73.643578 -47.408047) (xy 73.597268 -47.431643) (xy 73.547838 -47.447704) (xy 73.496503 -47.455834)
			(xy 73.444529 -47.455834) (xy 73.393194 -47.447704) (xy 73.343764 -47.431643) (xy 73.297454 -47.408047)
			(xy 73.255406 -47.377497) (xy 73.218655 -47.340746) (xy 73.188105 -47.298698) (xy 73.164509 -47.252388)
			(xy 73.148448 -47.202958) (xy 73.140318 -47.151623) (xy 73.000868 -47.151623) (xy 72.992738 -47.202958)
			(xy 72.976677 -47.252388) (xy 72.953081 -47.298698) (xy 72.922531 -47.340746) (xy 72.88578 -47.377497)
			(xy 72.843732 -47.408047) (xy 72.797422 -47.431643) (xy 72.747992 -47.447704) (xy 72.696657 -47.455834)
			(xy 72.644683 -47.455834) (xy 72.593348 -47.447704) (xy 72.543918 -47.431643) (xy 72.497608 -47.408047)
			(xy 72.45556 -47.377497) (xy 72.418809 -47.340746) (xy 72.388259 -47.298698) (xy 72.364663 -47.252388)
			(xy 72.348602 -47.202958) (xy 72.340472 -47.151623) (xy 65.479629 -47.151623) (xy 65.286636 -47.344584)
			(xy 64.828592 -47.802779) (xy 66.730362 -47.802779) (xy 66.730362 -47.749481) (xy 66.738305 -47.696777)
			(xy 66.754015 -47.645847) (xy 66.777141 -47.597826) (xy 66.807165 -47.553789) (xy 66.843417 -47.514718)
			(xy 66.885088 -47.481487) (xy 66.931246 -47.454838) (xy 66.98086 -47.435366) (xy 67.032822 -47.423506)
			(xy 67.085972 -47.419523) (xy 67.139122 -47.423506) (xy 67.191084 -47.435366) (xy 67.240698 -47.454838)
			(xy 67.286856 -47.481487) (xy 67.328527 -47.514718) (xy 67.364779 -47.553789) (xy 67.394803 -47.597826)
			(xy 67.417929 -47.645847) (xy 67.433639 -47.696777) (xy 67.441582 -47.749481) (xy 67.44208 -47.77613)
			(xy 67.441582 -47.802779) (xy 67.433639 -47.855483) (xy 67.419105 -47.902601) (xy 68.344278 -47.902601)
			(xy 68.344278 -47.849303) (xy 68.352221 -47.796599) (xy 68.367931 -47.745669) (xy 68.391057 -47.697648)
			(xy 68.421081 -47.653611) (xy 68.457333 -47.61454) (xy 68.499004 -47.581309) (xy 68.545162 -47.55466)
			(xy 68.594776 -47.535188) (xy 68.646738 -47.523328) (xy 68.699888 -47.519345) (xy 68.753038 -47.523328)
			(xy 68.805 -47.535188) (xy 68.854614 -47.55466) (xy 68.900772 -47.581309) (xy 68.942443 -47.61454)
			(xy 68.978695 -47.653611) (xy 69.008719 -47.697648) (xy 69.031845 -47.745669) (xy 69.047555 -47.796599)
			(xy 69.055498 -47.849303) (xy 69.055996 -47.875952) (xy 69.055498 -47.902601) (xy 69.053607 -47.915147)
			(xy 77.903834 -47.915147) (xy 77.903834 -47.863173) (xy 77.911964 -47.811838) (xy 77.928025 -47.762408)
			(xy 77.951621 -47.716098) (xy 77.982171 -47.67405) (xy 78.018922 -47.637299) (xy 78.06097 -47.606749)
			(xy 78.10728 -47.583153) (xy 78.15671 -47.567092) (xy 78.208045 -47.558962) (xy 78.260019 -47.558962)
			(xy 78.311354 -47.567092) (xy 78.360784 -47.583153) (xy 78.407094 -47.606749) (xy 78.449142 -47.637299)
			(xy 78.485893 -47.67405) (xy 78.516443 -47.716098) (xy 78.540039 -47.762408) (xy 78.5561 -47.811838)
			(xy 78.56423 -47.863173) (xy 78.56474 -47.88916) (xy 78.56423 -47.915147) (xy 78.703934 -47.915147)
			(xy 78.703934 -47.863173) (xy 78.712064 -47.811838) (xy 78.728125 -47.762408) (xy 78.751721 -47.716098)
			(xy 78.782271 -47.67405) (xy 78.819022 -47.637299) (xy 78.86107 -47.606749) (xy 78.90738 -47.583153)
			(xy 78.95681 -47.567092) (xy 79.008145 -47.558962) (xy 79.060119 -47.558962) (xy 79.111454 -47.567092)
			(xy 79.160884 -47.583153) (xy 79.207194 -47.606749) (xy 79.249242 -47.637299) (xy 79.285993 -47.67405)
			(xy 79.316543 -47.716098) (xy 79.340139 -47.762408) (xy 79.3562 -47.811838) (xy 79.36433 -47.863173)
			(xy 79.36484 -47.88916) (xy 79.36433 -47.915147) (xy 79.3562 -47.966482) (xy 79.340139 -48.015912)
			(xy 79.316543 -48.062222) (xy 79.285993 -48.10427) (xy 79.249242 -48.141021) (xy 79.207194 -48.171571)
			(xy 79.160884 -48.195167) (xy 79.111454 -48.211228) (xy 79.060119 -48.219358) (xy 79.008145 -48.219358)
			(xy 78.95681 -48.211228) (xy 78.90738 -48.195167) (xy 78.86107 -48.171571) (xy 78.819022 -48.141021)
			(xy 78.782271 -48.10427) (xy 78.751721 -48.062222) (xy 78.728125 -48.015912) (xy 78.712064 -47.966482)
			(xy 78.703934 -47.915147) (xy 78.56423 -47.915147) (xy 78.5561 -47.966482) (xy 78.540039 -48.015912)
			(xy 78.516443 -48.062222) (xy 78.485893 -48.10427) (xy 78.449142 -48.141021) (xy 78.407094 -48.171571)
			(xy 78.360784 -48.195167) (xy 78.311354 -48.211228) (xy 78.260019 -48.219358) (xy 78.208045 -48.219358)
			(xy 78.15671 -48.211228) (xy 78.10728 -48.195167) (xy 78.06097 -48.171571) (xy 78.018922 -48.141021)
			(xy 77.982171 -48.10427) (xy 77.951621 -48.062222) (xy 77.928025 -48.015912) (xy 77.911964 -47.966482)
			(xy 77.903834 -47.915147) (xy 69.053607 -47.915147) (xy 69.047555 -47.955305) (xy 69.031845 -48.006235)
			(xy 69.008719 -48.054256) (xy 68.978695 -48.098293) (xy 68.942443 -48.137364) (xy 68.900772 -48.170595)
			(xy 68.854614 -48.197244) (xy 68.805 -48.216716) (xy 68.753038 -48.228576) (xy 68.699888 -48.23256)
			(xy 68.646738 -48.228576) (xy 68.594776 -48.216716) (xy 68.545162 -48.197244) (xy 68.499004 -48.170595)
			(xy 68.457333 -48.137364) (xy 68.421081 -48.098293) (xy 68.391057 -48.054256) (xy 68.367931 -48.006235)
			(xy 68.352221 -47.955305) (xy 68.344278 -47.902601) (xy 67.419105 -47.902601) (xy 67.417929 -47.906413)
			(xy 67.394803 -47.954434) (xy 67.364779 -47.998471) (xy 67.328527 -48.037542) (xy 67.286856 -48.070773)
			(xy 67.240698 -48.097422) (xy 67.191084 -48.116894) (xy 67.139122 -48.128754) (xy 67.085972 -48.132738)
			(xy 67.032822 -48.128754) (xy 66.98086 -48.116894) (xy 66.931246 -48.097422) (xy 66.885088 -48.070773)
			(xy 66.843417 -48.037542) (xy 66.807165 -47.998471) (xy 66.777141 -47.954434) (xy 66.754015 -47.906413)
			(xy 66.738305 -47.855483) (xy 66.730362 -47.802779) (xy 64.828592 -47.802779) (xy 64.515746 -48.115728)
			(xy 64.509955 -48.128871) (xy 64.50517 -48.157178) (xy 64.508442 -48.185699) (xy 64.519512 -48.212187)
			(xy 64.537508 -48.234555) (xy 64.561011 -48.25104) (xy 64.57442 -48.25619) (xy 64.600539 -48.263643)
			(xy 64.650088 -48.285884) (xy 64.695338 -48.315921) (xy 64.735072 -48.352948) (xy 64.768223 -48.395969)
			(xy 64.7939 -48.443828) (xy 64.811412 -48.495239) (xy 64.820289 -48.54882) (xy 64.8208 -48.575976)
			(xy 64.820319 -48.601963) (xy 64.959994 -48.601963) (xy 64.959994 -48.549989) (xy 64.968124 -48.498654)
			(xy 64.984185 -48.449224) (xy 65.007781 -48.402914) (xy 65.038331 -48.360866) (xy 65.075082 -48.324115)
			(xy 65.11713 -48.293565) (xy 65.16344 -48.269969) (xy 65.21287 -48.253908) (xy 65.264205 -48.245778)
			(xy 65.316179 -48.245778) (xy 65.367514 -48.253908) (xy 65.416944 -48.269969) (xy 65.463254 -48.293565)
			(xy 65.505302 -48.324115) (xy 65.514672 -48.333485) (xy 72.18223 -48.333485) (xy 72.18223 -48.281511)
			(xy 72.19036 -48.230176) (xy 72.206421 -48.180746) (xy 72.230017 -48.134436) (xy 72.260567 -48.092388)
			(xy 72.297318 -48.055637) (xy 72.339366 -48.025087) (xy 72.385676 -48.001491) (xy 72.435106 -47.98543)
			(xy 72.486441 -47.9773) (xy 72.538415 -47.9773) (xy 72.58975 -47.98543) (xy 72.63918 -48.001491)
			(xy 72.68549 -48.025087) (xy 72.727538 -48.055637) (xy 72.764289 -48.092388) (xy 72.794839 -48.134436)
			(xy 72.818435 -48.180746) (xy 72.834496 -48.230176) (xy 72.842626 -48.281511) (xy 72.843136 -48.307498)
			(xy 72.842626 -48.333485) (xy 72.834496 -48.38482) (xy 72.818435 -48.43425) (xy 72.794839 -48.48056)
			(xy 72.764289 -48.522608) (xy 72.727538 -48.559359) (xy 72.68549 -48.589909) (xy 72.63918 -48.613505)
			(xy 72.58975 -48.629566) (xy 72.538415 -48.637696) (xy 72.486441 -48.637696) (xy 72.435106 -48.629566)
			(xy 72.385676 -48.613505) (xy 72.339366 -48.589909) (xy 72.297318 -48.559359) (xy 72.260567 -48.522608)
			(xy 72.230017 -48.48056) (xy 72.206421 -48.43425) (xy 72.19036 -48.38482) (xy 72.18223 -48.333485)
			(xy 65.514672 -48.333485) (xy 65.542053 -48.360866) (xy 65.572603 -48.402914) (xy 65.596199 -48.449224)
			(xy 65.61226 -48.498654) (xy 65.62039 -48.549989) (xy 65.6209 -48.575976) (xy 65.62039 -48.601963)
			(xy 65.61226 -48.653298) (xy 65.596199 -48.702728) (xy 65.58982 -48.715247) (xy 73.140318 -48.715247)
			(xy 73.140318 -48.663273) (xy 73.148448 -48.611938) (xy 73.164509 -48.562508) (xy 73.188105 -48.516198)
			(xy 73.218655 -48.47415) (xy 73.255406 -48.437399) (xy 73.297454 -48.406849) (xy 73.343764 -48.383253)
			(xy 73.393194 -48.367192) (xy 73.444529 -48.359062) (xy 73.496503 -48.359062) (xy 73.547838 -48.367192)
			(xy 73.597268 -48.383253) (xy 73.643578 -48.406849) (xy 73.685626 -48.437399) (xy 73.722377 -48.47415)
			(xy 73.752927 -48.516198) (xy 73.776523 -48.562508) (xy 73.792584 -48.611938) (xy 73.800714 -48.663273)
			(xy 73.801224 -48.68926) (xy 73.800714 -48.715247) (xy 73.940418 -48.715247) (xy 73.940418 -48.663273)
			(xy 73.948548 -48.611938) (xy 73.964609 -48.562508) (xy 73.988205 -48.516198) (xy 74.018755 -48.47415)
			(xy 74.055506 -48.437399) (xy 74.097554 -48.406849) (xy 74.143864 -48.383253) (xy 74.193294 -48.367192)
			(xy 74.244629 -48.359062) (xy 74.296603 -48.359062) (xy 74.347938 -48.367192) (xy 74.397368 -48.383253)
			(xy 74.443678 -48.406849) (xy 74.485726 -48.437399) (xy 74.522477 -48.47415) (xy 74.553027 -48.516198)
			(xy 74.576623 -48.562508) (xy 74.592684 -48.611938) (xy 74.600814 -48.663273) (xy 74.601324 -48.68926)
			(xy 74.600814 -48.715247) (xy 77.903834 -48.715247) (xy 77.903834 -48.663273) (xy 77.911964 -48.611938)
			(xy 77.928025 -48.562508) (xy 77.951621 -48.516198) (xy 77.982171 -48.47415) (xy 78.018922 -48.437399)
			(xy 78.06097 -48.406849) (xy 78.10728 -48.383253) (xy 78.15671 -48.367192) (xy 78.208045 -48.359062)
			(xy 78.260019 -48.359062) (xy 78.311354 -48.367192) (xy 78.360784 -48.383253) (xy 78.407094 -48.406849)
			(xy 78.449142 -48.437399) (xy 78.485893 -48.47415) (xy 78.516443 -48.516198) (xy 78.540039 -48.562508)
			(xy 78.5561 -48.611938) (xy 78.56423 -48.663273) (xy 78.56474 -48.68926) (xy 78.56423 -48.715247)
			(xy 78.703934 -48.715247) (xy 78.703934 -48.663273) (xy 78.712064 -48.611938) (xy 78.728125 -48.562508)
			(xy 78.751721 -48.516198) (xy 78.782271 -48.47415) (xy 78.819022 -48.437399) (xy 78.86107 -48.406849)
			(xy 78.90738 -48.383253) (xy 78.95681 -48.367192) (xy 79.008145 -48.359062) (xy 79.060119 -48.359062)
			(xy 79.111454 -48.367192) (xy 79.160884 -48.383253) (xy 79.207194 -48.406849) (xy 79.249242 -48.437399)
			(xy 79.285993 -48.47415) (xy 79.316543 -48.516198) (xy 79.340139 -48.562508) (xy 79.3562 -48.611938)
			(xy 79.36433 -48.663273) (xy 79.36484 -48.68926) (xy 79.36433 -48.715247) (xy 79.50378 -48.715247)
			(xy 79.50378 -48.663273) (xy 79.51191 -48.611938) (xy 79.527971 -48.562508) (xy 79.551567 -48.516198)
			(xy 79.582117 -48.47415) (xy 79.618868 -48.437399) (xy 79.660916 -48.406849) (xy 79.707226 -48.383253)
			(xy 79.756656 -48.367192) (xy 79.807991 -48.359062) (xy 79.859965 -48.359062) (xy 79.9113 -48.367192)
			(xy 79.96073 -48.383253) (xy 80.00704 -48.406849) (xy 80.049088 -48.437399) (xy 80.085839 -48.47415)
			(xy 80.116389 -48.516198) (xy 80.139985 -48.562508) (xy 80.156046 -48.611938) (xy 80.164176 -48.663273)
			(xy 80.164686 -48.68926) (xy 80.164176 -48.715247) (xy 80.156046 -48.766582) (xy 80.139985 -48.816012)
			(xy 80.116389 -48.862322) (xy 80.109071 -48.872394) (xy 83.795362 -48.872394) (xy 83.795809 -48.845023)
			(xy 83.803629 -48.790842) (xy 83.819122 -48.738339) (xy 83.841968 -48.688592) (xy 83.871698 -48.642626)
			(xy 83.889342 -48.621696) (xy 83.898581 -48.610372) (xy 83.910753 -48.583812) (xy 83.914922 -48.554895)
			(xy 83.91075 -48.525979) (xy 83.898576 -48.499421) (xy 83.889342 -48.488092) (xy 83.871695 -48.467164)
			(xy 83.841969 -48.421196) (xy 83.819123 -48.371449) (xy 83.803627 -48.318946) (xy 83.795798 -48.264767)
			(xy 83.795799 -48.210024) (xy 83.803629 -48.155845) (xy 83.819126 -48.103343) (xy 83.841973 -48.053596)
			(xy 83.8717 -48.007628) (xy 83.889342 -47.986696) (xy 83.898581 -47.975372) (xy 83.910753 -47.948812)
			(xy 83.914922 -47.919895) (xy 83.91075 -47.890979) (xy 83.898576 -47.864421) (xy 83.889342 -47.853092)
			(xy 83.871692 -47.832168) (xy 83.841981 -47.786194) (xy 83.819146 -47.736444) (xy 83.803658 -47.683942)
			(xy 83.795833 -47.629764) (xy 83.795362 -47.602394) (xy 83.795848 -47.575143) (xy 83.803604 -47.521195)
			(xy 83.818959 -47.4689) (xy 83.841601 -47.419323) (xy 83.871067 -47.373473) (xy 83.906758 -47.332282)
			(xy 83.947949 -47.296591) (xy 83.993799 -47.267125) (xy 84.043376 -47.244483) (xy 84.095671 -47.229128)
			(xy 84.149619 -47.221372) (xy 84.204121 -47.221372) (xy 84.204274 -47.221394) (xy 85.927692 -47.221394)
			(xy 85.928218 -47.192689) (xy 85.936827 -47.135928) (xy 85.953835 -47.081096) (xy 85.978858 -47.029426)
			(xy 86.011334 -46.982085) (xy 86.05053 -46.940137) (xy 86.072726 -46.921928) (xy 86.084425 -46.912049)
			(xy 86.101766 -46.88683) (xy 86.110846 -46.857602) (xy 86.110846 -46.826996) (xy 86.101766 -46.797768)
			(xy 86.084424 -46.77255) (xy 86.072726 -46.76267) (xy 86.050543 -46.744444) (xy 86.011332 -46.702509)
			(xy 85.978846 -46.655174) (xy 85.953818 -46.603506) (xy 85.936811 -46.548672) (xy 85.92821 -46.491909)
			(xy 85.927692 -46.463204) (xy 85.928232 -46.434107) (xy 85.937063 -46.376587) (xy 85.954536 -46.321079)
			(xy 85.980245 -46.268872) (xy 86.013592 -46.22118) (xy 86.053802 -46.179113) (xy 86.076536 -46.160944)
			(xy 86.086884 -46.152523) (xy 86.103137 -46.131377) (xy 86.113355 -46.106741) (xy 86.116841 -46.080299)
			(xy 86.113355 -46.053857) (xy 86.103137 -46.029222) (xy 86.086883 -46.008076) (xy 86.076536 -45.999654)
			(xy 86.053787 -45.981505) (xy 86.013593 -45.939424) (xy 85.980257 -45.891725) (xy 85.954553 -45.839516)
			(xy 85.937079 -45.784009) (xy 85.92824 -45.726491) (xy 85.927692 -45.697394) (xy 85.928171 -45.668475)
			(xy 85.936903 -45.611301) (xy 85.954167 -45.556099) (xy 85.979566 -45.504137) (xy 86.012518 -45.456605)
			(xy 86.052268 -45.414591) (xy 86.074758 -45.396404) (xy 86.086572 -45.386515) (xy 86.104094 -45.36119)
			(xy 86.113272 -45.331794) (xy 86.113271 -45.300999) (xy 86.104091 -45.271603) (xy 86.086567 -45.24628)
			(xy 86.074758 -45.236384) (xy 86.052258 -45.218213) (xy 86.012526 -45.176188) (xy 85.97959 -45.128648)
			(xy 85.954205 -45.076683) (xy 85.936952 -45.021483) (xy 85.928226 -44.964311) (xy 85.927692 -44.935394)
			(xy 85.928178 -44.908143) (xy 85.935934 -44.854195) (xy 85.951289 -44.8019) (xy 85.973931 -44.752323)
			(xy 86.003397 -44.706473) (xy 86.039088 -44.665282) (xy 86.080279 -44.629591) (xy 86.126129 -44.600125)
			(xy 86.175706 -44.577483) (xy 86.228001 -44.562128) (xy 86.281949 -44.554372) (xy 86.336451 -44.554372)
			(xy 86.390399 -44.562128) (xy 86.442694 -44.577483) (xy 86.492271 -44.600125) (xy 86.538121 -44.629591)
			(xy 86.579312 -44.665282) (xy 86.615003 -44.706473) (xy 86.644469 -44.752323) (xy 86.667111 -44.8019)
			(xy 86.682466 -44.854195) (xy 86.690222 -44.908143) (xy 86.690708 -44.935394) (xy 86.69022 -44.964312)
			(xy 86.68149 -45.021487) (xy 86.664228 -45.076688) (xy 86.638831 -45.12865) (xy 86.60588 -45.176183)
			(xy 86.566131 -45.218196) (xy 86.543642 -45.236384) (xy 86.53184 -45.246286) (xy 86.514317 -45.271607)
			(xy 86.505138 -45.301) (xy 86.505137 -45.331793) (xy 86.514314 -45.361186) (xy 86.531835 -45.386508)
			(xy 86.543642 -45.396404) (xy 86.566136 -45.414582) (xy 86.605869 -45.456606) (xy 86.638805 -45.504144)
			(xy 86.664191 -45.556107) (xy 86.681446 -45.611307) (xy 86.690173 -45.668477) (xy 86.690708 -45.697394)
			(xy 86.690167 -45.726491) (xy 86.681336 -45.784011) (xy 86.663863 -45.839519) (xy 86.638154 -45.891726)
			(xy 86.604807 -45.939418) (xy 86.564598 -45.981485) (xy 86.541864 -45.999654) (xy 86.531588 -46.00813)
			(xy 86.51542 -46.029286) (xy 86.505259 -46.053899) (xy 86.501794 -46.080299) (xy 86.505259 -46.1067)
			(xy 86.515419 -46.131312) (xy 86.531587 -46.152469) (xy 86.541864 -46.160944) (xy 86.564612 -46.179094)
			(xy 86.604807 -46.221175) (xy 86.638143 -46.268873) (xy 86.663846 -46.321082) (xy 86.68132 -46.37659)
			(xy 86.690159 -46.434107) (xy 86.690708 -46.463204) (xy 86.690181 -46.491909) (xy 86.681572 -46.548669)
			(xy 86.664564 -46.603502) (xy 86.639541 -46.655172) (xy 86.607066 -46.702513) (xy 86.56787 -46.744461)
			(xy 86.545674 -46.76267) (xy 86.534025 -46.772578) (xy 86.516769 -46.797811) (xy 86.507738 -46.827015)
			(xy 86.507738 -46.857584) (xy 86.516769 -46.886788) (xy 86.534024 -46.912021) (xy 86.545674 -46.921928)
			(xy 86.567856 -46.940155) (xy 86.607067 -46.98209) (xy 86.639553 -47.029425) (xy 86.664582 -47.081092)
			(xy 86.681589 -47.135926) (xy 86.690189 -47.192689) (xy 86.690708 -47.221394) (xy 86.690222 -47.248645)
			(xy 86.682466 -47.302593) (xy 86.667111 -47.354888) (xy 86.644469 -47.404465) (xy 86.615003 -47.450315)
			(xy 86.579312 -47.491506) (xy 86.538121 -47.527197) (xy 86.492271 -47.556663) (xy 86.442694 -47.579305)
			(xy 86.390399 -47.59466) (xy 86.336451 -47.602416) (xy 86.281949 -47.602416) (xy 86.228001 -47.59466)
			(xy 86.175706 -47.579305) (xy 86.126129 -47.556663) (xy 86.080279 -47.527197) (xy 86.039088 -47.491506)
			(xy 86.003397 -47.450315) (xy 85.973931 -47.404465) (xy 85.951289 -47.354888) (xy 85.935934 -47.302593)
			(xy 85.928178 -47.248645) (xy 85.927692 -47.221394) (xy 84.204274 -47.221394) (xy 84.258069 -47.229128)
			(xy 84.310364 -47.244483) (xy 84.359941 -47.267125) (xy 84.405791 -47.296591) (xy 84.446982 -47.332282)
			(xy 84.482673 -47.373473) (xy 84.512139 -47.419323) (xy 84.534781 -47.4689) (xy 84.550136 -47.521195)
			(xy 84.557892 -47.575143) (xy 84.558378 -47.602394) (xy 84.557914 -47.629764) (xy 84.550096 -47.683944)
			(xy 84.534607 -47.736447) (xy 84.511765 -47.786194) (xy 84.48204 -47.832161) (xy 84.464398 -47.853092)
			(xy 84.455167 -47.864424) (xy 84.442989 -47.89098) (xy 84.438816 -47.919895) (xy 84.442987 -47.948811)
			(xy 84.455162 -47.975369) (xy 84.464398 -47.986696) (xy 84.482032 -48.007634) (xy 84.511755 -48.053601)
			(xy 84.534599 -48.103347) (xy 84.550095 -48.155848) (xy 84.557923 -48.210025) (xy 84.557923 -48.237394)
			(xy 85.927182 -48.237394) (xy 85.931253 -48.181772) (xy 85.943379 -48.127335) (xy 85.963302 -48.075244)
			(xy 85.990598 -48.026609) (xy 86.024684 -47.982466) (xy 86.064833 -47.943757) (xy 86.110191 -47.911306)
			(xy 86.159791 -47.885805) (xy 86.212575 -47.867798) (xy 86.267418 -47.857668) (xy 86.323152 -47.855631)
			(xy 86.378589 -47.861731) (xy 86.432546 -47.875837) (xy 86.483875 -47.897649) (xy 86.531481 -47.926703)
			(xy 86.574349 -47.962378) (xy 86.611566 -48.003915) (xy 86.642339 -48.050428) (xy 86.666011 -48.100925)
			(xy 86.682079 -48.154332) (xy 86.690199 -48.209508) (xy 86.690708 -48.237394) (xy 86.690199 -48.26528)
			(xy 86.682079 -48.320456) (xy 86.666011 -48.373863) (xy 86.642339 -48.42436) (xy 86.611566 -48.470873)
			(xy 86.574349 -48.51241) (xy 86.531481 -48.548085) (xy 86.483875 -48.577139) (xy 86.432546 -48.598951)
			(xy 86.378589 -48.613057) (xy 86.323152 -48.619157) (xy 86.267418 -48.61712) (xy 86.212575 -48.60699)
			(xy 86.159791 -48.588983) (xy 86.110191 -48.563482) (xy 86.064833 -48.531031) (xy 86.024684 -48.492322)
			(xy 85.990598 -48.448179) (xy 85.963302 -48.399544) (xy 85.943379 -48.347453) (xy 85.931253 -48.293016)
			(xy 85.927182 -48.237394) (xy 84.557923 -48.237394) (xy 84.557924 -48.264766) (xy 84.550097 -48.318943)
			(xy 84.534602 -48.371444) (xy 84.511759 -48.421191) (xy 84.482037 -48.467159) (xy 84.464398 -48.488092)
			(xy 84.455167 -48.499424) (xy 84.442989 -48.52598) (xy 84.438816 -48.554895) (xy 84.442987 -48.583811)
			(xy 84.455162 -48.610369) (xy 84.464398 -48.621696) (xy 84.482048 -48.642619) (xy 84.511759 -48.688594)
			(xy 84.534592 -48.738344) (xy 84.550081 -48.790847) (xy 84.557906 -48.845024) (xy 84.558378 -48.872394)
			(xy 84.557892 -48.899645) (xy 84.550136 -48.953593) (xy 84.534781 -49.005888) (xy 84.512139 -49.055465)
			(xy 84.482673 -49.101315) (xy 84.452579 -49.136046) (xy 85.317582 -49.136046) (xy 85.321653 -49.080424)
			(xy 85.333779 -49.025987) (xy 85.353702 -48.973896) (xy 85.380998 -48.925261) (xy 85.415084 -48.881118)
			(xy 85.455233 -48.842409) (xy 85.500591 -48.809958) (xy 85.550191 -48.784457) (xy 85.602975 -48.76645)
			(xy 85.657818 -48.75632) (xy 85.713552 -48.754283) (xy 85.768989 -48.760383) (xy 85.822946 -48.774489)
			(xy 85.874275 -48.796301) (xy 85.921881 -48.825355) (xy 85.964749 -48.86103) (xy 86.001966 -48.902567)
			(xy 86.032739 -48.94908) (xy 86.056411 -48.999577) (xy 86.072479 -49.052984) (xy 86.080599 -49.10816)
			(xy 86.081108 -49.136046) (xy 86.080599 -49.163932) (xy 86.072479 -49.219108) (xy 86.056411 -49.272515)
			(xy 86.032739 -49.323012) (xy 86.001966 -49.369525) (xy 85.964749 -49.411062) (xy 85.921881 -49.446737)
			(xy 85.874275 -49.475791) (xy 85.822946 -49.497603) (xy 85.768989 -49.511709) (xy 85.713552 -49.517809)
			(xy 85.657818 -49.515772) (xy 85.602975 -49.505642) (xy 85.550191 -49.487635) (xy 85.500591 -49.462134)
			(xy 85.455233 -49.429683) (xy 85.415084 -49.390974) (xy 85.380998 -49.346831) (xy 85.353702 -49.298196)
			(xy 85.333779 -49.246105) (xy 85.321653 -49.191668) (xy 85.317582 -49.136046) (xy 84.452579 -49.136046)
			(xy 84.446982 -49.142506) (xy 84.405791 -49.178197) (xy 84.359941 -49.207663) (xy 84.310364 -49.230305)
			(xy 84.258069 -49.24566) (xy 84.204121 -49.253416) (xy 84.149619 -49.253416) (xy 84.095671 -49.24566)
			(xy 84.043376 -49.230305) (xy 83.993799 -49.207663) (xy 83.947949 -49.178197) (xy 83.906758 -49.142506)
			(xy 83.871067 -49.101315) (xy 83.841601 -49.055465) (xy 83.818959 -49.005888) (xy 83.803604 -48.953593)
			(xy 83.795848 -48.899645) (xy 83.795362 -48.872394) (xy 80.109071 -48.872394) (xy 80.085839 -48.90437)
			(xy 80.049088 -48.941121) (xy 80.00704 -48.971671) (xy 79.96073 -48.995267) (xy 79.9113 -49.011328)
			(xy 79.859965 -49.019458) (xy 79.807991 -49.019458) (xy 79.756656 -49.011328) (xy 79.707226 -48.995267)
			(xy 79.660916 -48.971671) (xy 79.618868 -48.941121) (xy 79.582117 -48.90437) (xy 79.551567 -48.862322)
			(xy 79.527971 -48.816012) (xy 79.51191 -48.766582) (xy 79.50378 -48.715247) (xy 79.36433 -48.715247)
			(xy 79.3562 -48.766582) (xy 79.340139 -48.816012) (xy 79.316543 -48.862322) (xy 79.285993 -48.90437)
			(xy 79.249242 -48.941121) (xy 79.207194 -48.971671) (xy 79.160884 -48.995267) (xy 79.111454 -49.011328)
			(xy 79.060119 -49.019458) (xy 79.008145 -49.019458) (xy 78.95681 -49.011328) (xy 78.90738 -48.995267)
			(xy 78.86107 -48.971671) (xy 78.819022 -48.941121) (xy 78.782271 -48.90437) (xy 78.751721 -48.862322)
			(xy 78.728125 -48.816012) (xy 78.712064 -48.766582) (xy 78.703934 -48.715247) (xy 78.56423 -48.715247)
			(xy 78.5561 -48.766582) (xy 78.540039 -48.816012) (xy 78.516443 -48.862322) (xy 78.485893 -48.90437)
			(xy 78.449142 -48.941121) (xy 78.407094 -48.971671) (xy 78.360784 -48.995267) (xy 78.311354 -49.011328)
			(xy 78.260019 -49.019458) (xy 78.208045 -49.019458) (xy 78.15671 -49.011328) (xy 78.10728 -48.995267)
			(xy 78.06097 -48.971671) (xy 78.018922 -48.941121) (xy 77.982171 -48.90437) (xy 77.951621 -48.862322)
			(xy 77.928025 -48.816012) (xy 77.911964 -48.766582) (xy 77.903834 -48.715247) (xy 74.600814 -48.715247)
			(xy 74.592684 -48.766582) (xy 74.576623 -48.816012) (xy 74.553027 -48.862322) (xy 74.522477 -48.90437)
			(xy 74.485726 -48.941121) (xy 74.443678 -48.971671) (xy 74.397368 -48.995267) (xy 74.347938 -49.011328)
			(xy 74.296603 -49.019458) (xy 74.244629 -49.019458) (xy 74.193294 -49.011328) (xy 74.143864 -48.995267)
			(xy 74.097554 -48.971671) (xy 74.055506 -48.941121) (xy 74.018755 -48.90437) (xy 73.988205 -48.862322)
			(xy 73.964609 -48.816012) (xy 73.948548 -48.766582) (xy 73.940418 -48.715247) (xy 73.800714 -48.715247)
			(xy 73.792584 -48.766582) (xy 73.776523 -48.816012) (xy 73.752927 -48.862322) (xy 73.722377 -48.90437)
			(xy 73.685626 -48.941121) (xy 73.643578 -48.971671) (xy 73.597268 -48.995267) (xy 73.547838 -49.011328)
			(xy 73.496503 -49.019458) (xy 73.444529 -49.019458) (xy 73.393194 -49.011328) (xy 73.343764 -48.995267)
			(xy 73.297454 -48.971671) (xy 73.255406 -48.941121) (xy 73.218655 -48.90437) (xy 73.188105 -48.862322)
			(xy 73.164509 -48.816012) (xy 73.148448 -48.766582) (xy 73.140318 -48.715247) (xy 65.58982 -48.715247)
			(xy 65.572603 -48.749038) (xy 65.542053 -48.791086) (xy 65.505302 -48.827837) (xy 65.463254 -48.858387)
			(xy 65.416944 -48.881983) (xy 65.367514 -48.898044) (xy 65.316179 -48.906174) (xy 65.264205 -48.906174)
			(xy 65.21287 -48.898044) (xy 65.16344 -48.881983) (xy 65.11713 -48.858387) (xy 65.075082 -48.827837)
			(xy 65.038331 -48.791086) (xy 65.007781 -48.749038) (xy 64.984185 -48.702728) (xy 64.968124 -48.653298)
			(xy 64.959994 -48.601963) (xy 64.820319 -48.601963) (xy 64.820319 -48.601966) (xy 64.81219 -48.653307)
			(xy 64.79613 -48.702744) (xy 64.772534 -48.74906) (xy 64.741982 -48.791115) (xy 64.705227 -48.827871)
			(xy 64.663174 -48.858425) (xy 64.616859 -48.882024) (xy 64.567423 -48.898087) (xy 64.516082 -48.906217)
			(xy 64.490092 -48.906684) (xy 64.477342 -48.906593) (xy 64.451913 -48.904687) (xy 64.439292 -48.902874)
			(xy 64.41449 -48.898542) (xy 64.366488 -48.88336) (xy 64.321341 -48.86108) (xy 64.280092 -48.832216)
			(xy 64.243692 -48.797435) (xy 64.212984 -48.75754) (xy 64.188675 -48.713452) (xy 64.171327 -48.666189)
			(xy 64.161342 -48.616844) (xy 64.159638 -48.591724) (xy 64.158622 -48.572166) (xy 64.108838 -48.522382)
			(xy 64.01943 -48.61179) (xy 64.01689 -48.628046) (xy 64.012299 -48.653612) (xy 63.996202 -48.702994)
			(xy 63.972581 -48.749252) (xy 63.942018 -48.791247) (xy 63.905263 -48.827946) (xy 63.863221 -48.858446)
			(xy 63.816927 -48.881996) (xy 63.767521 -48.898017) (xy 63.716216 -48.906115) (xy 63.690246 -48.906684)
			(xy 63.680892 -48.906639) (xy 63.662212 -48.90562) (xy 63.652908 -48.904652) (xy 63.646304 -48.903636)
			(xy 63.630048 -48.901096) (xy 63.625476 -48.900334) (xy 62.954916 -48.900334) (xy 62.950344 -48.901096)
			(xy 62.935429 -48.903692) (xy 62.905284 -48.906494) (xy 62.890146 -48.906684) (xy 62.875008 -48.906504)
			(xy 62.84486 -48.903707) (xy 62.829948 -48.901096) (xy 62.825376 -48.900334) (xy 62.15507 -48.900334)
			(xy 62.150498 -48.901096) (xy 62.135583 -48.90369) (xy 62.105437 -48.906488) (xy 62.0903 -48.906684)
			(xy 62.075162 -48.906502) (xy 62.045015 -48.903701) (xy 62.030102 -48.901096) (xy 62.02553 -48.900334)
			(xy 61.35497 -48.900334) (xy 61.350398 -48.901096) (xy 61.335483 -48.90369) (xy 61.305337 -48.906488)
			(xy 61.2902 -48.906684) (xy 61.263676 -48.906165) (xy 61.211306 -48.897707) (xy 61.16096 -48.880992)
			(xy 61.113931 -48.856449) (xy 61.071426 -48.824709) (xy 61.034537 -48.786587) (xy 61.004211 -48.743062)
			(xy 60.981228 -48.695251) (xy 60.966177 -48.644383) (xy 60.962286 -48.61814) (xy 60.96 -48.600868)
			(xy 60.82411 -48.464978) (xy 60.554108 -48.19523) (xy 60.554108 -48.189642) (xy 59.88812 -47.5234)
			(xy 56.095138 -47.5234) (xy 56.081131 -47.523877) (xy 56.054186 -47.531553) (xy 56.030337 -47.546256)
			(xy 56.011375 -47.566881) (xy 55.998725 -47.591879) (xy 55.993337 -47.619373) (xy 55.995616 -47.647297)
			(xy 56.000142 -47.66056) (xy 56.009849 -47.688462) (xy 56.02033 -47.746595) (xy 56.02097 -47.77613)
			(xy 56.02046 -47.802117) (xy 56.01233 -47.853452) (xy 55.996269 -47.902882) (xy 55.972673 -47.949192)
			(xy 55.942123 -47.99124) (xy 55.905372 -48.027991) (xy 55.863324 -48.058541) (xy 55.817014 -48.082137)
			(xy 55.767584 -48.098198) (xy 55.716249 -48.106328) (xy 55.664275 -48.106328) (xy 55.61294 -48.098198)
			(xy 55.56351 -48.082137) (xy 55.5172 -48.058541) (xy 55.475152 -48.027991) (xy 55.438401 -47.99124)
			(xy 55.407851 -47.949192) (xy 55.384255 -47.902882) (xy 55.368194 -47.853452) (xy 55.360064 -47.802117)
			(xy 55.359554 -47.77613) (xy 55.360199 -47.746595) (xy 55.370668 -47.688459) (xy 55.380382 -47.66056)
			(xy 55.38487 -47.647281) (xy 55.387174 -47.619357) (xy 55.381803 -47.591858) (xy 55.369161 -47.566852)
			(xy 55.350199 -47.546224) (xy 55.326346 -47.531525) (xy 55.299395 -47.523861) (xy 55.285386 -47.5234)
			(xy 54.963568 -47.5234) (xy 53.894403 -48.592565) (xy 55.369462 -48.592565) (xy 55.369462 -48.540591)
			(xy 55.377592 -48.489256) (xy 55.393653 -48.439826) (xy 55.417249 -48.393516) (xy 55.447799 -48.351468)
			(xy 55.48455 -48.314717) (xy 55.526598 -48.284167) (xy 55.572908 -48.260571) (xy 55.622338 -48.24451)
			(xy 55.673673 -48.23638) (xy 55.725647 -48.23638) (xy 55.776982 -48.24451) (xy 55.826412 -48.260571)
			(xy 55.872722 -48.284167) (xy 55.91477 -48.314717) (xy 55.951521 -48.351468) (xy 55.982071 -48.393516)
			(xy 56.005667 -48.439826) (xy 56.021728 -48.489256) (xy 56.029858 -48.540591) (xy 56.030368 -48.566578)
			(xy 56.029858 -48.592565) (xy 56.02837 -48.601963) (xy 56.15991 -48.601963) (xy 56.15991 -48.549989)
			(xy 56.16804 -48.498654) (xy 56.184101 -48.449224) (xy 56.207697 -48.402914) (xy 56.238247 -48.360866)
			(xy 56.274998 -48.324115) (xy 56.317046 -48.293565) (xy 56.363356 -48.269969) (xy 56.412786 -48.253908)
			(xy 56.464121 -48.245778) (xy 56.516095 -48.245778) (xy 56.56743 -48.253908) (xy 56.61686 -48.269969)
			(xy 56.66317 -48.293565) (xy 56.705218 -48.324115) (xy 56.741969 -48.360866) (xy 56.772519 -48.402914)
			(xy 56.796115 -48.449224) (xy 56.812176 -48.498654) (xy 56.820306 -48.549989) (xy 56.820816 -48.575976)
			(xy 56.820306 -48.601963) (xy 57.76011 -48.601963) (xy 57.76011 -48.549989) (xy 57.76824 -48.498654)
			(xy 57.784301 -48.449224) (xy 57.807897 -48.402914) (xy 57.838447 -48.360866) (xy 57.875198 -48.324115)
			(xy 57.917246 -48.293565) (xy 57.963556 -48.269969) (xy 58.012986 -48.253908) (xy 58.064321 -48.245778)
			(xy 58.116295 -48.245778) (xy 58.16763 -48.253908) (xy 58.21706 -48.269969) (xy 58.26337 -48.293565)
			(xy 58.305418 -48.324115) (xy 58.342169 -48.360866) (xy 58.372719 -48.402914) (xy 58.396315 -48.449224)
			(xy 58.412376 -48.498654) (xy 58.420506 -48.549989) (xy 58.421016 -48.575976) (xy 58.420506 -48.601963)
			(xy 58.559956 -48.601963) (xy 58.559956 -48.549989) (xy 58.568086 -48.498654) (xy 58.584147 -48.449224)
			(xy 58.607743 -48.402914) (xy 58.638293 -48.360866) (xy 58.675044 -48.324115) (xy 58.717092 -48.293565)
			(xy 58.763402 -48.269969) (xy 58.812832 -48.253908) (xy 58.864167 -48.245778) (xy 58.916141 -48.245778)
			(xy 58.967476 -48.253908) (xy 59.016906 -48.269969) (xy 59.063216 -48.293565) (xy 59.105264 -48.324115)
			(xy 59.142015 -48.360866) (xy 59.172565 -48.402914) (xy 59.196161 -48.449224) (xy 59.212222 -48.498654)
			(xy 59.220352 -48.549989) (xy 59.220862 -48.575976) (xy 59.220352 -48.601963) (xy 59.212222 -48.653298)
			(xy 59.196161 -48.702728) (xy 59.172565 -48.749038) (xy 59.142015 -48.791086) (xy 59.105264 -48.827837)
			(xy 59.063216 -48.858387) (xy 59.016906 -48.881983) (xy 58.967476 -48.898044) (xy 58.916141 -48.906174)
			(xy 58.864167 -48.906174) (xy 58.812832 -48.898044) (xy 58.763402 -48.881983) (xy 58.717092 -48.858387)
			(xy 58.675044 -48.827837) (xy 58.638293 -48.791086) (xy 58.607743 -48.749038) (xy 58.584147 -48.702728)
			(xy 58.568086 -48.653298) (xy 58.559956 -48.601963) (xy 58.420506 -48.601963) (xy 58.412376 -48.653298)
			(xy 58.396315 -48.702728) (xy 58.372719 -48.749038) (xy 58.342169 -48.791086) (xy 58.305418 -48.827837)
			(xy 58.26337 -48.858387) (xy 58.21706 -48.881983) (xy 58.16763 -48.898044) (xy 58.116295 -48.906174)
			(xy 58.064321 -48.906174) (xy 58.012986 -48.898044) (xy 57.963556 -48.881983) (xy 57.917246 -48.858387)
			(xy 57.875198 -48.827837) (xy 57.838447 -48.791086) (xy 57.807897 -48.749038) (xy 57.784301 -48.702728)
			(xy 57.76824 -48.653298) (xy 57.76011 -48.601963) (xy 56.820306 -48.601963) (xy 56.812176 -48.653298)
			(xy 56.796115 -48.702728) (xy 56.772519 -48.749038) (xy 56.741969 -48.791086) (xy 56.705218 -48.827837)
			(xy 56.66317 -48.858387) (xy 56.61686 -48.881983) (xy 56.56743 -48.898044) (xy 56.516095 -48.906174)
			(xy 56.464121 -48.906174) (xy 56.412786 -48.898044) (xy 56.363356 -48.881983) (xy 56.317046 -48.858387)
			(xy 56.274998 -48.827837) (xy 56.238247 -48.791086) (xy 56.207697 -48.749038) (xy 56.184101 -48.702728)
			(xy 56.16804 -48.653298) (xy 56.15991 -48.601963) (xy 56.02837 -48.601963) (xy 56.021728 -48.6439)
			(xy 56.005667 -48.69333) (xy 55.982071 -48.73964) (xy 55.951521 -48.781688) (xy 55.91477 -48.818439)
			(xy 55.872722 -48.848989) (xy 55.826412 -48.872585) (xy 55.776982 -48.888646) (xy 55.725647 -48.896776)
			(xy 55.673673 -48.896776) (xy 55.622338 -48.888646) (xy 55.572908 -48.872585) (xy 55.526598 -48.848989)
			(xy 55.48455 -48.818439) (xy 55.447799 -48.781688) (xy 55.417249 -48.73964) (xy 55.393653 -48.69333)
			(xy 55.377592 -48.6439) (xy 55.369462 -48.592565) (xy 53.894403 -48.592565) (xy 53.206904 -49.280064)
			(xy 52.688236 -49.280064) (xy 52.453207 -49.515093) (xy 72.340472 -49.515093) (xy 72.340472 -49.463119)
			(xy 72.348602 -49.411784) (xy 72.364663 -49.362354) (xy 72.388259 -49.316044) (xy 72.418809 -49.273996)
			(xy 72.45556 -49.237245) (xy 72.497608 -49.206695) (xy 72.543918 -49.183099) (xy 72.593348 -49.167038)
			(xy 72.644683 -49.158908) (xy 72.696657 -49.158908) (xy 72.747992 -49.167038) (xy 72.797422 -49.183099)
			(xy 72.843732 -49.206695) (xy 72.88578 -49.237245) (xy 72.922531 -49.273996) (xy 72.953081 -49.316044)
			(xy 72.976677 -49.362354) (xy 72.992738 -49.411784) (xy 73.000868 -49.463119) (xy 73.001378 -49.489106)
			(xy 73.000868 -49.515093) (xy 73.140318 -49.515093) (xy 73.140318 -49.463119) (xy 73.148448 -49.411784)
			(xy 73.164509 -49.362354) (xy 73.188105 -49.316044) (xy 73.218655 -49.273996) (xy 73.255406 -49.237245)
			(xy 73.297454 -49.206695) (xy 73.343764 -49.183099) (xy 73.393194 -49.167038) (xy 73.444529 -49.158908)
			(xy 73.496503 -49.158908) (xy 73.547838 -49.167038) (xy 73.597268 -49.183099) (xy 73.643578 -49.206695)
			(xy 73.685626 -49.237245) (xy 73.722377 -49.273996) (xy 73.752927 -49.316044) (xy 73.776523 -49.362354)
			(xy 73.792584 -49.411784) (xy 73.800714 -49.463119) (xy 73.801224 -49.489106) (xy 73.800714 -49.515093)
			(xy 73.792584 -49.566428) (xy 73.776523 -49.615858) (xy 73.752927 -49.662168) (xy 73.722377 -49.704216)
			(xy 73.685626 -49.740967) (xy 73.643578 -49.771517) (xy 73.597268 -49.795113) (xy 73.547838 -49.811174)
			(xy 73.496503 -49.819304) (xy 73.444529 -49.819304) (xy 73.393194 -49.811174) (xy 73.343764 -49.795113)
			(xy 73.297454 -49.771517) (xy 73.255406 -49.740967) (xy 73.218655 -49.704216) (xy 73.188105 -49.662168)
			(xy 73.164509 -49.615858) (xy 73.148448 -49.566428) (xy 73.140318 -49.515093) (xy 73.000868 -49.515093)
			(xy 72.992738 -49.566428) (xy 72.976677 -49.615858) (xy 72.953081 -49.662168) (xy 72.922531 -49.704216)
			(xy 72.88578 -49.740967) (xy 72.843732 -49.771517) (xy 72.797422 -49.795113) (xy 72.747992 -49.811174)
			(xy 72.696657 -49.819304) (xy 72.644683 -49.819304) (xy 72.593348 -49.811174) (xy 72.543918 -49.795113)
			(xy 72.497608 -49.771517) (xy 72.45556 -49.740967) (xy 72.418809 -49.704216) (xy 72.388259 -49.662168)
			(xy 72.364663 -49.615858) (xy 72.348602 -49.566428) (xy 72.340472 -49.515093) (xy 52.453207 -49.515093)
			(xy 52.18176 -49.78654) (xy 52.030376 -49.78654) (xy 52.015925 -49.787048) (xy 51.98818 -49.795148)
			(xy 51.963813 -49.810692) (xy 51.944774 -49.832438) (xy 51.932585 -49.858645) (xy 51.928222 -49.887217)
			(xy 51.932034 -49.915867) (xy 51.943716 -49.942304) (xy 51.952652 -49.953672) (xy 51.970783 -49.976219)
			(xy 51.999757 -50.026293) (xy 52.019599 -50.080636) (xy 52.029707 -50.137599) (xy 52.030376 -50.166524)
			(xy 52.029866 -50.192511) (xy 52.96967 -50.192511) (xy 52.96967 -50.140537) (xy 52.9778 -50.089202)
			(xy 52.993861 -50.039772) (xy 53.017457 -49.993462) (xy 53.048007 -49.951414) (xy 53.084758 -49.914663)
			(xy 53.126806 -49.884113) (xy 53.173116 -49.860517) (xy 53.222546 -49.844456) (xy 53.273881 -49.836326)
			(xy 53.325855 -49.836326) (xy 53.37719 -49.844456) (xy 53.42662 -49.860517) (xy 53.47293 -49.884113)
			(xy 53.514978 -49.914663) (xy 53.551729 -49.951414) (xy 53.582279 -49.993462) (xy 53.605875 -50.039772)
			(xy 53.621936 -50.089202) (xy 53.630066 -50.140537) (xy 53.630576 -50.166524) (xy 53.630066 -50.192511)
			(xy 53.769516 -50.192511) (xy 53.769516 -50.140537) (xy 53.777646 -50.089202) (xy 53.793707 -50.039772)
			(xy 53.817303 -49.993462) (xy 53.847853 -49.951414) (xy 53.884604 -49.914663) (xy 53.926652 -49.884113)
			(xy 53.972962 -49.860517) (xy 54.022392 -49.844456) (xy 54.073727 -49.836326) (xy 54.125701 -49.836326)
			(xy 54.177036 -49.844456) (xy 54.226466 -49.860517) (xy 54.272776 -49.884113) (xy 54.314824 -49.914663)
			(xy 54.351575 -49.951414) (xy 54.382125 -49.993462) (xy 54.405721 -50.039772) (xy 54.421782 -50.089202)
			(xy 54.429912 -50.140537) (xy 54.430422 -50.166524) (xy 54.429912 -50.192511) (xy 55.360064 -50.192511)
			(xy 55.360064 -50.140537) (xy 55.368194 -50.089202) (xy 55.384255 -50.039772) (xy 55.407851 -49.993462)
			(xy 55.438401 -49.951414) (xy 55.475152 -49.914663) (xy 55.5172 -49.884113) (xy 55.56351 -49.860517)
			(xy 55.61294 -49.844456) (xy 55.664275 -49.836326) (xy 55.716249 -49.836326) (xy 55.767584 -49.844456)
			(xy 55.817014 -49.860517) (xy 55.863324 -49.884113) (xy 55.905372 -49.914663) (xy 55.942123 -49.951414)
			(xy 55.972673 -49.993462) (xy 55.996269 -50.039772) (xy 56.01233 -50.089202) (xy 56.02046 -50.140537)
			(xy 56.02097 -50.166524) (xy 56.02046 -50.192511) (xy 56.15991 -50.192511) (xy 56.15991 -50.140537)
			(xy 56.16804 -50.089202) (xy 56.184101 -50.039772) (xy 56.207697 -49.993462) (xy 56.238247 -49.951414)
			(xy 56.274998 -49.914663) (xy 56.317046 -49.884113) (xy 56.363356 -49.860517) (xy 56.412786 -49.844456)
			(xy 56.464121 -49.836326) (xy 56.516095 -49.836326) (xy 56.56743 -49.844456) (xy 56.61686 -49.860517)
			(xy 56.66317 -49.884113) (xy 56.705218 -49.914663) (xy 56.741969 -49.951414) (xy 56.772519 -49.993462)
			(xy 56.796115 -50.039772) (xy 56.812176 -50.089202) (xy 56.820306 -50.140537) (xy 56.820816 -50.166524)
			(xy 56.820306 -50.192511) (xy 56.818818 -50.201909) (xy 56.96001 -50.201909) (xy 56.96001 -50.149935)
			(xy 56.96814 -50.0986) (xy 56.984201 -50.04917) (xy 57.007797 -50.00286) (xy 57.038347 -49.960812)
			(xy 57.075098 -49.924061) (xy 57.117146 -49.893511) (xy 57.163456 -49.869915) (xy 57.212886 -49.853854)
			(xy 57.264221 -49.845724) (xy 57.316195 -49.845724) (xy 57.36753 -49.853854) (xy 57.41696 -49.869915)
			(xy 57.46327 -49.893511) (xy 57.505318 -49.924061) (xy 57.542069 -49.960812) (xy 57.572619 -50.00286)
			(xy 57.596215 -50.04917) (xy 57.612276 -50.0986) (xy 57.620406 -50.149935) (xy 57.620916 -50.175922)
			(xy 57.620406 -50.201909) (xy 57.612276 -50.253244) (xy 57.596215 -50.302674) (xy 57.572619 -50.348984)
			(xy 57.542069 -50.391032) (xy 57.505318 -50.427783) (xy 57.46327 -50.458333) (xy 57.41696 -50.481929)
			(xy 57.36753 -50.49799) (xy 57.316195 -50.50612) (xy 57.264221 -50.50612) (xy 57.212886 -50.49799)
			(xy 57.163456 -50.481929) (xy 57.117146 -50.458333) (xy 57.075098 -50.427783) (xy 57.038347 -50.391032)
			(xy 57.007797 -50.348984) (xy 56.984201 -50.302674) (xy 56.96814 -50.253244) (xy 56.96001 -50.201909)
			(xy 56.818818 -50.201909) (xy 56.812176 -50.243846) (xy 56.796115 -50.293276) (xy 56.772519 -50.339586)
			(xy 56.741969 -50.381634) (xy 56.705218 -50.418385) (xy 56.66317 -50.448935) (xy 56.61686 -50.472531)
			(xy 56.56743 -50.488592) (xy 56.516095 -50.496722) (xy 56.464121 -50.496722) (xy 56.412786 -50.488592)
			(xy 56.363356 -50.472531) (xy 56.317046 -50.448935) (xy 56.274998 -50.418385) (xy 56.238247 -50.381634)
			(xy 56.207697 -50.339586) (xy 56.184101 -50.293276) (xy 56.16804 -50.243846) (xy 56.15991 -50.192511)
			(xy 56.02046 -50.192511) (xy 56.01233 -50.243846) (xy 55.996269 -50.293276) (xy 55.972673 -50.339586)
			(xy 55.942123 -50.381634) (xy 55.905372 -50.418385) (xy 55.863324 -50.448935) (xy 55.817014 -50.472531)
			(xy 55.767584 -50.488592) (xy 55.716249 -50.496722) (xy 55.664275 -50.496722) (xy 55.61294 -50.488592)
			(xy 55.56351 -50.472531) (xy 55.5172 -50.448935) (xy 55.475152 -50.418385) (xy 55.438401 -50.381634)
			(xy 55.407851 -50.339586) (xy 55.384255 -50.293276) (xy 55.368194 -50.243846) (xy 55.360064 -50.192511)
			(xy 54.429912 -50.192511) (xy 54.421782 -50.243846) (xy 54.405721 -50.293276) (xy 54.382125 -50.339586)
			(xy 54.351575 -50.381634) (xy 54.314824 -50.418385) (xy 54.272776 -50.448935) (xy 54.226466 -50.472531)
			(xy 54.177036 -50.488592) (xy 54.125701 -50.496722) (xy 54.073727 -50.496722) (xy 54.022392 -50.488592)
			(xy 53.972962 -50.472531) (xy 53.926652 -50.448935) (xy 53.884604 -50.418385) (xy 53.847853 -50.381634)
			(xy 53.817303 -50.339586) (xy 53.793707 -50.293276) (xy 53.777646 -50.243846) (xy 53.769516 -50.192511)
			(xy 53.630066 -50.192511) (xy 53.621936 -50.243846) (xy 53.605875 -50.293276) (xy 53.582279 -50.339586)
			(xy 53.551729 -50.381634) (xy 53.514978 -50.418385) (xy 53.47293 -50.448935) (xy 53.42662 -50.472531)
			(xy 53.37719 -50.488592) (xy 53.325855 -50.496722) (xy 53.273881 -50.496722) (xy 53.222546 -50.488592)
			(xy 53.173116 -50.472531) (xy 53.126806 -50.448935) (xy 53.084758 -50.418385) (xy 53.048007 -50.381634)
			(xy 53.017457 -50.339586) (xy 52.993861 -50.293276) (xy 52.9778 -50.243846) (xy 52.96967 -50.192511)
			(xy 52.029866 -50.192511) (xy 52.021736 -50.243846) (xy 52.005675 -50.293276) (xy 51.982079 -50.339586)
			(xy 51.951529 -50.381634) (xy 51.914778 -50.418385) (xy 51.87273 -50.448935) (xy 51.82642 -50.472531)
			(xy 51.77699 -50.488592) (xy 51.725655 -50.496722) (xy 51.673681 -50.496722) (xy 51.622346 -50.488592)
			(xy 51.572916 -50.472531) (xy 51.526606 -50.448935) (xy 51.484558 -50.418385) (xy 51.447807 -50.381634)
			(xy 51.417257 -50.339586) (xy 51.393661 -50.293276) (xy 51.3776 -50.243846) (xy 51.36947 -50.192511)
			(xy 51.36896 -50.166524) (xy 51.369368 -50.142801) (xy 51.376148 -50.095842) (xy 51.389573 -50.050335)
			(xy 51.409366 -50.007215) (xy 51.435122 -49.967369) (xy 51.46631 -49.931614) (xy 51.484022 -49.915826)
			(xy 51.491197 -49.909097) (xy 51.500239 -49.891649) (xy 51.502059 -49.87208) (xy 51.496391 -49.853263)
			(xy 51.484064 -49.837957) (xy 51.466889 -49.828406) (xy 51.447382 -49.826012) (xy 51.437794 -49.828196)
			(xy 51.418461 -49.832972) (xy 51.378966 -49.838063) (xy 51.359054 -49.838356) (xy 50.607468 -49.838356)
			(xy 50.47869 -49.967134) (xy 50.400204 -49.967134) (xy 50.400204 -50.028348) (xy 50.404268 -50.037746)
			(xy 50.412553 -50.058192) (xy 50.4242 -50.100742) (xy 50.430068 -50.144466) (xy 50.43043 -50.166524)
			(xy 50.429919 -50.192511) (xy 50.421785 -50.243843) (xy 50.405722 -50.293272) (xy 50.382126 -50.33958)
			(xy 50.351576 -50.381627) (xy 50.314825 -50.418377) (xy 50.272778 -50.448927) (xy 50.22647 -50.472523)
			(xy 50.177041 -50.488586) (xy 50.125709 -50.496719) (xy 50.099722 -50.497232) (xy 50.071785 -50.496643)
			(xy 50.016708 -50.487238) (xy 49.963995 -50.468709) (xy 49.915147 -50.441584) (xy 49.892966 -50.424588)
			(xy 49.881318 -50.417084) (xy 49.855151 -50.40801) (xy 49.827507 -50.406304) (xy 49.800423 -50.412092)
			(xy 49.775891 -50.424948) (xy 49.755718 -50.443924) (xy 49.741389 -50.467625) (xy 49.733958 -50.494306)
			(xy 49.733454 -50.508154) (xy 49.733454 -50.62474) (xy 49.733924 -50.638585) (xy 49.741373 -50.665254)
			(xy 49.755713 -50.688942) (xy 49.775889 -50.707907) (xy 49.800418 -50.720754) (xy 49.827496 -50.726541)
			(xy 49.855134 -50.72484) (xy 49.881299 -50.715777) (xy 49.892966 -50.708306) (xy 49.915128 -50.691284)
			(xy 49.963981 -50.664162) (xy 50.0167 -50.645647) (xy 50.071784 -50.636266) (xy 50.099722 -50.635662)
			(xy 50.12571 -50.636173) (xy 50.177047 -50.644307) (xy 50.226479 -50.660372) (xy 50.27279 -50.683971)
			(xy 50.314839 -50.714524) (xy 50.351591 -50.751278) (xy 50.382141 -50.793329) (xy 50.405737 -50.839641)
			(xy 50.421798 -50.889075) (xy 50.429928 -50.940412) (xy 50.429928 -50.992357) (xy 51.36947 -50.992357)
			(xy 51.36947 -50.940383) (xy 51.3776 -50.889048) (xy 51.393661 -50.839618) (xy 51.417257 -50.793308)
			(xy 51.447807 -50.75126) (xy 51.484558 -50.714509) (xy 51.526606 -50.683959) (xy 51.572916 -50.660363)
			(xy 51.622346 -50.644302) (xy 51.673681 -50.636172) (xy 51.725655 -50.636172) (xy 51.77699 -50.644302)
			(xy 51.82642 -50.660363) (xy 51.87273 -50.683959) (xy 51.914778 -50.714509) (xy 51.951529 -50.75126)
			(xy 51.982079 -50.793308) (xy 52.005675 -50.839618) (xy 52.021736 -50.889048) (xy 52.029866 -50.940383)
			(xy 52.030376 -50.96637) (xy 52.029866 -50.992357) (xy 52.96967 -50.992357) (xy 52.96967 -50.940383)
			(xy 52.9778 -50.889048) (xy 52.993861 -50.839618) (xy 53.017457 -50.793308) (xy 53.048007 -50.75126)
			(xy 53.084758 -50.714509) (xy 53.126806 -50.683959) (xy 53.173116 -50.660363) (xy 53.222546 -50.644302)
			(xy 53.273881 -50.636172) (xy 53.325855 -50.636172) (xy 53.37719 -50.644302) (xy 53.42662 -50.660363)
			(xy 53.47293 -50.683959) (xy 53.514978 -50.714509) (xy 53.551729 -50.75126) (xy 53.582279 -50.793308)
			(xy 53.605875 -50.839618) (xy 53.621936 -50.889048) (xy 53.630066 -50.940383) (xy 53.630576 -50.96637)
			(xy 53.630066 -50.992357) (xy 53.769516 -50.992357) (xy 53.769516 -50.940383) (xy 53.777646 -50.889048)
			(xy 53.793707 -50.839618) (xy 53.817303 -50.793308) (xy 53.847853 -50.75126) (xy 53.884604 -50.714509)
			(xy 53.926652 -50.683959) (xy 53.972962 -50.660363) (xy 54.022392 -50.644302) (xy 54.073727 -50.636172)
			(xy 54.125701 -50.636172) (xy 54.177036 -50.644302) (xy 54.226466 -50.660363) (xy 54.272776 -50.683959)
			(xy 54.314824 -50.714509) (xy 54.351575 -50.75126) (xy 54.382125 -50.793308) (xy 54.405721 -50.839618)
			(xy 54.421782 -50.889048) (xy 54.429912 -50.940383) (xy 54.430422 -50.96637) (xy 54.429912 -50.992357)
			(xy 55.360064 -50.992357) (xy 55.360064 -50.940383) (xy 55.368194 -50.889048) (xy 55.384255 -50.839618)
			(xy 55.407851 -50.793308) (xy 55.438401 -50.75126) (xy 55.475152 -50.714509) (xy 55.5172 -50.683959)
			(xy 55.56351 -50.660363) (xy 55.61294 -50.644302) (xy 55.664275 -50.636172) (xy 55.716249 -50.636172)
			(xy 55.767584 -50.644302) (xy 55.817014 -50.660363) (xy 55.863324 -50.683959) (xy 55.905372 -50.714509)
			(xy 55.942123 -50.75126) (xy 55.972673 -50.793308) (xy 55.996269 -50.839618) (xy 56.01233 -50.889048)
			(xy 56.02046 -50.940383) (xy 56.02097 -50.96637) (xy 56.02046 -50.992357) (xy 56.01233 -51.043692)
			(xy 55.996269 -51.093122) (xy 55.972673 -51.139432) (xy 55.942123 -51.18148) (xy 55.905372 -51.218231)
			(xy 55.863324 -51.248781) (xy 55.817014 -51.272377) (xy 55.767584 -51.288438) (xy 55.716249 -51.296568)
			(xy 55.664275 -51.296568) (xy 55.61294 -51.288438) (xy 55.56351 -51.272377) (xy 55.5172 -51.248781)
			(xy 55.475152 -51.218231) (xy 55.438401 -51.18148) (xy 55.407851 -51.139432) (xy 55.384255 -51.093122)
			(xy 55.368194 -51.043692) (xy 55.360064 -50.992357) (xy 54.429912 -50.992357) (xy 54.421782 -51.043692)
			(xy 54.405721 -51.093122) (xy 54.382125 -51.139432) (xy 54.351575 -51.18148) (xy 54.314824 -51.218231)
			(xy 54.272776 -51.248781) (xy 54.226466 -51.272377) (xy 54.177036 -51.288438) (xy 54.125701 -51.296568)
			(xy 54.073727 -51.296568) (xy 54.022392 -51.288438) (xy 53.972962 -51.272377) (xy 53.926652 -51.248781)
			(xy 53.884604 -51.218231) (xy 53.847853 -51.18148) (xy 53.817303 -51.139432) (xy 53.793707 -51.093122)
			(xy 53.777646 -51.043692) (xy 53.769516 -50.992357) (xy 53.630066 -50.992357) (xy 53.621936 -51.043692)
			(xy 53.605875 -51.093122) (xy 53.582279 -51.139432) (xy 53.551729 -51.18148) (xy 53.514978 -51.218231)
			(xy 53.47293 -51.248781) (xy 53.42662 -51.272377) (xy 53.37719 -51.288438) (xy 53.325855 -51.296568)
			(xy 53.273881 -51.296568) (xy 53.222546 -51.288438) (xy 53.173116 -51.272377) (xy 53.126806 -51.248781)
			(xy 53.084758 -51.218231) (xy 53.048007 -51.18148) (xy 53.017457 -51.139432) (xy 52.993861 -51.093122)
			(xy 52.9778 -51.043692) (xy 52.96967 -50.992357) (xy 52.029866 -50.992357) (xy 52.021736 -51.043692)
			(xy 52.005675 -51.093122) (xy 51.982079 -51.139432) (xy 51.951529 -51.18148) (xy 51.914778 -51.218231)
			(xy 51.87273 -51.248781) (xy 51.82642 -51.272377) (xy 51.77699 -51.288438) (xy 51.725655 -51.296568)
			(xy 51.673681 -51.296568) (xy 51.622346 -51.288438) (xy 51.572916 -51.272377) (xy 51.526606 -51.248781)
			(xy 51.484558 -51.218231) (xy 51.447807 -51.18148) (xy 51.417257 -51.139432) (xy 51.393661 -51.093122)
			(xy 51.3776 -51.043692) (xy 51.36947 -50.992357) (xy 50.429928 -50.992357) (xy 50.429928 -50.992388)
			(xy 50.421798 -51.043725) (xy 50.405737 -51.093159) (xy 50.382141 -51.139471) (xy 50.351591 -51.181522)
			(xy 50.314839 -51.218276) (xy 50.27279 -51.248829) (xy 50.226479 -51.272428) (xy 50.177047 -51.288493)
			(xy 50.12571 -51.296627) (xy 50.099722 -51.297078) (xy 50.071785 -51.296489) (xy 50.016707 -51.287086)
			(xy 49.963993 -51.268559) (xy 49.915142 -51.241437) (xy 49.892966 -51.224434) (xy 49.88132 -51.216928)
			(xy 49.855156 -51.20785) (xy 49.827514 -51.206142) (xy 49.800431 -51.21193) (xy 49.775901 -51.224787)
			(xy 49.755733 -51.243766) (xy 49.741411 -51.26747) (xy 49.73399 -51.294152) (xy 49.733454 -51.308)
			(xy 49.733454 -51.42484) (xy 49.733924 -51.438685) (xy 49.741373 -51.465354) (xy 49.755713 -51.489042)
			(xy 49.775889 -51.508007) (xy 49.800418 -51.520854) (xy 49.827496 -51.526641) (xy 49.855134 -51.52494)
			(xy 49.881299 -51.515877) (xy 49.892966 -51.508406) (xy 49.915128 -51.491384) (xy 49.963981 -51.464262)
			(xy 50.0167 -51.445747) (xy 50.071784 -51.436366) (xy 50.099722 -51.435762) (xy 50.125709 -51.436273)
			(xy 50.177042 -51.444406) (xy 50.226472 -51.460469) (xy 50.272781 -51.484065) (xy 50.314828 -51.514615)
			(xy 50.35158 -51.551366) (xy 50.38213 -51.593413) (xy 50.405728 -51.639721) (xy 50.421792 -51.68915)
			(xy 50.429926 -51.740483) (xy 50.43043 -51.76647) (xy 50.429929 -51.792383) (xy 50.429917 -51.792457)
			(xy 53.769516 -51.792457) (xy 53.769516 -51.740483) (xy 53.777646 -51.689148) (xy 53.793707 -51.639718)
			(xy 53.817303 -51.593408) (xy 53.847853 -51.55136) (xy 53.884604 -51.514609) (xy 53.926652 -51.484059)
			(xy 53.972962 -51.460463) (xy 54.022392 -51.444402) (xy 54.073727 -51.436272) (xy 54.125701 -51.436272)
			(xy 54.177036 -51.444402) (xy 54.226466 -51.460463) (xy 54.272776 -51.484059) (xy 54.314824 -51.514609)
			(xy 54.351575 -51.55136) (xy 54.382125 -51.593408) (xy 54.405721 -51.639718) (xy 54.421782 -51.689148)
			(xy 54.429912 -51.740483) (xy 54.430422 -51.76647) (xy 54.429912 -51.792457) (xy 55.360064 -51.792457)
			(xy 55.360064 -51.740483) (xy 55.368194 -51.689148) (xy 55.384255 -51.639718) (xy 55.407851 -51.593408)
			(xy 55.438401 -51.55136) (xy 55.475152 -51.514609) (xy 55.5172 -51.484059) (xy 55.56351 -51.460463)
			(xy 55.61294 -51.444402) (xy 55.664275 -51.436272) (xy 55.716249 -51.436272) (xy 55.767584 -51.444402)
			(xy 55.817014 -51.460463) (xy 55.863324 -51.484059) (xy 55.905372 -51.514609) (xy 55.942123 -51.55136)
			(xy 55.972673 -51.593408) (xy 55.996269 -51.639718) (xy 56.01233 -51.689148) (xy 56.02046 -51.740483)
			(xy 56.02097 -51.76647) (xy 56.02046 -51.792457) (xy 56.01233 -51.843792) (xy 55.996269 -51.893222)
			(xy 55.972673 -51.939532) (xy 55.942123 -51.98158) (xy 55.905372 -52.018331) (xy 55.863324 -52.048881)
			(xy 55.817014 -52.072477) (xy 55.767584 -52.088538) (xy 55.716249 -52.096668) (xy 55.664275 -52.096668)
			(xy 55.61294 -52.088538) (xy 55.56351 -52.072477) (xy 55.5172 -52.048881) (xy 55.475152 -52.018331)
			(xy 55.438401 -51.98158) (xy 55.407851 -51.939532) (xy 55.384255 -51.893222) (xy 55.368194 -51.843792)
			(xy 55.360064 -51.792457) (xy 54.429912 -51.792457) (xy 54.421782 -51.843792) (xy 54.405721 -51.893222)
			(xy 54.382125 -51.939532) (xy 54.351575 -51.98158) (xy 54.314824 -52.018331) (xy 54.272776 -52.048881)
			(xy 54.226466 -52.072477) (xy 54.177036 -52.088538) (xy 54.125701 -52.096668) (xy 54.073727 -52.096668)
			(xy 54.022392 -52.088538) (xy 53.972962 -52.072477) (xy 53.926652 -52.048881) (xy 53.884604 -52.018331)
			(xy 53.847853 -51.98158) (xy 53.817303 -51.939532) (xy 53.793707 -51.893222) (xy 53.777646 -51.843792)
			(xy 53.769516 -51.792457) (xy 50.429917 -51.792457) (xy 50.421849 -51.843576) (xy 50.405884 -51.892882)
			(xy 50.382423 -51.939094) (xy 50.352041 -51.981081) (xy 50.315481 -52.017815) (xy 50.27364 -52.048397)
			(xy 50.22754 -52.072078) (xy 50.178311 -52.088278) (xy 50.127157 -52.096602) (xy 50.101246 -52.097178)
			(xy 50.091271 -52.097709) (xy 50.072862 -52.105413) (xy 50.058783 -52.119556) (xy 50.051163 -52.138)
			(xy 50.0507 -52.147978) (xy 50.0507 -52.592557) (xy 50.569624 -52.592557) (xy 50.569624 -52.540583)
			(xy 50.577754 -52.489248) (xy 50.593815 -52.439818) (xy 50.617411 -52.393508) (xy 50.647961 -52.35146)
			(xy 50.684712 -52.314709) (xy 50.72676 -52.284159) (xy 50.77307 -52.260563) (xy 50.8225 -52.244502)
			(xy 50.873835 -52.236372) (xy 50.925809 -52.236372) (xy 50.977144 -52.244502) (xy 51.026574 -52.260563)
			(xy 51.072884 -52.284159) (xy 51.114932 -52.314709) (xy 51.151683 -52.35146) (xy 51.182233 -52.393508)
			(xy 51.205829 -52.439818) (xy 51.22189 -52.489248) (xy 51.23002 -52.540583) (xy 51.23053 -52.56657)
			(xy 51.23002 -52.592557) (xy 51.36947 -52.592557) (xy 51.36947 -52.540583) (xy 51.3776 -52.489248)
			(xy 51.393661 -52.439818) (xy 51.417257 -52.393508) (xy 51.447807 -52.35146) (xy 51.484558 -52.314709)
			(xy 51.526606 -52.284159) (xy 51.572916 -52.260563) (xy 51.622346 -52.244502) (xy 51.673681 -52.236372)
			(xy 51.725655 -52.236372) (xy 51.77699 -52.244502) (xy 51.82642 -52.260563) (xy 51.87273 -52.284159)
			(xy 51.914778 -52.314709) (xy 51.951529 -52.35146) (xy 51.982079 -52.393508) (xy 52.005675 -52.439818)
			(xy 52.021736 -52.489248) (xy 52.029866 -52.540583) (xy 52.030376 -52.56657) (xy 52.029866 -52.592557)
			(xy 52.16957 -52.592557) (xy 52.16957 -52.540583) (xy 52.1777 -52.489248) (xy 52.193761 -52.439818)
			(xy 52.217357 -52.393508) (xy 52.247907 -52.35146) (xy 52.284658 -52.314709) (xy 52.326706 -52.284159)
			(xy 52.373016 -52.260563) (xy 52.422446 -52.244502) (xy 52.473781 -52.236372) (xy 52.525755 -52.236372)
			(xy 52.57709 -52.244502) (xy 52.62652 -52.260563) (xy 52.67283 -52.284159) (xy 52.714878 -52.314709)
			(xy 52.751629 -52.35146) (xy 52.782179 -52.393508) (xy 52.805775 -52.439818) (xy 52.821836 -52.489248)
			(xy 52.829966 -52.540583) (xy 52.830476 -52.56657) (xy 52.829966 -52.592557) (xy 52.96967 -52.592557)
			(xy 52.96967 -52.540583) (xy 52.9778 -52.489248) (xy 52.993861 -52.439818) (xy 53.017457 -52.393508)
			(xy 53.048007 -52.35146) (xy 53.084758 -52.314709) (xy 53.126806 -52.284159) (xy 53.173116 -52.260563)
			(xy 53.222546 -52.244502) (xy 53.273881 -52.236372) (xy 53.325855 -52.236372) (xy 53.37719 -52.244502)
			(xy 53.42662 -52.260563) (xy 53.47293 -52.284159) (xy 53.514978 -52.314709) (xy 53.551729 -52.35146)
			(xy 53.582279 -52.393508) (xy 53.605875 -52.439818) (xy 53.621936 -52.489248) (xy 53.630066 -52.540583)
			(xy 53.630576 -52.56657) (xy 53.630066 -52.592557) (xy 53.769516 -52.592557) (xy 53.769516 -52.540583)
			(xy 53.777646 -52.489248) (xy 53.793707 -52.439818) (xy 53.817303 -52.393508) (xy 53.847853 -52.35146)
			(xy 53.884604 -52.314709) (xy 53.926652 -52.284159) (xy 53.972962 -52.260563) (xy 54.022392 -52.244502)
			(xy 54.073727 -52.236372) (xy 54.125701 -52.236372) (xy 54.177036 -52.244502) (xy 54.226466 -52.260563)
			(xy 54.272776 -52.284159) (xy 54.314824 -52.314709) (xy 54.351575 -52.35146) (xy 54.382125 -52.393508)
			(xy 54.405721 -52.439818) (xy 54.421782 -52.489248) (xy 54.429912 -52.540583) (xy 54.430422 -52.56657)
			(xy 54.429912 -52.592557) (xy 54.421782 -52.643892) (xy 54.405721 -52.693322) (xy 54.382125 -52.739632)
			(xy 54.351575 -52.78168) (xy 54.314824 -52.818431) (xy 54.272776 -52.848981) (xy 54.226466 -52.872577)
			(xy 54.177036 -52.888638) (xy 54.125701 -52.896768) (xy 54.073727 -52.896768) (xy 54.022392 -52.888638)
			(xy 53.972962 -52.872577) (xy 53.926652 -52.848981) (xy 53.884604 -52.818431) (xy 53.847853 -52.78168)
			(xy 53.817303 -52.739632) (xy 53.793707 -52.693322) (xy 53.777646 -52.643892) (xy 53.769516 -52.592557)
			(xy 53.630066 -52.592557) (xy 53.621936 -52.643892) (xy 53.605875 -52.693322) (xy 53.582279 -52.739632)
			(xy 53.551729 -52.78168) (xy 53.514978 -52.818431) (xy 53.47293 -52.848981) (xy 53.42662 -52.872577)
			(xy 53.37719 -52.888638) (xy 53.325855 -52.896768) (xy 53.273881 -52.896768) (xy 53.222546 -52.888638)
			(xy 53.173116 -52.872577) (xy 53.126806 -52.848981) (xy 53.084758 -52.818431) (xy 53.048007 -52.78168)
			(xy 53.017457 -52.739632) (xy 52.993861 -52.693322) (xy 52.9778 -52.643892) (xy 52.96967 -52.592557)
			(xy 52.829966 -52.592557) (xy 52.821836 -52.643892) (xy 52.805775 -52.693322) (xy 52.782179 -52.739632)
			(xy 52.751629 -52.78168) (xy 52.714878 -52.818431) (xy 52.67283 -52.848981) (xy 52.62652 -52.872577)
			(xy 52.57709 -52.888638) (xy 52.525755 -52.896768) (xy 52.473781 -52.896768) (xy 52.422446 -52.888638)
			(xy 52.373016 -52.872577) (xy 52.326706 -52.848981) (xy 52.284658 -52.818431) (xy 52.247907 -52.78168)
			(xy 52.217357 -52.739632) (xy 52.193761 -52.693322) (xy 52.1777 -52.643892) (xy 52.16957 -52.592557)
			(xy 52.029866 -52.592557) (xy 52.021736 -52.643892) (xy 52.005675 -52.693322) (xy 51.982079 -52.739632)
			(xy 51.951529 -52.78168) (xy 51.914778 -52.818431) (xy 51.87273 -52.848981) (xy 51.82642 -52.872577)
			(xy 51.77699 -52.888638) (xy 51.725655 -52.896768) (xy 51.673681 -52.896768) (xy 51.622346 -52.888638)
			(xy 51.572916 -52.872577) (xy 51.526606 -52.848981) (xy 51.484558 -52.818431) (xy 51.447807 -52.78168)
			(xy 51.417257 -52.739632) (xy 51.393661 -52.693322) (xy 51.3776 -52.643892) (xy 51.36947 -52.592557)
			(xy 51.23002 -52.592557) (xy 51.22189 -52.643892) (xy 51.205829 -52.693322) (xy 51.182233 -52.739632)
			(xy 51.151683 -52.78168) (xy 51.114932 -52.818431) (xy 51.072884 -52.848981) (xy 51.026574 -52.872577)
			(xy 50.977144 -52.888638) (xy 50.925809 -52.896768) (xy 50.873835 -52.896768) (xy 50.8225 -52.888638)
			(xy 50.77307 -52.872577) (xy 50.72676 -52.848981) (xy 50.684712 -52.818431) (xy 50.647961 -52.78168)
			(xy 50.617411 -52.739632) (xy 50.593815 -52.693322) (xy 50.577754 -52.643892) (xy 50.569624 -52.592557)
			(xy 50.0507 -52.592557) (xy 50.0507 -53.392403) (xy 50.569624 -53.392403) (xy 50.569624 -53.340429)
			(xy 50.577754 -53.289094) (xy 50.593815 -53.239664) (xy 50.617411 -53.193354) (xy 50.647961 -53.151306)
			(xy 50.684712 -53.114555) (xy 50.72676 -53.084005) (xy 50.77307 -53.060409) (xy 50.8225 -53.044348)
			(xy 50.873835 -53.036218) (xy 50.925809 -53.036218) (xy 50.977144 -53.044348) (xy 51.026574 -53.060409)
			(xy 51.072884 -53.084005) (xy 51.114932 -53.114555) (xy 51.151683 -53.151306) (xy 51.182233 -53.193354)
			(xy 51.205829 -53.239664) (xy 51.22189 -53.289094) (xy 51.23002 -53.340429) (xy 51.23053 -53.366416)
			(xy 51.23002 -53.392403) (xy 51.36947 -53.392403) (xy 51.36947 -53.340429) (xy 51.3776 -53.289094)
			(xy 51.393661 -53.239664) (xy 51.417257 -53.193354) (xy 51.447807 -53.151306) (xy 51.484558 -53.114555)
			(xy 51.526606 -53.084005) (xy 51.572916 -53.060409) (xy 51.622346 -53.044348) (xy 51.673681 -53.036218)
			(xy 51.725655 -53.036218) (xy 51.77699 -53.044348) (xy 51.82642 -53.060409) (xy 51.87273 -53.084005)
			(xy 51.914778 -53.114555) (xy 51.951529 -53.151306) (xy 51.982079 -53.193354) (xy 52.005675 -53.239664)
			(xy 52.021736 -53.289094) (xy 52.029866 -53.340429) (xy 52.030376 -53.366416) (xy 52.029866 -53.392403)
			(xy 52.021736 -53.443738) (xy 52.005675 -53.493168) (xy 51.982079 -53.539478) (xy 51.951529 -53.581526)
			(xy 51.914778 -53.618277) (xy 51.87273 -53.648827) (xy 51.82642 -53.672423) (xy 51.77699 -53.688484)
			(xy 51.725655 -53.696614) (xy 51.673681 -53.696614) (xy 51.622346 -53.688484) (xy 51.572916 -53.672423)
			(xy 51.526606 -53.648827) (xy 51.484558 -53.618277) (xy 51.447807 -53.581526) (xy 51.417257 -53.539478)
			(xy 51.393661 -53.493168) (xy 51.3776 -53.443738) (xy 51.36947 -53.392403) (xy 51.23002 -53.392403)
			(xy 51.22189 -53.443738) (xy 51.205829 -53.493168) (xy 51.182233 -53.539478) (xy 51.151683 -53.581526)
			(xy 51.114932 -53.618277) (xy 51.072884 -53.648827) (xy 51.026574 -53.672423) (xy 50.977144 -53.688484)
			(xy 50.925809 -53.696614) (xy 50.873835 -53.696614) (xy 50.8225 -53.688484) (xy 50.77307 -53.672423)
			(xy 50.72676 -53.648827) (xy 50.684712 -53.618277) (xy 50.647961 -53.581526) (xy 50.617411 -53.539478)
			(xy 50.593815 -53.493168) (xy 50.577754 -53.443738) (xy 50.569624 -53.392403) (xy 50.0507 -53.392403)
			(xy 50.0507 -54.192503) (xy 50.569624 -54.192503) (xy 50.569624 -54.140529) (xy 50.577754 -54.089194)
			(xy 50.593815 -54.039764) (xy 50.617411 -53.993454) (xy 50.647961 -53.951406) (xy 50.684712 -53.914655)
			(xy 50.72676 -53.884105) (xy 50.77307 -53.860509) (xy 50.8225 -53.844448) (xy 50.873835 -53.836318)
			(xy 50.925809 -53.836318) (xy 50.977144 -53.844448) (xy 51.026574 -53.860509) (xy 51.072884 -53.884105)
			(xy 51.114932 -53.914655) (xy 51.151683 -53.951406) (xy 51.182233 -53.993454) (xy 51.205829 -54.039764)
			(xy 51.22189 -54.089194) (xy 51.23002 -54.140529) (xy 51.23053 -54.166516) (xy 51.23002 -54.192503)
			(xy 51.229915 -54.193165) (xy 51.344058 -54.193165) (xy 51.344058 -54.139867) (xy 51.352001 -54.087163)
			(xy 51.367711 -54.036233) (xy 51.390837 -53.988212) (xy 51.420861 -53.944175) (xy 51.457113 -53.905104)
			(xy 51.498784 -53.871873) (xy 51.544942 -53.845224) (xy 51.594556 -53.825752) (xy 51.646518 -53.813892)
			(xy 51.699668 -53.809909) (xy 51.752818 -53.813892) (xy 51.80478 -53.825752) (xy 51.854394 -53.845224)
			(xy 51.900552 -53.871873) (xy 51.942223 -53.905104) (xy 51.978475 -53.944175) (xy 52.008499 -53.988212)
			(xy 52.031625 -54.036233) (xy 52.047335 -54.087163) (xy 52.055278 -54.139867) (xy 52.055776 -54.166516)
			(xy 52.055278 -54.193165) (xy 52.047335 -54.245869) (xy 52.031625 -54.296799) (xy 52.008499 -54.34482)
			(xy 51.978475 -54.388857) (xy 51.942223 -54.427928) (xy 51.900552 -54.461159) (xy 51.854394 -54.487808)
			(xy 51.80478 -54.50728) (xy 51.752818 -54.51914) (xy 51.699668 -54.523124) (xy 51.646518 -54.51914)
			(xy 51.594556 -54.50728) (xy 51.544942 -54.487808) (xy 51.498784 -54.461159) (xy 51.457113 -54.427928)
			(xy 51.420861 -54.388857) (xy 51.390837 -54.34482) (xy 51.367711 -54.296799) (xy 51.352001 -54.245869)
			(xy 51.344058 -54.193165) (xy 51.229915 -54.193165) (xy 51.22189 -54.243838) (xy 51.205829 -54.293268)
			(xy 51.182233 -54.339578) (xy 51.151683 -54.381626) (xy 51.114932 -54.418377) (xy 51.072884 -54.448927)
			(xy 51.026574 -54.472523) (xy 50.977144 -54.488584) (xy 50.925809 -54.496714) (xy 50.873835 -54.496714)
			(xy 50.8225 -54.488584) (xy 50.77307 -54.472523) (xy 50.72676 -54.448927) (xy 50.684712 -54.418377)
			(xy 50.647961 -54.381626) (xy 50.617411 -54.339578) (xy 50.593815 -54.293268) (xy 50.577754 -54.243838)
			(xy 50.569624 -54.192503) (xy 50.0507 -54.192503) (xy 50.0507 -54.26456) (xy 49.71796 -54.5973) (xy 47.6631 -54.5973)
			(xy 47.042324 -55.218076) (xy 47.042324 -55.468012) (xy 47.0661 -55.479954) (xy 47.109821 -55.510266)
			(xy 47.148126 -55.547186) (xy 47.180028 -55.589761) (xy 47.204704 -55.636894) (xy 47.221518 -55.687368)
			(xy 47.230036 -55.739883) (xy 47.230039 -55.792449) (xy 47.369478 -55.792449) (xy 47.369478 -55.740475)
			(xy 47.377608 -55.68914) (xy 47.393669 -55.63971) (xy 47.417265 -55.5934) (xy 47.447815 -55.551352)
			(xy 47.484566 -55.514601) (xy 47.526614 -55.484051) (xy 47.572924 -55.460455) (xy 47.622354 -55.444394)
			(xy 47.673689 -55.436264) (xy 47.725663 -55.436264) (xy 47.776998 -55.444394) (xy 47.826428 -55.460455)
			(xy 47.872738 -55.484051) (xy 47.914786 -55.514601) (xy 47.951537 -55.551352) (xy 47.982087 -55.5934)
			(xy 48.005683 -55.63971) (xy 48.021744 -55.68914) (xy 48.029874 -55.740475) (xy 48.030384 -55.766462)
			(xy 48.029874 -55.792449) (xy 48.021744 -55.843784) (xy 48.005683 -55.893214) (xy 47.982087 -55.939524)
			(xy 47.951537 -55.981572) (xy 47.914786 -56.018323) (xy 47.872738 -56.048873) (xy 47.826428 -56.072469)
			(xy 47.776998 -56.08853) (xy 47.725663 -56.09666) (xy 47.673689 -56.09666) (xy 47.622354 -56.08853)
			(xy 47.572924 -56.072469) (xy 47.526614 -56.048873) (xy 47.484566 -56.018323) (xy 47.447815 -55.981572)
			(xy 47.417265 -55.939524) (xy 47.393669 -55.893214) (xy 47.377608 -55.843784) (xy 47.369478 -55.792449)
			(xy 47.230039 -55.792449) (xy 47.230039 -55.793084) (xy 47.221526 -55.8456) (xy 47.204717 -55.896076)
			(xy 47.180046 -55.943211) (xy 47.148148 -55.985789) (xy 47.109846 -56.022713) (xy 47.066128 -56.05303)
			(xy 47.042324 -56.064912) (xy 47.042324 -56.268112) (xy 47.0661 -56.280054) (xy 47.109821 -56.310366)
			(xy 47.148126 -56.347286) (xy 47.180028 -56.389861) (xy 47.204704 -56.436994) (xy 47.221518 -56.487468)
			(xy 47.230036 -56.539983) (xy 47.230039 -56.592549) (xy 47.369478 -56.592549) (xy 47.369478 -56.540575)
			(xy 47.377608 -56.48924) (xy 47.393669 -56.43981) (xy 47.417265 -56.3935) (xy 47.447815 -56.351452)
			(xy 47.484566 -56.314701) (xy 47.526614 -56.284151) (xy 47.572924 -56.260555) (xy 47.622354 -56.244494)
			(xy 47.673689 -56.236364) (xy 47.725663 -56.236364) (xy 47.776998 -56.244494) (xy 47.826428 -56.260555)
			(xy 47.872738 -56.284151) (xy 47.914786 -56.314701) (xy 47.951537 -56.351452) (xy 47.982087 -56.3935)
			(xy 48.005683 -56.43981) (xy 48.021744 -56.48924) (xy 48.029874 -56.540575) (xy 48.030384 -56.566562)
			(xy 48.029874 -56.592549) (xy 48.021744 -56.643884) (xy 48.005683 -56.693314) (xy 47.982087 -56.739624)
			(xy 47.951537 -56.781672) (xy 47.914786 -56.818423) (xy 47.872738 -56.848973) (xy 47.826428 -56.872569)
			(xy 47.776998 -56.88863) (xy 47.725663 -56.89676) (xy 47.673689 -56.89676) (xy 47.622354 -56.88863)
			(xy 47.572924 -56.872569) (xy 47.526614 -56.848973) (xy 47.484566 -56.818423) (xy 47.447815 -56.781672)
			(xy 47.417265 -56.739624) (xy 47.393669 -56.693314) (xy 47.377608 -56.643884) (xy 47.369478 -56.592549)
			(xy 47.230039 -56.592549) (xy 47.230039 -56.593184) (xy 47.221526 -56.6457) (xy 47.204717 -56.696176)
			(xy 47.180046 -56.743311) (xy 47.148148 -56.785889) (xy 47.109846 -56.822813) (xy 47.066128 -56.85313)
			(xy 47.042324 -56.865012) (xy 47.042324 -57.067958) (xy 47.066096 -57.079899) (xy 47.10981 -57.110211)
			(xy 47.148108 -57.147128) (xy 47.180003 -57.1897) (xy 47.204674 -57.236828) (xy 47.221482 -57.287297)
			(xy 47.229996 -57.339806) (xy 47.229996 -57.392395) (xy 47.369478 -57.392395) (xy 47.369478 -57.340421)
			(xy 47.377608 -57.289086) (xy 47.393669 -57.239656) (xy 47.417265 -57.193346) (xy 47.447815 -57.151298)
			(xy 47.484566 -57.114547) (xy 47.526614 -57.083997) (xy 47.572924 -57.060401) (xy 47.622354 -57.04434)
			(xy 47.673689 -57.03621) (xy 47.725663 -57.03621) (xy 47.776998 -57.04434) (xy 47.826428 -57.060401)
			(xy 47.872738 -57.083997) (xy 47.914786 -57.114547) (xy 47.951537 -57.151298) (xy 47.982087 -57.193346)
			(xy 48.005683 -57.239656) (xy 48.021744 -57.289086) (xy 48.029874 -57.340421) (xy 48.030384 -57.366408)
			(xy 48.029874 -57.392395) (xy 48.021744 -57.44373) (xy 48.005683 -57.49316) (xy 47.982087 -57.53947)
			(xy 47.951537 -57.581518) (xy 47.914786 -57.618269) (xy 47.872738 -57.648819) (xy 47.826428 -57.672415)
			(xy 47.776998 -57.688476) (xy 47.725663 -57.696606) (xy 47.673689 -57.696606) (xy 47.622354 -57.688476)
			(xy 47.572924 -57.672415) (xy 47.526614 -57.648819) (xy 47.484566 -57.618269) (xy 47.447815 -57.581518)
			(xy 47.417265 -57.53947) (xy 47.393669 -57.49316) (xy 47.377608 -57.44373) (xy 47.369478 -57.392395)
			(xy 47.229996 -57.392395) (xy 47.229996 -57.393001) (xy 47.221481 -57.445509) (xy 47.204671 -57.495978)
			(xy 47.18 -57.543106) (xy 47.148103 -57.585677) (xy 47.109804 -57.622593) (xy 47.06609 -57.652904)
			(xy 47.042324 -57.664858) (xy 47.042324 -57.868058) (xy 47.066096 -57.879999) (xy 47.10981 -57.910311)
			(xy 47.148108 -57.947228) (xy 47.180003 -57.9898) (xy 47.204674 -58.036928) (xy 47.221482 -58.087397)
			(xy 47.229996 -58.139906) (xy 47.229996 -58.192495) (xy 47.369478 -58.192495) (xy 47.369478 -58.140521)
			(xy 47.377608 -58.089186) (xy 47.393669 -58.039756) (xy 47.417265 -57.993446) (xy 47.447815 -57.951398)
			(xy 47.484566 -57.914647) (xy 47.526614 -57.884097) (xy 47.572924 -57.860501) (xy 47.622354 -57.84444)
			(xy 47.673689 -57.83631) (xy 47.725663 -57.83631) (xy 47.776998 -57.84444) (xy 47.826428 -57.860501)
			(xy 47.872738 -57.884097) (xy 47.914786 -57.914647) (xy 47.951537 -57.951398) (xy 47.982087 -57.993446)
			(xy 48.005683 -58.039756) (xy 48.021744 -58.089186) (xy 48.029874 -58.140521) (xy 48.030384 -58.166508)
			(xy 48.029874 -58.192495) (xy 48.021744 -58.24383) (xy 48.005683 -58.29326) (xy 47.982087 -58.33957)
			(xy 47.951537 -58.381618) (xy 47.914786 -58.418369) (xy 47.872738 -58.448919) (xy 47.826428 -58.472515)
			(xy 47.776998 -58.488576) (xy 47.725663 -58.496706) (xy 47.673689 -58.496706) (xy 47.622354 -58.488576)
			(xy 47.572924 -58.472515) (xy 47.526614 -58.448919) (xy 47.484566 -58.418369) (xy 47.447815 -58.381618)
			(xy 47.417265 -58.33957) (xy 47.393669 -58.29326) (xy 47.377608 -58.24383) (xy 47.369478 -58.192495)
			(xy 47.229996 -58.192495) (xy 47.229996 -58.193101) (xy 47.221481 -58.245609) (xy 47.204671 -58.296078)
			(xy 47.18 -58.343206) (xy 47.148103 -58.385777) (xy 47.109804 -58.422693) (xy 47.06609 -58.453004)
			(xy 47.042324 -58.464958) (xy 47.042324 -58.667904) (xy 47.0661 -58.679846) (xy 47.109822 -58.710158)
			(xy 47.148129 -58.747079) (xy 47.180032 -58.789654) (xy 47.204709 -58.836788) (xy 47.221524 -58.887263)
			(xy 47.230043 -58.939779) (xy 47.230046 -58.992981) (xy 47.221534 -59.045498) (xy 47.204725 -59.095976)
			(xy 47.180053 -59.143112) (xy 47.148155 -59.185692) (xy 47.109853 -59.222616) (xy 47.066135 -59.252934)
			(xy 47.042324 -59.264804) (xy 47.042324 -62.596522) (xy 47.044102 -62.5983) (xy 47.044102 -63.006224)
			(xy 47.044568 -63.020375) (xy 47.052343 -63.047588) (xy 47.067288 -63.071623) (xy 47.088256 -63.090632)
			(xy 47.113636 -63.103156) (xy 47.141479 -63.108233) (xy 47.155608 -63.107316) (xy 47.171055 -63.104938)
			(xy 47.202209 -63.102395) (xy 47.217838 -63.102236) (xy 47.244331 -63.102692) (xy 47.296808 -63.110025)
			(xy 47.347766 -63.124544) (xy 47.396226 -63.145971) (xy 47.441258 -63.173893) (xy 47.481996 -63.207775)
			(xy 47.517657 -63.246965) (xy 47.547556 -63.29071) (xy 47.571117 -63.338169) (xy 47.58789 -63.388431)
			(xy 47.59755 -63.440529) (xy 47.599092 -63.46698) (xy 47.5996 -63.478664) (xy 47.5996 -63.483744)
			(xy 47.599051 -63.512825) (xy 47.590223 -63.570314) (xy 47.572777 -63.625798) (xy 47.547118 -63.677994)
			(xy 47.513839 -63.725695) (xy 47.49419 -63.747142) (xy 48.818546 -65.071498) (xy 48.840232 -65.056226)
			(xy 48.886983 -65.031171) (xy 48.936748 -65.012819) (xy 48.962564 -65.006728) (xy 48.977288 -65.002993)
			(xy 49.003782 -64.988166) (xy 49.024735 -64.966196) (xy 49.03829 -64.93903) (xy 49.043245 -64.909077)
			(xy 49.041812 -64.893952) (xy 49.040248 -64.881311) (xy 49.038598 -64.855889) (xy 49.03851 -64.843152)
			(xy 49.038996 -64.815901) (xy 49.046752 -64.761953) (xy 49.062107 -64.709658) (xy 49.084749 -64.660081)
			(xy 49.114215 -64.614231) (xy 49.149906 -64.57304) (xy 49.191097 -64.537349) (xy 49.236947 -64.507883)
			(xy 49.286524 -64.485241) (xy 49.338819 -64.469886) (xy 49.392767 -64.46213) (xy 49.447269 -64.46213)
			(xy 49.501217 -64.469886) (xy 49.553512 -64.485241) (xy 49.603089 -64.507883) (xy 49.648939 -64.537349)
			(xy 49.69013 -64.57304) (xy 49.725821 -64.614231) (xy 49.755287 -64.660081) (xy 49.777929 -64.709658)
			(xy 49.793284 -64.761953) (xy 49.80104 -64.815901) (xy 49.801526 -64.843152) (xy 49.801022 -64.87126)
			(xy 49.792767 -64.926868) (xy 49.776444 -64.980662) (xy 49.752405 -65.031481) (xy 49.721172 -65.078222)
			(xy 49.683419 -65.119876) (xy 49.639963 -65.155541) (xy 49.591746 -65.184444) (xy 49.53981 -65.205962)
			(xy 49.48528 -65.219627) (xy 49.457356 -65.222882) (xy 49.446501 -65.224514) (xy 49.427582 -65.235601)
			(xy 49.414985 -65.253551) (xy 49.410993 -65.275114) (xy 49.41316 -65.285874) (xy 49.415692 -65.296056)
			(xy 49.419759 -65.316642) (xy 49.421288 -65.327022) (xy 49.427384 -65.37071) (xy 50.59172 -65.37071)
		)
		(stroke
			(width 0)
			(type solid)
		)
		(fill yes)
		(layer "In7.Cu")
		(net "P1V0_AUX")
	)
	(gr_poly
		(pts
			(xy -3.999992 -119.892064) (xy -3.944185 -119.891542) (xy -3.832883 -119.883201) (xy -3.722516 -119.866566)
			(xy -3.6137 -119.841729) (xy -3.507045 -119.80883) (xy -3.403146 -119.768053) (xy -3.302586 -119.719626)
			(xy -3.205925 -119.663818) (xy -3.113705 -119.600944) (xy -3.026442 -119.531354) (xy -2.944623 -119.455437)
			(xy -2.868706 -119.373618) (xy -2.799116 -119.286355) (xy -2.736242 -119.194135) (xy -2.680434 -119.097474)
			(xy -2.632007 -118.996914) (xy -2.59123 -118.893015) (xy -2.558331 -118.78636) (xy -2.533494 -118.677544)
			(xy -2.516859 -118.567177) (xy -2.508518 -118.455875) (xy -2.507996 -118.400068) (xy -2.507996 -6.59003)
			(xy -2.508518 -6.534223) (xy -2.516859 -6.422921) (xy -2.533494 -6.312554) (xy -2.558331 -6.203738)
			(xy -2.59123 -6.097083) (xy -2.632007 -5.993184) (xy -2.680434 -5.892624) (xy -2.736242 -5.795963)
			(xy -2.799116 -5.703743) (xy -2.868706 -5.61648) (xy -2.944623 -5.534661) (xy -3.026442 -5.458744)
			(xy -3.113705 -5.389154) (xy -3.205925 -5.32628) (xy -3.302586 -5.270472) (xy -3.403146 -5.222045)
			(xy -3.507045 -5.181268) (xy -3.6137 -5.148369) (xy -3.722516 -5.123532) (xy -3.832883 -5.106897)
			(xy -3.944185 -5.098556) (xy -3.999992 -5.098034) (xy -17.78 -5.098034) (xy -17.835807 -5.098556)
			(xy -17.947109 -5.106897) (xy -18.057476 -5.123532) (xy -18.166292 -5.148369) (xy -18.272947 -5.181268)
			(xy -18.376846 -5.222045) (xy -18.477406 -5.270472) (xy -18.574067 -5.32628) (xy -18.666287 -5.389154)
			(xy -18.75355 -5.458744) (xy -18.835369 -5.534661) (xy -18.911286 -5.61648) (xy -18.980876 -5.703743)
			(xy -19.04375 -5.795963) (xy -19.099558 -5.892624) (xy -19.147985 -5.993184) (xy -19.188762 -6.097083)
			(xy -19.221661 -6.203738) (xy -19.246498 -6.312554) (xy -19.263133 -6.422921) (xy -19.271474 -6.534223)
			(xy -19.271996 -6.59003) (xy -19.271996 -115.464644) (xy -16.875771 -115.464644) (xy -16.875771 -115.335504)
			(xy -16.867821 -115.206609) (xy -16.851951 -115.078449) (xy -16.828222 -114.951508) (xy -16.796723 -114.826269)
			(xy -16.757574 -114.703206) (xy -16.710923 -114.582787) (xy -16.656948 -114.465468) (xy -16.595853 -114.351694)
			(xy -16.52787 -114.241897) (xy -16.453256 -114.136494) (xy -16.372295 -114.035884) (xy -16.285295 -113.940449)
			(xy -16.192584 -113.85055) (xy -16.094514 -113.766529) (xy -15.991459 -113.688705) (xy -15.883808 -113.617373)
			(xy -15.771969 -113.552803) (xy -15.656368 -113.495241) (xy -15.537443 -113.444904) (xy -15.415644 -113.401984)
			(xy -15.291434 -113.366643) (xy -15.165285 -113.339016) (xy -15.037673 -113.319207) (xy -14.909084 -113.307291)
			(xy -14.780006 -113.303315) (xy -14.650928 -113.307291) (xy -14.522339 -113.319207) (xy -14.394727 -113.339016)
			(xy -14.268578 -113.366643) (xy -14.144368 -113.401984) (xy -14.022569 -113.444904) (xy -13.903644 -113.495241)
			(xy -13.788043 -113.552803) (xy -13.676204 -113.617373) (xy -13.568553 -113.688705) (xy -13.465498 -113.766529)
			(xy -13.367428 -113.85055) (xy -13.274717 -113.940449) (xy -13.187717 -114.035884) (xy -13.106756 -114.136494)
			(xy -13.032142 -114.241897) (xy -12.964159 -114.351694) (xy -12.903064 -114.465468) (xy -12.849089 -114.582787)
			(xy -12.802438 -114.703206) (xy -12.763289 -114.826269) (xy -12.73179 -114.951508) (xy -12.708061 -115.078449)
			(xy -12.692191 -115.206609) (xy -12.684241 -115.335504) (xy -12.683744 -115.400074) (xy -12.684241 -115.464644)
			(xy -12.692191 -115.593539) (xy -12.708061 -115.721699) (xy -12.73179 -115.84864) (xy -12.763289 -115.973879)
			(xy -12.802438 -116.096942) (xy -12.849089 -116.217361) (xy -12.903064 -116.33468) (xy -12.964159 -116.448454)
			(xy -13.032142 -116.558251) (xy -13.106756 -116.663654) (xy -13.187717 -116.764264) (xy -13.274717 -116.859699)
			(xy -13.367428 -116.949598) (xy -13.465498 -117.033619) (xy -13.568553 -117.111443) (xy -13.676204 -117.182775)
			(xy -13.788043 -117.247345) (xy -13.903644 -117.304907) (xy -14.022569 -117.355244) (xy -14.144368 -117.398164)
			(xy -14.268578 -117.433505) (xy -14.394727 -117.461132) (xy -14.522339 -117.480941) (xy -14.650928 -117.492857)
			(xy -14.780006 -117.496834) (xy -14.909084 -117.492857) (xy -15.037673 -117.480941) (xy -15.165285 -117.461132)
			(xy -15.291434 -117.433505) (xy -15.415644 -117.398164) (xy -15.537443 -117.355244) (xy -15.656368 -117.304907)
			(xy -15.771969 -117.247345) (xy -15.883808 -117.182775) (xy -15.991459 -117.111443) (xy -16.094514 -117.033619)
			(xy -16.192584 -116.949598) (xy -16.285295 -116.859699) (xy -16.372295 -116.764264) (xy -16.453256 -116.663654)
			(xy -16.52787 -116.558251) (xy -16.595853 -116.448454) (xy -16.656948 -116.33468) (xy -16.710923 -116.217361)
			(xy -16.757574 -116.096942) (xy -16.796723 -115.973879) (xy -16.828222 -115.84864) (xy -16.851951 -115.721699)
			(xy -16.867821 -115.593539) (xy -16.875771 -115.464644) (xy -19.271996 -115.464644) (xy -19.271996 -118.400068)
			(xy -19.271474 -118.455875) (xy -19.263133 -118.567177) (xy -19.246498 -118.677544) (xy -19.221661 -118.78636)
			(xy -19.188762 -118.893015) (xy -19.147985 -118.996914) (xy -19.099558 -119.097474) (xy -19.04375 -119.194135)
			(xy -18.980876 -119.286355) (xy -18.911286 -119.373618) (xy -18.835369 -119.455437) (xy -18.75355 -119.531354)
			(xy -18.666287 -119.600944) (xy -18.574067 -119.663818) (xy -18.477406 -119.719626) (xy -18.376846 -119.768053)
			(xy -18.272947 -119.80883) (xy -18.166292 -119.841729) (xy -18.057476 -119.866566) (xy -17.947109 -119.883201)
			(xy -17.835807 -119.891542) (xy -17.78 -119.892064)
		)
		(stroke
			(width 0)
			(type solid)
		)
		(fill yes)
		(layer "In8.Cu")
		(net "T_GND")
	)
	(gr_poly
		(pts
			(xy 10.256012 -118.78437) (xy 10.256012 -114.799872) (xy 10.256503 -114.755847) (xy 10.264197 -114.668134)
			(xy 10.279504 -114.581425) (xy 10.302308 -114.49638) (xy 10.332434 -114.413645) (xy 10.369655 -114.333849)
			(xy 10.413686 -114.257599) (xy 10.464194 -114.185476) (xy 10.520793 -114.118028) (xy 10.583054 -114.055768)
			(xy 10.650503 -113.999169) (xy 10.722626 -113.948662) (xy 10.798876 -113.904631) (xy 10.878672 -113.867411)
			(xy 10.961408 -113.837285) (xy 11.046453 -113.814482) (xy 11.133162 -113.799176) (xy 11.220875 -113.791483)
			(xy 11.2649 -113.790984) (xy 12.765024 -113.790984) (xy 12.809049 -113.791474) (xy 12.896764 -113.799165)
			(xy 12.983474 -113.81447) (xy 13.068521 -113.837272) (xy 13.078373 -113.840859) (xy 20.444184 -113.840859)
			(xy 20.444184 -113.786321) (xy 20.451946 -113.732337) (xy 20.467311 -113.680007) (xy 20.489968 -113.630397)
			(xy 20.519454 -113.584516) (xy 20.555169 -113.543299) (xy 20.596386 -113.507584) (xy 20.642267 -113.478098)
			(xy 20.691877 -113.455441) (xy 20.744207 -113.440076) (xy 20.798191 -113.432314) (xy 20.82546 -113.431828)
			(xy 21.71446 -113.431828) (xy 21.741732 -113.432309) (xy 21.795722 -113.440066) (xy 21.848058 -113.455428)
			(xy 21.897675 -113.478083) (xy 21.943562 -113.507569) (xy 21.984786 -113.543285) (xy 22.020507 -113.584506)
			(xy 22.049998 -113.63039) (xy 22.072658 -113.680004) (xy 22.088025 -113.732339) (xy 22.095788 -113.786328)
			(xy 22.095788 -113.840872) (xy 22.088025 -113.894861) (xy 22.072658 -113.947196) (xy 22.049998 -113.99681)
			(xy 22.020507 -114.042694) (xy 21.984786 -114.083915) (xy 21.943562 -114.119631) (xy 21.897675 -114.149117)
			(xy 21.848058 -114.171772) (xy 21.795722 -114.187134) (xy 21.741732 -114.194891) (xy 21.71446 -114.195352)
			(xy 20.82546 -114.195352) (xy 20.798191 -114.194866) (xy 20.744207 -114.187104) (xy 20.691877 -114.171739)
			(xy 20.642267 -114.149082) (xy 20.596386 -114.119596) (xy 20.555169 -114.083881) (xy 20.519454 -114.042664)
			(xy 20.489968 -113.996783) (xy 20.467311 -113.947173) (xy 20.451946 -113.894843) (xy 20.444184 -113.840859)
			(xy 13.078373 -113.840859) (xy 13.151258 -113.867397) (xy 13.231056 -113.904617) (xy 13.307307 -113.948648)
			(xy 13.379432 -113.999155) (xy 13.446881 -114.055754) (xy 13.509143 -114.118016) (xy 13.565743 -114.185465)
			(xy 13.61625 -114.25759) (xy 13.660282 -114.33384) (xy 13.697502 -114.413638) (xy 13.727627 -114.496375)
			(xy 13.750429 -114.581422) (xy 13.765734 -114.668132) (xy 13.773426 -114.755847) (xy 13.773912 -114.799872)
			(xy 13.773912 -116.038376) (xy 13.96492 -116.038376) (xy 13.96492 -115.149376) (xy 13.965406 -115.122125)
			(xy 13.973162 -115.068177) (xy 13.988517 -115.015882) (xy 14.011159 -114.966305) (xy 14.040625 -114.920455)
			(xy 14.076316 -114.879264) (xy 14.117507 -114.843573) (xy 14.163357 -114.814107) (xy 14.212934 -114.791465)
			(xy 14.265229 -114.77611) (xy 14.319177 -114.768354) (xy 14.373679 -114.768354) (xy 14.427627 -114.77611)
			(xy 14.479922 -114.791465) (xy 14.529499 -114.814107) (xy 14.575349 -114.843573) (xy 14.61654 -114.879264)
			(xy 14.652231 -114.920455) (xy 14.681697 -114.966305) (xy 14.704339 -115.015882) (xy 14.719694 -115.068177)
			(xy 14.72745 -115.122125) (xy 14.727936 -115.149376) (xy 14.727936 -116.038376) (xy 15.764764 -116.038376)
			(xy 15.764764 -115.149376) (xy 15.76525 -115.122107) (xy 15.773012 -115.068123) (xy 15.788377 -115.015793)
			(xy 15.811034 -114.966183) (xy 15.84052 -114.920302) (xy 15.876235 -114.879085) (xy 15.917452 -114.84337)
			(xy 15.963333 -114.813884) (xy 16.012943 -114.791227) (xy 16.065273 -114.775862) (xy 16.119257 -114.7681)
			(xy 16.173795 -114.7681) (xy 16.227779 -114.775862) (xy 16.280109 -114.791227) (xy 16.329719 -114.813884)
			(xy 16.3756 -114.84337) (xy 16.416817 -114.879085) (xy 16.452532 -114.920302) (xy 16.482018 -114.966183)
			(xy 16.504675 -115.015793) (xy 16.510811 -115.036691) (xy 23.190153 -115.036691) (xy 23.190153 -114.982149)
			(xy 23.197916 -114.928162) (xy 23.213282 -114.875829) (xy 23.23594 -114.826216) (xy 23.265428 -114.780333)
			(xy 23.301145 -114.739113) (xy 23.342366 -114.703395) (xy 23.38825 -114.673908) (xy 23.437863 -114.651251)
			(xy 23.490196 -114.635885) (xy 23.544183 -114.628123) (xy 23.571454 -114.62766) (xy 24.460454 -114.62766)
			(xy 24.487723 -114.628143) (xy 24.541707 -114.635905) (xy 24.594036 -114.651271) (xy 24.643646 -114.673927)
			(xy 24.689527 -114.703413) (xy 24.730744 -114.739129) (xy 24.766459 -114.780347) (xy 24.795945 -114.826227)
			(xy 24.818601 -114.875838) (xy 24.833966 -114.928167) (xy 24.841728 -114.982151) (xy 24.841728 -115.036689)
			(xy 24.833966 -115.090673) (xy 24.818601 -115.143002) (xy 24.795945 -115.192613) (xy 24.766459 -115.238493)
			(xy 24.730744 -115.279711) (xy 24.689527 -115.315427) (xy 24.643646 -115.344913) (xy 24.594036 -115.367569)
			(xy 24.541707 -115.382935) (xy 24.487723 -115.390697) (xy 24.460454 -115.391184) (xy 23.571454 -115.391184)
			(xy 23.544183 -115.390717) (xy 23.490196 -115.382955) (xy 23.437863 -115.367589) (xy 23.38825 -115.344932)
			(xy 23.342366 -115.315445) (xy 23.301145 -115.279727) (xy 23.265428 -115.238507) (xy 23.23594 -115.192624)
			(xy 23.213282 -115.143011) (xy 23.197916 -115.090678) (xy 23.190153 -115.036691) (xy 16.510811 -115.036691)
			(xy 16.52004 -115.068123) (xy 16.527802 -115.122107) (xy 16.528288 -115.149376) (xy 16.528288 -116.038376)
			(xy 16.527802 -116.065645) (xy 16.52004 -116.119629) (xy 16.504675 -116.171959) (xy 16.482018 -116.221569)
			(xy 16.452532 -116.26745) (xy 16.416817 -116.308667) (xy 16.3756 -116.344382) (xy 16.329719 -116.373868)
			(xy 16.280109 -116.396525) (xy 16.227779 -116.41189) (xy 16.173795 -116.419652) (xy 16.119257 -116.419652)
			(xy 16.065273 -116.41189) (xy 16.012943 -116.396525) (xy 15.963333 -116.373868) (xy 15.917452 -116.344382)
			(xy 15.876235 -116.308667) (xy 15.84052 -116.26745) (xy 15.811034 -116.221569) (xy 15.788377 -116.171959)
			(xy 15.773012 -116.119629) (xy 15.76525 -116.065645) (xy 15.764764 -116.038376) (xy 14.727936 -116.038376)
			(xy 14.72745 -116.065627) (xy 14.719694 -116.119575) (xy 14.704339 -116.17187) (xy 14.681697 -116.221447)
			(xy 14.652231 -116.267297) (xy 14.61654 -116.308488) (xy 14.575349 -116.344179) (xy 14.529499 -116.373645)
			(xy 14.479922 -116.396287) (xy 14.427627 -116.411642) (xy 14.373679 -116.419398) (xy 14.319177 -116.419398)
			(xy 14.265229 -116.411642) (xy 14.212934 -116.396287) (xy 14.163357 -116.373645) (xy 14.117507 -116.344179)
			(xy 14.076316 -116.308488) (xy 14.040625 -116.267297) (xy 14.011159 -116.221447) (xy 13.988517 -116.17187)
			(xy 13.973162 -116.119575) (xy 13.965406 -116.065627) (xy 13.96492 -116.038376) (xy 13.773912 -116.038376)
			(xy 13.773912 -117.3734) (xy 31.116016 -117.3734) (xy 31.116016 -114.77498) (xy 31.116505 -114.713316)
			(xy 31.124564 -114.590252) (xy 31.140653 -114.467979) (xy 31.164706 -114.34702) (xy 31.196619 -114.227893)
			(xy 31.236255 -114.111108) (xy 31.283445 -113.997166) (xy 31.337986 -113.886554) (xy 31.399645 -113.779747)
			(xy 31.468158 -113.677201) (xy 31.543231 -113.579356) (xy 31.624543 -113.48663) (xy 31.711746 -113.399422)
			(xy 31.804466 -113.318103) (xy 31.902306 -113.243024) (xy 32.004847 -113.174504) (xy 32.11165 -113.112838)
			(xy 32.222258 -113.058289) (xy 32.336197 -113.011092) (xy 32.452979 -112.971448) (xy 32.572104 -112.939527)
			(xy 32.693062 -112.915466) (xy 32.815334 -112.899368) (xy 32.938397 -112.891302) (xy 33.061725 -112.891302)
			(xy 33.184788 -112.899368) (xy 33.30706 -112.915466) (xy 33.428018 -112.939527) (xy 33.547143 -112.971448)
			(xy 33.663925 -113.011092) (xy 33.777864 -113.058289) (xy 33.888472 -113.112838) (xy 33.995275 -113.174504)
			(xy 34.097816 -113.243024) (xy 34.195656 -113.318103) (xy 34.288376 -113.399422) (xy 34.375579 -113.48663)
			(xy 34.456891 -113.579356) (xy 34.531964 -113.677201) (xy 34.600477 -113.779747) (xy 34.662136 -113.886554)
			(xy 34.716677 -113.997166) (xy 34.763867 -114.111108) (xy 34.803503 -114.227893) (xy 34.835416 -114.34702)
			(xy 34.859469 -114.467979) (xy 34.875558 -114.590252) (xy 34.883617 -114.713316) (xy 34.884106 -114.77498)
			(xy 34.884106 -117.3734) (xy 43.825922 -117.3734) (xy 43.825922 -114.324892) (xy 43.826423 -114.271251)
			(xy 43.83444 -114.164269) (xy 43.85043 -114.058186) (xy 43.874302 -113.953594) (xy 43.905924 -113.851078)
			(xy 43.945119 -113.751213) (xy 43.991666 -113.654555) (xy 44.045307 -113.561646) (xy 44.105741 -113.473006)
			(xy 44.17263 -113.38913) (xy 44.245601 -113.310487) (xy 44.324244 -113.237516) (xy 44.40812 -113.170627)
			(xy 44.49676 -113.110193) (xy 44.589669 -113.056552) (xy 44.686327 -113.010005) (xy 44.786192 -112.97081)
			(xy 44.888708 -112.939188) (xy 44.9933 -112.915316) (xy 45.099383 -112.899326) (xy 45.206365 -112.891309)
			(xy 45.313647 -112.891309) (xy 45.420629 -112.899326) (xy 45.526712 -112.915316) (xy 45.631304 -112.939188)
			(xy 45.73382 -112.97081) (xy 45.833685 -113.010005) (xy 45.930343 -113.056552) (xy 46.023252 -113.110193)
			(xy 46.111892 -113.170627) (xy 46.195768 -113.237516) (xy 46.274411 -113.310487) (xy 46.347382 -113.38913)
			(xy 46.414271 -113.473006) (xy 46.474705 -113.561646) (xy 46.528346 -113.654555) (xy 46.574893 -113.751213)
			(xy 46.614088 -113.851078) (xy 46.64571 -113.953594) (xy 46.669582 -114.058186) (xy 46.685572 -114.164269)
			(xy 46.693589 -114.271251) (xy 46.69409 -114.324892) (xy 46.69409 -117.3734) (xy 64.026034 -117.3734)
			(xy 64.026034 -114.525044) (xy 64.026532 -114.468001) (xy 64.03449 -114.354194) (xy 64.050367 -114.24122)
			(xy 64.074087 -114.129628) (xy 64.105533 -114.019962) (xy 64.144553 -113.912757) (xy 64.190955 -113.808535)
			(xy 64.244515 -113.707804) (xy 64.304971 -113.611054) (xy 64.372028 -113.518758) (xy 64.445361 -113.431363)
			(xy 64.524611 -113.349297) (xy 64.609393 -113.27296) (xy 64.699293 -113.202722) (xy 64.793874 -113.138926)
			(xy 64.892674 -113.081884) (xy 64.995213 -113.031872) (xy 65.100991 -112.989135) (xy 65.209492 -112.953881)
			(xy 65.320188 -112.926281) (xy 65.43254 -112.906471) (xy 65.546 -112.894546) (xy 65.660016 -112.890564)
			(xy 65.774032 -112.894546) (xy 65.887492 -112.906471) (xy 65.999844 -112.926281) (xy 66.11054 -112.953881)
			(xy 66.219041 -112.989135) (xy 66.324819 -113.031872) (xy 66.427358 -113.081884) (xy 66.526158 -113.138926)
			(xy 66.620739 -113.202722) (xy 66.710639 -113.27296) (xy 66.795421 -113.349297) (xy 66.874671 -113.431363)
			(xy 66.948004 -113.518758) (xy 67.015061 -113.611054) (xy 67.075517 -113.707804) (xy 67.129077 -113.808535)
			(xy 67.175479 -113.912757) (xy 67.214499 -114.019962) (xy 67.245945 -114.129628) (xy 67.269665 -114.24122)
			(xy 67.285542 -114.354194) (xy 67.2935 -114.468001) (xy 67.293998 -114.525044) (xy 67.293998 -117.3734)
			(xy 76.230988 -117.3734) (xy 76.230988 -114.799872) (xy 76.231478 -114.755847) (xy 76.23917 -114.668133)
			(xy 76.254475 -114.581423) (xy 76.277277 -114.496376) (xy 76.307402 -114.413639) (xy 76.344622 -114.333842)
			(xy 76.388653 -114.257592) (xy 76.439161 -114.185468) (xy 76.49576 -114.118018) (xy 76.558021 -114.055757)
			(xy 76.625471 -113.999158) (xy 76.697595 -113.948651) (xy 76.773846 -113.90462) (xy 76.853643 -113.867401)
			(xy 76.93638 -113.837275) (xy 77.021427 -113.814474) (xy 77.108137 -113.799169) (xy 77.195851 -113.791478)
			(xy 77.239876 -113.790984) (xy 78.74 -113.790984) (xy 78.784039 -113.79145) (xy 78.871783 -113.799127)
			(xy 78.958523 -113.814422) (xy 79.043601 -113.837219) (xy 79.126367 -113.867344) (xy 79.206193 -113.904568)
			(xy 79.282471 -113.948608) (xy 79.354621 -113.999129) (xy 79.422092 -114.055745) (xy 79.484372 -114.118027)
			(xy 79.540987 -114.1855) (xy 79.591506 -114.257651) (xy 79.635544 -114.33393) (xy 79.672766 -114.413757)
			(xy 79.702889 -114.496524) (xy 79.725684 -114.581602) (xy 79.740976 -114.668343) (xy 79.748651 -114.756087)
			(xy 79.749142 -114.800126) (xy 79.749142 -118.7196) (xy 79.85379 -118.824248) (xy 80.16875 -118.824248)
			(xy 80.272636 -118.720616) (xy 83.93684 -118.720616) (xy 84.094574 -118.878096) (xy 84.394548 -118.878096)
			(xy 84.491068 -118.781576) (xy 84.491068 -114.799872) (xy 84.491558 -114.755847) (xy 84.49925 -114.668132)
			(xy 84.514555 -114.581421) (xy 84.537356 -114.496374) (xy 84.567482 -114.413636) (xy 84.604701 -114.333838)
			(xy 84.648732 -114.257587) (xy 84.69924 -114.185462) (xy 84.755839 -114.118012) (xy 84.8181 -114.05575)
			(xy 84.885549 -113.999149) (xy 84.957674 -113.948641) (xy 85.033924 -113.904609) (xy 85.113722 -113.867388)
			(xy 85.196458 -113.837261) (xy 85.281506 -113.814458) (xy 85.368216 -113.799152) (xy 85.455931 -113.791459)
			(xy 85.499956 -113.790984) (xy 88.000078 -113.790984) (xy 88.055848 -113.790476) (xy 88.167076 -113.782142)
			(xy 88.277371 -113.76552) (xy 88.386115 -113.740701) (xy 88.4927 -113.707825) (xy 88.596531 -113.667076)
			(xy 88.697025 -113.618682) (xy 88.793622 -113.562913) (xy 88.885782 -113.500081) (xy 88.972988 -113.430538)
			(xy 89.054754 -113.354672) (xy 89.130621 -113.272908) (xy 89.200166 -113.185703) (xy 89.262999 -113.093545)
			(xy 89.31877 -112.996948) (xy 89.367166 -112.896454) (xy 89.407917 -112.792625) (xy 89.440794 -112.68604)
			(xy 89.465615 -112.577297) (xy 89.48224 -112.467002) (xy 89.490575 -112.355774) (xy 89.491058 -112.300004)
			(xy 89.491058 -85.5091) (xy 87.749888 -85.5091) (xy 87.705865 -85.508603) (xy 87.618157 -85.500897)
			(xy 87.531453 -85.485581) (xy 87.446413 -85.46277) (xy 87.363683 -85.432637) (xy 87.283893 -85.395413)
			(xy 87.207648 -85.351379) (xy 87.13553 -85.300871) (xy 87.068085 -85.244273) (xy 87.005827 -85.182015)
			(xy 86.949229 -85.11457) (xy 86.898721 -85.042452) (xy 86.854687 -84.966207) (xy 86.817463 -84.886417)
			(xy 86.78733 -84.803687) (xy 86.764519 -84.718647) (xy 86.749203 -84.631943) (xy 86.741497 -84.544235)
			(xy 86.741 -84.500212) (xy 86.741 -81.999836) (xy 86.741491 -81.955812) (xy 86.749186 -81.868101)
			(xy 86.764493 -81.781393) (xy 86.787298 -81.69635) (xy 86.817425 -81.613616) (xy 86.854646 -81.533822)
			(xy 86.898678 -81.457575) (xy 86.949186 -81.385454) (xy 87.005786 -81.318008) (xy 87.068047 -81.255751)
			(xy 87.135495 -81.199154) (xy 87.207619 -81.14865) (xy 87.283869 -81.104622) (xy 87.363664 -81.067405)
			(xy 87.446399 -81.037282) (xy 87.531444 -81.014482) (xy 87.618152 -80.999179) (xy 87.705864 -80.991489)
			(xy 87.749888 -80.990948) (xy 89.491058 -80.990948) (xy 89.491058 -69.07022) (xy 89.492074 -69.069204)
			(xy 89.492074 -67.757802) (xy 89.491058 -67.756786) (xy 89.491058 -1.999996) (xy 89.490549 -1.944227)
			(xy 89.482214 -1.833001) (xy 89.465589 -1.722708) (xy 89.440769 -1.613967) (xy 89.407892 -1.507384)
			(xy 89.367142 -1.403556) (xy 89.318747 -1.303064) (xy 89.262977 -1.206469) (xy 89.200145 -1.114313)
			(xy 89.130601 -1.027109) (xy 89.054735 -0.945346) (xy 88.972971 -0.869482) (xy 88.885767 -0.79994)
			(xy 88.793609 -0.737109) (xy 88.697013 -0.681341) (xy 88.59652 -0.632947) (xy 88.492692 -0.592199)
			(xy 88.386108 -0.559324) (xy 88.277366 -0.534506) (xy 88.167074 -0.517883) (xy 88.055847 -0.50955)
			(xy 88.000078 -0.509016) (xy 1.999996 -0.509016) (xy 1.944227 -0.509538) (xy 1.833001 -0.517873)
			(xy 1.722709 -0.534497) (xy 1.613967 -0.559317) (xy 1.507385 -0.592194) (xy 1.403557 -0.632943) (xy 1.303065 -0.681338)
			(xy 1.20647 -0.737107) (xy 1.114313 -0.799938) (xy 1.027109 -0.869481) (xy 0.945346 -0.945346) (xy 0.869481 -1.027109)
			(xy 0.799938 -1.114313) (xy 0.737107 -1.20647) (xy 0.681338 -1.303065) (xy 0.632943 -1.403557) (xy 0.592194 -1.507385)
			(xy 0.559317 -1.613967) (xy 0.534497 -1.722709) (xy 0.517873 -1.833001) (xy 0.509538 -1.944227) (xy 0.509016 -1.999996)
			(xy 0.509016 -4.69011) (xy 3.634743 -4.69011) (xy 3.638781 -4.606614) (xy 3.65086 -4.523897) (xy 3.670865 -4.442732)
			(xy 3.69861 -4.363877) (xy 3.733837 -4.288068) (xy 3.776216 -4.216013) (xy 3.825351 -4.148384) (xy 3.880784 -4.085813)
			(xy 3.941997 -4.028884) (xy 4.008419 -3.978129) (xy 4.079429 -3.934021) (xy 4.154365 -3.896973) (xy 4.232527 -3.867331)
			(xy 4.313184 -3.84537) (xy 4.395585 -3.831296) (xy 4.478959 -3.825241) (xy 4.562529 -3.827261) (xy 4.645513 -3.837337)
			(xy 4.727138 -3.855375) (xy 4.80664 -3.881207) (xy 4.883279 -3.914592) (xy 4.956337 -3.955217) (xy 5.025133 -4.002704)
			(xy 5.089025 -4.056609) (xy 5.147417 -4.116428) (xy 5.199762 -4.181604) (xy 5.245572 -4.251528) (xy 5.284421 -4.325547)
			(xy 5.315943 -4.402969) (xy 5.339847 -4.483073) (xy 5.355907 -4.565109) (xy 5.363975 -4.648313) (xy 5.36448 -4.69011)
			(xy 10.635237 -4.69011) (xy 10.639274 -4.606638) (xy 10.651349 -4.523946) (xy 10.671348 -4.442805)
			(xy 10.699086 -4.363973) (xy 10.734302 -4.288186) (xy 10.776668 -4.216152) (xy 10.825789 -4.148543)
			(xy 10.881206 -4.08599) (xy 10.942401 -4.029078) (xy 11.008803 -3.978338) (xy 11.079793 -3.934243)
			(xy 11.154707 -3.897206) (xy 11.232845 -3.867572) (xy 11.313479 -3.845618) (xy 11.395856 -3.831548)
			(xy 11.479206 -3.825495) (xy 11.562751 -3.827514) (xy 11.645711 -3.837588) (xy 11.727311 -3.85562)
			(xy 11.80679 -3.881445) (xy 11.883406 -3.914819) (xy 11.956443 -3.955433) (xy 12.025219 -4.002906)
			(xy 12.089092 -4.056795) (xy 12.147467 -4.116597) (xy 12.199797 -4.181754) (xy 12.245594 -4.251657)
			(xy 12.28443 -4.325654) (xy 12.315944 -4.403054) (xy 12.33984 -4.483134) (xy 12.355896 -4.565146)
			(xy 12.363962 -4.648325) (xy 12.364466 -4.69011) (xy 12.363962 -4.731895) (xy 12.355896 -4.815074)
			(xy 12.33984 -4.897086) (xy 12.315944 -4.977166) (xy 12.28443 -5.054566) (xy 12.265749 -5.09016)
			(xy 66.234821 -5.09016) (xy 66.238859 -5.006664) (xy 66.250938 -4.923947) (xy 66.270943 -4.842782)
			(xy 66.298688 -4.763927) (xy 66.333915 -4.688118) (xy 66.376294 -4.616063) (xy 66.425429 -4.548434)
			(xy 66.480862 -4.485863) (xy 66.542075 -4.428934) (xy 66.608497 -4.378179) (xy 66.679507 -4.334071)
			(xy 66.754443 -4.297023) (xy 66.832605 -4.267381) (xy 66.913262 -4.24542) (xy 66.995663 -4.231346)
			(xy 67.079037 -4.225291) (xy 67.162607 -4.227311) (xy 67.245591 -4.237387) (xy 67.327216 -4.255425)
			(xy 67.406718 -4.281257) (xy 67.483357 -4.314642) (xy 67.556415 -4.355267) (xy 67.625211 -4.402754)
			(xy 67.689103 -4.456659) (xy 67.747495 -4.516478) (xy 67.79984 -4.581654) (xy 67.84565 -4.651578)
			(xy 67.884499 -4.725597) (xy 67.916021 -4.803019) (xy 67.939925 -4.883123) (xy 67.955985 -4.965159)
			(xy 67.964053 -5.048363) (xy 67.964558 -5.09016) (xy 73.235315 -5.09016) (xy 73.239352 -5.006688)
			(xy 73.251427 -4.923996) (xy 73.271426 -4.842855) (xy 73.299164 -4.764023) (xy 73.33438 -4.688236)
			(xy 73.376746 -4.616202) (xy 73.425867 -4.548593) (xy 73.481284 -4.48604) (xy 73.542479 -4.429128)
			(xy 73.608881 -4.378388) (xy 73.679871 -4.334293) (xy 73.754785 -4.297256) (xy 73.832923 -4.267622)
			(xy 73.913557 -4.245668) (xy 73.995934 -4.231598) (xy 74.079284 -4.225545) (xy 74.162829 -4.227564)
			(xy 74.245789 -4.237638) (xy 74.327389 -4.25567) (xy 74.406868 -4.281495) (xy 74.483484 -4.314869)
			(xy 74.556521 -4.355483) (xy 74.625297 -4.402956) (xy 74.68917 -4.456845) (xy 74.747545 -4.516647)
			(xy 74.799875 -4.581804) (xy 74.845672 -4.651707) (xy 74.865827 -4.69011) (xy 77.634595 -4.69011)
			(xy 77.638634 -4.606589) (xy 77.650716 -4.523848) (xy 77.670728 -4.44266) (xy 77.698481 -4.363781)
			(xy 77.733718 -4.28795) (xy 77.776109 -4.215873) (xy 77.825259 -4.148225) (xy 77.880708 -4.085635)
			(xy 77.941939 -4.02869) (xy 78.008381 -3.97792) (xy 78.079412 -3.933799) (xy 78.15437 -3.89674) (xy 78.232554 -3.867089)
			(xy 78.313236 -3.845122) (xy 78.395661 -3.831044) (xy 78.479059 -3.824987) (xy 78.562653 -3.827008)
			(xy 78.645662 -3.837087) (xy 78.727311 -3.85513) (xy 78.806836 -3.88097) (xy 78.883497 -3.914364)
			(xy 78.956577 -3.955001) (xy 79.025394 -4.002502) (xy 79.089304 -4.056423) (xy 79.147713 -4.11626)
			(xy 79.200073 -4.181455) (xy 79.245897 -4.251399) (xy 79.284757 -4.32544) (xy 79.316289 -4.402885)
			(xy 79.340199 -4.483012) (xy 79.356265 -4.565073) (xy 79.364335 -4.648301) (xy 79.36484 -4.69011)
			(xy 84.635089 -4.69011) (xy 84.639127 -4.606614) (xy 84.651206 -4.523897) (xy 84.671211 -4.442732)
			(xy 84.698956 -4.363877) (xy 84.734183 -4.288068) (xy 84.776562 -4.216013) (xy 84.825697 -4.148384)
			(xy 84.88113 -4.085813) (xy 84.942343 -4.028884) (xy 85.008765 -3.978129) (xy 85.079775 -3.934021)
			(xy 85.154711 -3.896973) (xy 85.232873 -3.867331) (xy 85.31353 -3.84537) (xy 85.395931 -3.831296)
			(xy 85.479305 -3.825241) (xy 85.562875 -3.827261) (xy 85.645859 -3.837337) (xy 85.727484 -3.855375)
			(xy 85.806986 -3.881207) (xy 85.883625 -3.914592) (xy 85.956683 -3.955217) (xy 86.025479 -4.002704)
			(xy 86.089371 -4.056609) (xy 86.147763 -4.116428) (xy 86.200108 -4.181604) (xy 86.245918 -4.251528)
			(xy 86.284767 -4.325547) (xy 86.316289 -4.402969) (xy 86.340193 -4.483073) (xy 86.356253 -4.565109)
			(xy 86.364321 -4.648313) (xy 86.364826 -4.69011) (xy 86.364321 -4.731907) (xy 86.356253 -4.815111)
			(xy 86.340193 -4.897147) (xy 86.316289 -4.977251) (xy 86.284767 -5.054673) (xy 86.245918 -5.128692)
			(xy 86.200108 -5.198616) (xy 86.147763 -5.263792) (xy 86.089371 -5.323611) (xy 86.025479 -5.377516)
			(xy 85.956683 -5.425003) (xy 85.883625 -5.465628) (xy 85.806986 -5.499013) (xy 85.727484 -5.524845)
			(xy 85.645859 -5.542883) (xy 85.562875 -5.552959) (xy 85.479305 -5.554979) (xy 85.395931 -5.548924)
			(xy 85.31353 -5.53485) (xy 85.232873 -5.512889) (xy 85.154711 -5.483247) (xy 85.079775 -5.446199)
			(xy 85.008765 -5.402091) (xy 84.942343 -5.351336) (xy 84.88113 -5.294407) (xy 84.825697 -5.231836)
			(xy 84.776562 -5.164207) (xy 84.734183 -5.092152) (xy 84.698956 -5.016343) (xy 84.671211 -4.937488)
			(xy 84.651206 -4.856323) (xy 84.639127 -4.773606) (xy 84.635089 -4.69011) (xy 79.36484 -4.69011)
			(xy 79.364335 -4.731919) (xy 79.356265 -4.815147) (xy 79.340199 -4.897208) (xy 79.316289 -4.977335)
			(xy 79.284757 -5.05478) (xy 79.245897 -5.128821) (xy 79.200073 -5.198765) (xy 79.147713 -5.26396)
			(xy 79.089304 -5.323797) (xy 79.025394 -5.377718) (xy 78.956577 -5.425219) (xy 78.883497 -5.465856)
			(xy 78.806836 -5.49925) (xy 78.727311 -5.52509) (xy 78.645662 -5.543133) (xy 78.562653 -5.553212)
			(xy 78.479059 -5.555233) (xy 78.395661 -5.549176) (xy 78.313236 -5.535098) (xy 78.232554 -5.513131)
			(xy 78.15437 -5.48348) (xy 78.079412 -5.446421) (xy 78.008381 -5.4023) (xy 77.941939 -5.35153) (xy 77.880708 -5.294585)
			(xy 77.825259 -5.231995) (xy 77.776109 -5.164347) (xy 77.733718 -5.09227) (xy 77.698481 -5.016439)
			(xy 77.670728 -4.93756) (xy 77.650716 -4.856372) (xy 77.638634 -4.773631) (xy 77.634595 -4.69011)
			(xy 74.865827 -4.69011) (xy 74.884508 -4.725704) (xy 74.916022 -4.803104) (xy 74.939918 -4.883184)
			(xy 74.955974 -4.965196) (xy 74.96404 -5.048375) (xy 74.964544 -5.09016) (xy 74.96404 -5.131945)
			(xy 74.955974 -5.215124) (xy 74.939918 -5.297136) (xy 74.916022 -5.377216) (xy 74.884508 -5.454616)
			(xy 74.845672 -5.528613) (xy 74.799875 -5.598516) (xy 74.747545 -5.663673) (xy 74.68917 -5.723475)
			(xy 74.625297 -5.777364) (xy 74.556521 -5.824837) (xy 74.483484 -5.865451) (xy 74.406868 -5.898825)
			(xy 74.327389 -5.92465) (xy 74.245789 -5.942682) (xy 74.162829 -5.952756) (xy 74.079284 -5.954775)
			(xy 73.995934 -5.948722) (xy 73.913557 -5.934652) (xy 73.832923 -5.912698) (xy 73.754785 -5.883064)
			(xy 73.679871 -5.846027) (xy 73.608881 -5.801932) (xy 73.542479 -5.751192) (xy 73.481284 -5.69428)
			(xy 73.425867 -5.631727) (xy 73.376746 -5.564118) (xy 73.33438 -5.492084) (xy 73.299164 -5.416297)
			(xy 73.271426 -5.337465) (xy 73.251427 -5.256324) (xy 73.239352 -5.173632) (xy 73.235315 -5.09016)
			(xy 67.964558 -5.09016) (xy 67.964053 -5.131957) (xy 67.955985 -5.215161) (xy 67.939925 -5.297197)
			(xy 67.916021 -5.377301) (xy 67.884499 -5.454723) (xy 67.84565 -5.528742) (xy 67.79984 -5.598666)
			(xy 67.747495 -5.663842) (xy 67.689103 -5.723661) (xy 67.625211 -5.777566) (xy 67.556415 -5.825053)
			(xy 67.483357 -5.865678) (xy 67.406718 -5.899063) (xy 67.327216 -5.924895) (xy 67.245591 -5.942933)
			(xy 67.162607 -5.953009) (xy 67.079037 -5.955029) (xy 66.995663 -5.948974) (xy 66.913262 -5.9349)
			(xy 66.832605 -5.912939) (xy 66.754443 -5.883297) (xy 66.679507 -5.846249) (xy 66.608497 -5.802141)
			(xy 66.542075 -5.751386) (xy 66.480862 -5.694457) (xy 66.425429 -5.631886) (xy 66.376294 -5.564257)
			(xy 66.333915 -5.492202) (xy 66.298688 -5.416393) (xy 66.270943 -5.337538) (xy 66.250938 -5.256373)
			(xy 66.238859 -5.173656) (xy 66.234821 -5.09016) (xy 12.265749 -5.09016) (xy 12.245594 -5.128563)
			(xy 12.199797 -5.198466) (xy 12.147467 -5.263623) (xy 12.089092 -5.323425) (xy 12.025219 -5.377314)
			(xy 11.956443 -5.424787) (xy 11.883406 -5.465401) (xy 11.80679 -5.498775) (xy 11.727311 -5.5246)
			(xy 11.645711 -5.542632) (xy 11.562751 -5.552706) (xy 11.479206 -5.554725) (xy 11.395856 -5.548672)
			(xy 11.313479 -5.534602) (xy 11.232845 -5.512648) (xy 11.154707 -5.483014) (xy 11.079793 -5.445977)
			(xy 11.008803 -5.401882) (xy 10.942401 -5.351142) (xy 10.881206 -5.29423) (xy 10.825789 -5.231677)
			(xy 10.776668 -5.164068) (xy 10.734302 -5.092034) (xy 10.699086 -5.016247) (xy 10.671348 -4.937415)
			(xy 10.651349 -4.856274) (xy 10.639274 -4.773582) (xy 10.635237 -4.69011) (xy 5.36448 -4.69011) (xy 5.363975 -4.731907)
			(xy 5.355907 -4.815111) (xy 5.339847 -4.897147) (xy 5.315943 -4.977251) (xy 5.284421 -5.054673) (xy 5.245572 -5.128692)
			(xy 5.199762 -5.198616) (xy 5.147417 -5.263792) (xy 5.089025 -5.323611) (xy 5.025133 -5.377516) (xy 4.956337 -5.425003)
			(xy 4.883279 -5.465628) (xy 4.80664 -5.499013) (xy 4.727138 -5.524845) (xy 4.645513 -5.542883) (xy 4.562529 -5.552959)
			(xy 4.478959 -5.554979) (xy 4.395585 -5.548924) (xy 4.313184 -5.53485) (xy 4.232527 -5.512889) (xy 4.154365 -5.483247)
			(xy 4.079429 -5.446199) (xy 4.008419 -5.402091) (xy 3.941997 -5.351336) (xy 3.880784 -5.294407) (xy 3.825351 -5.231836)
			(xy 3.776216 -5.164207) (xy 3.733837 -5.092152) (xy 3.69861 -5.016343) (xy 3.670865 -4.937488) (xy 3.65086 -4.856323)
			(xy 3.638781 -4.773606) (xy 3.634743 -4.69011) (xy 0.509016 -4.69011) (xy 0.509016 -13.417248) (xy 41.210697 -13.417248)
			(xy 41.210697 -13.342672) (xy 41.218492 -13.268505) (xy 41.233997 -13.195559) (xy 41.257043 -13.124633)
			(xy 41.287375 -13.056505) (xy 41.324663 -12.991921) (xy 41.368498 -12.931588) (xy 41.418399 -12.876167)
			(xy 41.473819 -12.826266) (xy 41.534152 -12.782432) (xy 41.598737 -12.745144) (xy 41.666865 -12.714812)
			(xy 41.737791 -12.691767) (xy 41.810737 -12.676262) (xy 41.884904 -12.668467) (xy 41.922192 -12.667996)
			(xy 43.922188 -12.667996) (xy 43.959474 -12.668551) (xy 44.033637 -12.676344) (xy 44.106579 -12.691848)
			(xy 44.177502 -12.714891) (xy 44.245627 -12.745221) (xy 44.310208 -12.782506) (xy 44.370538 -12.826338)
			(xy 44.425956 -12.876235) (xy 44.475855 -12.931652) (xy 44.519687 -12.991982) (xy 44.556974 -13.056563)
			(xy 44.587305 -13.124687) (xy 44.610349 -13.195609) (xy 44.625854 -13.268551) (xy 44.633649 -13.342714)
			(xy 44.633649 -13.417286) (xy 44.625854 -13.491449) (xy 44.610349 -13.564391) (xy 44.587305 -13.635313)
			(xy 44.556974 -13.703437) (xy 44.519687 -13.768018) (xy 44.475855 -13.828348) (xy 44.425956 -13.883765)
			(xy 44.370538 -13.933662) (xy 44.310208 -13.977494) (xy 44.245627 -14.014779) (xy 44.177502 -14.045109)
			(xy 44.106579 -14.068152) (xy 44.033637 -14.083656) (xy 43.959474 -14.091449) (xy 43.922188 -14.09192)
			(xy 41.922192 -14.09192) (xy 41.884904 -14.091453) (xy 41.810737 -14.083658) (xy 41.737791 -14.068153)
			(xy 41.666865 -14.045108) (xy 41.598737 -14.014776) (xy 41.534152 -13.977488) (xy 41.473819 -13.933654)
			(xy 41.418399 -13.883753) (xy 41.368498 -13.828332) (xy 41.324663 -13.767999) (xy 41.287375 -13.703415)
			(xy 41.257043 -13.635287) (xy 41.233997 -13.564361) (xy 41.218492 -13.491415) (xy 41.210697 -13.417248)
			(xy 0.509016 -13.417248) (xy 0.509016 -14.917388) (xy 38.210708 -14.917388) (xy 38.210708 -14.842812)
			(xy 38.218503 -14.768646) (xy 38.234008 -14.6957) (xy 38.257053 -14.624775) (xy 38.287386 -14.556647)
			(xy 38.324673 -14.492062) (xy 38.368507 -14.43173) (xy 38.418408 -14.376309) (xy 38.473828 -14.326409)
			(xy 38.534161 -14.282574) (xy 38.598745 -14.245287) (xy 38.666873 -14.214954) (xy 38.737798 -14.191909)
			(xy 38.810744 -14.176403) (xy 38.88491 -14.168608) (xy 38.922198 -14.16812) (xy 40.922194 -14.16812)
			(xy 40.959481 -14.168627) (xy 41.033646 -14.176422) (xy 41.106591 -14.191926) (xy 41.177515 -14.21497)
			(xy 41.245641 -14.245301) (xy 41.310224 -14.282588) (xy 41.370556 -14.326421) (xy 41.425975 -14.37632)
			(xy 41.475875 -14.431739) (xy 41.519709 -14.492071) (xy 41.556996 -14.556653) (xy 41.587328 -14.62478)
			(xy 41.610373 -14.695704) (xy 41.625877 -14.768648) (xy 41.633673 -14.842813) (xy 41.633673 -14.917387)
			(xy 44.210708 -14.917387) (xy 44.210708 -14.842813) (xy 44.218503 -14.768647) (xy 44.234008 -14.695702)
			(xy 44.257052 -14.624777) (xy 44.287384 -14.55665) (xy 44.324671 -14.492066) (xy 44.368504 -14.431734)
			(xy 44.418404 -14.376314) (xy 44.473823 -14.326413) (xy 44.534154 -14.282578) (xy 44.598737 -14.24529)
			(xy 44.666864 -14.214957) (xy 44.737788 -14.191911) (xy 44.810733 -14.176405) (xy 44.884899 -14.168609)
			(xy 44.922186 -14.16812) (xy 46.922182 -14.16812) (xy 46.959469 -14.168626) (xy 47.033636 -14.17642)
			(xy 47.106581 -14.191923) (xy 47.177506 -14.214967) (xy 47.245634 -14.245298) (xy 47.310218 -14.282584)
			(xy 47.370551 -14.326417) (xy 47.425971 -14.376316) (xy 47.475872 -14.431735) (xy 47.519706 -14.492067)
			(xy 47.556994 -14.55665) (xy 47.587327 -14.624777) (xy 47.610372 -14.695702) (xy 47.625877 -14.768647)
			(xy 47.633673 -14.842813) (xy 47.633673 -14.917387) (xy 47.625877 -14.991553) (xy 47.610372 -15.064498)
			(xy 47.587327 -15.135423) (xy 47.556994 -15.20355) (xy 47.519706 -15.268133) (xy 47.475872 -15.328465)
			(xy 47.425971 -15.383884) (xy 47.370551 -15.433783) (xy 47.310218 -15.477616) (xy 47.245634 -15.514902)
			(xy 47.177506 -15.545233) (xy 47.106581 -15.568277) (xy 47.033636 -15.58378) (xy 46.959469 -15.591574)
			(xy 46.922182 -15.592044) (xy 44.922186 -15.592044) (xy 44.884899 -15.591591) (xy 44.810733 -15.583795)
			(xy 44.737788 -15.568289) (xy 44.666864 -15.545243) (xy 44.598737 -15.51491) (xy 44.534154 -15.477622)
			(xy 44.473823 -15.433787) (xy 44.418404 -15.383886) (xy 44.368504 -15.328466) (xy 44.324671 -15.268134)
			(xy 44.287384 -15.20355) (xy 44.257052 -15.135423) (xy 44.234008 -15.064498) (xy 44.218503 -14.991553)
			(xy 44.210708 -14.917387) (xy 41.633673 -14.917387) (xy 41.625877 -14.991552) (xy 41.610373 -15.064496)
			(xy 41.587328 -15.13542) (xy 41.556996 -15.203547) (xy 41.519709 -15.268129) (xy 41.475875 -15.328461)
			(xy 41.425975 -15.38388) (xy 41.370556 -15.433779) (xy 41.310224 -15.477612) (xy 41.245641 -15.514899)
			(xy 41.177515 -15.54523) (xy 41.106591 -15.568274) (xy 41.033646 -15.583778) (xy 40.959481 -15.591573)
			(xy 40.922194 -15.592044) (xy 38.922198 -15.592044) (xy 38.88491 -15.591592) (xy 38.810744 -15.583797)
			(xy 38.737798 -15.568291) (xy 38.666873 -15.545246) (xy 38.598745 -15.514913) (xy 38.534161 -15.477626)
			(xy 38.473828 -15.433791) (xy 38.418408 -15.383891) (xy 38.368507 -15.32847) (xy 38.324673 -15.268138)
			(xy 38.287386 -15.203553) (xy 38.257053 -15.135425) (xy 38.234008 -15.0645) (xy 38.218503 -14.991554)
			(xy 38.210708 -14.917388) (xy 0.509016 -14.917388) (xy 0.509016 -17.38737) (xy 4.838435 -17.38737)
			(xy 4.838435 -17.25823) (xy 4.846385 -17.129335) (xy 4.862255 -17.001175) (xy 4.885984 -16.874234)
			(xy 4.917483 -16.748995) (xy 4.956632 -16.625932) (xy 5.003283 -16.505513) (xy 5.057258 -16.388194)
			(xy 5.118353 -16.27442) (xy 5.186336 -16.164623) (xy 5.26095 -16.05922) (xy 5.341911 -15.95861) (xy 5.428911 -15.863175)
			(xy 5.521622 -15.773276) (xy 5.619692 -15.689255) (xy 5.722747 -15.611431) (xy 5.830398 -15.540099)
			(xy 5.942237 -15.475529) (xy 6.057838 -15.417967) (xy 6.176763 -15.36763) (xy 6.298562 -15.32471)
			(xy 6.422772 -15.289369) (xy 6.548921 -15.261742) (xy 6.676533 -15.241933) (xy 6.805122 -15.230017)
			(xy 6.9342 -15.226041) (xy 7.063278 -15.230017) (xy 7.191867 -15.241933) (xy 7.319479 -15.261742)
			(xy 7.445628 -15.289369) (xy 7.569838 -15.32471) (xy 7.691637 -15.36763) (xy 7.810562 -15.417967)
			(xy 7.926163 -15.475529) (xy 8.038002 -15.540099) (xy 8.145653 -15.611431) (xy 8.248708 -15.689255)
			(xy 8.346778 -15.773276) (xy 8.439489 -15.863175) (xy 8.526489 -15.95861) (xy 8.60745 -16.05922)
			(xy 8.682064 -16.164623) (xy 8.750047 -16.27442) (xy 8.811142 -16.388194) (xy 8.865117 -16.505513)
			(xy 8.911768 -16.625932) (xy 8.950917 -16.748995) (xy 8.982416 -16.874234) (xy 8.996233 -16.94815)
			(xy 25.574752 -16.94815) (xy 25.574752 -16.05915) (xy 25.575238 -16.031899) (xy 25.582994 -15.977951)
			(xy 25.598349 -15.925656) (xy 25.620991 -15.876079) (xy 25.650457 -15.830229) (xy 25.686148 -15.789038)
			(xy 25.727339 -15.753347) (xy 25.773189 -15.723881) (xy 25.822766 -15.701239) (xy 25.875061 -15.685884)
			(xy 25.929009 -15.678128) (xy 25.983511 -15.678128) (xy 26.037459 -15.685884) (xy 26.089754 -15.701239)
			(xy 26.139331 -15.723881) (xy 26.185181 -15.753347) (xy 26.226372 -15.789038) (xy 26.262063 -15.830229)
			(xy 26.291529 -15.876079) (xy 26.314171 -15.925656) (xy 26.329526 -15.977951) (xy 26.337282 -16.031899)
			(xy 26.337768 -16.05915) (xy 26.337768 -16.94815) (xy 26.337282 -16.975401) (xy 26.329526 -17.029349)
			(xy 26.314171 -17.081644) (xy 26.291529 -17.131221) (xy 26.262063 -17.177071) (xy 26.226372 -17.218262)
			(xy 26.185181 -17.253953) (xy 26.139331 -17.283419) (xy 26.089754 -17.306061) (xy 26.037459 -17.321416)
			(xy 25.983511 -17.329172) (xy 25.929009 -17.329172) (xy 25.875061 -17.321416) (xy 25.822766 -17.306061)
			(xy 25.773189 -17.283419) (xy 25.727339 -17.253953) (xy 25.686148 -17.218262) (xy 25.650457 -17.177071)
			(xy 25.620991 -17.131221) (xy 25.598349 -17.081644) (xy 25.582994 -17.029349) (xy 25.575238 -16.975401)
			(xy 25.574752 -16.94815) (xy 8.996233 -16.94815) (xy 9.006145 -17.001175) (xy 9.022015 -17.129335)
			(xy 9.029965 -17.25823) (xy 9.030462 -17.3228) (xy 9.029965 -17.38737) (xy 9.022015 -17.516265) (xy 9.006145 -17.644425)
			(xy 8.982416 -17.771366) (xy 8.950917 -17.896605) (xy 8.911768 -18.019668) (xy 8.865117 -18.140087)
			(xy 8.811142 -18.257406) (xy 8.750047 -18.37118) (xy 8.682064 -18.480977) (xy 8.60745 -18.58638)
			(xy 8.526489 -18.68699) (xy 8.439489 -18.782425) (xy 8.346778 -18.872324) (xy 8.248708 -18.956345)
			(xy 8.145653 -19.034169) (xy 8.038002 -19.105501) (xy 7.926163 -19.170071) (xy 7.810562 -19.227633)
			(xy 7.691637 -19.27797) (xy 7.569838 -19.32089) (xy 7.445628 -19.356231) (xy 7.319479 -19.383858)
			(xy 7.191867 -19.403667) (xy 7.063278 -19.415583) (xy 6.9342 -19.41956) (xy 6.805122 -19.415583)
			(xy 6.676533 -19.403667) (xy 6.548921 -19.383858) (xy 6.422772 -19.356231) (xy 6.298562 -19.32089)
			(xy 6.176763 -19.27797) (xy 6.057838 -19.227633) (xy 5.942237 -19.170071) (xy 5.830398 -19.105501)
			(xy 5.722747 -19.034169) (xy 5.619692 -18.956345) (xy 5.521622 -18.872324) (xy 5.428911 -18.782425)
			(xy 5.341911 -18.68699) (xy 5.26095 -18.58638) (xy 5.186336 -18.480977) (xy 5.118353 -18.37118) (xy 5.057258 -18.257406)
			(xy 5.003283 -18.140087) (xy 4.956632 -18.019668) (xy 4.917483 -17.896605) (xy 4.885984 -17.771366)
			(xy 4.862255 -17.644425) (xy 4.846385 -17.516265) (xy 4.838435 -17.38737) (xy 0.509016 -17.38737)
			(xy 0.509016 -24.482675) (xy 40.239076 -24.482675) (xy 40.239076 -24.428125) (xy 40.246839 -24.374131)
			(xy 40.262209 -24.321791) (xy 40.284871 -24.272172) (xy 40.314365 -24.226283) (xy 40.350089 -24.185059)
			(xy 40.391317 -24.149339) (xy 40.437209 -24.119851) (xy 40.486831 -24.097194) (xy 40.539172 -24.08183)
			(xy 40.593167 -24.074073) (xy 40.620442 -24.073612) (xy 41.509442 -24.073612) (xy 41.536708 -24.074153)
			(xy 41.590683 -24.081919) (xy 41.643004 -24.097287) (xy 41.692605 -24.119944) (xy 41.738478 -24.149429)
			(xy 41.779688 -24.185142) (xy 41.815396 -24.226356) (xy 41.844876 -24.272232) (xy 41.867528 -24.321836)
			(xy 41.88289 -24.374158) (xy 41.89065 -24.428134) (xy 41.89065 -24.482666) (xy 41.890649 -24.482675)
			(xy 42.632776 -24.482675) (xy 42.632776 -24.428125) (xy 42.640539 -24.374132) (xy 42.655909 -24.321792)
			(xy 42.67857 -24.272173) (xy 42.708064 -24.226285) (xy 42.743788 -24.185061) (xy 42.785015 -24.149341)
			(xy 42.830907 -24.119852) (xy 42.880528 -24.097195) (xy 42.932869 -24.081831) (xy 42.986863 -24.074073)
			(xy 43.014138 -24.073612) (xy 43.903138 -24.073612) (xy 43.930404 -24.074153) (xy 43.98438 -24.081918)
			(xy 44.036701 -24.097286) (xy 44.086303 -24.119943) (xy 44.132176 -24.149428) (xy 44.173386 -24.185141)
			(xy 44.209095 -24.226354) (xy 44.238575 -24.27223) (xy 44.261227 -24.321835) (xy 44.27659 -24.374158)
			(xy 44.28435 -24.428134) (xy 44.28435 -24.482666) (xy 44.27659 -24.536642) (xy 44.261227 -24.588965)
			(xy 44.238575 -24.63857) (xy 44.209095 -24.684446) (xy 44.173386 -24.725659) (xy 44.132176 -24.761372)
			(xy 44.086303 -24.790857) (xy 44.036701 -24.813514) (xy 43.98438 -24.828882) (xy 43.930404 -24.836647)
			(xy 43.903138 -24.837136) (xy 43.014138 -24.837136) (xy 42.986863 -24.836727) (xy 42.932869 -24.828969)
			(xy 42.880528 -24.813605) (xy 42.830907 -24.790948) (xy 42.785015 -24.761459) (xy 42.743788 -24.725739)
			(xy 42.708064 -24.684515) (xy 42.67857 -24.638627) (xy 42.655909 -24.589008) (xy 42.640539 -24.536668)
			(xy 42.632776 -24.482675) (xy 41.890649 -24.482675) (xy 41.88289 -24.536642) (xy 41.867528 -24.588964)
			(xy 41.844876 -24.638568) (xy 41.815396 -24.684444) (xy 41.779688 -24.725658) (xy 41.738478 -24.761371)
			(xy 41.692605 -24.790856) (xy 41.643004 -24.813513) (xy 41.590683 -24.828881) (xy 41.536708 -24.836647)
			(xy 41.509442 -24.837136) (xy 40.620442 -24.837136) (xy 40.593167 -24.836727) (xy 40.539172 -24.82897)
			(xy 40.486831 -24.813606) (xy 40.437209 -24.790949) (xy 40.391317 -24.761461) (xy 40.350089 -24.725741)
			(xy 40.314365 -24.684517) (xy 40.284871 -24.638628) (xy 40.262209 -24.589009) (xy 40.246839 -24.536669)
			(xy 40.239076 -24.482675) (xy 0.509016 -24.482675) (xy 0.509016 -26.898451) (xy 62.226946 -26.898451)
			(xy 62.226946 -26.843949) (xy 62.234702 -26.790001) (xy 62.250056 -26.737705) (xy 62.272695 -26.688127)
			(xy 62.302159 -26.642275) (xy 62.337849 -26.601083) (xy 62.379037 -26.565388) (xy 62.424885 -26.535918)
			(xy 62.47446 -26.513272) (xy 62.526754 -26.497912) (xy 62.580701 -26.490149) (xy 62.607952 -26.48966)
			(xy 63.496952 -26.48966) (xy 63.524205 -26.490184) (xy 63.578156 -26.497935) (xy 63.630456 -26.513285)
			(xy 63.680038 -26.535923) (xy 63.725893 -26.565387) (xy 63.767088 -26.601078) (xy 63.802784 -26.642269)
			(xy 63.832254 -26.68812) (xy 63.854898 -26.737699) (xy 63.870255 -26.789997) (xy 63.878013 -26.843947)
			(xy 63.878013 -26.898453) (xy 63.870255 -26.952403) (xy 63.863218 -26.976368) (xy 64.442847 -26.976368)
			(xy 64.442847 -26.921832) (xy 64.450609 -26.867852) (xy 64.465973 -26.815525) (xy 64.488628 -26.765918)
			(xy 64.518112 -26.72004) (xy 64.553826 -26.678824) (xy 64.595041 -26.643111) (xy 64.64092 -26.613627)
			(xy 64.690527 -26.590972) (xy 64.742854 -26.575608) (xy 64.796834 -26.567847) (xy 64.824102 -26.567384)
			(xy 65.713102 -26.567384) (xy 65.740375 -26.567779) (xy 65.794364 -26.575542) (xy 65.8467 -26.590909)
			(xy 65.896316 -26.613568) (xy 65.942202 -26.643057) (xy 65.983424 -26.678777) (xy 66.019144 -26.72)
			(xy 66.048633 -26.765886) (xy 66.071292 -26.815502) (xy 66.086659 -26.867838) (xy 66.094421 -26.921827)
			(xy 66.094421 -26.976373) (xy 66.086659 -27.030362) (xy 66.071292 -27.082698) (xy 66.048633 -27.132314)
			(xy 66.019144 -27.1782) (xy 65.983424 -27.219423) (xy 65.942202 -27.255143) (xy 65.896316 -27.284632)
			(xy 65.8467 -27.307291) (xy 65.794364 -27.322658) (xy 65.740375 -27.330421) (xy 65.713102 -27.330908)
			(xy 64.824102 -27.330908) (xy 64.796834 -27.330353) (xy 64.742854 -27.322592) (xy 64.690527 -27.307228)
			(xy 64.64092 -27.284573) (xy 64.595041 -27.255089) (xy 64.553826 -27.219376) (xy 64.518112 -27.17816)
			(xy 64.488628 -27.132282) (xy 64.465973 -27.082675) (xy 64.450609 -27.030348) (xy 64.442847 -26.976368)
			(xy 63.863218 -26.976368) (xy 63.854898 -27.004701) (xy 63.832254 -27.05428) (xy 63.802784 -27.100131)
			(xy 63.767088 -27.141322) (xy 63.725893 -27.177013) (xy 63.680038 -27.206477) (xy 63.630456 -27.229115)
			(xy 63.578156 -27.244465) (xy 63.524205 -27.252216) (xy 63.496952 -27.252676) (xy 62.607952 -27.252676)
			(xy 62.580701 -27.252251) (xy 62.526754 -27.244488) (xy 62.47446 -27.229128) (xy 62.424885 -27.206482)
			(xy 62.379037 -27.177012) (xy 62.337849 -27.141317) (xy 62.302159 -27.100125) (xy 62.272695 -27.054273)
			(xy 62.250056 -27.004695) (xy 62.234702 -26.952399) (xy 62.226946 -26.898451) (xy 0.509016 -26.898451)
			(xy 0.509016 -48.189134) (xy 23.749 -48.189134) (xy 23.749 -46.588934) (xy 23.749498 -46.511651)
			(xy 23.757454 -46.357291) (xy 23.773347 -46.203545) (xy 23.797133 -46.050821) (xy 23.82875 -45.899525)
			(xy 23.868113 -45.750056) (xy 23.915118 -45.602812) (xy 23.969642 -45.458182) (xy 24.031538 -45.316552)
			(xy 24.100643 -45.178295) (xy 24.176774 -45.04378) (xy 24.259728 -44.913361) (xy 24.349287 -44.787386)
			(xy 24.445211 -44.666189) (xy 24.547248 -44.55009) (xy 24.655125 -44.439398) (xy 24.768558 -44.334406)
			(xy 24.887246 -44.235393) (xy 25.010873 -44.14262) (xy 25.139112 -44.056335) (xy 25.271623 -43.976766)
			(xy 25.408055 -43.904124) (xy 25.548045 -43.838602) (xy 25.691222 -43.780373) (xy 25.837207 -43.729592)
			(xy 25.985613 -43.686393) (xy 26.136045 -43.650891) (xy 26.288106 -43.623181) (xy 26.441392 -43.603335)
			(xy 26.595496 -43.591406) (xy 26.75001 -43.587427) (xy 26.904524 -43.591406) (xy 27.058628 -43.603335)
			(xy 27.211914 -43.623181) (xy 27.363975 -43.650891) (xy 27.514407 -43.686393) (xy 27.662813 -43.729592)
			(xy 27.808798 -43.780373) (xy 27.951975 -43.838602) (xy 28.091965 -43.904124) (xy 28.228397 -43.976766)
			(xy 28.360908 -44.056335) (xy 28.489147 -44.14262) (xy 28.612774 -44.235393) (xy 28.731462 -44.334406)
			(xy 28.844895 -44.439398) (xy 28.952772 -44.55009) (xy 29.054809 -44.666189) (xy 29.150733 -44.787386)
			(xy 29.240292 -44.913361) (xy 29.252254 -44.932168) (xy 66.731138 -44.932168) (xy 66.731138 -44.877632)
			(xy 66.738899 -44.823652) (xy 66.754264 -44.771325) (xy 66.776918 -44.721717) (xy 66.806402 -44.675839)
			(xy 66.842114 -44.634623) (xy 66.883329 -44.598909) (xy 66.929207 -44.569424) (xy 66.978814 -44.546768)
			(xy 67.03114 -44.531402) (xy 67.08512 -44.523639) (xy 67.112388 -44.523152) (xy 68.001388 -44.523152)
			(xy 68.028661 -44.523587) (xy 68.082651 -44.531348) (xy 68.134987 -44.546714) (xy 68.184603 -44.569371)
			(xy 68.23049 -44.59886) (xy 68.271713 -44.634578) (xy 68.307433 -44.6758) (xy 68.336923 -44.721686)
			(xy 68.359582 -44.771302) (xy 68.37495 -44.823638) (xy 68.382712 -44.877627) (xy 68.382712 -44.932173)
			(xy 68.37495 -44.986162) (xy 68.359582 -45.038498) (xy 68.336923 -45.088114) (xy 68.307433 -45.134)
			(xy 68.271713 -45.175222) (xy 68.23049 -45.21094) (xy 68.184603 -45.240429) (xy 68.134987 -45.263086)
			(xy 68.082651 -45.278452) (xy 68.028661 -45.286213) (xy 68.001388 -45.286676) (xy 67.112388 -45.286676)
			(xy 67.08512 -45.286161) (xy 67.03114 -45.278398) (xy 66.978814 -45.263032) (xy 66.929207 -45.240376)
			(xy 66.883329 -45.210891) (xy 66.842114 -45.175177) (xy 66.806402 -45.133961) (xy 66.776918 -45.088083)
			(xy 66.754264 -45.038475) (xy 66.738899 -44.986148) (xy 66.731138 -44.932168) (xy 29.252254 -44.932168)
			(xy 29.323246 -45.04378) (xy 29.399377 -45.178295) (xy 29.468482 -45.316552) (xy 29.530378 -45.458182)
			(xy 29.584902 -45.602812) (xy 29.631907 -45.750056) (xy 29.67127 -45.899525) (xy 29.702887 -46.050821)
			(xy 29.726673 -46.203545) (xy 29.742566 -46.357291) (xy 29.750522 -46.511651) (xy 29.75102 -46.588934)
			(xy 29.75102 -48.189134) (xy 29.750522 -48.266417) (xy 29.742566 -48.420777) (xy 29.726673 -48.574523)
			(xy 29.702887 -48.727247) (xy 29.67127 -48.878543) (xy 29.631907 -49.028012) (xy 29.584902 -49.175256)
			(xy 29.530378 -49.319886) (xy 29.468482 -49.461516) (xy 29.399377 -49.599773) (xy 29.323246 -49.734288)
			(xy 29.240292 -49.864707) (xy 29.150733 -49.990682) (xy 29.054809 -50.111879) (xy 28.952772 -50.227978)
			(xy 28.844895 -50.33867) (xy 28.731462 -50.443662) (xy 28.612774 -50.542675) (xy 28.489147 -50.635448)
			(xy 28.360908 -50.721733) (xy 28.228397 -50.801302) (xy 28.091965 -50.873944) (xy 27.951975 -50.939466)
			(xy 27.808798 -50.997695) (xy 27.662813 -51.048476) (xy 27.514407 -51.091675) (xy 27.363975 -51.127177)
			(xy 27.211914 -51.154887) (xy 27.058628 -51.174733) (xy 26.904524 -51.186662) (xy 26.75001 -51.190642)
			(xy 26.595496 -51.186662) (xy 26.441392 -51.174733) (xy 26.288106 -51.154887) (xy 26.136045 -51.127177)
			(xy 25.985613 -51.091675) (xy 25.837207 -51.048476) (xy 25.691222 -50.997695) (xy 25.548045 -50.939466)
			(xy 25.408055 -50.873944) (xy 25.271623 -50.801302) (xy 25.139112 -50.721733) (xy 25.010873 -50.635448)
			(xy 24.887246 -50.542675) (xy 24.768558 -50.443662) (xy 24.655125 -50.33867) (xy 24.547248 -50.227978)
			(xy 24.445211 -50.111879) (xy 24.349287 -49.990682) (xy 24.259728 -49.864707) (xy 24.176774 -49.734288)
			(xy 24.100643 -49.599773) (xy 24.031538 -49.461516) (xy 23.969642 -49.319886) (xy 23.915118 -49.175256)
			(xy 23.868113 -49.028012) (xy 23.82875 -48.878543) (xy 23.797133 -48.727247) (xy 23.773347 -48.574523)
			(xy 23.757454 -48.420777) (xy 23.749498 -48.266417) (xy 23.749 -48.189134) (xy 0.509016 -48.189134)
			(xy 0.509016 -52.67175) (xy 66.314303 -52.67175) (xy 66.314303 -52.61725) (xy 66.32206 -52.563304)
			(xy 66.337415 -52.511011) (xy 66.360056 -52.461436) (xy 66.389522 -52.415587) (xy 66.425214 -52.374399)
			(xy 66.466403 -52.33871) (xy 66.512253 -52.309246) (xy 66.56183 -52.286608) (xy 66.614123 -52.271256)
			(xy 66.66807 -52.263502) (xy 66.69532 -52.26304) (xy 67.58432 -52.26304) (xy 67.611574 -52.263431)
			(xy 67.665526 -52.271191) (xy 67.717825 -52.28655) (xy 67.767406 -52.309195) (xy 67.81326 -52.338666)
			(xy 67.854453 -52.374362) (xy 67.890146 -52.415556) (xy 67.919615 -52.461412) (xy 67.942257 -52.510994)
			(xy 67.957613 -52.563293) (xy 67.96537 -52.617246) (xy 67.96537 -52.671754) (xy 67.957613 -52.725707)
			(xy 67.942257 -52.778006) (xy 67.919615 -52.827588) (xy 67.890146 -52.873444) (xy 67.854453 -52.914638)
			(xy 67.81326 -52.950334) (xy 67.767406 -52.979805) (xy 67.717825 -53.00245) (xy 67.665526 -53.017809)
			(xy 67.611574 -53.025569) (xy 67.58432 -53.026056) (xy 66.69532 -53.026056) (xy 66.66807 -53.025498)
			(xy 66.614123 -53.017744) (xy 66.56183 -53.002392) (xy 66.512253 -52.979754) (xy 66.466403 -52.95029)
			(xy 66.425214 -52.914601) (xy 66.389522 -52.873413) (xy 66.360056 -52.827564) (xy 66.337415 -52.777989)
			(xy 66.32206 -52.725696) (xy 66.314303 -52.67175) (xy 0.509016 -52.67175) (xy 0.509016 -54.53387)
			(xy 66.568023 -54.53387) (xy 66.568023 -54.47933) (xy 66.575786 -54.425344) (xy 66.591152 -54.373013)
			(xy 66.61381 -54.323401) (xy 66.643298 -54.277519) (xy 66.679015 -54.236301) (xy 66.720235 -54.200586)
			(xy 66.766119 -54.1711) (xy 66.815732 -54.148445) (xy 66.868064 -54.133081) (xy 66.92205 -54.125322)
			(xy 66.94932 -54.12486) (xy 67.83832 -54.12486) (xy 67.86559 -54.125304) (xy 67.919575 -54.133068)
			(xy 67.971905 -54.148436) (xy 68.021515 -54.171095) (xy 68.067396 -54.200583) (xy 68.108614 -54.2363)
			(xy 68.144329 -54.27752) (xy 68.173815 -54.323402) (xy 68.196471 -54.373014) (xy 68.211836 -54.425345)
			(xy 68.219598 -54.47933) (xy 68.219598 -54.53387) (xy 68.211836 -54.587855) (xy 68.196471 -54.640186)
			(xy 68.173815 -54.689798) (xy 68.144329 -54.73568) (xy 68.108614 -54.7769) (xy 68.067396 -54.812617)
			(xy 68.021515 -54.842105) (xy 67.971905 -54.864764) (xy 67.919575 -54.880132) (xy 67.86559 -54.887896)
			(xy 67.83832 -54.888384) (xy 66.94932 -54.888384) (xy 66.92205 -54.887878) (xy 66.868064 -54.880119)
			(xy 66.815732 -54.864755) (xy 66.766119 -54.8421) (xy 66.720235 -54.812614) (xy 66.679015 -54.776899)
			(xy 66.643298 -54.735681) (xy 66.61381 -54.689799) (xy 66.591152 -54.640187) (xy 66.575786 -54.587856)
			(xy 66.568023 -54.53387) (xy 0.509016 -54.53387) (xy 0.509016 -58.166508) (xy 60.959492 -58.166508)
			(xy 60.959492 -57.366662) (xy 60.959966 -57.340674) (xy 60.968103 -57.289338) (xy 60.984169 -57.239907)
			(xy 61.007769 -57.193597) (xy 61.038323 -57.15155) (xy 61.075078 -57.114799) (xy 61.11713 -57.08425)
			(xy 61.163442 -57.060654) (xy 61.212875 -57.044594) (xy 61.264212 -57.036464) (xy 61.2902 -57.035954)
			(xy 61.317668 -57.036479) (xy 61.371851 -57.04555) (xy 61.423791 -57.063444) (xy 61.472065 -57.089668)
			(xy 61.515345 -57.123503) (xy 61.534294 -57.143396) (xy 61.55212 -57.162087) (xy 61.582322 -57.203984)
			(xy 61.605643 -57.250068) (xy 61.621515 -57.299217) (xy 61.629551 -57.350236) (xy 61.630052 -57.37606)
			(xy 61.629773 -57.39555) (xy 61.625189 -57.43426) (xy 61.620908 -57.453276) (xy 61.620908 -58.166508)
			(xy 61.620398 -58.192491) (xy 63.359983 -58.192491) (xy 63.359983 -58.140509) (xy 63.368116 -58.089167)
			(xy 63.38418 -58.03973) (xy 63.407782 -57.993415) (xy 63.438338 -57.951362) (xy 63.475097 -57.914608)
			(xy 63.517154 -57.884058) (xy 63.563473 -57.860463) (xy 63.612912 -57.844405) (xy 63.664255 -57.83628)
			(xy 63.690246 -57.8358) (xy 64.490092 -57.8358) (xy 64.516082 -57.836267) (xy 64.567423 -57.844397)
			(xy 64.61686 -57.860459) (xy 64.663175 -57.884057) (xy 64.705229 -57.91461) (xy 64.741985 -57.951365)
			(xy 64.772539 -57.993418) (xy 64.796138 -58.039733) (xy 64.812201 -58.089169) (xy 64.820333 -58.14051)
			(xy 64.820333 -58.19249) (xy 64.812201 -58.243831) (xy 64.796138 -58.293267) (xy 64.772539 -58.339582)
			(xy 64.741985 -58.381635) (xy 64.705229 -58.41839) (xy 64.663175 -58.448943) (xy 64.61686 -58.472541)
			(xy 64.567423 -58.488603) (xy 64.516082 -58.496733) (xy 64.490092 -58.497216) (xy 63.690246 -58.497216)
			(xy 63.664255 -58.49672) (xy 63.612912 -58.488595) (xy 63.563473 -58.472537) (xy 63.517154 -58.448942)
			(xy 63.475097 -58.418392) (xy 63.438338 -58.381638) (xy 63.407782 -58.339585) (xy 63.38418 -58.29327)
			(xy 63.368116 -58.243833) (xy 63.359983 -58.192491) (xy 61.620398 -58.192491) (xy 61.620398 -58.192495)
			(xy 61.612268 -58.24383) (xy 61.596207 -58.29326) (xy 61.572611 -58.33957) (xy 61.542061 -58.381618)
			(xy 61.50531 -58.418369) (xy 61.463262 -58.448919) (xy 61.416952 -58.472515) (xy 61.367522 -58.488576)
			(xy 61.316187 -58.496706) (xy 61.264213 -58.496706) (xy 61.212878 -58.488576) (xy 61.163448 -58.472515)
			(xy 61.117138 -58.448919) (xy 61.07509 -58.418369) (xy 61.038339 -58.381618) (xy 61.007789 -58.33957)
			(xy 60.984193 -58.29326) (xy 60.968132 -58.24383) (xy 60.960002 -58.192495) (xy 60.959492 -58.166508)
			(xy 0.509016 -58.166508) (xy 0.509016 -58.992411) (xy 61.759802 -58.992411) (xy 61.759802 -58.940389)
			(xy 61.76794 -58.889008) (xy 61.784015 -58.839533) (xy 61.807633 -58.793181) (xy 61.83821 -58.751095)
			(xy 61.874995 -58.71431) (xy 61.917081 -58.683733) (xy 61.963433 -58.660115) (xy 62.012908 -58.64404)
			(xy 62.064289 -58.635902) (xy 62.0903 -58.635392) (xy 62.890146 -58.635392) (xy 62.916147 -58.635998)
			(xy 62.967508 -58.644139) (xy 63.016964 -58.660214) (xy 63.063296 -58.683827) (xy 63.105364 -58.714397)
			(xy 63.142133 -58.751171) (xy 63.172697 -58.793243) (xy 63.196303 -58.839579) (xy 63.212372 -58.889036)
			(xy 63.220506 -58.940399) (xy 63.220506 -58.992401) (xy 63.220505 -58.99241) (xy 64.159602 -58.99241)
			(xy 64.159602 -58.94039) (xy 64.16774 -58.889009) (xy 64.183815 -58.839535) (xy 64.207431 -58.793184)
			(xy 64.238008 -58.751098) (xy 64.274792 -58.714313) (xy 64.316877 -58.683735) (xy 64.363227 -58.660118)
			(xy 64.412702 -58.644042) (xy 64.464082 -58.635903) (xy 64.490092 -58.635392) (xy 65.289938 -58.635392)
			(xy 65.31594 -58.635997) (xy 65.367302 -58.644137) (xy 65.416758 -58.660212) (xy 65.463091 -58.683825)
			(xy 65.505161 -58.714394) (xy 65.541931 -58.751168) (xy 65.572495 -58.793241) (xy 65.596103 -58.839577)
			(xy 65.612171 -58.889035) (xy 65.620306 -58.940398) (xy 65.620306 -58.992402) (xy 65.612171 -59.043765)
			(xy 65.596103 -59.093223) (xy 65.572495 -59.139559) (xy 65.541931 -59.181632) (xy 65.505161 -59.218406)
			(xy 65.463091 -59.248975) (xy 65.416758 -59.272588) (xy 65.367302 -59.288663) (xy 65.31594 -59.296803)
			(xy 65.289938 -59.297316) (xy 64.490092 -59.297316) (xy 64.464082 -59.296897) (xy 64.412702 -59.288758)
			(xy 64.363227 -59.272682) (xy 64.316877 -59.249065) (xy 64.274792 -59.218487) (xy 64.238008 -59.181702)
			(xy 64.207431 -59.139616) (xy 64.183815 -59.093265) (xy 64.16774 -59.043791) (xy 64.159602 -58.99241)
			(xy 63.220505 -58.99241) (xy 63.212372 -59.043763) (xy 63.196303 -59.093221) (xy 63.172697 -59.139557)
			(xy 63.142133 -59.181629) (xy 63.105364 -59.218403) (xy 63.063296 -59.248973) (xy 63.016964 -59.272586)
			(xy 62.967508 -59.288661) (xy 62.916147 -59.296802) (xy 62.890146 -59.297316) (xy 62.0903 -59.297316)
			(xy 62.064289 -59.296898) (xy 62.012908 -59.28876) (xy 61.963433 -59.272685) (xy 61.917081 -59.249067)
			(xy 61.874995 -59.21849) (xy 61.83821 -59.181705) (xy 61.807633 -59.139619) (xy 61.784015 -59.093267)
			(xy 61.76794 -59.043792) (xy 61.759802 -58.992411) (xy 0.509016 -58.992411) (xy 0.509016 -59.792515)
			(xy 63.359676 -59.792515) (xy 63.359676 -59.740485) (xy 63.367816 -59.689095) (xy 63.383895 -59.639612)
			(xy 63.407519 -59.593254) (xy 63.438104 -59.551162) (xy 63.474897 -59.514374) (xy 63.516993 -59.483794)
			(xy 63.563355 -59.460178) (xy 63.61284 -59.444105) (xy 63.664231 -59.435972) (xy 63.690246 -59.435492)
			(xy 64.490092 -59.435492) (xy 64.516098 -59.436067) (xy 64.56747 -59.444202) (xy 64.616937 -59.460274)
			(xy 64.66328 -59.483886) (xy 64.705359 -59.514457) (xy 64.742138 -59.551235) (xy 64.77271 -59.593313)
			(xy 64.796323 -59.639656) (xy 64.812396 -59.689122) (xy 64.820533 -59.740494) (xy 64.820533 -59.792506)
			(xy 64.812396 -59.843878) (xy 64.796323 -59.893344) (xy 64.77271 -59.939687) (xy 64.742138 -59.981765)
			(xy 64.705359 -60.018543) (xy 64.66328 -60.049114) (xy 64.616937 -60.072726) (xy 64.56747 -60.088798)
			(xy 64.516098 -60.096933) (xy 64.490092 -60.097416) (xy 63.690246 -60.097416) (xy 63.664231 -60.097028)
			(xy 63.61284 -60.088895) (xy 63.563355 -60.072822) (xy 63.516993 -60.049206) (xy 63.474897 -60.018626)
			(xy 63.438104 -59.981838) (xy 63.407519 -59.939746) (xy 63.383895 -59.893388) (xy 63.367816 -59.843905)
			(xy 63.359676 -59.792515) (xy 0.509016 -59.792515) (xy 0.509016 -60.3494) (xy 60.569868 -60.3494)
			(xy 60.573857 -60.296174) (xy 60.585733 -60.244137) (xy 60.605233 -60.194451) (xy 60.631919 -60.148227)
			(xy 60.665197 -60.106496) (xy 60.704323 -60.07019) (xy 60.748422 -60.040121) (xy 60.796511 -60.016961)
			(xy 60.847514 -60.001226) (xy 60.900292 -59.993268) (xy 60.92698 -59.992768) (xy 60.949767 -59.993141)
			(xy 60.994967 -59.998968) (xy 61.03906 -60.010491) (xy 61.06033 -60.018676) (xy 61.555376 -60.018676)
			(xy 61.564012 -60.015374) (xy 61.594178 -60.00485) (xy 61.657039 -59.993478) (xy 61.68898 -59.992768)
			(xy 61.717333 -59.993267) (xy 61.773326 -60.002234) (xy 61.827196 -60.019945) (xy 61.877586 -60.045954)
			(xy 61.923227 -60.079606) (xy 61.943488 -60.099448) (xy 61.962622 -60.116719) (xy 61.995857 -60.156112)
			(xy 62.022581 -60.200183) (xy 62.042146 -60.247865) (xy 62.054078 -60.298005) (xy 62.058089 -60.34939)
			(xy 62.054081 -60.400774) (xy 62.042152 -60.450915) (xy 62.022591 -60.498599) (xy 61.99587 -60.542671)
			(xy 61.962636 -60.582066) (xy 61.943488 -60.59932) (xy 61.923242 -60.619175) (xy 61.877589 -60.652806)
			(xy 61.827194 -60.678797) (xy 61.773323 -60.696496) (xy 61.717332 -60.705456) (xy 61.68898 -60.706)
			(xy 61.657039 -60.705289) (xy 61.594177 -60.693921) (xy 61.564012 -60.683394) (xy 61.555376 -60.680092)
			(xy 61.06033 -60.680092) (xy 61.039069 -60.688303) (xy 60.994975 -60.699837) (xy 60.949769 -60.705644)
			(xy 60.92698 -60.706) (xy 60.900292 -60.705532) (xy 60.847514 -60.697574) (xy 60.796511 -60.681839)
			(xy 60.748422 -60.658679) (xy 60.704323 -60.62861) (xy 60.665197 -60.592304) (xy 60.631919 -60.550573)
			(xy 60.605233 -60.504349) (xy 60.585733 -60.454663) (xy 60.573857 -60.402626) (xy 60.569868 -60.3494)
			(xy 0.509016 -60.3494) (xy 0.509016 -61.539628) (xy 0.508 -61.540644) (xy 0.508 -62.988444) (xy 0.509016 -62.98946)
			(xy 0.509016 -75.635104) (xy 15.732516 -75.635104) (xy 15.736498 -75.545176) (xy 15.748412 -75.455952)
			(xy 15.768165 -75.36813) (xy 15.795602 -75.282397) (xy 15.830509 -75.199425) (xy 15.872613 -75.119862)
			(xy 15.921583 -75.044332) (xy 15.977038 -74.973426) (xy 16.038542 -74.907698) (xy 16.105614 -74.847663)
			(xy 16.17773 -74.793791) (xy 16.254325 -74.746503) (xy 16.334799 -74.70617) (xy 16.418523 -74.673107)
			(xy 16.504842 -74.647573) (xy 16.59308 -74.629768) (xy 16.682545 -74.61983) (xy 16.77254 -74.617839)
			(xy 16.862357 -74.623809) (xy 16.951296 -74.637694) (xy 17.03866 -74.659385) (xy 17.123765 -74.688712)
			(xy 17.205944 -74.725446) (xy 17.284556 -74.7693) (xy 17.358984 -74.819929) (xy 17.428646 -74.876939)
			(xy 17.492997 -74.939882) (xy 17.551534 -75.008266) (xy 17.603797 -75.081556) (xy 17.649379 -75.159178)
			(xy 17.687922 -75.240525) (xy 17.719125 -75.32496) (xy 17.742743 -75.411822) (xy 17.758592 -75.500432)
			(xy 17.766548 -75.590096) (xy 17.767046 -75.635104) (xy 35.491176 -75.635104) (xy 35.495155 -75.535091)
			(xy 35.507068 -75.43571) (xy 35.526839 -75.33759) (xy 35.554343 -75.241351) (xy 35.589406 -75.147602)
			(xy 35.631807 -75.056934) (xy 35.681278 -74.969922) (xy 35.737505 -74.887115) (xy 35.800133 -74.809038)
			(xy 35.868767 -74.736183) (xy 35.942972 -74.669011) (xy 36.02228 -74.607948) (xy 36.106188 -74.553378)
			(xy 36.194166 -74.505647) (xy 36.285659 -74.465057) (xy 36.380087 -74.431865) (xy 36.476854 -74.40628)
			(xy 36.575348 -74.388463) (xy 36.674946 -74.378529) (xy 36.775018 -74.376539) (xy 36.874932 -74.382506)
			(xy 36.974056 -74.396392) (xy 37.071764 -74.41811) (xy 37.167437 -74.447522) (xy 37.260471 -74.484443)
			(xy 37.350277 -74.528638) (xy 37.436289 -74.579828) (xy 37.517961 -74.637691) (xy 37.594778 -74.701859)
			(xy 37.666254 -74.771928) (xy 37.731937 -74.847454) (xy 37.791412 -74.92796) (xy 37.844303 -75.012936)
			(xy 37.890275 -75.101846) (xy 37.929037 -75.194128) (xy 37.960346 -75.289197) (xy 37.984002 -75.386454)
			(xy 37.999856 -75.485282) (xy 38.007809 -75.585058) (xy 38.008306 -75.635104) (xy 38.007809 -75.68515)
			(xy 37.999856 -75.784926) (xy 37.984002 -75.883754) (xy 37.960346 -75.981011) (xy 37.929037 -76.07608)
			(xy 37.890275 -76.168362) (xy 37.844303 -76.257272) (xy 37.791412 -76.342248) (xy 37.731937 -76.422754)
			(xy 37.666254 -76.49828) (xy 37.594778 -76.568349) (xy 37.517961 -76.632517) (xy 37.436289 -76.69038)
			(xy 37.350277 -76.74157) (xy 37.260471 -76.785765) (xy 37.167437 -76.822686) (xy 37.071764 -76.852098)
			(xy 36.974056 -76.873816) (xy 36.874932 -76.887702) (xy 36.775018 -76.893669) (xy 36.674946 -76.891679)
			(xy 36.575348 -76.881745) (xy 36.476854 -76.863928) (xy 36.380087 -76.838343) (xy 36.285659 -76.805151)
			(xy 36.194166 -76.764561) (xy 36.106188 -76.71683) (xy 36.02228 -76.66226) (xy 35.942972 -76.601197)
			(xy 35.868767 -76.534025) (xy 35.800133 -76.46117) (xy 35.737505 -76.383093) (xy 35.681278 -76.300286)
			(xy 35.631807 -76.213274) (xy 35.589406 -76.122606) (xy 35.554343 -76.028857) (xy 35.526839 -75.932618)
			(xy 35.507068 -75.834498) (xy 35.495155 -75.735117) (xy 35.491176 -75.635104) (xy 17.767046 -75.635104)
			(xy 17.766548 -75.680112) (xy 17.758592 -75.769776) (xy 17.742743 -75.858386) (xy 17.719125 -75.945248)
			(xy 17.687922 -76.029683) (xy 17.649379 -76.11103) (xy 17.603797 -76.188652) (xy 17.551534 -76.261942)
			(xy 17.492997 -76.330326) (xy 17.428646 -76.393269) (xy 17.358984 -76.450279) (xy 17.284556 -76.500908)
			(xy 17.205944 -76.544762) (xy 17.123765 -76.581496) (xy 17.03866 -76.610823) (xy 16.951296 -76.632514)
			(xy 16.862357 -76.646399) (xy 16.77254 -76.652369) (xy 16.682545 -76.650378) (xy 16.59308 -76.64044)
			(xy 16.504842 -76.622635) (xy 16.418523 -76.597101) (xy 16.334799 -76.564038) (xy 16.254325 -76.523705)
			(xy 16.17773 -76.476417) (xy 16.105614 -76.422545) (xy 16.038542 -76.36251) (xy 15.977038 -76.296782)
			(xy 15.921583 -76.225876) (xy 15.872613 -76.150346) (xy 15.830509 -76.070783) (xy 15.795602 -75.987811)
			(xy 15.768165 -75.902078) (xy 15.748412 -75.814256) (xy 15.736498 -75.725032) (xy 15.732516 -75.635104)
			(xy 0.509016 -75.635104) (xy 0.509016 -80.990948) (xy 2.249932 -80.990948) (xy 2.293971 -80.991429)
			(xy 2.381714 -80.999105) (xy 2.468454 -81.0144) (xy 2.553531 -81.037196) (xy 2.636297 -81.067321)
			(xy 2.716123 -81.104545) (xy 2.792401 -81.148584) (xy 2.86455 -81.199103) (xy 2.932022 -81.255719)
			(xy 2.994302 -81.318) (xy 3.050918 -81.385471) (xy 3.101437 -81.457621) (xy 3.145476 -81.533899)
			(xy 3.1827 -81.613725) (xy 3.212824 -81.696491) (xy 3.23562 -81.781568) (xy 3.250915 -81.868308)
			(xy 3.258592 -81.956051) (xy 3.259074 -82.00009) (xy 3.259074 -84.499958) (xy 3.258594 -84.543997)
			(xy 3.250917 -84.63174) (xy 3.235623 -84.718481) (xy 3.212827 -84.803558) (xy 3.182702 -84.886325)
			(xy 3.145479 -84.966151) (xy 3.10144 -85.042429) (xy 3.05092 -85.114579) (xy 2.994305 -85.182051)
			(xy 2.932024 -85.244332) (xy 2.864552 -85.300948) (xy 2.792403 -85.351468) (xy 2.716124 -85.395507)
			(xy 2.636298 -85.432731) (xy 2.553532 -85.462855) (xy 2.468455 -85.485652) (xy 2.381714 -85.500947)
			(xy 2.293971 -85.508623) (xy 2.249932 -85.5091) (xy 0.509016 -85.5091) (xy 0.509016 -97.978249) (xy 45.046914 -97.978249)
			(xy 45.046914 -97.923751) (xy 45.05467 -97.869809) (xy 45.070024 -97.817519) (xy 45.092663 -97.767947)
			(xy 45.122126 -97.722101) (xy 45.157814 -97.680914) (xy 45.199001 -97.645226) (xy 45.244847 -97.615763)
			(xy 45.294419 -97.593124) (xy 45.346709 -97.57777) (xy 45.400651 -97.570014) (xy 45.4279 -97.569528)
			(xy 46.3169 -97.569528) (xy 46.344154 -97.569942) (xy 46.398107 -97.577699) (xy 46.450406 -97.593056)
			(xy 46.499988 -97.615699) (xy 46.545843 -97.645168) (xy 46.587037 -97.680863) (xy 46.622732 -97.722057)
			(xy 46.652201 -97.767912) (xy 46.674844 -97.817494) (xy 46.690201 -97.869793) (xy 46.697958 -97.923746)
			(xy 46.697958 -97.978254) (xy 46.690201 -98.032207) (xy 46.674844 -98.084506) (xy 46.652201 -98.134088)
			(xy 46.622732 -98.179943) (xy 46.587037 -98.221137) (xy 46.545843 -98.256832) (xy 46.499988 -98.286301)
			(xy 46.450406 -98.308944) (xy 46.398107 -98.324301) (xy 46.344154 -98.332058) (xy 46.3169 -98.332544)
			(xy 45.4279 -98.332544) (xy 45.400651 -98.331986) (xy 45.346709 -98.32423) (xy 45.294419 -98.308876)
			(xy 45.244847 -98.286237) (xy 45.199001 -98.256774) (xy 45.157814 -98.221086) (xy 45.122126 -98.179899)
			(xy 45.092663 -98.134053) (xy 45.070024 -98.084481) (xy 45.05467 -98.032191) (xy 45.046914 -97.978249)
			(xy 0.509016 -97.978249) (xy 0.509016 -98.410049) (xy 40.017714 -98.410049) (xy 40.017714 -98.355551)
			(xy 40.02547 -98.301609) (xy 40.040824 -98.249319) (xy 40.063463 -98.199747) (xy 40.092926 -98.153901)
			(xy 40.128614 -98.112714) (xy 40.169801 -98.077026) (xy 40.215647 -98.047563) (xy 40.265219 -98.024924)
			(xy 40.317509 -98.00957) (xy 40.371451 -98.001814) (xy 40.3987 -98.001328) (xy 41.2877 -98.001328)
			(xy 41.314954 -98.001742) (xy 41.368907 -98.009499) (xy 41.421206 -98.024856) (xy 41.470788 -98.047499)
			(xy 41.516643 -98.076968) (xy 41.557837 -98.112663) (xy 41.593532 -98.153857) (xy 41.623001 -98.199712)
			(xy 41.645644 -98.249294) (xy 41.661001 -98.301593) (xy 41.668758 -98.355546) (xy 41.668758 -98.410054)
			(xy 41.661001 -98.464007) (xy 41.645644 -98.516306) (xy 41.623001 -98.565888) (xy 41.593532 -98.611743)
			(xy 41.557837 -98.652937) (xy 41.516643 -98.688632) (xy 41.470788 -98.718101) (xy 41.421206 -98.740744)
			(xy 41.368907 -98.756101) (xy 41.314954 -98.763858) (xy 41.2877 -98.764344) (xy 40.3987 -98.764344)
			(xy 40.371451 -98.763786) (xy 40.317509 -98.75603) (xy 40.265219 -98.740676) (xy 40.215647 -98.718037)
			(xy 40.169801 -98.688574) (xy 40.128614 -98.652886) (xy 40.092926 -98.611699) (xy 40.063463 -98.565853)
			(xy 40.040824 -98.516281) (xy 40.02547 -98.463991) (xy 40.017714 -98.410049) (xy 0.509016 -98.410049)
			(xy 0.509016 -104.205349) (xy 54.921178 -104.205349) (xy 54.921178 -104.150851) (xy 54.928933 -104.096908)
			(xy 54.944285 -104.044617) (xy 54.966923 -103.995043) (xy 54.996385 -103.949195) (xy 55.032071 -103.908006)
			(xy 55.073255 -103.872315) (xy 55.119099 -103.842847) (xy 55.16867 -103.820203) (xy 55.220959 -103.804843)
			(xy 55.274901 -103.797081) (xy 55.30215 -103.796592) (xy 56.19115 -103.796592) (xy 56.218405 -103.797052)
			(xy 56.272362 -103.804803) (xy 56.324665 -103.820155) (xy 56.374252 -103.842794) (xy 56.420111 -103.872261)
			(xy 56.46131 -103.907955) (xy 56.497009 -103.949149) (xy 56.526482 -103.995004) (xy 56.549128 -104.044588)
			(xy 56.564486 -104.09689) (xy 56.572245 -104.150845) (xy 56.572245 -104.205355) (xy 56.564486 -104.25931)
			(xy 56.549128 -104.311612) (xy 56.526482 -104.361196) (xy 56.497009 -104.407051) (xy 56.46131 -104.448245)
			(xy 56.420111 -104.483939) (xy 56.374252 -104.513406) (xy 56.324665 -104.536045) (xy 56.272362 -104.551397)
			(xy 56.218405 -104.559148) (xy 56.19115 -104.559608) (xy 55.30215 -104.559608) (xy 55.274901 -104.559119)
			(xy 55.220959 -104.551357) (xy 55.16867 -104.535997) (xy 55.119099 -104.513353) (xy 55.073255 -104.483885)
			(xy 55.032071 -104.448194) (xy 54.996385 -104.407005) (xy 54.966923 -104.361157) (xy 54.944285 -104.311583)
			(xy 54.928933 -104.259292) (xy 54.921178 -104.205349) (xy 0.509016 -104.205349) (xy 0.509016 -107.774051)
			(xy 13.017478 -107.774051) (xy 13.017478 -107.719549) (xy 13.025234 -107.665601) (xy 13.040589 -107.613306)
			(xy 13.063231 -107.563729) (xy 13.092697 -107.517879) (xy 13.128388 -107.476688) (xy 13.169579 -107.440997)
			(xy 13.215429 -107.411531) (xy 13.265006 -107.388889) (xy 13.317301 -107.373534) (xy 13.371249 -107.365778)
			(xy 13.3985 -107.365292) (xy 14.2875 -107.365292) (xy 14.314751 -107.365778) (xy 14.368699 -107.373534)
			(xy 14.420994 -107.388889) (xy 14.470571 -107.411531) (xy 14.516421 -107.440997) (xy 14.557612 -107.476688)
			(xy 14.593303 -107.517879) (xy 14.622769 -107.563729) (xy 14.645411 -107.613306) (xy 14.660766 -107.665601)
			(xy 14.668522 -107.719549) (xy 14.668522 -107.77382) (xy 17.94482 -107.77382) (xy 17.94482 -107.71928)
			(xy 17.952582 -107.665296) (xy 17.967948 -107.612966) (xy 17.990604 -107.563355) (xy 18.02009 -107.517474)
			(xy 18.055806 -107.476256) (xy 18.097024 -107.44054) (xy 18.142905 -107.411054) (xy 18.192516 -107.388398)
			(xy 18.244846 -107.373032) (xy 18.29883 -107.36527) (xy 18.3261 -107.364784) (xy 19.2151 -107.364784)
			(xy 19.242369 -107.365278) (xy 19.296352 -107.37304) (xy 19.348681 -107.388405) (xy 19.398291 -107.411061)
			(xy 19.444171 -107.440547) (xy 19.485388 -107.476262) (xy 19.521103 -107.517479) (xy 19.550589 -107.563359)
			(xy 19.573245 -107.612969) (xy 19.58861 -107.665298) (xy 19.596372 -107.719281) (xy 19.596372 -107.773819)
			(xy 19.58861 -107.827802) (xy 19.573245 -107.880131) (xy 19.550589 -107.929741) (xy 19.521103 -107.975621)
			(xy 19.485388 -108.016838) (xy 19.444171 -108.052553) (xy 19.398291 -108.082039) (xy 19.348681 -108.104695)
			(xy 19.296352 -108.12006) (xy 19.242369 -108.127822) (xy 19.2151 -108.128308) (xy 18.3261 -108.128308)
			(xy 18.29883 -108.12783) (xy 18.244846 -108.120068) (xy 18.192516 -108.104702) (xy 18.142905 -108.082046)
			(xy 18.097024 -108.05256) (xy 18.055806 -108.016844) (xy 18.02009 -107.975626) (xy 17.990604 -107.929745)
			(xy 17.967948 -107.880134) (xy 17.952582 -107.827804) (xy 17.94482 -107.77382) (xy 14.668522 -107.77382)
			(xy 14.668522 -107.774051) (xy 14.660766 -107.827999) (xy 14.645411 -107.880294) (xy 14.622769 -107.929871)
			(xy 14.593303 -107.975721) (xy 14.557612 -108.016912) (xy 14.516421 -108.052603) (xy 14.470571 -108.082069)
			(xy 14.420994 -108.104711) (xy 14.368699 -108.120066) (xy 14.314751 -108.127822) (xy 14.2875 -108.128308)
			(xy 13.3985 -108.128308) (xy 13.371249 -108.127822) (xy 13.317301 -108.120066) (xy 13.265006 -108.104711)
			(xy 13.215429 -108.082069) (xy 13.169579 -108.052603) (xy 13.128388 -108.016912) (xy 13.092697 -107.975721)
			(xy 13.063231 -107.929871) (xy 13.040589 -107.880294) (xy 13.025234 -107.827999) (xy 13.017478 -107.774051)
			(xy 0.509016 -107.774051) (xy 0.509016 -109.570609) (xy 15.016716 -109.570609) (xy 15.016716 -109.516071)
			(xy 15.024478 -109.462088) (xy 15.039843 -109.409759) (xy 15.062499 -109.360149) (xy 15.091985 -109.314268)
			(xy 15.127699 -109.273051) (xy 15.168917 -109.237336) (xy 15.214797 -109.20785) (xy 15.264407 -109.185194)
			(xy 15.316736 -109.169828) (xy 15.370719 -109.162067) (xy 15.397988 -109.16158) (xy 16.286988 -109.16158)
			(xy 16.314259 -109.162039) (xy 16.368247 -109.169801) (xy 16.42058 -109.185167) (xy 16.470193 -109.207825)
			(xy 16.516078 -109.237313) (xy 16.557298 -109.27303) (xy 16.593016 -109.314251) (xy 16.622504 -109.360135)
			(xy 16.645162 -109.409748) (xy 16.660528 -109.462081) (xy 16.668291 -109.516069) (xy 16.668291 -109.570611)
			(xy 16.660528 -109.624599) (xy 16.645162 -109.676932) (xy 16.622504 -109.726545) (xy 16.593016 -109.772429)
			(xy 16.557298 -109.81365) (xy 16.516078 -109.849367) (xy 16.470193 -109.878855) (xy 16.42058 -109.901513)
			(xy 16.368247 -109.916879) (xy 16.314259 -109.924641) (xy 16.286988 -109.925104) (xy 15.397988 -109.925104)
			(xy 15.370719 -109.924613) (xy 15.316736 -109.916852) (xy 15.264407 -109.901486) (xy 15.214797 -109.87883)
			(xy 15.168917 -109.849344) (xy 15.127699 -109.813629) (xy 15.091985 -109.772412) (xy 15.062499 -109.726531)
			(xy 15.039843 -109.676921) (xy 15.024478 -109.624592) (xy 15.016716 -109.570609) (xy 0.509016 -109.570609)
			(xy 0.509016 -109.998056) (xy 84.426541 -109.998056) (xy 84.426541 -109.868916) (xy 84.434491 -109.740021)
			(xy 84.450361 -109.611861) (xy 84.47409 -109.48492) (xy 84.505589 -109.359681) (xy 84.544738 -109.236618)
			(xy 84.591389 -109.116199) (xy 84.645364 -108.99888) (xy 84.706459 -108.885106) (xy 84.774442 -108.775309)
			(xy 84.849056 -108.669906) (xy 84.930017 -108.569296) (xy 85.017017 -108.473861) (xy 85.109728 -108.383962)
			(xy 85.207798 -108.299941) (xy 85.310853 -108.222117) (xy 85.418504 -108.150785) (xy 85.530343 -108.086215)
			(xy 85.645944 -108.028653) (xy 85.764869 -107.978316) (xy 85.886668 -107.935396) (xy 86.010878 -107.900055)
			(xy 86.137027 -107.872428) (xy 86.264639 -107.852619) (xy 86.393228 -107.840703) (xy 86.522306 -107.836727)
			(xy 86.651384 -107.840703) (xy 86.779973 -107.852619) (xy 86.907585 -107.872428) (xy 87.033734 -107.900055)
			(xy 87.157944 -107.935396) (xy 87.279743 -107.978316) (xy 87.398668 -108.028653) (xy 87.514269 -108.086215)
			(xy 87.626108 -108.150785) (xy 87.733759 -108.222117) (xy 87.836814 -108.299941) (xy 87.934884 -108.383962)
			(xy 88.027595 -108.473861) (xy 88.114595 -108.569296) (xy 88.195556 -108.669906) (xy 88.27017 -108.775309)
			(xy 88.338153 -108.885106) (xy 88.399248 -108.99888) (xy 88.453223 -109.116199) (xy 88.499874 -109.236618)
			(xy 88.539023 -109.359681) (xy 88.570522 -109.48492) (xy 88.594251 -109.611861) (xy 88.610121 -109.740021)
			(xy 88.618071 -109.868916) (xy 88.618568 -109.933486) (xy 88.618071 -109.998056) (xy 88.610121 -110.126951)
			(xy 88.594251 -110.255111) (xy 88.570522 -110.382052) (xy 88.539023 -110.507291) (xy 88.499874 -110.630354)
			(xy 88.453223 -110.750773) (xy 88.399248 -110.868092) (xy 88.338153 -110.981866) (xy 88.27017 -111.091663)
			(xy 88.195556 -111.197066) (xy 88.114595 -111.297676) (xy 88.027595 -111.393111) (xy 87.934884 -111.48301)
			(xy 87.836814 -111.567031) (xy 87.733759 -111.644855) (xy 87.626108 -111.716187) (xy 87.514269 -111.780757)
			(xy 87.398668 -111.838319) (xy 87.279743 -111.888656) (xy 87.157944 -111.931576) (xy 87.033734 -111.966917)
			(xy 86.907585 -111.994544) (xy 86.779973 -112.014353) (xy 86.651384 -112.026269) (xy 86.522306 -112.030246)
			(xy 86.393228 -112.026269) (xy 86.264639 -112.014353) (xy 86.137027 -111.994544) (xy 86.010878 -111.966917)
			(xy 85.886668 -111.931576) (xy 85.764869 -111.888656) (xy 85.645944 -111.838319) (xy 85.530343 -111.780757)
			(xy 85.418504 -111.716187) (xy 85.310853 -111.644855) (xy 85.207798 -111.567031) (xy 85.109728 -111.48301)
			(xy 85.017017 -111.393111) (xy 84.930017 -111.297676) (xy 84.849056 -111.197066) (xy 84.774442 -111.091663)
			(xy 84.706459 -110.981866) (xy 84.645364 -110.868092) (xy 84.591389 -110.750773) (xy 84.544738 -110.630354)
			(xy 84.505589 -110.507291) (xy 84.47409 -110.382052) (xy 84.450361 -110.255111) (xy 84.434491 -110.126951)
			(xy 84.426541 -109.998056) (xy 0.509016 -109.998056) (xy 0.509016 -112.300004) (xy 0.509494 -112.35115)
			(xy 53.778158 -112.35115) (xy 53.778158 -112.29665) (xy 53.785913 -112.242703) (xy 53.801267 -112.19041)
			(xy 53.823905 -112.140833) (xy 53.853369 -112.094983) (xy 53.889057 -112.053792) (xy 53.930243 -112.018099)
			(xy 53.976089 -111.988629) (xy 54.025663 -111.965984) (xy 54.077955 -111.950624) (xy 54.1319 -111.942861)
			(xy 54.15915 -111.942372) (xy 55.04815 -111.942372) (xy 55.075404 -111.942872) (xy 55.129357 -111.950623)
			(xy 55.181658 -111.965974) (xy 55.231242 -111.988612) (xy 55.277099 -112.018077) (xy 55.318296 -112.053769)
			(xy 55.353993 -112.094961) (xy 55.383464 -112.140814) (xy 55.406109 -112.190395) (xy 55.421467 -112.242694)
			(xy 55.429225 -112.296646) (xy 55.429225 -112.351154) (xy 55.421467 -112.405106) (xy 55.406109 -112.457405)
			(xy 55.383464 -112.506986) (xy 55.353993 -112.552839) (xy 55.318296 -112.594031) (xy 55.277099 -112.629723)
			(xy 55.231242 -112.659188) (xy 55.181658 -112.681826) (xy 55.129357 -112.697177) (xy 55.075404 -112.704928)
			(xy 55.04815 -112.705388) (xy 54.15915 -112.705388) (xy 54.1319 -112.704939) (xy 54.077955 -112.697176)
			(xy 54.025663 -112.681816) (xy 53.976089 -112.659171) (xy 53.930243 -112.629701) (xy 53.889057 -112.594008)
			(xy 53.853369 -112.552817) (xy 53.823905 -112.506967) (xy 53.801267 -112.45739) (xy 53.785913 -112.405097)
			(xy 53.778158 -112.35115) (xy 0.509494 -112.35115) (xy 0.509537 -112.355773) (xy 0.517873 -112.466999)
			(xy 0.534497 -112.577291) (xy 0.559316 -112.686033) (xy 0.592193 -112.792616) (xy 0.632942 -112.896444)
			(xy 0.681337 -112.996936) (xy 0.737106 -113.093531) (xy 0.796039 -113.17997) (xy 23.969706 -113.17997)
			(xy 23.969706 -113.12543) (xy 23.977468 -113.071446) (xy 23.992833 -113.019115) (xy 24.015489 -112.969504)
			(xy 24.044974 -112.923622) (xy 24.080689 -112.882403) (xy 24.121906 -112.846686) (xy 24.167787 -112.817198)
			(xy 24.217397 -112.79454) (xy 24.269726 -112.779172) (xy 24.32371 -112.771408) (xy 24.35098 -112.77092)
			(xy 25.23998 -112.77092) (xy 25.267251 -112.771418) (xy 25.321237 -112.779178) (xy 25.37357 -112.794541)
			(xy 25.423183 -112.817197) (xy 25.469067 -112.846682) (xy 25.510288 -112.882398) (xy 25.546006 -112.923617)
			(xy 25.575494 -112.969499) (xy 25.598152 -113.019111) (xy 25.613518 -113.071443) (xy 25.62128 -113.125429)
			(xy 25.62128 -113.179971) (xy 25.613518 -113.233957) (xy 25.598152 -113.286289) (xy 25.575494 -113.335901)
			(xy 25.546006 -113.381783) (xy 25.510288 -113.423002) (xy 25.469067 -113.458718) (xy 25.423183 -113.488203)
			(xy 25.37357 -113.510859) (xy 25.321237 -113.526222) (xy 25.267251 -113.533982) (xy 25.23998 -113.534444)
			(xy 24.35098 -113.534444) (xy 24.32371 -113.533992) (xy 24.269726 -113.526228) (xy 24.217397 -113.51086)
			(xy 24.167787 -113.488202) (xy 24.121906 -113.458714) (xy 24.080689 -113.422997) (xy 24.044974 -113.381778)
			(xy 24.015489 -113.335896) (xy 23.992833 -113.286285) (xy 23.977468 -113.233954) (xy 23.969706 -113.17997)
			(xy 0.796039 -113.17997) (xy 0.799937 -113.185688) (xy 0.86948 -113.272892) (xy 0.945345 -113.354655)
			(xy 1.027108 -113.43052) (xy 1.114312 -113.500063) (xy 1.206469 -113.562894) (xy 1.303064 -113.618663)
			(xy 1.403556 -113.667058) (xy 1.507384 -113.707807) (xy 1.613967 -113.740684) (xy 1.722709 -113.765503)
			(xy 1.833001 -113.782127) (xy 1.944227 -113.790463) (xy 1.999996 -113.790984) (xy 4.500118 -113.790984)
			(xy 4.544143 -113.791475) (xy 4.631856 -113.799169) (xy 4.718565 -113.814476) (xy 4.803611 -113.83728)
			(xy 4.886347 -113.867406) (xy 4.966143 -113.904627) (xy 5.042392 -113.948658) (xy 5.114516 -113.999166)
			(xy 5.181964 -114.055765) (xy 5.244225 -114.118026) (xy 5.300824 -114.185474) (xy 5.351332 -114.257598)
			(xy 5.395363 -114.333847) (xy 5.432584 -114.413643) (xy 5.46271 -114.496379) (xy 5.485514 -114.581425)
			(xy 5.500821 -114.668134) (xy 5.508515 -114.755847) (xy 5.509006 -114.799872) (xy 5.509006 -118.711726)
			(xy 5.621528 -118.824248) (xy 5.936488 -118.824248) (xy 6.040374 -118.720616) (xy 9.704578 -118.720616)
			(xy 9.862312 -118.878096) (xy 10.162286 -118.878096)
		)
		(stroke
			(width 0)
			(type solid)
		)
		(fill yes)
		(layer "In8.Cu")
		(net "GND")
	)
	(gr_poly
		(pts
			(xy 121.000012 -119.892064) (xy 121.055819 -119.891554) (xy 121.16712 -119.883212) (xy 121.277487 -119.866576)
			(xy 121.386302 -119.841739) (xy 121.492956 -119.808839) (xy 121.596854 -119.768061) (xy 121.697414 -119.719632)
			(xy 121.794073 -119.663824) (xy 121.886292 -119.600949) (xy 121.973554 -119.531358) (xy 122.055371 -119.45544)
			(xy 122.131287 -119.373621) (xy 122.200875 -119.286356) (xy 122.263748 -119.194136) (xy 122.319553 -119.097475)
			(xy 122.367978 -118.996914) (xy 122.408754 -118.893015) (xy 122.44165 -118.786359) (xy 122.466484 -118.677544)
			(xy 122.483117 -118.567176) (xy 122.491456 -118.455875) (xy 122.492008 -118.400068) (xy 122.492008 129.499868)
			(xy 122.4915 129.555676) (xy 122.483161 129.666981) (xy 122.466528 129.777352) (xy 122.441693 129.886171)
			(xy 122.408795 129.992829) (xy 122.368019 130.096731) (xy 122.319592 130.197295) (xy 122.263785 130.293959)
			(xy 122.200911 130.386183) (xy 122.13132 130.473449) (xy 122.055402 130.555271) (xy 121.973583 130.631191)
			(xy 121.886318 130.700784) (xy 121.794097 130.763662) (xy 121.697434 130.819471) (xy 121.596872 130.867901)
			(xy 121.492971 130.908681) (xy 121.386313 130.941581) (xy 121.277495 130.96642) (xy 121.167125 130.983056)
			(xy 121.05582 130.991398) (xy 121.000012 130.991864) (xy 94.000066 130.991864) (xy 93.94426 130.991341)
			(xy 93.832961 130.982998) (xy 93.722596 130.96636) (xy 93.613784 130.941522) (xy 93.507131 130.908622)
			(xy 93.403236 130.867843) (xy 93.302679 130.819414) (xy 93.206021 130.763606) (xy 93.113805 130.700731)
			(xy 93.026545 130.631141) (xy 92.94473 130.555224) (xy 92.868816 130.473405) (xy 92.79923 130.386142)
			(xy 92.736359 130.293923) (xy 92.680555 130.197263) (xy 92.632131 130.096703) (xy 92.591357 129.992806)
			(xy 92.558461 129.886153) (xy 92.533627 129.777339) (xy 92.516995 129.666973) (xy 92.508656 129.555674)
			(xy 92.50807 129.499868) (xy 92.50807 126.435304) (xy 115.904253 126.435304) (xy 115.904253 126.564444)
			(xy 115.912203 126.693339) (xy 115.928073 126.821499) (xy 115.951802 126.94844) (xy 115.983301 127.073679)
			(xy 116.02245 127.196742) (xy 116.069101 127.317161) (xy 116.123076 127.43448) (xy 116.184171 127.548254)
			(xy 116.252154 127.658051) (xy 116.326768 127.763454) (xy 116.407729 127.864064) (xy 116.494729 127.959499)
			(xy 116.58744 128.049398) (xy 116.68551 128.133419) (xy 116.788565 128.211243) (xy 116.896216 128.282575)
			(xy 117.008055 128.347145) (xy 117.123656 128.404707) (xy 117.242581 128.455044) (xy 117.36438 128.497964)
			(xy 117.48859 128.533305) (xy 117.614739 128.560932) (xy 117.742351 128.580741) (xy 117.87094 128.592657)
			(xy 118.000018 128.596634) (xy 118.129096 128.592657) (xy 118.257685 128.580741) (xy 118.385297 128.560932)
			(xy 118.511446 128.533305) (xy 118.635656 128.497964) (xy 118.757455 128.455044) (xy 118.87638 128.404707)
			(xy 118.991981 128.347145) (xy 119.10382 128.282575) (xy 119.211471 128.211243) (xy 119.314526 128.133419)
			(xy 119.412596 128.049398) (xy 119.505307 127.959499) (xy 119.592307 127.864064) (xy 119.673268 127.763454)
			(xy 119.747882 127.658051) (xy 119.815865 127.548254) (xy 119.87696 127.43448) (xy 119.930935 127.317161)
			(xy 119.977586 127.196742) (xy 120.016735 127.073679) (xy 120.048234 126.94844) (xy 120.071963 126.821499)
			(xy 120.087833 126.693339) (xy 120.095783 126.564444) (xy 120.09628 126.499874) (xy 120.095783 126.435304)
			(xy 120.087833 126.306409) (xy 120.071963 126.178249) (xy 120.048234 126.051308) (xy 120.016735 125.926069)
			(xy 119.977586 125.803006) (xy 119.930935 125.682587) (xy 119.87696 125.565268) (xy 119.815865 125.451494)
			(xy 119.747882 125.341697) (xy 119.673268 125.236294) (xy 119.592307 125.135684) (xy 119.505307 125.040249)
			(xy 119.412596 124.95035) (xy 119.314526 124.866329) (xy 119.211471 124.788505) (xy 119.10382 124.717173)
			(xy 118.991981 124.652603) (xy 118.87638 124.595041) (xy 118.757455 124.544704) (xy 118.635656 124.501784)
			(xy 118.511446 124.466443) (xy 118.385297 124.438816) (xy 118.257685 124.419007) (xy 118.129096 124.407091)
			(xy 118.000018 124.403115) (xy 117.87094 124.407091) (xy 117.742351 124.419007) (xy 117.614739 124.438816)
			(xy 117.48859 124.466443) (xy 117.36438 124.501784) (xy 117.242581 124.544704) (xy 117.123656 124.595041)
			(xy 117.008055 124.652603) (xy 116.896216 124.717173) (xy 116.788565 124.788505) (xy 116.68551 124.866329)
			(xy 116.58744 124.95035) (xy 116.494729 125.040249) (xy 116.407729 125.135684) (xy 116.326768 125.236294)
			(xy 116.252154 125.341697) (xy 116.184171 125.451494) (xy 116.123076 125.565268) (xy 116.069101 125.682587)
			(xy 116.02245 125.803006) (xy 115.983301 125.926069) (xy 115.951802 126.051308) (xy 115.928073 126.178249)
			(xy 115.912203 126.306409) (xy 115.904253 126.435304) (xy 92.50807 126.435304) (xy 92.50807 122.226375)
			(xy 99.070401 122.226375) (xy 99.070401 122.312125) (xy 99.078313 122.397508) (xy 99.094069 122.481798)
			(xy 99.117536 122.564274) (xy 99.148512 122.644233) (xy 99.186734 122.720993) (xy 99.231875 122.793899)
			(xy 99.283551 122.862328) (xy 99.34132 122.925698) (xy 99.40469 122.983467) (xy 99.473119 123.035143)
			(xy 99.546025 123.080284) (xy 99.622785 123.118506) (xy 99.702744 123.149482) (xy 99.78522 123.172949)
			(xy 99.86951 123.188705) (xy 99.954893 123.196617) (xy 100.040643 123.196617) (xy 100.126026 123.188705)
			(xy 100.210316 123.172949) (xy 100.292792 123.149482) (xy 100.372751 123.118506) (xy 100.449511 123.080284)
			(xy 100.522417 123.035143) (xy 100.590846 122.983467) (xy 100.654216 122.925698) (xy 100.711985 122.862328)
			(xy 100.763661 122.793899) (xy 100.808802 122.720993) (xy 100.847024 122.644233) (xy 100.878 122.564274)
			(xy 100.901467 122.481798) (xy 100.917223 122.397508) (xy 100.925135 122.312125) (xy 100.92563 122.26925)
			(xy 100.925135 122.226375) (xy 101.610401 122.226375) (xy 101.610401 122.312125) (xy 101.618313 122.397508)
			(xy 101.634069 122.481798) (xy 101.657536 122.564274) (xy 101.688512 122.644233) (xy 101.726734 122.720993)
			(xy 101.771875 122.793899) (xy 101.823551 122.862328) (xy 101.88132 122.925698) (xy 101.94469 122.983467)
			(xy 102.013119 123.035143) (xy 102.086025 123.080284) (xy 102.162785 123.118506) (xy 102.242744 123.149482)
			(xy 102.32522 123.172949) (xy 102.40951 123.188705) (xy 102.494893 123.196617) (xy 102.580643 123.196617)
			(xy 102.666026 123.188705) (xy 102.750316 123.172949) (xy 102.832792 123.149482) (xy 102.912751 123.118506)
			(xy 102.989511 123.080284) (xy 103.062417 123.035143) (xy 103.130846 122.983467) (xy 103.194216 122.925698)
			(xy 103.251985 122.862328) (xy 103.303661 122.793899) (xy 103.348802 122.720993) (xy 103.387024 122.644233)
			(xy 103.418 122.564274) (xy 103.441467 122.481798) (xy 103.457223 122.397508) (xy 103.465135 122.312125)
			(xy 103.46563 122.26925) (xy 103.465135 122.226375) (xy 103.457223 122.140992) (xy 103.441467 122.056702)
			(xy 103.418 121.974226) (xy 103.387024 121.894267) (xy 103.348802 121.817507) (xy 103.303661 121.744601)
			(xy 103.251985 121.676172) (xy 103.194216 121.612802) (xy 103.130846 121.555033) (xy 103.062417 121.503357)
			(xy 102.989511 121.458216) (xy 102.912751 121.419994) (xy 102.832792 121.389018) (xy 102.750316 121.365551)
			(xy 102.666026 121.349795) (xy 102.580643 121.341883) (xy 102.494893 121.341883) (xy 102.40951 121.349795)
			(xy 102.32522 121.365551) (xy 102.242744 121.389018) (xy 102.162785 121.419994) (xy 102.086025 121.458216)
			(xy 102.013119 121.503357) (xy 101.94469 121.555033) (xy 101.88132 121.612802) (xy 101.823551 121.676172)
			(xy 101.771875 121.744601) (xy 101.726734 121.817507) (xy 101.688512 121.894267) (xy 101.657536 121.974226)
			(xy 101.634069 122.056702) (xy 101.618313 122.140992) (xy 101.610401 122.226375) (xy 100.925135 122.226375)
			(xy 100.917223 122.140992) (xy 100.901467 122.056702) (xy 100.878 121.974226) (xy 100.847024 121.894267)
			(xy 100.808802 121.817507) (xy 100.763661 121.744601) (xy 100.711985 121.676172) (xy 100.654216 121.612802)
			(xy 100.590846 121.555033) (xy 100.522417 121.503357) (xy 100.449511 121.458216) (xy 100.372751 121.419994)
			(xy 100.292792 121.389018) (xy 100.210316 121.365551) (xy 100.126026 121.349795) (xy 100.040643 121.341883)
			(xy 99.954893 121.341883) (xy 99.86951 121.349795) (xy 99.78522 121.365551) (xy 99.702744 121.389018)
			(xy 99.622785 121.419994) (xy 99.546025 121.458216) (xy 99.473119 121.503357) (xy 99.40469 121.555033)
			(xy 99.34132 121.612802) (xy 99.283551 121.676172) (xy 99.231875 121.744601) (xy 99.186734 121.817507)
			(xy 99.148512 121.894267) (xy 99.117536 121.974226) (xy 99.094069 122.056702) (xy 99.078313 122.140992)
			(xy 99.070401 122.226375) (xy 92.50807 122.226375) (xy 92.50807 117.881334) (xy 100.454746 117.881334)
			(xy 100.454746 117.935866) (xy 100.462507 117.989844) (xy 100.47787 118.042168) (xy 100.500522 118.091773)
			(xy 100.530003 118.13765) (xy 100.565713 118.178864) (xy 100.606924 118.214578) (xy 100.652799 118.244063)
			(xy 100.702402 118.266719) (xy 100.754725 118.282087) (xy 100.808702 118.289851) (xy 100.835968 118.29034)
			(xy 101.699568 118.29034) (xy 101.726842 118.289923) (xy 101.780835 118.282164) (xy 101.833175 118.266799)
			(xy 101.882795 118.244142) (xy 101.928685 118.214654) (xy 101.969912 118.178934) (xy 102.005635 118.137711)
			(xy 102.035127 118.091823) (xy 102.057788 118.042205) (xy 102.073157 117.989867) (xy 102.08092 117.935874)
			(xy 102.08092 117.881326) (xy 102.073157 117.827333) (xy 102.057788 117.774995) (xy 102.035127 117.725377)
			(xy 102.005635 117.679489) (xy 101.969912 117.638266) (xy 101.928685 117.602546) (xy 101.882795 117.573058)
			(xy 101.833175 117.550401) (xy 101.780836 117.535036) (xy 101.726842 117.527277) (xy 101.699568 117.526816)
			(xy 100.835968 117.526816) (xy 100.808702 117.527349) (xy 100.754725 117.535113) (xy 100.702402 117.550481)
			(xy 100.652799 117.573137) (xy 100.606924 117.602622) (xy 100.565713 117.638336) (xy 100.530003 117.67955)
			(xy 100.500522 117.725427) (xy 100.47787 117.775032) (xy 100.462507 117.827356) (xy 100.454746 117.881334)
			(xy 92.50807 117.881334) (xy 92.50807 115.606627) (xy 93.714049 115.606627) (xy 93.714049 115.692377)
			(xy 93.721961 115.77776) (xy 93.737717 115.86205) (xy 93.761184 115.944526) (xy 93.79216 116.024485)
			(xy 93.830382 116.101245) (xy 93.875523 116.174151) (xy 93.927199 116.24258) (xy 93.984968 116.30595)
			(xy 94.048338 116.363719) (xy 94.116767 116.415395) (xy 94.189673 116.460536) (xy 94.266433 116.498758)
			(xy 94.346392 116.529734) (xy 94.428868 116.553201) (xy 94.513158 116.568957) (xy 94.598541 116.576869)
			(xy 94.684291 116.576869) (xy 94.769674 116.568957) (xy 94.853964 116.553201) (xy 94.93644 116.529734)
			(xy 95.016399 116.498758) (xy 95.093159 116.460536) (xy 95.166065 116.415395) (xy 95.234494 116.363719)
			(xy 95.297864 116.30595) (xy 95.355633 116.24258) (xy 95.407309 116.174151) (xy 95.45245 116.101245)
			(xy 95.490672 116.024485) (xy 95.521648 115.944526) (xy 95.545115 115.86205) (xy 95.560871 115.77776)
			(xy 95.568783 115.692377) (xy 95.569278 115.649502) (xy 95.568783 115.606627) (xy 96.254049 115.606627)
			(xy 96.254049 115.692377) (xy 96.261961 115.77776) (xy 96.277717 115.86205) (xy 96.301184 115.944526)
			(xy 96.33216 116.024485) (xy 96.370382 116.101245) (xy 96.415523 116.174151) (xy 96.467199 116.24258)
			(xy 96.524968 116.30595) (xy 96.588338 116.363719) (xy 96.656767 116.415395) (xy 96.729673 116.460536)
			(xy 96.806433 116.498758) (xy 96.886392 116.529734) (xy 96.968868 116.553201) (xy 97.053158 116.568957)
			(xy 97.138541 116.576869) (xy 97.224291 116.576869) (xy 97.309674 116.568957) (xy 97.393964 116.553201)
			(xy 97.47644 116.529734) (xy 97.556399 116.498758) (xy 97.633159 116.460536) (xy 97.706065 116.415395)
			(xy 97.774494 116.363719) (xy 97.837864 116.30595) (xy 97.895633 116.24258) (xy 97.947309 116.174151)
			(xy 97.99245 116.101245) (xy 98.030672 116.024485) (xy 98.061648 115.944526) (xy 98.081039 115.876375)
			(xy 99.070401 115.876375) (xy 99.070401 115.962125) (xy 99.078313 116.047508) (xy 99.094069 116.131798)
			(xy 99.117536 116.214274) (xy 99.148512 116.294233) (xy 99.186734 116.370993) (xy 99.231875 116.443899)
			(xy 99.283551 116.512328) (xy 99.34132 116.575698) (xy 99.40469 116.633467) (xy 99.473119 116.685143)
			(xy 99.546025 116.730284) (xy 99.622785 116.768506) (xy 99.702744 116.799482) (xy 99.78522 116.822949)
			(xy 99.86951 116.838705) (xy 99.954893 116.846617) (xy 100.040643 116.846617) (xy 100.126026 116.838705)
			(xy 100.210316 116.822949) (xy 100.292792 116.799482) (xy 100.372751 116.768506) (xy 100.449511 116.730284)
			(xy 100.522417 116.685143) (xy 100.590846 116.633467) (xy 100.654216 116.575698) (xy 100.711985 116.512328)
			(xy 100.763661 116.443899) (xy 100.808802 116.370993) (xy 100.847024 116.294233) (xy 100.878 116.214274)
			(xy 100.901467 116.131798) (xy 100.917223 116.047508) (xy 100.925135 115.962125) (xy 100.92563 115.91925)
			(xy 100.925135 115.876375) (xy 101.610401 115.876375) (xy 101.610401 115.962125) (xy 101.618313 116.047508)
			(xy 101.634069 116.131798) (xy 101.657536 116.214274) (xy 101.688512 116.294233) (xy 101.726734 116.370993)
			(xy 101.771875 116.443899) (xy 101.823551 116.512328) (xy 101.88132 116.575698) (xy 101.94469 116.633467)
			(xy 102.013119 116.685143) (xy 102.086025 116.730284) (xy 102.162785 116.768506) (xy 102.242744 116.799482)
			(xy 102.32522 116.822949) (xy 102.40951 116.838705) (xy 102.494893 116.846617) (xy 102.580643 116.846617)
			(xy 102.666026 116.838705) (xy 102.750316 116.822949) (xy 102.832792 116.799482) (xy 102.912751 116.768506)
			(xy 102.989511 116.730284) (xy 103.062417 116.685143) (xy 103.130846 116.633467) (xy 103.194216 116.575698)
			(xy 103.251985 116.512328) (xy 103.303661 116.443899) (xy 103.348802 116.370993) (xy 103.387024 116.294233)
			(xy 103.418 116.214274) (xy 103.441467 116.131798) (xy 103.457223 116.047508) (xy 103.465135 115.962125)
			(xy 103.46563 115.91925) (xy 103.465135 115.876375) (xy 103.457223 115.790992) (xy 103.441467 115.706702)
			(xy 103.418 115.624226) (xy 103.387024 115.544267) (xy 103.348802 115.467507) (xy 103.303661 115.394601)
			(xy 103.251985 115.326172) (xy 103.194216 115.262802) (xy 103.130846 115.205033) (xy 103.062417 115.153357)
			(xy 102.989511 115.108216) (xy 102.912751 115.069994) (xy 102.832792 115.039018) (xy 102.750316 115.015551)
			(xy 102.666026 114.999795) (xy 102.580643 114.991883) (xy 102.494893 114.991883) (xy 102.40951 114.999795)
			(xy 102.32522 115.015551) (xy 102.242744 115.039018) (xy 102.162785 115.069994) (xy 102.086025 115.108216)
			(xy 102.013119 115.153357) (xy 101.94469 115.205033) (xy 101.88132 115.262802) (xy 101.823551 115.326172)
			(xy 101.771875 115.394601) (xy 101.726734 115.467507) (xy 101.688512 115.544267) (xy 101.657536 115.624226)
			(xy 101.634069 115.706702) (xy 101.618313 115.790992) (xy 101.610401 115.876375) (xy 100.925135 115.876375)
			(xy 100.917223 115.790992) (xy 100.901467 115.706702) (xy 100.878 115.624226) (xy 100.847024 115.544267)
			(xy 100.808802 115.467507) (xy 100.763661 115.394601) (xy 100.711985 115.326172) (xy 100.654216 115.262802)
			(xy 100.590846 115.205033) (xy 100.522417 115.153357) (xy 100.449511 115.108216) (xy 100.372751 115.069994)
			(xy 100.292792 115.039018) (xy 100.210316 115.015551) (xy 100.126026 114.999795) (xy 100.040643 114.991883)
			(xy 99.954893 114.991883) (xy 99.86951 114.999795) (xy 99.78522 115.015551) (xy 99.702744 115.039018)
			(xy 99.622785 115.069994) (xy 99.546025 115.108216) (xy 99.473119 115.153357) (xy 99.40469 115.205033)
			(xy 99.34132 115.262802) (xy 99.283551 115.326172) (xy 99.231875 115.394601) (xy 99.186734 115.467507)
			(xy 99.148512 115.544267) (xy 99.117536 115.624226) (xy 99.094069 115.706702) (xy 99.078313 115.790992)
			(xy 99.070401 115.876375) (xy 98.081039 115.876375) (xy 98.085115 115.86205) (xy 98.100871 115.77776)
			(xy 98.108783 115.692377) (xy 98.109278 115.649502) (xy 98.108783 115.606627) (xy 98.100871 115.521244)
			(xy 98.085115 115.436954) (xy 98.061648 115.354478) (xy 98.030672 115.274519) (xy 97.99245 115.197759)
			(xy 97.947309 115.124853) (xy 97.895633 115.056424) (xy 97.837864 114.993054) (xy 97.774494 114.935285)
			(xy 97.706065 114.883609) (xy 97.633159 114.838468) (xy 97.556399 114.800246) (xy 97.47644 114.76927)
			(xy 97.393964 114.745803) (xy 97.309674 114.730047) (xy 97.224291 114.722135) (xy 97.138541 114.722135)
			(xy 97.053158 114.730047) (xy 96.968868 114.745803) (xy 96.886392 114.76927) (xy 96.806433 114.800246)
			(xy 96.729673 114.838468) (xy 96.656767 114.883609) (xy 96.588338 114.935285) (xy 96.524968 114.993054)
			(xy 96.467199 115.056424) (xy 96.415523 115.124853) (xy 96.370382 115.197759) (xy 96.33216 115.274519)
			(xy 96.301184 115.354478) (xy 96.277717 115.436954) (xy 96.261961 115.521244) (xy 96.254049 115.606627)
			(xy 95.568783 115.606627) (xy 95.560871 115.521244) (xy 95.545115 115.436954) (xy 95.521648 115.354478)
			(xy 95.490672 115.274519) (xy 95.45245 115.197759) (xy 95.407309 115.124853) (xy 95.355633 115.056424)
			(xy 95.297864 114.993054) (xy 95.234494 114.935285) (xy 95.166065 114.883609) (xy 95.093159 114.838468)
			(xy 95.016399 114.800246) (xy 94.93644 114.76927) (xy 94.853964 114.745803) (xy 94.769674 114.730047)
			(xy 94.684291 114.722135) (xy 94.598541 114.722135) (xy 94.513158 114.730047) (xy 94.428868 114.745803)
			(xy 94.346392 114.76927) (xy 94.266433 114.800246) (xy 94.189673 114.838468) (xy 94.116767 114.883609)
			(xy 94.048338 114.935285) (xy 93.984968 114.993054) (xy 93.927199 115.056424) (xy 93.875523 115.124853)
			(xy 93.830382 115.197759) (xy 93.79216 115.274519) (xy 93.761184 115.354478) (xy 93.737717 115.436954)
			(xy 93.721961 115.521244) (xy 93.714049 115.606627) (xy 92.50807 115.606627) (xy 92.50807 111.261526)
			(xy 95.098272 111.261526) (xy 95.098272 111.316074) (xy 95.106035 111.370066) (xy 95.121403 111.422404)
			(xy 95.144064 111.472023) (xy 95.173555 111.517911) (xy 95.209277 111.559134) (xy 95.250502 111.594855)
			(xy 95.296392 111.624344) (xy 95.346011 111.647003) (xy 95.398349 111.662369) (xy 95.452342 111.67013)
			(xy 95.479616 111.670592) (xy 96.343216 111.670592) (xy 96.370482 111.670045) (xy 96.42446 111.662282)
			(xy 96.476784 111.646916) (xy 96.526388 111.624261) (xy 96.572263 111.594777) (xy 96.613476 111.559064)
			(xy 96.649186 111.51785) (xy 96.678668 111.471974) (xy 96.701322 111.422369) (xy 96.716685 111.370044)
			(xy 96.724446 111.316067) (xy 96.724446 111.261534) (xy 96.716685 111.207556) (xy 96.701322 111.155231)
			(xy 96.678668 111.105626) (xy 96.649186 111.05975) (xy 96.613476 111.018536) (xy 96.572263 110.982823)
			(xy 96.526388 110.953339) (xy 96.476784 110.930684) (xy 96.42446 110.915318) (xy 96.370482 110.907555)
			(xy 96.343216 110.907068) (xy 95.479616 110.907068) (xy 95.452342 110.90747) (xy 95.398349 110.915231)
			(xy 95.346011 110.930597) (xy 95.296392 110.953256) (xy 95.250502 110.982745) (xy 95.209277 111.018466)
			(xy 95.173555 111.059689) (xy 95.144064 111.105577) (xy 95.121403 111.155196) (xy 95.106035 111.207534)
			(xy 95.098272 111.261526) (xy 92.50807 111.261526) (xy 92.50807 109.256627) (xy 93.714049 109.256627)
			(xy 93.714049 109.342377) (xy 93.721961 109.42776) (xy 93.737717 109.51205) (xy 93.761184 109.594526)
			(xy 93.79216 109.674485) (xy 93.830382 109.751245) (xy 93.875523 109.824151) (xy 93.927199 109.89258)
			(xy 93.984968 109.95595) (xy 94.048338 110.013719) (xy 94.116767 110.065395) (xy 94.189673 110.110536)
			(xy 94.266433 110.148758) (xy 94.346392 110.179734) (xy 94.428868 110.203201) (xy 94.513158 110.218957)
			(xy 94.598541 110.226869) (xy 94.684291 110.226869) (xy 94.769674 110.218957) (xy 94.853964 110.203201)
			(xy 94.93644 110.179734) (xy 95.016399 110.148758) (xy 95.093159 110.110536) (xy 95.166065 110.065395)
			(xy 95.234494 110.013719) (xy 95.297864 109.95595) (xy 95.355633 109.89258) (xy 95.407309 109.824151)
			(xy 95.45245 109.751245) (xy 95.490672 109.674485) (xy 95.521648 109.594526) (xy 95.545115 109.51205)
			(xy 95.560871 109.42776) (xy 95.568783 109.342377) (xy 95.569278 109.299502) (xy 95.568783 109.256627)
			(xy 96.254049 109.256627) (xy 96.254049 109.342377) (xy 96.261961 109.42776) (xy 96.277717 109.51205)
			(xy 96.301184 109.594526) (xy 96.33216 109.674485) (xy 96.370382 109.751245) (xy 96.415523 109.824151)
			(xy 96.467199 109.89258) (xy 96.524968 109.95595) (xy 96.588338 110.013719) (xy 96.656767 110.065395)
			(xy 96.729673 110.110536) (xy 96.806433 110.148758) (xy 96.886392 110.179734) (xy 96.968868 110.203201)
			(xy 97.053158 110.218957) (xy 97.138541 110.226869) (xy 97.224291 110.226869) (xy 97.309674 110.218957)
			(xy 97.393964 110.203201) (xy 97.47644 110.179734) (xy 97.556399 110.148758) (xy 97.633159 110.110536)
			(xy 97.706065 110.065395) (xy 97.774494 110.013719) (xy 97.837864 109.95595) (xy 97.895633 109.89258)
			(xy 97.947309 109.824151) (xy 97.99245 109.751245) (xy 98.030672 109.674485) (xy 98.061648 109.594526)
			(xy 98.085115 109.51205) (xy 98.100871 109.42776) (xy 98.108783 109.342377) (xy 98.109278 109.299502)
			(xy 98.108783 109.256627) (xy 98.100871 109.171244) (xy 98.085115 109.086954) (xy 98.061648 109.004478)
			(xy 98.030672 108.924519) (xy 97.99245 108.847759) (xy 97.947309 108.774853) (xy 97.895633 108.706424)
			(xy 97.837864 108.643054) (xy 97.774494 108.585285) (xy 97.706065 108.533609) (xy 97.633159 108.488468)
			(xy 97.556399 108.450246) (xy 97.47644 108.41927) (xy 97.393964 108.395803) (xy 97.309674 108.380047)
			(xy 97.224291 108.372135) (xy 97.138541 108.372135) (xy 97.053158 108.380047) (xy 96.968868 108.395803)
			(xy 96.886392 108.41927) (xy 96.806433 108.450246) (xy 96.729673 108.488468) (xy 96.656767 108.533609)
			(xy 96.588338 108.585285) (xy 96.524968 108.643054) (xy 96.467199 108.706424) (xy 96.415523 108.774853)
			(xy 96.370382 108.847759) (xy 96.33216 108.924519) (xy 96.301184 109.004478) (xy 96.277717 109.086954)
			(xy 96.261961 109.171244) (xy 96.254049 109.256627) (xy 95.568783 109.256627) (xy 95.560871 109.171244)
			(xy 95.545115 109.086954) (xy 95.521648 109.004478) (xy 95.490672 108.924519) (xy 95.45245 108.847759)
			(xy 95.407309 108.774853) (xy 95.355633 108.706424) (xy 95.297864 108.643054) (xy 95.234494 108.585285)
			(xy 95.166065 108.533609) (xy 95.093159 108.488468) (xy 95.016399 108.450246) (xy 94.93644 108.41927)
			(xy 94.853964 108.395803) (xy 94.769674 108.380047) (xy 94.684291 108.372135) (xy 94.598541 108.372135)
			(xy 94.513158 108.380047) (xy 94.428868 108.395803) (xy 94.346392 108.41927) (xy 94.266433 108.450246)
			(xy 94.189673 108.488468) (xy 94.116767 108.533609) (xy 94.048338 108.585285) (xy 93.984968 108.643054)
			(xy 93.927199 108.706424) (xy 93.875523 108.774853) (xy 93.830382 108.847759) (xy 93.79216 108.924519)
			(xy 93.761184 109.004478) (xy 93.737717 109.086954) (xy 93.721961 109.171244) (xy 93.714049 109.256627)
			(xy 92.50807 109.256627) (xy 92.50807 56.800039) (xy 93.729289 56.800039) (xy 93.729289 56.885789)
			(xy 93.737201 56.971172) (xy 93.752957 57.055462) (xy 93.776424 57.137938) (xy 93.8074 57.217897)
			(xy 93.845622 57.294657) (xy 93.890763 57.367563) (xy 93.942439 57.435992) (xy 94.000208 57.499362)
			(xy 94.063578 57.557131) (xy 94.132007 57.608807) (xy 94.204913 57.653948) (xy 94.281673 57.69217)
			(xy 94.361632 57.723146) (xy 94.444108 57.746613) (xy 94.528398 57.762369) (xy 94.613781 57.770281)
			(xy 94.699531 57.770281) (xy 94.784914 57.762369) (xy 94.869204 57.746613) (xy 94.95168 57.723146)
			(xy 95.031639 57.69217) (xy 95.108399 57.653948) (xy 95.181305 57.608807) (xy 95.249734 57.557131)
			(xy 95.313104 57.499362) (xy 95.370873 57.435992) (xy 95.422549 57.367563) (xy 95.46769 57.294657)
			(xy 95.505912 57.217897) (xy 95.536888 57.137938) (xy 95.560355 57.055462) (xy 95.576111 56.971172)
			(xy 95.584023 56.885789) (xy 95.584518 56.842914) (xy 95.584023 56.800039) (xy 96.269289 56.800039)
			(xy 96.269289 56.885789) (xy 96.277201 56.971172) (xy 96.292957 57.055462) (xy 96.316424 57.137938)
			(xy 96.3474 57.217897) (xy 96.385622 57.294657) (xy 96.430763 57.367563) (xy 96.482439 57.435992)
			(xy 96.540208 57.499362) (xy 96.603578 57.557131) (xy 96.672007 57.608807) (xy 96.744913 57.653948)
			(xy 96.821673 57.69217) (xy 96.901632 57.723146) (xy 96.984108 57.746613) (xy 97.068398 57.762369)
			(xy 97.153781 57.770281) (xy 97.239531 57.770281) (xy 97.324914 57.762369) (xy 97.409204 57.746613)
			(xy 97.49168 57.723146) (xy 97.571639 57.69217) (xy 97.648399 57.653948) (xy 97.721305 57.608807)
			(xy 97.789734 57.557131) (xy 97.853104 57.499362) (xy 97.910873 57.435992) (xy 97.962549 57.367563)
			(xy 98.00769 57.294657) (xy 98.045912 57.217897) (xy 98.076888 57.137938) (xy 98.100355 57.055462)
			(xy 98.116111 56.971172) (xy 98.124023 56.885789) (xy 98.124518 56.842914) (xy 98.124023 56.800039)
			(xy 98.116111 56.714656) (xy 98.100355 56.630366) (xy 98.076888 56.54789) (xy 98.045912 56.467931)
			(xy 98.00769 56.391171) (xy 97.962549 56.318265) (xy 97.910873 56.249836) (xy 97.853104 56.186466)
			(xy 97.789734 56.128697) (xy 97.721305 56.077021) (xy 97.648399 56.03188) (xy 97.571639 55.993658)
			(xy 97.49168 55.962682) (xy 97.409204 55.939215) (xy 97.324914 55.923459) (xy 97.239531 55.915547)
			(xy 97.153781 55.915547) (xy 97.068398 55.923459) (xy 96.984108 55.939215) (xy 96.901632 55.962682)
			(xy 96.821673 55.993658) (xy 96.744913 56.03188) (xy 96.672007 56.077021) (xy 96.603578 56.128697)
			(xy 96.540208 56.186466) (xy 96.482439 56.249836) (xy 96.430763 56.318265) (xy 96.385622 56.391171)
			(xy 96.3474 56.467931) (xy 96.316424 56.54789) (xy 96.292957 56.630366) (xy 96.277201 56.714656)
			(xy 96.269289 56.800039) (xy 95.584023 56.800039) (xy 95.576111 56.714656) (xy 95.560355 56.630366)
			(xy 95.536888 56.54789) (xy 95.505912 56.467931) (xy 95.46769 56.391171) (xy 95.422549 56.318265)
			(xy 95.370873 56.249836) (xy 95.313104 56.186466) (xy 95.249734 56.128697) (xy 95.181305 56.077021)
			(xy 95.108399 56.03188) (xy 95.031639 55.993658) (xy 94.95168 55.962682) (xy 94.869204 55.939215)
			(xy 94.784914 55.923459) (xy 94.699531 55.915547) (xy 94.613781 55.915547) (xy 94.528398 55.923459)
			(xy 94.444108 55.939215) (xy 94.361632 55.962682) (xy 94.281673 55.993658) (xy 94.204913 56.03188)
			(xy 94.132007 56.077021) (xy 94.063578 56.128697) (xy 94.000208 56.186466) (xy 93.942439 56.249836)
			(xy 93.890763 56.318265) (xy 93.845622 56.391171) (xy 93.8074 56.467931) (xy 93.776424 56.54789)
			(xy 93.752957 56.630366) (xy 93.737201 56.714656) (xy 93.729289 56.800039) (xy 92.50807 56.800039)
			(xy 92.50807 54.826334) (xy 95.113638 54.826334) (xy 95.113638 54.880866) (xy 95.121398 54.934844)
			(xy 95.136761 54.987168) (xy 95.159413 55.036774) (xy 95.188894 55.082651) (xy 95.224603 55.123866)
			(xy 95.265814 55.15958) (xy 95.311688 55.189066) (xy 95.36129 55.211724) (xy 95.413613 55.227092)
			(xy 95.46759 55.234859) (xy 95.494856 55.235348) (xy 96.358456 55.235348) (xy 96.38573 55.234915)
			(xy 96.439724 55.227158) (xy 96.492064 55.211795) (xy 96.541684 55.189139) (xy 96.587575 55.159652)
			(xy 96.628802 55.123933) (xy 96.664525 55.08271) (xy 96.694018 55.036823) (xy 96.71668 54.987205)
			(xy 96.732049 54.934867) (xy 96.739812 54.880874) (xy 96.739812 54.826326) (xy 96.732049 54.772333)
			(xy 96.71668 54.719995) (xy 96.694018 54.670377) (xy 96.664525 54.62449) (xy 96.628802 54.583267)
			(xy 96.587575 54.547548) (xy 96.541684 54.518061) (xy 96.492064 54.495405) (xy 96.439724 54.480042)
			(xy 96.38573 54.472285) (xy 96.358456 54.471824) (xy 95.494856 54.471824) (xy 95.46759 54.472341)
			(xy 95.413613 54.480108) (xy 95.36129 54.495476) (xy 95.311688 54.518134) (xy 95.265814 54.54762)
			(xy 95.224603 54.583334) (xy 95.188894 54.624549) (xy 95.159413 54.670426) (xy 95.136761 54.720032)
			(xy 95.121399 54.772356) (xy 95.113638 54.826334) (xy 92.50807 54.826334) (xy 92.50807 50.450039)
			(xy 93.729289 50.450039) (xy 93.729289 50.535789) (xy 93.737201 50.621172) (xy 93.752957 50.705462)
			(xy 93.776424 50.787938) (xy 93.8074 50.867897) (xy 93.845622 50.944657) (xy 93.890763 51.017563)
			(xy 93.942439 51.085992) (xy 94.000208 51.149362) (xy 94.063578 51.207131) (xy 94.132007 51.258807)
			(xy 94.204913 51.303948) (xy 94.281673 51.34217) (xy 94.361632 51.373146) (xy 94.444108 51.396613)
			(xy 94.528398 51.412369) (xy 94.613781 51.420281) (xy 94.699531 51.420281) (xy 94.784914 51.412369)
			(xy 94.869204 51.396613) (xy 94.95168 51.373146) (xy 95.031639 51.34217) (xy 95.108399 51.303948)
			(xy 95.181305 51.258807) (xy 95.249734 51.207131) (xy 95.313104 51.149362) (xy 95.370873 51.085992)
			(xy 95.422549 51.017563) (xy 95.46769 50.944657) (xy 95.505912 50.867897) (xy 95.536888 50.787938)
			(xy 95.560355 50.705462) (xy 95.576111 50.621172) (xy 95.584023 50.535789) (xy 95.584518 50.492914)
			(xy 95.584023 50.450039) (xy 96.269289 50.450039) (xy 96.269289 50.535789) (xy 96.277201 50.621172)
			(xy 96.292957 50.705462) (xy 96.316424 50.787938) (xy 96.3474 50.867897) (xy 96.385622 50.944657)
			(xy 96.430763 51.017563) (xy 96.482439 51.085992) (xy 96.540208 51.149362) (xy 96.603578 51.207131)
			(xy 96.672007 51.258807) (xy 96.744913 51.303948) (xy 96.821673 51.34217) (xy 96.901632 51.373146)
			(xy 96.984108 51.396613) (xy 97.068398 51.412369) (xy 97.153781 51.420281) (xy 97.239531 51.420281)
			(xy 97.324914 51.412369) (xy 97.409204 51.396613) (xy 97.49168 51.373146) (xy 97.571639 51.34217)
			(xy 97.648399 51.303948) (xy 97.721305 51.258807) (xy 97.789734 51.207131) (xy 97.853104 51.149362)
			(xy 97.910873 51.085992) (xy 97.962549 51.017563) (xy 98.00769 50.944657) (xy 98.045912 50.867897)
			(xy 98.076888 50.787938) (xy 98.100355 50.705462) (xy 98.116111 50.621172) (xy 98.124023 50.535789)
			(xy 98.124518 50.492914) (xy 98.124023 50.450039) (xy 98.116111 50.364656) (xy 98.100355 50.280366)
			(xy 98.076888 50.19789) (xy 98.045912 50.117931) (xy 98.00769 50.041171) (xy 97.962549 49.968265)
			(xy 97.910873 49.899836) (xy 97.853104 49.836466) (xy 97.789734 49.778697) (xy 97.721305 49.727021)
			(xy 97.648399 49.68188) (xy 97.571639 49.643658) (xy 97.49168 49.612682) (xy 97.409204 49.589215)
			(xy 97.324914 49.573459) (xy 97.239531 49.565547) (xy 97.153781 49.565547) (xy 97.068398 49.573459)
			(xy 96.984108 49.589215) (xy 96.901632 49.612682) (xy 96.821673 49.643658) (xy 96.744913 49.68188)
			(xy 96.672007 49.727021) (xy 96.603578 49.778697) (xy 96.540208 49.836466) (xy 96.482439 49.899836)
			(xy 96.430763 49.968265) (xy 96.385622 50.041171) (xy 96.3474 50.117931) (xy 96.316424 50.19789)
			(xy 96.292957 50.280366) (xy 96.277201 50.364656) (xy 96.269289 50.450039) (xy 95.584023 50.450039)
			(xy 95.576111 50.364656) (xy 95.560355 50.280366) (xy 95.536888 50.19789) (xy 95.505912 50.117931)
			(xy 95.46769 50.041171) (xy 95.422549 49.968265) (xy 95.370873 49.899836) (xy 95.313104 49.836466)
			(xy 95.249734 49.778697) (xy 95.181305 49.727021) (xy 95.108399 49.68188) (xy 95.031639 49.643658)
			(xy 94.95168 49.612682) (xy 94.869204 49.589215) (xy 94.784914 49.573459) (xy 94.699531 49.565547)
			(xy 94.613781 49.565547) (xy 94.528398 49.573459) (xy 94.444108 49.589215) (xy 94.361632 49.612682)
			(xy 94.281673 49.643658) (xy 94.204913 49.68188) (xy 94.132007 49.727021) (xy 94.063578 49.778697)
			(xy 94.000208 49.836466) (xy 93.942439 49.899836) (xy 93.890763 49.968265) (xy 93.845622 50.041171)
			(xy 93.8074 50.117931) (xy 93.776424 50.19789) (xy 93.752957 50.280366) (xy 93.737201 50.364656)
			(xy 93.729289 50.450039) (xy 92.50807 50.450039) (xy 92.50807 44.925539) (xy 93.706937 44.925539)
			(xy 93.706937 45.011289) (xy 93.714849 45.096672) (xy 93.730605 45.180962) (xy 93.754072 45.263438)
			(xy 93.785048 45.343397) (xy 93.82327 45.420157) (xy 93.868411 45.493063) (xy 93.920087 45.561492)
			(xy 93.977856 45.624862) (xy 94.041226 45.682631) (xy 94.109655 45.734307) (xy 94.182561 45.779448)
			(xy 94.259321 45.81767) (xy 94.33928 45.848646) (xy 94.421756 45.872113) (xy 94.506046 45.887869)
			(xy 94.591429 45.895781) (xy 94.677179 45.895781) (xy 94.762562 45.887869) (xy 94.846852 45.872113)
			(xy 94.929328 45.848646) (xy 95.009287 45.81767) (xy 95.086047 45.779448) (xy 95.158953 45.734307)
			(xy 95.227382 45.682631) (xy 95.290752 45.624862) (xy 95.348521 45.561492) (xy 95.400197 45.493063)
			(xy 95.445338 45.420157) (xy 95.48356 45.343397) (xy 95.514536 45.263438) (xy 95.538003 45.180962)
			(xy 95.553759 45.096672) (xy 95.561671 45.011289) (xy 95.562166 44.968414) (xy 95.561671 44.925539)
			(xy 96.246937 44.925539) (xy 96.246937 45.011289) (xy 96.254849 45.096672) (xy 96.270605 45.180962)
			(xy 96.294072 45.263438) (xy 96.325048 45.343397) (xy 96.36327 45.420157) (xy 96.408411 45.493063)
			(xy 96.460087 45.561492) (xy 96.517856 45.624862) (xy 96.581226 45.682631) (xy 96.649655 45.734307)
			(xy 96.722561 45.779448) (xy 96.799321 45.81767) (xy 96.87928 45.848646) (xy 96.961756 45.872113)
			(xy 97.046046 45.887869) (xy 97.131429 45.895781) (xy 97.217179 45.895781) (xy 97.302562 45.887869)
			(xy 97.386852 45.872113) (xy 97.469328 45.848646) (xy 97.549287 45.81767) (xy 97.626047 45.779448)
			(xy 97.698953 45.734307) (xy 97.767382 45.682631) (xy 97.830752 45.624862) (xy 97.888521 45.561492)
			(xy 97.940197 45.493063) (xy 97.985338 45.420157) (xy 98.02356 45.343397) (xy 98.054536 45.263438)
			(xy 98.078003 45.180962) (xy 98.093759 45.096672) (xy 98.101671 45.011289) (xy 98.102166 44.968414)
			(xy 98.101671 44.925539) (xy 98.093759 44.840156) (xy 98.078003 44.755866) (xy 98.054536 44.67339)
			(xy 98.02356 44.593431) (xy 97.985338 44.516671) (xy 97.940197 44.443765) (xy 97.888521 44.375336)
			(xy 97.830752 44.311966) (xy 97.767382 44.254197) (xy 97.698953 44.202521) (xy 97.626047 44.15738)
			(xy 97.549287 44.119158) (xy 97.469328 44.088182) (xy 97.386852 44.064715) (xy 97.302562 44.048959)
			(xy 97.217179 44.041047) (xy 97.131429 44.041047) (xy 97.046046 44.048959) (xy 96.961756 44.064715)
			(xy 96.87928 44.088182) (xy 96.799321 44.119158) (xy 96.722561 44.15738) (xy 96.649655 44.202521)
			(xy 96.581226 44.254197) (xy 96.517856 44.311966) (xy 96.460087 44.375336) (xy 96.408411 44.443765)
			(xy 96.36327 44.516671) (xy 96.325048 44.593431) (xy 96.294072 44.67339) (xy 96.270605 44.755866)
			(xy 96.254849 44.840156) (xy 96.246937 44.925539) (xy 95.561671 44.925539) (xy 95.553759 44.840156)
			(xy 95.538003 44.755866) (xy 95.514536 44.67339) (xy 95.48356 44.593431) (xy 95.445338 44.516671)
			(xy 95.400197 44.443765) (xy 95.348521 44.375336) (xy 95.290752 44.311966) (xy 95.227382 44.254197)
			(xy 95.158953 44.202521) (xy 95.086047 44.15738) (xy 95.009287 44.119158) (xy 94.929328 44.088182)
			(xy 94.846852 44.064715) (xy 94.762562 44.048959) (xy 94.677179 44.041047) (xy 94.591429 44.041047)
			(xy 94.506046 44.048959) (xy 94.421756 44.064715) (xy 94.33928 44.088182) (xy 94.259321 44.119158)
			(xy 94.182561 44.15738) (xy 94.109655 44.202521) (xy 94.041226 44.254197) (xy 93.977856 44.311966)
			(xy 93.920087 44.375336) (xy 93.868411 44.443765) (xy 93.82327 44.516671) (xy 93.785048 44.593431)
			(xy 93.754072 44.67339) (xy 93.730605 44.755866) (xy 93.714849 44.840156) (xy 93.706937 44.925539)
			(xy 92.50807 44.925539) (xy 92.50807 40.580426) (xy 95.09116 40.580426) (xy 95.09116 40.634974) (xy 95.098923 40.688967)
			(xy 95.114291 40.741306) (xy 95.136951 40.790925) (xy 95.166442 40.836814) (xy 95.202164 40.878039)
			(xy 95.243389 40.91376) (xy 95.289279 40.943251) (xy 95.338898 40.965911) (xy 95.391237 40.981278)
			(xy 95.44523 40.989041) (xy 95.472504 40.989504) (xy 96.336104 40.989504) (xy 96.36337 40.988933)
			(xy 96.417347 40.981172) (xy 96.469671 40.965808) (xy 96.519275 40.943154) (xy 96.56515 40.913671)
			(xy 96.606363 40.87796) (xy 96.642074 40.836747) (xy 96.671556 40.790871) (xy 96.69421 40.741267)
			(xy 96.709573 40.688944) (xy 96.717334 40.634966) (xy 96.717334 40.580434) (xy 96.709573 40.526456)
			(xy 96.69421 40.474133) (xy 96.671556 40.424529) (xy 96.642074 40.378653) (xy 96.606363 40.33744)
			(xy 96.56515 40.301729) (xy 96.519275 40.272246) (xy 96.469671 40.249592) (xy 96.417347 40.234228)
			(xy 96.36337 40.226467) (xy 96.336104 40.22598) (xy 95.472504 40.22598) (xy 95.44523 40.226359) (xy 95.391237 40.234122)
			(xy 95.338898 40.249489) (xy 95.289279 40.272149) (xy 95.243389 40.30164) (xy 95.202164 40.337361)
			(xy 95.166442 40.378586) (xy 95.136951 40.424475) (xy 95.114291 40.474094) (xy 95.098923 40.526433)
			(xy 95.09116 40.580426) (xy 92.50807 40.580426) (xy 92.50807 38.575539) (xy 93.706937 38.575539)
			(xy 93.706937 38.661289) (xy 93.714849 38.746672) (xy 93.730605 38.830962) (xy 93.754072 38.913438)
			(xy 93.785048 38.993397) (xy 93.82327 39.070157) (xy 93.868411 39.143063) (xy 93.920087 39.211492)
			(xy 93.977856 39.274862) (xy 94.041226 39.332631) (xy 94.109655 39.384307) (xy 94.182561 39.429448)
			(xy 94.259321 39.46767) (xy 94.33928 39.498646) (xy 94.421756 39.522113) (xy 94.506046 39.537869)
			(xy 94.591429 39.545781) (xy 94.677179 39.545781) (xy 94.762562 39.537869) (xy 94.846852 39.522113)
			(xy 94.929328 39.498646) (xy 95.009287 39.46767) (xy 95.086047 39.429448) (xy 95.158953 39.384307)
			(xy 95.227382 39.332631) (xy 95.290752 39.274862) (xy 95.348521 39.211492) (xy 95.400197 39.143063)
			(xy 95.445338 39.070157) (xy 95.48356 38.993397) (xy 95.514536 38.913438) (xy 95.538003 38.830962)
			(xy 95.553759 38.746672) (xy 95.561671 38.661289) (xy 95.562166 38.618414) (xy 95.561671 38.575539)
			(xy 96.246937 38.575539) (xy 96.246937 38.661289) (xy 96.254849 38.746672) (xy 96.270605 38.830962)
			(xy 96.294072 38.913438) (xy 96.325048 38.993397) (xy 96.36327 39.070157) (xy 96.408411 39.143063)
			(xy 96.460087 39.211492) (xy 96.517856 39.274862) (xy 96.581226 39.332631) (xy 96.649655 39.384307)
			(xy 96.722561 39.429448) (xy 96.799321 39.46767) (xy 96.87928 39.498646) (xy 96.961756 39.522113)
			(xy 97.046046 39.537869) (xy 97.131429 39.545781) (xy 97.217179 39.545781) (xy 97.302562 39.537869)
			(xy 97.386852 39.522113) (xy 97.469328 39.498646) (xy 97.549287 39.46767) (xy 97.626047 39.429448)
			(xy 97.698953 39.384307) (xy 97.767382 39.332631) (xy 97.830752 39.274862) (xy 97.888521 39.211492)
			(xy 97.940197 39.143063) (xy 97.985338 39.070157) (xy 98.02356 38.993397) (xy 98.054536 38.913438)
			(xy 98.078003 38.830962) (xy 98.093759 38.746672) (xy 98.101671 38.661289) (xy 98.102166 38.618414)
			(xy 98.101671 38.575539) (xy 98.093759 38.490156) (xy 98.078003 38.405866) (xy 98.054536 38.32339)
			(xy 98.02356 38.243431) (xy 97.985338 38.166671) (xy 97.940197 38.093765) (xy 97.888521 38.025336)
			(xy 97.830752 37.961966) (xy 97.767382 37.904197) (xy 97.698953 37.852521) (xy 97.626047 37.80738)
			(xy 97.549287 37.769158) (xy 97.469328 37.738182) (xy 97.386852 37.714715) (xy 97.302562 37.698959)
			(xy 97.217179 37.691047) (xy 97.131429 37.691047) (xy 97.046046 37.698959) (xy 96.961756 37.714715)
			(xy 96.87928 37.738182) (xy 96.799321 37.769158) (xy 96.722561 37.80738) (xy 96.649655 37.852521)
			(xy 96.581226 37.904197) (xy 96.517856 37.961966) (xy 96.460087 38.025336) (xy 96.408411 38.093765)
			(xy 96.36327 38.166671) (xy 96.325048 38.243431) (xy 96.294072 38.32339) (xy 96.270605 38.405866)
			(xy 96.254849 38.490156) (xy 96.246937 38.575539) (xy 95.561671 38.575539) (xy 95.553759 38.490156)
			(xy 95.538003 38.405866) (xy 95.514536 38.32339) (xy 95.48356 38.243431) (xy 95.445338 38.166671)
			(xy 95.400197 38.093765) (xy 95.348521 38.025336) (xy 95.290752 37.961966) (xy 95.227382 37.904197)
			(xy 95.158953 37.852521) (xy 95.086047 37.80738) (xy 95.009287 37.769158) (xy 94.929328 37.738182)
			(xy 94.846852 37.714715) (xy 94.762562 37.698959) (xy 94.677179 37.691047) (xy 94.591429 37.691047)
			(xy 94.506046 37.698959) (xy 94.421756 37.714715) (xy 94.33928 37.738182) (xy 94.259321 37.769158)
			(xy 94.182561 37.80738) (xy 94.109655 37.852521) (xy 94.041226 37.904197) (xy 93.977856 37.961966)
			(xy 93.920087 38.025336) (xy 93.868411 38.093765) (xy 93.82327 38.166671) (xy 93.785048 38.243431)
			(xy 93.754072 38.32339) (xy 93.730605 38.405866) (xy 93.714849 38.490156) (xy 93.706937 38.575539)
			(xy 92.50807 38.575539) (xy 92.50807 32.685787) (xy 99.092753 32.685787) (xy 99.092753 32.771537)
			(xy 99.100665 32.85692) (xy 99.116421 32.94121) (xy 99.139888 33.023686) (xy 99.170864 33.103645)
			(xy 99.209086 33.180405) (xy 99.254227 33.253311) (xy 99.305903 33.32174) (xy 99.363672 33.38511)
			(xy 99.427042 33.442879) (xy 99.495471 33.494555) (xy 99.568377 33.539696) (xy 99.645137 33.577918)
			(xy 99.725096 33.608894) (xy 99.807572 33.632361) (xy 99.891862 33.648117) (xy 99.977245 33.656029)
			(xy 100.062995 33.656029) (xy 100.148378 33.648117) (xy 100.232668 33.632361) (xy 100.315144 33.608894)
			(xy 100.395103 33.577918) (xy 100.471863 33.539696) (xy 100.544769 33.494555) (xy 100.613198 33.442879)
			(xy 100.676568 33.38511) (xy 100.734337 33.32174) (xy 100.786013 33.253311) (xy 100.831154 33.180405)
			(xy 100.869376 33.103645) (xy 100.900352 33.023686) (xy 100.923819 32.94121) (xy 100.939575 32.85692)
			(xy 100.947487 32.771537) (xy 100.947982 32.728662) (xy 100.947487 32.685787) (xy 101.632753 32.685787)
			(xy 101.632753 32.771537) (xy 101.640665 32.85692) (xy 101.656421 32.94121) (xy 101.679888 33.023686)
			(xy 101.710864 33.103645) (xy 101.749086 33.180405) (xy 101.794227 33.253311) (xy 101.845903 33.32174)
			(xy 101.903672 33.38511) (xy 101.967042 33.442879) (xy 102.035471 33.494555) (xy 102.108377 33.539696)
			(xy 102.185137 33.577918) (xy 102.265096 33.608894) (xy 102.347572 33.632361) (xy 102.431862 33.648117)
			(xy 102.517245 33.656029) (xy 102.602995 33.656029) (xy 102.688378 33.648117) (xy 102.772668 33.632361)
			(xy 102.855144 33.608894) (xy 102.935103 33.577918) (xy 103.011863 33.539696) (xy 103.084769 33.494555)
			(xy 103.153198 33.442879) (xy 103.216568 33.38511) (xy 103.274337 33.32174) (xy 103.326013 33.253311)
			(xy 103.371154 33.180405) (xy 103.409376 33.103645) (xy 103.440352 33.023686) (xy 103.463819 32.94121)
			(xy 103.479575 32.85692) (xy 103.487487 32.771537) (xy 103.487982 32.728662) (xy 103.487487 32.685787)
			(xy 103.479575 32.600404) (xy 103.463819 32.516114) (xy 103.440352 32.433638) (xy 103.409376 32.353679)
			(xy 103.371154 32.276919) (xy 103.326013 32.204013) (xy 103.274337 32.135584) (xy 103.216568 32.072214)
			(xy 103.153198 32.014445) (xy 103.084769 31.962769) (xy 103.011863 31.917628) (xy 102.935103 31.879406)
			(xy 102.855144 31.84843) (xy 102.772668 31.824963) (xy 102.688378 31.809207) (xy 102.602995 31.801295)
			(xy 102.517245 31.801295) (xy 102.431862 31.809207) (xy 102.347572 31.824963) (xy 102.265096 31.84843)
			(xy 102.185137 31.879406) (xy 102.108377 31.917628) (xy 102.035471 31.962769) (xy 101.967042 32.014445)
			(xy 101.903672 32.072214) (xy 101.845903 32.135584) (xy 101.794227 32.204013) (xy 101.749086 32.276919)
			(xy 101.710864 32.353679) (xy 101.679888 32.433638) (xy 101.656421 32.516114) (xy 101.640665 32.600404)
			(xy 101.632753 32.685787) (xy 100.947487 32.685787) (xy 100.939575 32.600404) (xy 100.923819 32.516114)
			(xy 100.900352 32.433638) (xy 100.869376 32.353679) (xy 100.831154 32.276919) (xy 100.786013 32.204013)
			(xy 100.734337 32.135584) (xy 100.676568 32.072214) (xy 100.613198 32.014445) (xy 100.544769 31.962769)
			(xy 100.471863 31.917628) (xy 100.395103 31.879406) (xy 100.315144 31.84843) (xy 100.232668 31.824963)
			(xy 100.148378 31.809207) (xy 100.062995 31.801295) (xy 99.977245 31.801295) (xy 99.891862 31.809207)
			(xy 99.807572 31.824963) (xy 99.725096 31.84843) (xy 99.645137 31.879406) (xy 99.568377 31.917628)
			(xy 99.495471 31.962769) (xy 99.427042 32.014445) (xy 99.363672 32.072214) (xy 99.305903 32.135584)
			(xy 99.254227 32.204013) (xy 99.209086 32.276919) (xy 99.170864 32.353679) (xy 99.139888 32.433638)
			(xy 99.116421 32.516114) (xy 99.100665 32.600404) (xy 99.092753 32.685787) (xy 92.50807 32.685787)
			(xy 92.50807 30.712026) (xy 100.476968 30.712026) (xy 100.476968 30.766574) (xy 100.484731 30.820568)
			(xy 100.5001 30.872907) (xy 100.522761 30.922526) (xy 100.552253 30.968414) (xy 100.587976 31.009639)
			(xy 100.629202 31.045359) (xy 100.675092 31.074849) (xy 100.724712 31.097507) (xy 100.777052 31.112873)
			(xy 100.831046 31.120634) (xy 100.85832 31.121096) (xy 101.72192 31.121096) (xy 101.749186 31.12054)
			(xy 101.803163 31.112777) (xy 101.855485 31.097411) (xy 101.905088 31.074756) (xy 101.950963 31.045272)
			(xy 101.992174 31.00956) (xy 102.027884 30.968347) (xy 102.057366 30.922471) (xy 102.080018 30.872866)
			(xy 102.095381 30.820543) (xy 102.103142 30.766566) (xy 102.103142 30.712034) (xy 102.095381 30.658057)
			(xy 102.080018 30.605734) (xy 102.057366 30.556129) (xy 102.027884 30.510253) (xy 101.992174 30.46904)
			(xy 101.950963 30.433328) (xy 101.905088 30.403844) (xy 101.855485 30.381189) (xy 101.803163 30.365823)
			(xy 101.749186 30.35806) (xy 101.72192 30.357572) (xy 100.85832 30.357572) (xy 100.831046 30.357966)
			(xy 100.777052 30.365727) (xy 100.724712 30.381093) (xy 100.675092 30.403751) (xy 100.629202 30.433241)
			(xy 100.587976 30.468961) (xy 100.552253 30.510186) (xy 100.522761 30.556074) (xy 100.5001 30.605693)
			(xy 100.484731 30.658032) (xy 100.476968 30.712026) (xy 92.50807 30.712026) (xy 92.50807 26.335787)
			(xy 99.092753 26.335787) (xy 99.092753 26.421537) (xy 99.100665 26.50692) (xy 99.116421 26.59121)
			(xy 99.139888 26.673686) (xy 99.170864 26.753645) (xy 99.209086 26.830405) (xy 99.254227 26.903311)
			(xy 99.305903 26.97174) (xy 99.363672 27.03511) (xy 99.427042 27.092879) (xy 99.495471 27.144555)
			(xy 99.568377 27.189696) (xy 99.645137 27.227918) (xy 99.725096 27.258894) (xy 99.807572 27.282361)
			(xy 99.891862 27.298117) (xy 99.977245 27.306029) (xy 100.062995 27.306029) (xy 100.148378 27.298117)
			(xy 100.232668 27.282361) (xy 100.315144 27.258894) (xy 100.395103 27.227918) (xy 100.471863 27.189696)
			(xy 100.544769 27.144555) (xy 100.613198 27.092879) (xy 100.676568 27.03511) (xy 100.734337 26.97174)
			(xy 100.786013 26.903311) (xy 100.831154 26.830405) (xy 100.869376 26.753645) (xy 100.900352 26.673686)
			(xy 100.923819 26.59121) (xy 100.939575 26.50692) (xy 100.947487 26.421537) (xy 100.947982 26.378662)
			(xy 100.947487 26.335787) (xy 101.632753 26.335787) (xy 101.632753 26.421537) (xy 101.640665 26.50692)
			(xy 101.656421 26.59121) (xy 101.679888 26.673686) (xy 101.710864 26.753645) (xy 101.749086 26.830405)
			(xy 101.794227 26.903311) (xy 101.845903 26.97174) (xy 101.903672 27.03511) (xy 101.967042 27.092879)
			(xy 102.035471 27.144555) (xy 102.108377 27.189696) (xy 102.185137 27.227918) (xy 102.265096 27.258894)
			(xy 102.347572 27.282361) (xy 102.431862 27.298117) (xy 102.517245 27.306029) (xy 102.602995 27.306029)
			(xy 102.688378 27.298117) (xy 102.772668 27.282361) (xy 102.855144 27.258894) (xy 102.935103 27.227918)
			(xy 103.011863 27.189696) (xy 103.084769 27.144555) (xy 103.153198 27.092879) (xy 103.216568 27.03511)
			(xy 103.274337 26.97174) (xy 103.326013 26.903311) (xy 103.371154 26.830405) (xy 103.409376 26.753645)
			(xy 103.440352 26.673686) (xy 103.463819 26.59121) (xy 103.479575 26.50692) (xy 103.487487 26.421537)
			(xy 103.487982 26.378662) (xy 103.487487 26.335787) (xy 103.479575 26.250404) (xy 103.463819 26.166114)
			(xy 103.440352 26.083638) (xy 103.409376 26.003679) (xy 103.371154 25.926919) (xy 103.326013 25.854013)
			(xy 103.274337 25.785584) (xy 103.216568 25.722214) (xy 103.153198 25.664445) (xy 103.084769 25.612769)
			(xy 103.011863 25.567628) (xy 102.935103 25.529406) (xy 102.855144 25.49843) (xy 102.772668 25.474963)
			(xy 102.688378 25.459207) (xy 102.602995 25.451295) (xy 102.517245 25.451295) (xy 102.431862 25.459207)
			(xy 102.347572 25.474963) (xy 102.265096 25.49843) (xy 102.185137 25.529406) (xy 102.108377 25.567628)
			(xy 102.035471 25.612769) (xy 101.967042 25.664445) (xy 101.903672 25.722214) (xy 101.845903 25.785584)
			(xy 101.794227 25.854013) (xy 101.749086 25.926919) (xy 101.710864 26.003679) (xy 101.679888 26.083638)
			(xy 101.656421 26.166114) (xy 101.640665 26.250404) (xy 101.632753 26.335787) (xy 100.947487 26.335787)
			(xy 100.939575 26.250404) (xy 100.923819 26.166114) (xy 100.900352 26.083638) (xy 100.869376 26.003679)
			(xy 100.831154 25.926919) (xy 100.786013 25.854013) (xy 100.734337 25.785584) (xy 100.676568 25.722214)
			(xy 100.613198 25.664445) (xy 100.544769 25.612769) (xy 100.471863 25.567628) (xy 100.395103 25.529406)
			(xy 100.315144 25.49843) (xy 100.232668 25.474963) (xy 100.148378 25.459207) (xy 100.062995 25.451295)
			(xy 99.977245 25.451295) (xy 99.891862 25.459207) (xy 99.807572 25.474963) (xy 99.725096 25.49843)
			(xy 99.645137 25.529406) (xy 99.568377 25.567628) (xy 99.495471 25.612769) (xy 99.427042 25.664445)
			(xy 99.363672 25.722214) (xy 99.305903 25.785584) (xy 99.254227 25.854013) (xy 99.209086 25.926919)
			(xy 99.170864 26.003679) (xy 99.139888 26.083638) (xy 99.116421 26.166114) (xy 99.100665 26.250404)
			(xy 99.092753 26.335787) (xy 92.50807 26.335787) (xy 92.50807 20.841513) (xy 99.085133 20.841513)
			(xy 99.085133 20.927263) (xy 99.093045 21.012646) (xy 99.108801 21.096936) (xy 99.132268 21.179412)
			(xy 99.163244 21.259371) (xy 99.201466 21.336131) (xy 99.246607 21.409037) (xy 99.298283 21.477466)
			(xy 99.356052 21.540836) (xy 99.419422 21.598605) (xy 99.487851 21.650281) (xy 99.560757 21.695422)
			(xy 99.637517 21.733644) (xy 99.717476 21.76462) (xy 99.799952 21.788087) (xy 99.884242 21.803843)
			(xy 99.969625 21.811755) (xy 100.055375 21.811755) (xy 100.140758 21.803843) (xy 100.225048 21.788087)
			(xy 100.307524 21.76462) (xy 100.387483 21.733644) (xy 100.464243 21.695422) (xy 100.537149 21.650281)
			(xy 100.605578 21.598605) (xy 100.668948 21.540836) (xy 100.726717 21.477466) (xy 100.778393 21.409037)
			(xy 100.823534 21.336131) (xy 100.861756 21.259371) (xy 100.892732 21.179412) (xy 100.916199 21.096936)
			(xy 100.931955 21.012646) (xy 100.939867 20.927263) (xy 100.940362 20.884388) (xy 100.939867 20.841513)
			(xy 101.625133 20.841513) (xy 101.625133 20.927263) (xy 101.633045 21.012646) (xy 101.648801 21.096936)
			(xy 101.672268 21.179412) (xy 101.703244 21.259371) (xy 101.741466 21.336131) (xy 101.786607 21.409037)
			(xy 101.838283 21.477466) (xy 101.896052 21.540836) (xy 101.959422 21.598605) (xy 102.027851 21.650281)
			(xy 102.100757 21.695422) (xy 102.177517 21.733644) (xy 102.257476 21.76462) (xy 102.339952 21.788087)
			(xy 102.424242 21.803843) (xy 102.509625 21.811755) (xy 102.595375 21.811755) (xy 102.680758 21.803843)
			(xy 102.765048 21.788087) (xy 102.847524 21.76462) (xy 102.927483 21.733644) (xy 103.004243 21.695422)
			(xy 103.077149 21.650281) (xy 103.145578 21.598605) (xy 103.208948 21.540836) (xy 103.266717 21.477466)
			(xy 103.318393 21.409037) (xy 103.363534 21.336131) (xy 103.401756 21.259371) (xy 103.432732 21.179412)
			(xy 103.456199 21.096936) (xy 103.471955 21.012646) (xy 103.479867 20.927263) (xy 103.480362 20.884388)
			(xy 103.479867 20.841513) (xy 104.165133 20.841513) (xy 104.165133 20.927263) (xy 104.173045 21.012646)
			(xy 104.188801 21.096936) (xy 104.212268 21.179412) (xy 104.243244 21.259371) (xy 104.281466 21.336131)
			(xy 104.326607 21.409037) (xy 104.378283 21.477466) (xy 104.436052 21.540836) (xy 104.499422 21.598605)
			(xy 104.567851 21.650281) (xy 104.640757 21.695422) (xy 104.717517 21.733644) (xy 104.797476 21.76462)
			(xy 104.879952 21.788087) (xy 104.964242 21.803843) (xy 105.049625 21.811755) (xy 105.135375 21.811755)
			(xy 105.220758 21.803843) (xy 105.305048 21.788087) (xy 105.387524 21.76462) (xy 105.467483 21.733644)
			(xy 105.544243 21.695422) (xy 105.617149 21.650281) (xy 105.685578 21.598605) (xy 105.748948 21.540836)
			(xy 105.806717 21.477466) (xy 105.858393 21.409037) (xy 105.903534 21.336131) (xy 105.941756 21.259371)
			(xy 105.972732 21.179412) (xy 105.996199 21.096936) (xy 106.011955 21.012646) (xy 106.019867 20.927263)
			(xy 106.020362 20.884388) (xy 106.019867 20.841513) (xy 106.011955 20.75613) (xy 105.996199 20.67184)
			(xy 105.972732 20.589364) (xy 105.941756 20.509405) (xy 105.903534 20.432645) (xy 105.858393 20.359739)
			(xy 105.806717 20.29131) (xy 105.748948 20.22794) (xy 105.685578 20.170171) (xy 105.617149 20.118495)
			(xy 105.544243 20.073354) (xy 105.467483 20.035132) (xy 105.387524 20.004156) (xy 105.305048 19.980689)
			(xy 105.220758 19.964933) (xy 105.135375 19.957021) (xy 105.049625 19.957021) (xy 104.964242 19.964933)
			(xy 104.879952 19.980689) (xy 104.797476 20.004156) (xy 104.717517 20.035132) (xy 104.640757 20.073354)
			(xy 104.567851 20.118495) (xy 104.499422 20.170171) (xy 104.436052 20.22794) (xy 104.378283 20.29131)
			(xy 104.326607 20.359739) (xy 104.281466 20.432645) (xy 104.243244 20.509405) (xy 104.212268 20.589364)
			(xy 104.188801 20.67184) (xy 104.173045 20.75613) (xy 104.165133 20.841513) (xy 103.479867 20.841513)
			(xy 103.471955 20.75613) (xy 103.456199 20.67184) (xy 103.432732 20.589364) (xy 103.401756 20.509405)
			(xy 103.363534 20.432645) (xy 103.318393 20.359739) (xy 103.266717 20.29131) (xy 103.208948 20.22794)
			(xy 103.145578 20.170171) (xy 103.077149 20.118495) (xy 103.004243 20.073354) (xy 102.927483 20.035132)
			(xy 102.847524 20.004156) (xy 102.765048 19.980689) (xy 102.680758 19.964933) (xy 102.595375 19.957021)
			(xy 102.509625 19.957021) (xy 102.424242 19.964933) (xy 102.339952 19.980689) (xy 102.257476 20.004156)
			(xy 102.177517 20.035132) (xy 102.100757 20.073354) (xy 102.027851 20.118495) (xy 101.959422 20.170171)
			(xy 101.896052 20.22794) (xy 101.838283 20.29131) (xy 101.786607 20.359739) (xy 101.741466 20.432645)
			(xy 101.703244 20.509405) (xy 101.672268 20.589364) (xy 101.648801 20.67184) (xy 101.633045 20.75613)
			(xy 101.625133 20.841513) (xy 100.939867 20.841513) (xy 100.931955 20.75613) (xy 100.916199 20.67184)
			(xy 100.892732 20.589364) (xy 100.861756 20.509405) (xy 100.823534 20.432645) (xy 100.778393 20.359739)
			(xy 100.726717 20.29131) (xy 100.668948 20.22794) (xy 100.605578 20.170171) (xy 100.537149 20.118495)
			(xy 100.464243 20.073354) (xy 100.387483 20.035132) (xy 100.307524 20.004156) (xy 100.225048 19.980689)
			(xy 100.140758 19.964933) (xy 100.055375 19.957021) (xy 99.969625 19.957021) (xy 99.884242 19.964933)
			(xy 99.799952 19.980689) (xy 99.717476 20.004156) (xy 99.637517 20.035132) (xy 99.560757 20.073354)
			(xy 99.487851 20.118495) (xy 99.419422 20.170171) (xy 99.356052 20.22794) (xy 99.298283 20.29131)
			(xy 99.246607 20.359739) (xy 99.201466 20.432645) (xy 99.163244 20.509405) (xy 99.132268 20.589364)
			(xy 99.108801 20.67184) (xy 99.093045 20.75613) (xy 99.085133 20.841513) (xy 92.50807 20.841513)
			(xy 92.50807 14.491513) (xy 99.085133 14.491513) (xy 99.085133 14.577263) (xy 99.093045 14.662646)
			(xy 99.108801 14.746936) (xy 99.132268 14.829412) (xy 99.163244 14.909371) (xy 99.201466 14.986131)
			(xy 99.246607 15.059037) (xy 99.298283 15.127466) (xy 99.356052 15.190836) (xy 99.419422 15.248605)
			(xy 99.487851 15.300281) (xy 99.560757 15.345422) (xy 99.637517 15.383644) (xy 99.717476 15.41462)
			(xy 99.799952 15.438087) (xy 99.884242 15.453843) (xy 99.969625 15.461755) (xy 100.055375 15.461755)
			(xy 100.140758 15.453843) (xy 100.225048 15.438087) (xy 100.307524 15.41462) (xy 100.387483 15.383644)
			(xy 100.464243 15.345422) (xy 100.537149 15.300281) (xy 100.605578 15.248605) (xy 100.668948 15.190836)
			(xy 100.726717 15.127466) (xy 100.778393 15.059037) (xy 100.823534 14.986131) (xy 100.861756 14.909371)
			(xy 100.892732 14.829412) (xy 100.916199 14.746936) (xy 100.931955 14.662646) (xy 100.939867 14.577263)
			(xy 100.940362 14.534388) (xy 100.939867 14.491513) (xy 101.625133 14.491513) (xy 101.625133 14.577263)
			(xy 101.633045 14.662646) (xy 101.648801 14.746936) (xy 101.672268 14.829412) (xy 101.703244 14.909371)
			(xy 101.741466 14.986131) (xy 101.786607 15.059037) (xy 101.838283 15.127466) (xy 101.896052 15.190836)
			(xy 101.959422 15.248605) (xy 102.027851 15.300281) (xy 102.100757 15.345422) (xy 102.177517 15.383644)
			(xy 102.257476 15.41462) (xy 102.339952 15.438087) (xy 102.424242 15.453843) (xy 102.509625 15.461755)
			(xy 102.595375 15.461755) (xy 102.680758 15.453843) (xy 102.765048 15.438087) (xy 102.847524 15.41462)
			(xy 102.927483 15.383644) (xy 103.004243 15.345422) (xy 103.077149 15.300281) (xy 103.145578 15.248605)
			(xy 103.208948 15.190836) (xy 103.266717 15.127466) (xy 103.318393 15.059037) (xy 103.363534 14.986131)
			(xy 103.401756 14.909371) (xy 103.432732 14.829412) (xy 103.456199 14.746936) (xy 103.471955 14.662646)
			(xy 103.479867 14.577263) (xy 103.480362 14.534388) (xy 103.479867 14.491513) (xy 104.165133 14.491513)
			(xy 104.165133 14.577263) (xy 104.173045 14.662646) (xy 104.188801 14.746936) (xy 104.212268 14.829412)
			(xy 104.243244 14.909371) (xy 104.281466 14.986131) (xy 104.326607 15.059037) (xy 104.378283 15.127466)
			(xy 104.436052 15.190836) (xy 104.499422 15.248605) (xy 104.567851 15.300281) (xy 104.640757 15.345422)
			(xy 104.717517 15.383644) (xy 104.797476 15.41462) (xy 104.879952 15.438087) (xy 104.964242 15.453843)
			(xy 105.049625 15.461755) (xy 105.135375 15.461755) (xy 105.220758 15.453843) (xy 105.305048 15.438087)
			(xy 105.387524 15.41462) (xy 105.467483 15.383644) (xy 105.544243 15.345422) (xy 105.617149 15.300281)
			(xy 105.685578 15.248605) (xy 105.748948 15.190836) (xy 105.806717 15.127466) (xy 105.858393 15.059037)
			(xy 105.903534 14.986131) (xy 105.941756 14.909371) (xy 105.972732 14.829412) (xy 105.996199 14.746936)
			(xy 106.011955 14.662646) (xy 106.019867 14.577263) (xy 106.020362 14.534388) (xy 106.019867 14.491513)
			(xy 106.011955 14.40613) (xy 105.996199 14.32184) (xy 105.972732 14.239364) (xy 105.941756 14.159405)
			(xy 105.903534 14.082645) (xy 105.858393 14.009739) (xy 105.806717 13.94131) (xy 105.748948 13.87794)
			(xy 105.685578 13.820171) (xy 105.617149 13.768495) (xy 105.544243 13.723354) (xy 105.467483 13.685132)
			(xy 105.387524 13.654156) (xy 105.305048 13.630689) (xy 105.220758 13.614933) (xy 105.135375 13.607021)
			(xy 105.049625 13.607021) (xy 104.964242 13.614933) (xy 104.879952 13.630689) (xy 104.797476 13.654156)
			(xy 104.717517 13.685132) (xy 104.640757 13.723354) (xy 104.567851 13.768495) (xy 104.499422 13.820171)
			(xy 104.436052 13.87794) (xy 104.378283 13.94131) (xy 104.326607 14.009739) (xy 104.281466 14.082645)
			(xy 104.243244 14.159405) (xy 104.212268 14.239364) (xy 104.188801 14.32184) (xy 104.173045 14.40613)
			(xy 104.165133 14.491513) (xy 103.479867 14.491513) (xy 103.471955 14.40613) (xy 103.456199 14.32184)
			(xy 103.432732 14.239364) (xy 103.401756 14.159405) (xy 103.363534 14.082645) (xy 103.318393 14.009739)
			(xy 103.266717 13.94131) (xy 103.208948 13.87794) (xy 103.145578 13.820171) (xy 103.077149 13.768495)
			(xy 103.004243 13.723354) (xy 102.927483 13.685132) (xy 102.847524 13.654156) (xy 102.765048 13.630689)
			(xy 102.680758 13.614933) (xy 102.595375 13.607021) (xy 102.509625 13.607021) (xy 102.424242 13.614933)
			(xy 102.339952 13.630689) (xy 102.257476 13.654156) (xy 102.177517 13.685132) (xy 102.100757 13.723354)
			(xy 102.027851 13.768495) (xy 101.959422 13.820171) (xy 101.896052 13.87794) (xy 101.838283 13.94131)
			(xy 101.786607 14.009739) (xy 101.741466 14.082645) (xy 101.703244 14.159405) (xy 101.672268 14.239364)
			(xy 101.648801 14.32184) (xy 101.633045 14.40613) (xy 101.625133 14.491513) (xy 100.939867 14.491513)
			(xy 100.931955 14.40613) (xy 100.916199 14.32184) (xy 100.892732 14.239364) (xy 100.861756 14.159405)
			(xy 100.823534 14.082645) (xy 100.778393 14.009739) (xy 100.726717 13.94131) (xy 100.668948 13.87794)
			(xy 100.605578 13.820171) (xy 100.537149 13.768495) (xy 100.464243 13.723354) (xy 100.387483 13.685132)
			(xy 100.307524 13.654156) (xy 100.225048 13.630689) (xy 100.140758 13.614933) (xy 100.055375 13.607021)
			(xy 99.969625 13.607021) (xy 99.884242 13.614933) (xy 99.799952 13.630689) (xy 99.717476 13.654156)
			(xy 99.637517 13.685132) (xy 99.560757 13.723354) (xy 99.487851 13.768495) (xy 99.419422 13.820171)
			(xy 99.356052 13.87794) (xy 99.298283 13.94131) (xy 99.246607 14.009739) (xy 99.201466 14.082645)
			(xy 99.163244 14.159405) (xy 99.132268 14.239364) (xy 99.108801 14.32184) (xy 99.093045 14.40613)
			(xy 99.085133 14.491513) (xy 92.50807 14.491513) (xy 92.50807 -1.181049) (xy 93.729289 -1.181049)
			(xy 93.729289 -1.095299) (xy 93.737201 -1.009916) (xy 93.752957 -0.925626) (xy 93.776424 -0.84315)
			(xy 93.8074 -0.763191) (xy 93.845622 -0.686431) (xy 93.890763 -0.613525) (xy 93.942439 -0.545096)
			(xy 94.000208 -0.481726) (xy 94.063578 -0.423957) (xy 94.132007 -0.372281) (xy 94.204913 -0.32714)
			(xy 94.281673 -0.288918) (xy 94.361632 -0.257942) (xy 94.444108 -0.234475) (xy 94.528398 -0.218719)
			(xy 94.613781 -0.210807) (xy 94.699531 -0.210807) (xy 94.784914 -0.218719) (xy 94.869204 -0.234475)
			(xy 94.95168 -0.257942) (xy 95.031639 -0.288918) (xy 95.108399 -0.32714) (xy 95.181305 -0.372281)
			(xy 95.249734 -0.423957) (xy 95.313104 -0.481726) (xy 95.370873 -0.545096) (xy 95.422549 -0.613525)
			(xy 95.46769 -0.686431) (xy 95.505912 -0.763191) (xy 95.536888 -0.84315) (xy 95.560355 -0.925626)
			(xy 95.576111 -1.009916) (xy 95.584023 -1.095299) (xy 95.584518 -1.138174) (xy 95.584023 -1.181049)
			(xy 96.269289 -1.181049) (xy 96.269289 -1.095299) (xy 96.277201 -1.009916) (xy 96.292957 -0.925626)
			(xy 96.316424 -0.84315) (xy 96.3474 -0.763191) (xy 96.385622 -0.686431) (xy 96.430763 -0.613525)
			(xy 96.482439 -0.545096) (xy 96.540208 -0.481726) (xy 96.603578 -0.423957) (xy 96.672007 -0.372281)
			(xy 96.744913 -0.32714) (xy 96.821673 -0.288918) (xy 96.901632 -0.257942) (xy 96.984108 -0.234475)
			(xy 97.068398 -0.218719) (xy 97.153781 -0.210807) (xy 97.239531 -0.210807) (xy 97.324914 -0.218719)
			(xy 97.409204 -0.234475) (xy 97.49168 -0.257942) (xy 97.571639 -0.288918) (xy 97.648399 -0.32714)
			(xy 97.721305 -0.372281) (xy 97.789734 -0.423957) (xy 97.853104 -0.481726) (xy 97.910873 -0.545096)
			(xy 97.962549 -0.613525) (xy 98.00769 -0.686431) (xy 98.045912 -0.763191) (xy 98.076888 -0.84315)
			(xy 98.100355 -0.925626) (xy 98.116111 -1.009916) (xy 98.124023 -1.095299) (xy 98.124518 -1.138174)
			(xy 98.124023 -1.181049) (xy 98.116111 -1.266432) (xy 98.100355 -1.350722) (xy 98.076888 -1.433198)
			(xy 98.045912 -1.513157) (xy 98.00769 -1.589917) (xy 97.962549 -1.662823) (xy 97.910873 -1.731252)
			(xy 97.853104 -1.794622) (xy 97.789734 -1.852391) (xy 97.721305 -1.904067) (xy 97.648399 -1.949208)
			(xy 97.571639 -1.98743) (xy 97.49168 -2.018406) (xy 97.409204 -2.041873) (xy 97.324914 -2.057629)
			(xy 97.239531 -2.065541) (xy 97.153781 -2.065541) (xy 97.068398 -2.057629) (xy 96.984108 -2.041873)
			(xy 96.901632 -2.018406) (xy 96.821673 -1.98743) (xy 96.744913 -1.949208) (xy 96.672007 -1.904067)
			(xy 96.603578 -1.852391) (xy 96.540208 -1.794622) (xy 96.482439 -1.731252) (xy 96.430763 -1.662823)
			(xy 96.385622 -1.589917) (xy 96.3474 -1.513157) (xy 96.316424 -1.433198) (xy 96.292957 -1.350722)
			(xy 96.277201 -1.266432) (xy 96.269289 -1.181049) (xy 95.584023 -1.181049) (xy 95.576111 -1.266432)
			(xy 95.560355 -1.350722) (xy 95.536888 -1.433198) (xy 95.505912 -1.513157) (xy 95.46769 -1.589917)
			(xy 95.422549 -1.662823) (xy 95.370873 -1.731252) (xy 95.313104 -1.794622) (xy 95.249734 -1.852391)
			(xy 95.181305 -1.904067) (xy 95.108399 -1.949208) (xy 95.031639 -1.98743) (xy 94.95168 -2.018406)
			(xy 94.869204 -2.041873) (xy 94.784914 -2.057629) (xy 94.699531 -2.065541) (xy 94.613781 -2.065541)
			(xy 94.528398 -2.057629) (xy 94.444108 -2.041873) (xy 94.361632 -2.018406) (xy 94.281673 -1.98743)
			(xy 94.204913 -1.949208) (xy 94.132007 -1.904067) (xy 94.063578 -1.852391) (xy 94.000208 -1.794622)
			(xy 93.942439 -1.731252) (xy 93.890763 -1.662823) (xy 93.845622 -1.589917) (xy 93.8074 -1.513157)
			(xy 93.776424 -1.433198) (xy 93.752957 -1.350722) (xy 93.737201 -1.266432) (xy 93.729289 -1.181049)
			(xy 92.50807 -1.181049) (xy 92.50807 -3.154767) (xy 95.113626 -3.154767) (xy 95.113626 -3.100233)
			(xy 95.121387 -3.046253) (xy 95.13675 -2.993928) (xy 95.159403 -2.944321) (xy 95.188884 -2.898442)
			(xy 95.224595 -2.857226) (xy 95.265807 -2.821511) (xy 95.311682 -2.792024) (xy 95.361286 -2.769365)
			(xy 95.41361 -2.753996) (xy 95.467589 -2.746229) (xy 95.494856 -2.74574) (xy 96.358456 -2.74574)
			(xy 96.385729 -2.746196) (xy 96.439721 -2.753954) (xy 96.492059 -2.769316) (xy 96.541678 -2.791971)
			(xy 96.587568 -2.821458) (xy 96.628793 -2.857176) (xy 96.664516 -2.898397) (xy 96.694008 -2.944283)
			(xy 96.716668 -2.993899) (xy 96.732037 -3.046236) (xy 96.7398 -3.100227) (xy 96.7398 -3.154773) (xy 96.732037 -3.208764)
			(xy 96.716668 -3.261101) (xy 96.694008 -3.310717) (xy 96.664516 -3.356603) (xy 96.628793 -3.397824)
			(xy 96.587568 -3.433542) (xy 96.541678 -3.463029) (xy 96.492059 -3.485684) (xy 96.439721 -3.501046)
			(xy 96.385729 -3.508804) (xy 96.358456 -3.509264) (xy 95.494856 -3.509264) (xy 95.467589 -3.508771)
			(xy 95.41361 -3.501004) (xy 95.361286 -3.485635) (xy 95.311682 -3.462976) (xy 95.265807 -3.433489)
			(xy 95.224595 -3.397774) (xy 95.188884 -3.356558) (xy 95.159403 -3.310679) (xy 95.13675 -3.261072)
			(xy 95.121387 -3.208747) (xy 95.113626 -3.154767) (xy 92.50807 -3.154767) (xy 92.50807 -7.531049)
			(xy 93.729289 -7.531049) (xy 93.729289 -7.445299) (xy 93.737201 -7.359916) (xy 93.752957 -7.275626)
			(xy 93.776424 -7.19315) (xy 93.8074 -7.113191) (xy 93.845622 -7.036431) (xy 93.890763 -6.963525)
			(xy 93.942439 -6.895096) (xy 94.000208 -6.831726) (xy 94.063578 -6.773957) (xy 94.132007 -6.722281)
			(xy 94.204913 -6.67714) (xy 94.281673 -6.638918) (xy 94.361632 -6.607942) (xy 94.444108 -6.584475)
			(xy 94.528398 -6.568719) (xy 94.613781 -6.560807) (xy 94.699531 -6.560807) (xy 94.784914 -6.568719)
			(xy 94.869204 -6.584475) (xy 94.95168 -6.607942) (xy 95.031639 -6.638918) (xy 95.108399 -6.67714)
			(xy 95.181305 -6.722281) (xy 95.249734 -6.773957) (xy 95.313104 -6.831726) (xy 95.370873 -6.895096)
			(xy 95.422549 -6.963525) (xy 95.46769 -7.036431) (xy 95.505912 -7.113191) (xy 95.536888 -7.19315)
			(xy 95.560355 -7.275626) (xy 95.576111 -7.359916) (xy 95.584023 -7.445299) (xy 95.584518 -7.488174)
			(xy 95.584023 -7.531049) (xy 96.269289 -7.531049) (xy 96.269289 -7.445299) (xy 96.277201 -7.359916)
			(xy 96.292957 -7.275626) (xy 96.316424 -7.19315) (xy 96.3474 -7.113191) (xy 96.385622 -7.036431)
			(xy 96.430763 -6.963525) (xy 96.482439 -6.895096) (xy 96.540208 -6.831726) (xy 96.603578 -6.773957)
			(xy 96.672007 -6.722281) (xy 96.744913 -6.67714) (xy 96.821673 -6.638918) (xy 96.901632 -6.607942)
			(xy 96.984108 -6.584475) (xy 97.068398 -6.568719) (xy 97.153781 -6.560807) (xy 97.239531 -6.560807)
			(xy 97.324914 -6.568719) (xy 97.409204 -6.584475) (xy 97.49168 -6.607942) (xy 97.571639 -6.638918)
			(xy 97.648399 -6.67714) (xy 97.721305 -6.722281) (xy 97.789734 -6.773957) (xy 97.853104 -6.831726)
			(xy 97.910873 -6.895096) (xy 97.962549 -6.963525) (xy 98.00769 -7.036431) (xy 98.045912 -7.113191)
			(xy 98.076888 -7.19315) (xy 98.100355 -7.275626) (xy 98.116111 -7.359916) (xy 98.124023 -7.445299)
			(xy 98.124518 -7.488174) (xy 98.124023 -7.531049) (xy 98.116111 -7.616432) (xy 98.100355 -7.700722)
			(xy 98.076888 -7.783198) (xy 98.045912 -7.863157) (xy 98.00769 -7.939917) (xy 97.962549 -8.012823)
			(xy 97.910873 -8.081252) (xy 97.853104 -8.144622) (xy 97.789734 -8.202391) (xy 97.721305 -8.254067)
			(xy 97.648399 -8.299208) (xy 97.571639 -8.33743) (xy 97.49168 -8.368406) (xy 97.409204 -8.391873)
			(xy 97.324914 -8.407629) (xy 97.239531 -8.415541) (xy 97.153781 -8.415541) (xy 97.068398 -8.407629)
			(xy 96.984108 -8.391873) (xy 96.901632 -8.368406) (xy 96.821673 -8.33743) (xy 96.744913 -8.299208)
			(xy 96.672007 -8.254067) (xy 96.603578 -8.202391) (xy 96.540208 -8.144622) (xy 96.482439 -8.081252)
			(xy 96.430763 -8.012823) (xy 96.385622 -7.939917) (xy 96.3474 -7.863157) (xy 96.316424 -7.783198)
			(xy 96.292957 -7.700722) (xy 96.277201 -7.616432) (xy 96.269289 -7.531049) (xy 95.584023 -7.531049)
			(xy 95.576111 -7.616432) (xy 95.560355 -7.700722) (xy 95.536888 -7.783198) (xy 95.505912 -7.863157)
			(xy 95.46769 -7.939917) (xy 95.422549 -8.012823) (xy 95.370873 -8.081252) (xy 95.313104 -8.144622)
			(xy 95.249734 -8.202391) (xy 95.181305 -8.254067) (xy 95.108399 -8.299208) (xy 95.031639 -8.33743)
			(xy 94.95168 -8.368406) (xy 94.869204 -8.391873) (xy 94.784914 -8.407629) (xy 94.699531 -8.415541)
			(xy 94.613781 -8.415541) (xy 94.528398 -8.407629) (xy 94.444108 -8.391873) (xy 94.361632 -8.368406)
			(xy 94.281673 -8.33743) (xy 94.204913 -8.299208) (xy 94.132007 -8.254067) (xy 94.063578 -8.202391)
			(xy 94.000208 -8.144622) (xy 93.942439 -8.081252) (xy 93.890763 -8.012823) (xy 93.845622 -7.939917)
			(xy 93.8074 -7.863157) (xy 93.776424 -7.783198) (xy 93.752957 -7.700722) (xy 93.737201 -7.616432)
			(xy 93.729289 -7.531049) (xy 92.50807 -7.531049) (xy 92.50807 -13.055549) (xy 93.714049 -13.055549)
			(xy 93.714049 -12.969799) (xy 93.721961 -12.884416) (xy 93.737717 -12.800126) (xy 93.761184 -12.71765)
			(xy 93.79216 -12.637691) (xy 93.830382 -12.560931) (xy 93.875523 -12.488025) (xy 93.927199 -12.419596)
			(xy 93.984968 -12.356226) (xy 94.048338 -12.298457) (xy 94.116767 -12.246781) (xy 94.189673 -12.20164)
			(xy 94.266433 -12.163418) (xy 94.346392 -12.132442) (xy 94.428868 -12.108975) (xy 94.513158 -12.093219)
			(xy 94.598541 -12.085307) (xy 94.684291 -12.085307) (xy 94.769674 -12.093219) (xy 94.853964 -12.108975)
			(xy 94.93644 -12.132442) (xy 95.016399 -12.163418) (xy 95.093159 -12.20164) (xy 95.166065 -12.246781)
			(xy 95.234494 -12.298457) (xy 95.297864 -12.356226) (xy 95.355633 -12.419596) (xy 95.407309 -12.488025)
			(xy 95.45245 -12.560931) (xy 95.490672 -12.637691) (xy 95.521648 -12.71765) (xy 95.545115 -12.800126)
			(xy 95.560871 -12.884416) (xy 95.568783 -12.969799) (xy 95.569278 -13.012674) (xy 95.568783 -13.055549)
			(xy 96.254049 -13.055549) (xy 96.254049 -12.969799) (xy 96.261961 -12.884416) (xy 96.277717 -12.800126)
			(xy 96.301184 -12.71765) (xy 96.33216 -12.637691) (xy 96.370382 -12.560931) (xy 96.415523 -12.488025)
			(xy 96.467199 -12.419596) (xy 96.524968 -12.356226) (xy 96.588338 -12.298457) (xy 96.656767 -12.246781)
			(xy 96.729673 -12.20164) (xy 96.806433 -12.163418) (xy 96.886392 -12.132442) (xy 96.968868 -12.108975)
			(xy 97.053158 -12.093219) (xy 97.138541 -12.085307) (xy 97.224291 -12.085307) (xy 97.309674 -12.093219)
			(xy 97.393964 -12.108975) (xy 97.47644 -12.132442) (xy 97.556399 -12.163418) (xy 97.633159 -12.20164)
			(xy 97.706065 -12.246781) (xy 97.774494 -12.298457) (xy 97.837864 -12.356226) (xy 97.895633 -12.419596)
			(xy 97.947309 -12.488025) (xy 97.99245 -12.560931) (xy 98.030672 -12.637691) (xy 98.061648 -12.71765)
			(xy 98.085115 -12.800126) (xy 98.100871 -12.884416) (xy 98.108783 -12.969799) (xy 98.109278 -13.012674)
			(xy 98.108783 -13.055549) (xy 98.100871 -13.140932) (xy 98.085115 -13.225222) (xy 98.061648 -13.307698)
			(xy 98.030672 -13.387657) (xy 97.99245 -13.464417) (xy 97.947309 -13.537323) (xy 97.895633 -13.605752)
			(xy 97.837864 -13.669122) (xy 97.774494 -13.726891) (xy 97.706065 -13.778567) (xy 97.633159 -13.823708)
			(xy 97.556399 -13.86193) (xy 97.47644 -13.892906) (xy 97.393964 -13.916373) (xy 97.309674 -13.932129)
			(xy 97.224291 -13.940041) (xy 97.138541 -13.940041) (xy 97.053158 -13.932129) (xy 96.968868 -13.916373)
			(xy 96.886392 -13.892906) (xy 96.806433 -13.86193) (xy 96.729673 -13.823708) (xy 96.656767 -13.778567)
			(xy 96.588338 -13.726891) (xy 96.524968 -13.669122) (xy 96.467199 -13.605752) (xy 96.415523 -13.537323)
			(xy 96.370382 -13.464417) (xy 96.33216 -13.387657) (xy 96.301184 -13.307698) (xy 96.277717 -13.225222)
			(xy 96.261961 -13.140932) (xy 96.254049 -13.055549) (xy 95.568783 -13.055549) (xy 95.560871 -13.140932)
			(xy 95.545115 -13.225222) (xy 95.521648 -13.307698) (xy 95.490672 -13.387657) (xy 95.45245 -13.464417)
			(xy 95.407309 -13.537323) (xy 95.355633 -13.605752) (xy 95.297864 -13.669122) (xy 95.234494 -13.726891)
			(xy 95.166065 -13.778567) (xy 95.093159 -13.823708) (xy 95.016399 -13.86193) (xy 94.93644 -13.892906)
			(xy 94.853964 -13.916373) (xy 94.769674 -13.932129) (xy 94.684291 -13.940041) (xy 94.598541 -13.940041)
			(xy 94.513158 -13.932129) (xy 94.428868 -13.916373) (xy 94.346392 -13.892906) (xy 94.266433 -13.86193)
			(xy 94.189673 -13.823708) (xy 94.116767 -13.778567) (xy 94.048338 -13.726891) (xy 93.984968 -13.669122)
			(xy 93.927199 -13.605752) (xy 93.875523 -13.537323) (xy 93.830382 -13.464417) (xy 93.79216 -13.387657)
			(xy 93.761184 -13.307698) (xy 93.737717 -13.225222) (xy 93.721961 -13.140932) (xy 93.714049 -13.055549)
			(xy 92.50807 -13.055549) (xy 92.50807 -17.400568) (xy 95.098347 -17.400568) (xy 95.098347 -17.346032)
			(xy 95.106109 -17.29205) (xy 95.121474 -17.239722) (xy 95.14413 -17.190114) (xy 95.173616 -17.144235)
			(xy 95.209331 -17.103019) (xy 95.250548 -17.067306) (xy 95.296428 -17.037823) (xy 95.346037 -17.015169)
			(xy 95.398365 -16.999806) (xy 95.452348 -16.992046) (xy 95.479616 -16.991584) (xy 96.343216 -16.991584)
			(xy 96.370488 -16.99198) (xy 96.424476 -16.999744) (xy 96.47681 -17.015113) (xy 96.526424 -17.037773)
			(xy 96.572309 -17.067262) (xy 96.613529 -17.102982) (xy 96.649247 -17.144204) (xy 96.678735 -17.19009)
			(xy 96.701393 -17.239705) (xy 96.716759 -17.292039) (xy 96.724522 -17.346028) (xy 96.724522 -17.400572)
			(xy 96.716759 -17.454561) (xy 96.701393 -17.506895) (xy 96.678735 -17.55651) (xy 96.649247 -17.602396)
			(xy 96.613529 -17.643618) (xy 96.572309 -17.679338) (xy 96.526424 -17.708827) (xy 96.47681 -17.731487)
			(xy 96.424476 -17.746856) (xy 96.370488 -17.75462) (xy 96.343216 -17.755108) (xy 95.479616 -17.755108)
			(xy 95.452348 -17.754554) (xy 95.398365 -17.746794) (xy 95.346037 -17.731431) (xy 95.296428 -17.708777)
			(xy 95.250548 -17.679294) (xy 95.209331 -17.643581) (xy 95.173616 -17.602365) (xy 95.14413 -17.556486)
			(xy 95.121474 -17.506878) (xy 95.106109 -17.45455) (xy 95.098347 -17.400568) (xy 92.50807 -17.400568)
			(xy 92.50807 -19.405549) (xy 93.714049 -19.405549) (xy 93.714049 -19.319799) (xy 93.721961 -19.234416)
			(xy 93.737717 -19.150126) (xy 93.761184 -19.06765) (xy 93.79216 -18.987691) (xy 93.830382 -18.910931)
			(xy 93.875523 -18.838025) (xy 93.927199 -18.769596) (xy 93.984968 -18.706226) (xy 94.048338 -18.648457)
			(xy 94.116767 -18.596781) (xy 94.189673 -18.55164) (xy 94.266433 -18.513418) (xy 94.346392 -18.482442)
			(xy 94.428868 -18.458975) (xy 94.513158 -18.443219) (xy 94.598541 -18.435307) (xy 94.684291 -18.435307)
			(xy 94.769674 -18.443219) (xy 94.853964 -18.458975) (xy 94.93644 -18.482442) (xy 95.016399 -18.513418)
			(xy 95.093159 -18.55164) (xy 95.166065 -18.596781) (xy 95.234494 -18.648457) (xy 95.297864 -18.706226)
			(xy 95.355633 -18.769596) (xy 95.407309 -18.838025) (xy 95.45245 -18.910931) (xy 95.490672 -18.987691)
			(xy 95.521648 -19.06765) (xy 95.545115 -19.150126) (xy 95.560871 -19.234416) (xy 95.568783 -19.319799)
			(xy 95.569278 -19.362674) (xy 95.568783 -19.405549) (xy 96.254049 -19.405549) (xy 96.254049 -19.319799)
			(xy 96.261961 -19.234416) (xy 96.277717 -19.150126) (xy 96.301184 -19.06765) (xy 96.33216 -18.987691)
			(xy 96.370382 -18.910931) (xy 96.415523 -18.838025) (xy 96.467199 -18.769596) (xy 96.524968 -18.706226)
			(xy 96.588338 -18.648457) (xy 96.656767 -18.596781) (xy 96.729673 -18.55164) (xy 96.806433 -18.513418)
			(xy 96.886392 -18.482442) (xy 96.968868 -18.458975) (xy 97.053158 -18.443219) (xy 97.138541 -18.435307)
			(xy 97.224291 -18.435307) (xy 97.309674 -18.443219) (xy 97.393964 -18.458975) (xy 97.47644 -18.482442)
			(xy 97.556399 -18.513418) (xy 97.633159 -18.55164) (xy 97.706065 -18.596781) (xy 97.774494 -18.648457)
			(xy 97.837864 -18.706226) (xy 97.895633 -18.769596) (xy 97.947309 -18.838025) (xy 97.99245 -18.910931)
			(xy 98.030672 -18.987691) (xy 98.061648 -19.06765) (xy 98.085115 -19.150126) (xy 98.100871 -19.234416)
			(xy 98.108783 -19.319799) (xy 98.109278 -19.362674) (xy 98.108783 -19.405549) (xy 98.100871 -19.490932)
			(xy 98.085115 -19.575222) (xy 98.061648 -19.657698) (xy 98.030672 -19.737657) (xy 97.99245 -19.814417)
			(xy 97.947309 -19.887323) (xy 97.895633 -19.955752) (xy 97.837864 -20.019122) (xy 97.774494 -20.076891)
			(xy 97.706065 -20.128567) (xy 97.633159 -20.173708) (xy 97.556399 -20.21193) (xy 97.47644 -20.242906)
			(xy 97.393964 -20.266373) (xy 97.309674 -20.282129) (xy 97.224291 -20.290041) (xy 97.138541 -20.290041)
			(xy 97.053158 -20.282129) (xy 96.968868 -20.266373) (xy 96.886392 -20.242906) (xy 96.806433 -20.21193)
			(xy 96.729673 -20.173708) (xy 96.656767 -20.128567) (xy 96.588338 -20.076891) (xy 96.524968 -20.019122)
			(xy 96.467199 -19.955752) (xy 96.415523 -19.887323) (xy 96.370382 -19.814417) (xy 96.33216 -19.737657)
			(xy 96.301184 -19.657698) (xy 96.277717 -19.575222) (xy 96.261961 -19.490932) (xy 96.254049 -19.405549)
			(xy 95.568783 -19.405549) (xy 95.560871 -19.490932) (xy 95.545115 -19.575222) (xy 95.521648 -19.657698)
			(xy 95.490672 -19.737657) (xy 95.45245 -19.814417) (xy 95.407309 -19.887323) (xy 95.355633 -19.955752)
			(xy 95.297864 -20.019122) (xy 95.234494 -20.076891) (xy 95.166065 -20.128567) (xy 95.093159 -20.173708)
			(xy 95.016399 -20.21193) (xy 94.93644 -20.242906) (xy 94.853964 -20.266373) (xy 94.769674 -20.282129)
			(xy 94.684291 -20.290041) (xy 94.598541 -20.290041) (xy 94.513158 -20.282129) (xy 94.428868 -20.266373)
			(xy 94.346392 -20.242906) (xy 94.266433 -20.21193) (xy 94.189673 -20.173708) (xy 94.116767 -20.128567)
			(xy 94.048338 -20.076891) (xy 93.984968 -20.019122) (xy 93.927199 -19.955752) (xy 93.875523 -19.887323)
			(xy 93.830382 -19.814417) (xy 93.79216 -19.737657) (xy 93.761184 -19.657698) (xy 93.737717 -19.575222)
			(xy 93.721961 -19.490932) (xy 93.714049 -19.405549) (xy 92.50807 -19.405549) (xy 92.50807 -50.979527)
			(xy 99.085133 -50.979527) (xy 99.085133 -50.893777) (xy 99.093045 -50.808394) (xy 99.108801 -50.724104)
			(xy 99.132268 -50.641628) (xy 99.163244 -50.561669) (xy 99.201466 -50.484909) (xy 99.246607 -50.412003)
			(xy 99.298283 -50.343574) (xy 99.356052 -50.280204) (xy 99.419422 -50.222435) (xy 99.487851 -50.170759)
			(xy 99.560757 -50.125618) (xy 99.637517 -50.087396) (xy 99.717476 -50.05642) (xy 99.799952 -50.032953)
			(xy 99.884242 -50.017197) (xy 99.969625 -50.009285) (xy 100.055375 -50.009285) (xy 100.140758 -50.017197)
			(xy 100.225048 -50.032953) (xy 100.307524 -50.05642) (xy 100.387483 -50.087396) (xy 100.464243 -50.125618)
			(xy 100.537149 -50.170759) (xy 100.605578 -50.222435) (xy 100.668948 -50.280204) (xy 100.726717 -50.343574)
			(xy 100.778393 -50.412003) (xy 100.823534 -50.484909) (xy 100.861756 -50.561669) (xy 100.892732 -50.641628)
			(xy 100.916199 -50.724104) (xy 100.931955 -50.808394) (xy 100.939867 -50.893777) (xy 100.940362 -50.936652)
			(xy 100.939867 -50.979527) (xy 101.625133 -50.979527) (xy 101.625133 -50.893777) (xy 101.633045 -50.808394)
			(xy 101.648801 -50.724104) (xy 101.672268 -50.641628) (xy 101.703244 -50.561669) (xy 101.741466 -50.484909)
			(xy 101.786607 -50.412003) (xy 101.838283 -50.343574) (xy 101.896052 -50.280204) (xy 101.959422 -50.222435)
			(xy 102.027851 -50.170759) (xy 102.100757 -50.125618) (xy 102.177517 -50.087396) (xy 102.257476 -50.05642)
			(xy 102.339952 -50.032953) (xy 102.424242 -50.017197) (xy 102.509625 -50.009285) (xy 102.595375 -50.009285)
			(xy 102.680758 -50.017197) (xy 102.765048 -50.032953) (xy 102.847524 -50.05642) (xy 102.927483 -50.087396)
			(xy 103.004243 -50.125618) (xy 103.077149 -50.170759) (xy 103.145578 -50.222435) (xy 103.208948 -50.280204)
			(xy 103.266717 -50.343574) (xy 103.318393 -50.412003) (xy 103.363534 -50.484909) (xy 103.401756 -50.561669)
			(xy 103.432732 -50.641628) (xy 103.456199 -50.724104) (xy 103.471955 -50.808394) (xy 103.479867 -50.893777)
			(xy 103.480362 -50.936652) (xy 103.479867 -50.979527) (xy 104.165133 -50.979527) (xy 104.165133 -50.893777)
			(xy 104.173045 -50.808394) (xy 104.188801 -50.724104) (xy 104.212268 -50.641628) (xy 104.243244 -50.561669)
			(xy 104.281466 -50.484909) (xy 104.326607 -50.412003) (xy 104.378283 -50.343574) (xy 104.436052 -50.280204)
			(xy 104.499422 -50.222435) (xy 104.567851 -50.170759) (xy 104.640757 -50.125618) (xy 104.717517 -50.087396)
			(xy 104.797476 -50.05642) (xy 104.879952 -50.032953) (xy 104.964242 -50.017197) (xy 105.049625 -50.009285)
			(xy 105.135375 -50.009285) (xy 105.220758 -50.017197) (xy 105.305048 -50.032953) (xy 105.387524 -50.05642)
			(xy 105.467483 -50.087396) (xy 105.544243 -50.125618) (xy 105.617149 -50.170759) (xy 105.685578 -50.222435)
			(xy 105.748948 -50.280204) (xy 105.806717 -50.343574) (xy 105.858393 -50.412003) (xy 105.903534 -50.484909)
			(xy 105.941756 -50.561669) (xy 105.972732 -50.641628) (xy 105.996199 -50.724104) (xy 106.011955 -50.808394)
			(xy 106.019867 -50.893777) (xy 106.020362 -50.936652) (xy 106.019867 -50.979527) (xy 106.011955 -51.06491)
			(xy 105.996199 -51.1492) (xy 105.972732 -51.231676) (xy 105.941756 -51.311635) (xy 105.903534 -51.388395)
			(xy 105.858393 -51.461301) (xy 105.806717 -51.52973) (xy 105.748948 -51.5931) (xy 105.685578 -51.650869)
			(xy 105.617149 -51.702545) (xy 105.544243 -51.747686) (xy 105.467483 -51.785908) (xy 105.387524 -51.816884)
			(xy 105.305048 -51.840351) (xy 105.220758 -51.856107) (xy 105.135375 -51.864019) (xy 105.049625 -51.864019)
			(xy 104.964242 -51.856107) (xy 104.879952 -51.840351) (xy 104.797476 -51.816884) (xy 104.717517 -51.785908)
			(xy 104.640757 -51.747686) (xy 104.567851 -51.702545) (xy 104.499422 -51.650869) (xy 104.436052 -51.5931)
			(xy 104.378283 -51.52973) (xy 104.326607 -51.461301) (xy 104.281466 -51.388395) (xy 104.243244 -51.311635)
			(xy 104.212268 -51.231676) (xy 104.188801 -51.1492) (xy 104.173045 -51.06491) (xy 104.165133 -50.979527)
			(xy 103.479867 -50.979527) (xy 103.471955 -51.06491) (xy 103.456199 -51.1492) (xy 103.432732 -51.231676)
			(xy 103.401756 -51.311635) (xy 103.363534 -51.388395) (xy 103.318393 -51.461301) (xy 103.266717 -51.52973)
			(xy 103.208948 -51.5931) (xy 103.145578 -51.650869) (xy 103.077149 -51.702545) (xy 103.004243 -51.747686)
			(xy 102.927483 -51.785908) (xy 102.847524 -51.816884) (xy 102.765048 -51.840351) (xy 102.680758 -51.856107)
			(xy 102.595375 -51.864019) (xy 102.509625 -51.864019) (xy 102.424242 -51.856107) (xy 102.339952 -51.840351)
			(xy 102.257476 -51.816884) (xy 102.177517 -51.785908) (xy 102.100757 -51.747686) (xy 102.027851 -51.702545)
			(xy 101.959422 -51.650869) (xy 101.896052 -51.5931) (xy 101.838283 -51.52973) (xy 101.786607 -51.461301)
			(xy 101.741466 -51.388395) (xy 101.703244 -51.311635) (xy 101.672268 -51.231676) (xy 101.648801 -51.1492)
			(xy 101.633045 -51.06491) (xy 101.625133 -50.979527) (xy 100.939867 -50.979527) (xy 100.931955 -51.06491)
			(xy 100.916199 -51.1492) (xy 100.892732 -51.231676) (xy 100.861756 -51.311635) (xy 100.823534 -51.388395)
			(xy 100.778393 -51.461301) (xy 100.726717 -51.52973) (xy 100.668948 -51.5931) (xy 100.605578 -51.650869)
			(xy 100.537149 -51.702545) (xy 100.464243 -51.747686) (xy 100.387483 -51.785908) (xy 100.307524 -51.816884)
			(xy 100.225048 -51.840351) (xy 100.140758 -51.856107) (xy 100.055375 -51.864019) (xy 99.969625 -51.864019)
			(xy 99.884242 -51.856107) (xy 99.799952 -51.840351) (xy 99.717476 -51.816884) (xy 99.637517 -51.785908)
			(xy 99.560757 -51.747686) (xy 99.487851 -51.702545) (xy 99.419422 -51.650869) (xy 99.356052 -51.5931)
			(xy 99.298283 -51.52973) (xy 99.246607 -51.461301) (xy 99.201466 -51.388395) (xy 99.163244 -51.311635)
			(xy 99.132268 -51.231676) (xy 99.108801 -51.1492) (xy 99.093045 -51.06491) (xy 99.085133 -50.979527)
			(xy 92.50807 -50.979527) (xy 92.50807 -57.329527) (xy 99.085133 -57.329527) (xy 99.085133 -57.243777)
			(xy 99.093045 -57.158394) (xy 99.108801 -57.074104) (xy 99.132268 -56.991628) (xy 99.163244 -56.911669)
			(xy 99.201466 -56.834909) (xy 99.246607 -56.762003) (xy 99.298283 -56.693574) (xy 99.356052 -56.630204)
			(xy 99.419422 -56.572435) (xy 99.487851 -56.520759) (xy 99.560757 -56.475618) (xy 99.637517 -56.437396)
			(xy 99.717476 -56.40642) (xy 99.799952 -56.382953) (xy 99.884242 -56.367197) (xy 99.969625 -56.359285)
			(xy 100.055375 -56.359285) (xy 100.140758 -56.367197) (xy 100.225048 -56.382953) (xy 100.307524 -56.40642)
			(xy 100.387483 -56.437396) (xy 100.464243 -56.475618) (xy 100.537149 -56.520759) (xy 100.605578 -56.572435)
			(xy 100.668948 -56.630204) (xy 100.726717 -56.693574) (xy 100.778393 -56.762003) (xy 100.823534 -56.834909)
			(xy 100.861756 -56.911669) (xy 100.892732 -56.991628) (xy 100.916199 -57.074104) (xy 100.931955 -57.158394)
			(xy 100.939867 -57.243777) (xy 100.940362 -57.286652) (xy 100.939867 -57.329527) (xy 101.625133 -57.329527)
			(xy 101.625133 -57.243777) (xy 101.633045 -57.158394) (xy 101.648801 -57.074104) (xy 101.672268 -56.991628)
			(xy 101.703244 -56.911669) (xy 101.741466 -56.834909) (xy 101.786607 -56.762003) (xy 101.838283 -56.693574)
			(xy 101.896052 -56.630204) (xy 101.959422 -56.572435) (xy 102.027851 -56.520759) (xy 102.100757 -56.475618)
			(xy 102.177517 -56.437396) (xy 102.257476 -56.40642) (xy 102.339952 -56.382953) (xy 102.424242 -56.367197)
			(xy 102.509625 -56.359285) (xy 102.595375 -56.359285) (xy 102.680758 -56.367197) (xy 102.765048 -56.382953)
			(xy 102.847524 -56.40642) (xy 102.927483 -56.437396) (xy 103.004243 -56.475618) (xy 103.077149 -56.520759)
			(xy 103.145578 -56.572435) (xy 103.208948 -56.630204) (xy 103.266717 -56.693574) (xy 103.318393 -56.762003)
			(xy 103.363534 -56.834909) (xy 103.401756 -56.911669) (xy 103.432732 -56.991628) (xy 103.456199 -57.074104)
			(xy 103.471955 -57.158394) (xy 103.479867 -57.243777) (xy 103.480362 -57.286652) (xy 103.479867 -57.329527)
			(xy 104.165133 -57.329527) (xy 104.165133 -57.243777) (xy 104.173045 -57.158394) (xy 104.188801 -57.074104)
			(xy 104.212268 -56.991628) (xy 104.243244 -56.911669) (xy 104.281466 -56.834909) (xy 104.326607 -56.762003)
			(xy 104.378283 -56.693574) (xy 104.436052 -56.630204) (xy 104.499422 -56.572435) (xy 104.567851 -56.520759)
			(xy 104.640757 -56.475618) (xy 104.717517 -56.437396) (xy 104.797476 -56.40642) (xy 104.879952 -56.382953)
			(xy 104.964242 -56.367197) (xy 105.049625 -56.359285) (xy 105.135375 -56.359285) (xy 105.220758 -56.367197)
			(xy 105.305048 -56.382953) (xy 105.387524 -56.40642) (xy 105.467483 -56.437396) (xy 105.544243 -56.475618)
			(xy 105.617149 -56.520759) (xy 105.685578 -56.572435) (xy 105.748948 -56.630204) (xy 105.806717 -56.693574)
			(xy 105.858393 -56.762003) (xy 105.903534 -56.834909) (xy 105.941756 -56.911669) (xy 105.972732 -56.991628)
			(xy 105.996199 -57.074104) (xy 106.011955 -57.158394) (xy 106.019867 -57.243777) (xy 106.020362 -57.286652)
			(xy 106.019867 -57.329527) (xy 106.011955 -57.41491) (xy 105.996199 -57.4992) (xy 105.972732 -57.581676)
			(xy 105.941756 -57.661635) (xy 105.903534 -57.738395) (xy 105.858393 -57.811301) (xy 105.806717 -57.87973)
			(xy 105.748948 -57.9431) (xy 105.685578 -58.000869) (xy 105.617149 -58.052545) (xy 105.544243 -58.097686)
			(xy 105.467483 -58.135908) (xy 105.387524 -58.166884) (xy 105.305048 -58.190351) (xy 105.220758 -58.206107)
			(xy 105.135375 -58.214019) (xy 105.049625 -58.214019) (xy 104.964242 -58.206107) (xy 104.879952 -58.190351)
			(xy 104.797476 -58.166884) (xy 104.717517 -58.135908) (xy 104.640757 -58.097686) (xy 104.567851 -58.052545)
			(xy 104.499422 -58.000869) (xy 104.436052 -57.9431) (xy 104.378283 -57.87973) (xy 104.326607 -57.811301)
			(xy 104.281466 -57.738395) (xy 104.243244 -57.661635) (xy 104.212268 -57.581676) (xy 104.188801 -57.4992)
			(xy 104.173045 -57.41491) (xy 104.165133 -57.329527) (xy 103.479867 -57.329527) (xy 103.471955 -57.41491)
			(xy 103.456199 -57.4992) (xy 103.432732 -57.581676) (xy 103.401756 -57.661635) (xy 103.363534 -57.738395)
			(xy 103.318393 -57.811301) (xy 103.266717 -57.87973) (xy 103.208948 -57.9431) (xy 103.145578 -58.000869)
			(xy 103.077149 -58.052545) (xy 103.004243 -58.097686) (xy 102.927483 -58.135908) (xy 102.847524 -58.166884)
			(xy 102.765048 -58.190351) (xy 102.680758 -58.206107) (xy 102.595375 -58.214019) (xy 102.509625 -58.214019)
			(xy 102.424242 -58.206107) (xy 102.339952 -58.190351) (xy 102.257476 -58.166884) (xy 102.177517 -58.135908)
			(xy 102.100757 -58.097686) (xy 102.027851 -58.052545) (xy 101.959422 -58.000869) (xy 101.896052 -57.9431)
			(xy 101.838283 -57.87973) (xy 101.786607 -57.811301) (xy 101.741466 -57.738395) (xy 101.703244 -57.661635)
			(xy 101.672268 -57.581676) (xy 101.648801 -57.4992) (xy 101.633045 -57.41491) (xy 101.625133 -57.329527)
			(xy 100.939867 -57.329527) (xy 100.931955 -57.41491) (xy 100.916199 -57.4992) (xy 100.892732 -57.581676)
			(xy 100.861756 -57.661635) (xy 100.823534 -57.738395) (xy 100.778393 -57.811301) (xy 100.726717 -57.87973)
			(xy 100.668948 -57.9431) (xy 100.605578 -58.000869) (xy 100.537149 -58.052545) (xy 100.464243 -58.097686)
			(xy 100.387483 -58.135908) (xy 100.307524 -58.166884) (xy 100.225048 -58.190351) (xy 100.140758 -58.206107)
			(xy 100.055375 -58.214019) (xy 99.969625 -58.214019) (xy 99.884242 -58.206107) (xy 99.799952 -58.190351)
			(xy 99.717476 -58.166884) (xy 99.637517 -58.135908) (xy 99.560757 -58.097686) (xy 99.487851 -58.052545)
			(xy 99.419422 -58.000869) (xy 99.356052 -57.9431) (xy 99.298283 -57.87973) (xy 99.246607 -57.811301)
			(xy 99.201466 -57.738395) (xy 99.163244 -57.661635) (xy 99.132268 -57.581676) (xy 99.108801 -57.4992)
			(xy 99.093045 -57.41491) (xy 99.085133 -57.329527) (xy 92.50807 -57.329527) (xy 92.50807 -62.793575)
			(xy 99.085133 -62.793575) (xy 99.085133 -62.707825) (xy 99.093045 -62.622442) (xy 99.108801 -62.538152)
			(xy 99.132268 -62.455676) (xy 99.163244 -62.375717) (xy 99.201466 -62.298957) (xy 99.246607 -62.226051)
			(xy 99.298283 -62.157622) (xy 99.356052 -62.094252) (xy 99.419422 -62.036483) (xy 99.487851 -61.984807)
			(xy 99.560757 -61.939666) (xy 99.637517 -61.901444) (xy 99.717476 -61.870468) (xy 99.799952 -61.847001)
			(xy 99.884242 -61.831245) (xy 99.969625 -61.823333) (xy 100.055375 -61.823333) (xy 100.140758 -61.831245)
			(xy 100.225048 -61.847001) (xy 100.307524 -61.870468) (xy 100.387483 -61.901444) (xy 100.464243 -61.939666)
			(xy 100.537149 -61.984807) (xy 100.605578 -62.036483) (xy 100.668948 -62.094252) (xy 100.726717 -62.157622)
			(xy 100.778393 -62.226051) (xy 100.823534 -62.298957) (xy 100.861756 -62.375717) (xy 100.892732 -62.455676)
			(xy 100.916199 -62.538152) (xy 100.931955 -62.622442) (xy 100.939867 -62.707825) (xy 100.940362 -62.7507)
			(xy 100.939867 -62.793575) (xy 101.625133 -62.793575) (xy 101.625133 -62.707825) (xy 101.633045 -62.622442)
			(xy 101.648801 -62.538152) (xy 101.672268 -62.455676) (xy 101.703244 -62.375717) (xy 101.741466 -62.298957)
			(xy 101.786607 -62.226051) (xy 101.838283 -62.157622) (xy 101.896052 -62.094252) (xy 101.959422 -62.036483)
			(xy 102.027851 -61.984807) (xy 102.100757 -61.939666) (xy 102.177517 -61.901444) (xy 102.257476 -61.870468)
			(xy 102.339952 -61.847001) (xy 102.424242 -61.831245) (xy 102.509625 -61.823333) (xy 102.595375 -61.823333)
			(xy 102.680758 -61.831245) (xy 102.765048 -61.847001) (xy 102.847524 -61.870468) (xy 102.927483 -61.901444)
			(xy 103.004243 -61.939666) (xy 103.077149 -61.984807) (xy 103.145578 -62.036483) (xy 103.208948 -62.094252)
			(xy 103.266717 -62.157622) (xy 103.318393 -62.226051) (xy 103.363534 -62.298957) (xy 103.401756 -62.375717)
			(xy 103.432732 -62.455676) (xy 103.456199 -62.538152) (xy 103.471955 -62.622442) (xy 103.479867 -62.707825)
			(xy 103.480362 -62.7507) (xy 103.479867 -62.793575) (xy 104.165133 -62.793575) (xy 104.165133 -62.707825)
			(xy 104.173045 -62.622442) (xy 104.188801 -62.538152) (xy 104.212268 -62.455676) (xy 104.243244 -62.375717)
			(xy 104.281466 -62.298957) (xy 104.326607 -62.226051) (xy 104.378283 -62.157622) (xy 104.436052 -62.094252)
			(xy 104.499422 -62.036483) (xy 104.567851 -61.984807) (xy 104.640757 -61.939666) (xy 104.717517 -61.901444)
			(xy 104.797476 -61.870468) (xy 104.879952 -61.847001) (xy 104.964242 -61.831245) (xy 105.049625 -61.823333)
			(xy 105.135375 -61.823333) (xy 105.220758 -61.831245) (xy 105.305048 -61.847001) (xy 105.387524 -61.870468)
			(xy 105.467483 -61.901444) (xy 105.544243 -61.939666) (xy 105.617149 -61.984807) (xy 105.685578 -62.036483)
			(xy 105.748948 -62.094252) (xy 105.806717 -62.157622) (xy 105.858393 -62.226051) (xy 105.903534 -62.298957)
			(xy 105.941756 -62.375717) (xy 105.972732 -62.455676) (xy 105.996199 -62.538152) (xy 106.011955 -62.622442)
			(xy 106.019867 -62.707825) (xy 106.020362 -62.7507) (xy 106.019867 -62.793575) (xy 106.011955 -62.878958)
			(xy 105.996199 -62.963248) (xy 105.972732 -63.045724) (xy 105.941756 -63.125683) (xy 105.903534 -63.202443)
			(xy 105.858393 -63.275349) (xy 105.806717 -63.343778) (xy 105.748948 -63.407148) (xy 105.685578 -63.464917)
			(xy 105.617149 -63.516593) (xy 105.544243 -63.561734) (xy 105.467483 -63.599956) (xy 105.387524 -63.630932)
			(xy 105.305048 -63.654399) (xy 105.220758 -63.670155) (xy 105.135375 -63.678067) (xy 105.049625 -63.678067)
			(xy 104.964242 -63.670155) (xy 104.879952 -63.654399) (xy 104.797476 -63.630932) (xy 104.717517 -63.599956)
			(xy 104.640757 -63.561734) (xy 104.567851 -63.516593) (xy 104.499422 -63.464917) (xy 104.436052 -63.407148)
			(xy 104.378283 -63.343778) (xy 104.326607 -63.275349) (xy 104.281466 -63.202443) (xy 104.243244 -63.125683)
			(xy 104.212268 -63.045724) (xy 104.188801 -62.963248) (xy 104.173045 -62.878958) (xy 104.165133 -62.793575)
			(xy 103.479867 -62.793575) (xy 103.471955 -62.878958) (xy 103.456199 -62.963248) (xy 103.432732 -63.045724)
			(xy 103.401756 -63.125683) (xy 103.363534 -63.202443) (xy 103.318393 -63.275349) (xy 103.266717 -63.343778)
			(xy 103.208948 -63.407148) (xy 103.145578 -63.464917) (xy 103.077149 -63.516593) (xy 103.004243 -63.561734)
			(xy 102.927483 -63.599956) (xy 102.847524 -63.630932) (xy 102.765048 -63.654399) (xy 102.680758 -63.670155)
			(xy 102.595375 -63.678067) (xy 102.509625 -63.678067) (xy 102.424242 -63.670155) (xy 102.339952 -63.654399)
			(xy 102.257476 -63.630932) (xy 102.177517 -63.599956) (xy 102.100757 -63.561734) (xy 102.027851 -63.516593)
			(xy 101.959422 -63.464917) (xy 101.896052 -63.407148) (xy 101.838283 -63.343778) (xy 101.786607 -63.275349)
			(xy 101.741466 -63.202443) (xy 101.703244 -63.125683) (xy 101.672268 -63.045724) (xy 101.648801 -62.963248)
			(xy 101.633045 -62.878958) (xy 101.625133 -62.793575) (xy 100.939867 -62.793575) (xy 100.931955 -62.878958)
			(xy 100.916199 -62.963248) (xy 100.892732 -63.045724) (xy 100.861756 -63.125683) (xy 100.823534 -63.202443)
			(xy 100.778393 -63.275349) (xy 100.726717 -63.343778) (xy 100.668948 -63.407148) (xy 100.605578 -63.464917)
			(xy 100.537149 -63.516593) (xy 100.464243 -63.561734) (xy 100.387483 -63.599956) (xy 100.307524 -63.630932)
			(xy 100.225048 -63.654399) (xy 100.140758 -63.670155) (xy 100.055375 -63.678067) (xy 99.969625 -63.678067)
			(xy 99.884242 -63.670155) (xy 99.799952 -63.654399) (xy 99.717476 -63.630932) (xy 99.637517 -63.599956)
			(xy 99.560757 -63.561734) (xy 99.487851 -63.516593) (xy 99.419422 -63.464917) (xy 99.356052 -63.407148)
			(xy 99.298283 -63.343778) (xy 99.246607 -63.275349) (xy 99.201466 -63.202443) (xy 99.163244 -63.125683)
			(xy 99.132268 -63.045724) (xy 99.108801 -62.963248) (xy 99.093045 -62.878958) (xy 99.085133 -62.793575)
			(xy 92.50807 -62.793575) (xy 92.50807 -69.143575) (xy 99.085133 -69.143575) (xy 99.085133 -69.057825)
			(xy 99.093045 -68.972442) (xy 99.108801 -68.888152) (xy 99.132268 -68.805676) (xy 99.163244 -68.725717)
			(xy 99.201466 -68.648957) (xy 99.246607 -68.576051) (xy 99.298283 -68.507622) (xy 99.356052 -68.444252)
			(xy 99.419422 -68.386483) (xy 99.487851 -68.334807) (xy 99.560757 -68.289666) (xy 99.637517 -68.251444)
			(xy 99.717476 -68.220468) (xy 99.799952 -68.197001) (xy 99.884242 -68.181245) (xy 99.969625 -68.173333)
			(xy 100.055375 -68.173333) (xy 100.140758 -68.181245) (xy 100.225048 -68.197001) (xy 100.307524 -68.220468)
			(xy 100.387483 -68.251444) (xy 100.464243 -68.289666) (xy 100.537149 -68.334807) (xy 100.605578 -68.386483)
			(xy 100.668948 -68.444252) (xy 100.726717 -68.507622) (xy 100.778393 -68.576051) (xy 100.823534 -68.648957)
			(xy 100.861756 -68.725717) (xy 100.892732 -68.805676) (xy 100.916199 -68.888152) (xy 100.931955 -68.972442)
			(xy 100.939867 -69.057825) (xy 100.940362 -69.1007) (xy 100.939867 -69.143575) (xy 101.625133 -69.143575)
			(xy 101.625133 -69.057825) (xy 101.633045 -68.972442) (xy 101.648801 -68.888152) (xy 101.672268 -68.805676)
			(xy 101.703244 -68.725717) (xy 101.741466 -68.648957) (xy 101.786607 -68.576051) (xy 101.838283 -68.507622)
			(xy 101.896052 -68.444252) (xy 101.959422 -68.386483) (xy 102.027851 -68.334807) (xy 102.100757 -68.289666)
			(xy 102.177517 -68.251444) (xy 102.257476 -68.220468) (xy 102.339952 -68.197001) (xy 102.424242 -68.181245)
			(xy 102.509625 -68.173333) (xy 102.595375 -68.173333) (xy 102.680758 -68.181245) (xy 102.765048 -68.197001)
			(xy 102.847524 -68.220468) (xy 102.927483 -68.251444) (xy 103.004243 -68.289666) (xy 103.077149 -68.334807)
			(xy 103.145578 -68.386483) (xy 103.208948 -68.444252) (xy 103.266717 -68.507622) (xy 103.318393 -68.576051)
			(xy 103.363534 -68.648957) (xy 103.401756 -68.725717) (xy 103.432732 -68.805676) (xy 103.456199 -68.888152)
			(xy 103.471955 -68.972442) (xy 103.479867 -69.057825) (xy 103.480362 -69.1007) (xy 103.479867 -69.143575)
			(xy 104.165133 -69.143575) (xy 104.165133 -69.057825) (xy 104.173045 -68.972442) (xy 104.188801 -68.888152)
			(xy 104.212268 -68.805676) (xy 104.243244 -68.725717) (xy 104.281466 -68.648957) (xy 104.326607 -68.576051)
			(xy 104.378283 -68.507622) (xy 104.436052 -68.444252) (xy 104.499422 -68.386483) (xy 104.567851 -68.334807)
			(xy 104.640757 -68.289666) (xy 104.717517 -68.251444) (xy 104.797476 -68.220468) (xy 104.879952 -68.197001)
			(xy 104.964242 -68.181245) (xy 105.049625 -68.173333) (xy 105.135375 -68.173333) (xy 105.220758 -68.181245)
			(xy 105.305048 -68.197001) (xy 105.387524 -68.220468) (xy 105.467483 -68.251444) (xy 105.544243 -68.289666)
			(xy 105.617149 -68.334807) (xy 105.685578 -68.386483) (xy 105.748948 -68.444252) (xy 105.806717 -68.507622)
			(xy 105.858393 -68.576051) (xy 105.903534 -68.648957) (xy 105.941756 -68.725717) (xy 105.972732 -68.805676)
			(xy 105.996199 -68.888152) (xy 106.011955 -68.972442) (xy 106.019867 -69.057825) (xy 106.020362 -69.1007)
			(xy 106.019867 -69.143575) (xy 106.011955 -69.228958) (xy 105.996199 -69.313248) (xy 105.972732 -69.395724)
			(xy 105.941756 -69.475683) (xy 105.903534 -69.552443) (xy 105.858393 -69.625349) (xy 105.806717 -69.693778)
			(xy 105.748948 -69.757148) (xy 105.685578 -69.814917) (xy 105.617149 -69.866593) (xy 105.544243 -69.911734)
			(xy 105.467483 -69.949956) (xy 105.387524 -69.980932) (xy 105.305048 -70.004399) (xy 105.220758 -70.020155)
			(xy 105.135375 -70.028067) (xy 105.049625 -70.028067) (xy 104.964242 -70.020155) (xy 104.879952 -70.004399)
			(xy 104.797476 -69.980932) (xy 104.717517 -69.949956) (xy 104.640757 -69.911734) (xy 104.567851 -69.866593)
			(xy 104.499422 -69.814917) (xy 104.436052 -69.757148) (xy 104.378283 -69.693778) (xy 104.326607 -69.625349)
			(xy 104.281466 -69.552443) (xy 104.243244 -69.475683) (xy 104.212268 -69.395724) (xy 104.188801 -69.313248)
			(xy 104.173045 -69.228958) (xy 104.165133 -69.143575) (xy 103.479867 -69.143575) (xy 103.471955 -69.228958)
			(xy 103.456199 -69.313248) (xy 103.432732 -69.395724) (xy 103.401756 -69.475683) (xy 103.363534 -69.552443)
			(xy 103.318393 -69.625349) (xy 103.266717 -69.693778) (xy 103.208948 -69.757148) (xy 103.145578 -69.814917)
			(xy 103.077149 -69.866593) (xy 103.004243 -69.911734) (xy 102.927483 -69.949956) (xy 102.847524 -69.980932)
			(xy 102.765048 -70.004399) (xy 102.680758 -70.020155) (xy 102.595375 -70.028067) (xy 102.509625 -70.028067)
			(xy 102.424242 -70.020155) (xy 102.339952 -70.004399) (xy 102.257476 -69.980932) (xy 102.177517 -69.949956)
			(xy 102.100757 -69.911734) (xy 102.027851 -69.866593) (xy 101.959422 -69.814917) (xy 101.896052 -69.757148)
			(xy 101.838283 -69.693778) (xy 101.786607 -69.625349) (xy 101.741466 -69.552443) (xy 101.703244 -69.475683)
			(xy 101.672268 -69.395724) (xy 101.648801 -69.313248) (xy 101.633045 -69.228958) (xy 101.625133 -69.143575)
			(xy 100.939867 -69.143575) (xy 100.931955 -69.228958) (xy 100.916199 -69.313248) (xy 100.892732 -69.395724)
			(xy 100.861756 -69.475683) (xy 100.823534 -69.552443) (xy 100.778393 -69.625349) (xy 100.726717 -69.693778)
			(xy 100.668948 -69.757148) (xy 100.605578 -69.814917) (xy 100.537149 -69.866593) (xy 100.464243 -69.911734)
			(xy 100.387483 -69.949956) (xy 100.307524 -69.980932) (xy 100.225048 -70.004399) (xy 100.140758 -70.020155)
			(xy 100.055375 -70.028067) (xy 99.969625 -70.028067) (xy 99.884242 -70.020155) (xy 99.799952 -70.004399)
			(xy 99.717476 -69.980932) (xy 99.637517 -69.949956) (xy 99.560757 -69.911734) (xy 99.487851 -69.866593)
			(xy 99.419422 -69.814917) (xy 99.356052 -69.757148) (xy 99.298283 -69.693778) (xy 99.246607 -69.625349)
			(xy 99.201466 -69.552443) (xy 99.163244 -69.475683) (xy 99.132268 -69.395724) (xy 99.108801 -69.313248)
			(xy 99.093045 -69.228958) (xy 99.085133 -69.143575) (xy 92.50807 -69.143575) (xy 92.50807 -94.976137)
			(xy 93.729289 -94.976137) (xy 93.729289 -94.890387) (xy 93.737201 -94.805004) (xy 93.752957 -94.720714)
			(xy 93.776424 -94.638238) (xy 93.8074 -94.558279) (xy 93.845622 -94.481519) (xy 93.890763 -94.408613)
			(xy 93.942439 -94.340184) (xy 94.000208 -94.276814) (xy 94.063578 -94.219045) (xy 94.132007 -94.167369)
			(xy 94.204913 -94.122228) (xy 94.281673 -94.084006) (xy 94.361632 -94.05303) (xy 94.444108 -94.029563)
			(xy 94.528398 -94.013807) (xy 94.613781 -94.005895) (xy 94.699531 -94.005895) (xy 94.784914 -94.013807)
			(xy 94.869204 -94.029563) (xy 94.95168 -94.05303) (xy 95.031639 -94.084006) (xy 95.108399 -94.122228)
			(xy 95.181305 -94.167369) (xy 95.249734 -94.219045) (xy 95.313104 -94.276814) (xy 95.370873 -94.340184)
			(xy 95.422549 -94.408613) (xy 95.46769 -94.481519) (xy 95.505912 -94.558279) (xy 95.536888 -94.638238)
			(xy 95.560355 -94.720714) (xy 95.576111 -94.805004) (xy 95.584023 -94.890387) (xy 95.584518 -94.933262)
			(xy 95.584023 -94.976137) (xy 96.269289 -94.976137) (xy 96.269289 -94.890387) (xy 96.277201 -94.805004)
			(xy 96.292957 -94.720714) (xy 96.316424 -94.638238) (xy 96.3474 -94.558279) (xy 96.385622 -94.481519)
			(xy 96.430763 -94.408613) (xy 96.482439 -94.340184) (xy 96.540208 -94.276814) (xy 96.603578 -94.219045)
			(xy 96.672007 -94.167369) (xy 96.744913 -94.122228) (xy 96.821673 -94.084006) (xy 96.901632 -94.05303)
			(xy 96.984108 -94.029563) (xy 97.068398 -94.013807) (xy 97.153781 -94.005895) (xy 97.239531 -94.005895)
			(xy 97.324914 -94.013807) (xy 97.409204 -94.029563) (xy 97.49168 -94.05303) (xy 97.571639 -94.084006)
			(xy 97.648399 -94.122228) (xy 97.721305 -94.167369) (xy 97.789734 -94.219045) (xy 97.853104 -94.276814)
			(xy 97.910873 -94.340184) (xy 97.962549 -94.408613) (xy 98.00769 -94.481519) (xy 98.045912 -94.558279)
			(xy 98.076888 -94.638238) (xy 98.100355 -94.720714) (xy 98.116111 -94.805004) (xy 98.124023 -94.890387)
			(xy 98.124518 -94.933262) (xy 98.124023 -94.976137) (xy 98.116111 -95.06152) (xy 98.100355 -95.14581)
			(xy 98.076888 -95.228286) (xy 98.045912 -95.308245) (xy 98.00769 -95.385005) (xy 97.962549 -95.457911)
			(xy 97.910873 -95.52634) (xy 97.853104 -95.58971) (xy 97.789734 -95.647479) (xy 97.721305 -95.699155)
			(xy 97.648399 -95.744296) (xy 97.571639 -95.782518) (xy 97.49168 -95.813494) (xy 97.409204 -95.836961)
			(xy 97.324914 -95.852717) (xy 97.239531 -95.860629) (xy 97.153781 -95.860629) (xy 97.068398 -95.852717)
			(xy 96.984108 -95.836961) (xy 96.901632 -95.813494) (xy 96.821673 -95.782518) (xy 96.744913 -95.744296)
			(xy 96.672007 -95.699155) (xy 96.603578 -95.647479) (xy 96.540208 -95.58971) (xy 96.482439 -95.52634)
			(xy 96.430763 -95.457911) (xy 96.385622 -95.385005) (xy 96.3474 -95.308245) (xy 96.316424 -95.228286)
			(xy 96.292957 -95.14581) (xy 96.277201 -95.06152) (xy 96.269289 -94.976137) (xy 95.584023 -94.976137)
			(xy 95.576111 -95.06152) (xy 95.560355 -95.14581) (xy 95.536888 -95.228286) (xy 95.505912 -95.308245)
			(xy 95.46769 -95.385005) (xy 95.422549 -95.457911) (xy 95.370873 -95.52634) (xy 95.313104 -95.58971)
			(xy 95.249734 -95.647479) (xy 95.181305 -95.699155) (xy 95.108399 -95.744296) (xy 95.031639 -95.782518)
			(xy 94.95168 -95.813494) (xy 94.869204 -95.836961) (xy 94.784914 -95.852717) (xy 94.699531 -95.860629)
			(xy 94.613781 -95.860629) (xy 94.528398 -95.852717) (xy 94.444108 -95.836961) (xy 94.361632 -95.813494)
			(xy 94.281673 -95.782518) (xy 94.204913 -95.744296) (xy 94.132007 -95.699155) (xy 94.063578 -95.647479)
			(xy 94.000208 -95.58971) (xy 93.942439 -95.52634) (xy 93.890763 -95.457911) (xy 93.845622 -95.385005)
			(xy 93.8074 -95.308245) (xy 93.776424 -95.228286) (xy 93.752957 -95.14581) (xy 93.737201 -95.06152)
			(xy 93.729289 -94.976137) (xy 92.50807 -94.976137) (xy 92.50807 -96.949868) (xy 95.113614 -96.949868)
			(xy 95.113614 -96.895332) (xy 95.121375 -96.841351) (xy 95.136739 -96.789023) (xy 95.159392 -96.739415)
			(xy 95.188875 -96.693535) (xy 95.224586 -96.652317) (xy 95.2658 -96.616601) (xy 95.311676 -96.587113)
			(xy 95.361282 -96.564454) (xy 95.413608 -96.549084) (xy 95.467588 -96.541317) (xy 95.494856 -96.540828)
			(xy 96.358456 -96.540828) (xy 96.385728 -96.541308) (xy 96.439719 -96.549065) (xy 96.492055 -96.564427)
			(xy 96.541673 -96.587082) (xy 96.587561 -96.616568) (xy 96.628785 -96.652284) (xy 96.664506 -96.693504)
			(xy 96.693997 -96.739389) (xy 96.716657 -96.789004) (xy 96.732025 -96.841338) (xy 96.739788 -96.895328)
			(xy 96.739788 -96.949872) (xy 96.732025 -97.003862) (xy 96.716657 -97.056196) (xy 96.693997 -97.105811)
			(xy 96.664506 -97.151696) (xy 96.628785 -97.192916) (xy 96.587561 -97.228632) (xy 96.541673 -97.258118)
			(xy 96.492055 -97.280773) (xy 96.439719 -97.296135) (xy 96.385728 -97.303892) (xy 96.358456 -97.304352)
			(xy 95.494856 -97.304352) (xy 95.467588 -97.303883) (xy 95.413608 -97.296116) (xy 95.361282 -97.280746)
			(xy 95.311676 -97.258087) (xy 95.2658 -97.228599) (xy 95.224586 -97.192883) (xy 95.188875 -97.151665)
			(xy 95.159392 -97.105785) (xy 95.136739 -97.056177) (xy 95.121375 -97.003849) (xy 95.113614 -96.949868)
			(xy 92.50807 -96.949868) (xy 92.50807 -101.326137) (xy 93.729289 -101.326137) (xy 93.729289 -101.240387)
			(xy 93.737201 -101.155004) (xy 93.752957 -101.070714) (xy 93.776424 -100.988238) (xy 93.8074 -100.908279)
			(xy 93.845622 -100.831519) (xy 93.890763 -100.758613) (xy 93.942439 -100.690184) (xy 94.000208 -100.626814)
			(xy 94.063578 -100.569045) (xy 94.132007 -100.517369) (xy 94.204913 -100.472228) (xy 94.281673 -100.434006)
			(xy 94.361632 -100.40303) (xy 94.444108 -100.379563) (xy 94.528398 -100.363807) (xy 94.613781 -100.355895)
			(xy 94.699531 -100.355895) (xy 94.784914 -100.363807) (xy 94.869204 -100.379563) (xy 94.95168 -100.40303)
			(xy 95.031639 -100.434006) (xy 95.108399 -100.472228) (xy 95.181305 -100.517369) (xy 95.249734 -100.569045)
			(xy 95.313104 -100.626814) (xy 95.370873 -100.690184) (xy 95.422549 -100.758613) (xy 95.46769 -100.831519)
			(xy 95.505912 -100.908279) (xy 95.536888 -100.988238) (xy 95.560355 -101.070714) (xy 95.576111 -101.155004)
			(xy 95.584023 -101.240387) (xy 95.584518 -101.283262) (xy 95.584023 -101.326137) (xy 96.269289 -101.326137)
			(xy 96.269289 -101.240387) (xy 96.277201 -101.155004) (xy 96.292957 -101.070714) (xy 96.316424 -100.988238)
			(xy 96.3474 -100.908279) (xy 96.385622 -100.831519) (xy 96.430763 -100.758613) (xy 96.482439 -100.690184)
			(xy 96.540208 -100.626814) (xy 96.603578 -100.569045) (xy 96.672007 -100.517369) (xy 96.744913 -100.472228)
			(xy 96.821673 -100.434006) (xy 96.901632 -100.40303) (xy 96.984108 -100.379563) (xy 97.068398 -100.363807)
			(xy 97.153781 -100.355895) (xy 97.239531 -100.355895) (xy 97.324914 -100.363807) (xy 97.409204 -100.379563)
			(xy 97.49168 -100.40303) (xy 97.571639 -100.434006) (xy 97.648399 -100.472228) (xy 97.721305 -100.517369)
			(xy 97.789734 -100.569045) (xy 97.853104 -100.626814) (xy 97.910873 -100.690184) (xy 97.962549 -100.758613)
			(xy 98.00769 -100.831519) (xy 98.045912 -100.908279) (xy 98.076888 -100.988238) (xy 98.100355 -101.070714)
			(xy 98.116111 -101.155004) (xy 98.124023 -101.240387) (xy 98.124518 -101.283262) (xy 98.124023 -101.326137)
			(xy 98.122681 -101.340615) (xy 99.085133 -101.340615) (xy 99.085133 -101.254865) (xy 99.093045 -101.169482)
			(xy 99.108801 -101.085192) (xy 99.132268 -101.002716) (xy 99.163244 -100.922757) (xy 99.201466 -100.845997)
			(xy 99.246607 -100.773091) (xy 99.298283 -100.704662) (xy 99.356052 -100.641292) (xy 99.419422 -100.583523)
			(xy 99.487851 -100.531847) (xy 99.560757 -100.486706) (xy 99.637517 -100.448484) (xy 99.717476 -100.417508)
			(xy 99.799952 -100.394041) (xy 99.884242 -100.378285) (xy 99.969625 -100.370373) (xy 100.055375 -100.370373)
			(xy 100.140758 -100.378285) (xy 100.225048 -100.394041) (xy 100.307524 -100.417508) (xy 100.387483 -100.448484)
			(xy 100.464243 -100.486706) (xy 100.537149 -100.531847) (xy 100.605578 -100.583523) (xy 100.668948 -100.641292)
			(xy 100.726717 -100.704662) (xy 100.778393 -100.773091) (xy 100.823534 -100.845997) (xy 100.861756 -100.922757)
			(xy 100.892732 -101.002716) (xy 100.916199 -101.085192) (xy 100.931955 -101.169482) (xy 100.939867 -101.254865)
			(xy 100.940362 -101.29774) (xy 100.939867 -101.340615) (xy 101.625133 -101.340615) (xy 101.625133 -101.254865)
			(xy 101.633045 -101.169482) (xy 101.648801 -101.085192) (xy 101.672268 -101.002716) (xy 101.703244 -100.922757)
			(xy 101.741466 -100.845997) (xy 101.786607 -100.773091) (xy 101.838283 -100.704662) (xy 101.896052 -100.641292)
			(xy 101.959422 -100.583523) (xy 102.027851 -100.531847) (xy 102.100757 -100.486706) (xy 102.177517 -100.448484)
			(xy 102.257476 -100.417508) (xy 102.339952 -100.394041) (xy 102.424242 -100.378285) (xy 102.509625 -100.370373)
			(xy 102.595375 -100.370373) (xy 102.680758 -100.378285) (xy 102.765048 -100.394041) (xy 102.847524 -100.417508)
			(xy 102.927483 -100.448484) (xy 103.004243 -100.486706) (xy 103.077149 -100.531847) (xy 103.145578 -100.583523)
			(xy 103.208948 -100.641292) (xy 103.266717 -100.704662) (xy 103.318393 -100.773091) (xy 103.363534 -100.845997)
			(xy 103.401756 -100.922757) (xy 103.432732 -101.002716) (xy 103.456199 -101.085192) (xy 103.471955 -101.169482)
			(xy 103.479867 -101.254865) (xy 103.480362 -101.29774) (xy 103.479867 -101.340615) (xy 104.165133 -101.340615)
			(xy 104.165133 -101.254865) (xy 104.173045 -101.169482) (xy 104.188801 -101.085192) (xy 104.212268 -101.002716)
			(xy 104.243244 -100.922757) (xy 104.281466 -100.845997) (xy 104.326607 -100.773091) (xy 104.378283 -100.704662)
			(xy 104.436052 -100.641292) (xy 104.499422 -100.583523) (xy 104.567851 -100.531847) (xy 104.640757 -100.486706)
			(xy 104.717517 -100.448484) (xy 104.797476 -100.417508) (xy 104.879952 -100.394041) (xy 104.964242 -100.378285)
			(xy 105.049625 -100.370373) (xy 105.135375 -100.370373) (xy 105.220758 -100.378285) (xy 105.305048 -100.394041)
			(xy 105.387524 -100.417508) (xy 105.467483 -100.448484) (xy 105.544243 -100.486706) (xy 105.617149 -100.531847)
			(xy 105.685578 -100.583523) (xy 105.748948 -100.641292) (xy 105.806717 -100.704662) (xy 105.858393 -100.773091)
			(xy 105.903534 -100.845997) (xy 105.941756 -100.922757) (xy 105.972732 -101.002716) (xy 105.996199 -101.085192)
			(xy 106.011955 -101.169482) (xy 106.019867 -101.254865) (xy 106.020362 -101.29774) (xy 106.019867 -101.340615)
			(xy 106.011955 -101.425998) (xy 105.996199 -101.510288) (xy 105.972732 -101.592764) (xy 105.941756 -101.672723)
			(xy 105.903534 -101.749483) (xy 105.858393 -101.822389) (xy 105.806717 -101.890818) (xy 105.748948 -101.954188)
			(xy 105.685578 -102.011957) (xy 105.617149 -102.063633) (xy 105.544243 -102.108774) (xy 105.467483 -102.146996)
			(xy 105.387524 -102.177972) (xy 105.305048 -102.201439) (xy 105.220758 -102.217195) (xy 105.135375 -102.225107)
			(xy 105.049625 -102.225107) (xy 104.964242 -102.217195) (xy 104.879952 -102.201439) (xy 104.797476 -102.177972)
			(xy 104.717517 -102.146996) (xy 104.640757 -102.108774) (xy 104.567851 -102.063633) (xy 104.499422 -102.011957)
			(xy 104.436052 -101.954188) (xy 104.378283 -101.890818) (xy 104.326607 -101.822389) (xy 104.281466 -101.749483)
			(xy 104.243244 -101.672723) (xy 104.212268 -101.592764) (xy 104.188801 -101.510288) (xy 104.173045 -101.425998)
			(xy 104.165133 -101.340615) (xy 103.479867 -101.340615) (xy 103.471955 -101.425998) (xy 103.456199 -101.510288)
			(xy 103.432732 -101.592764) (xy 103.401756 -101.672723) (xy 103.363534 -101.749483) (xy 103.318393 -101.822389)
			(xy 103.266717 -101.890818) (xy 103.208948 -101.954188) (xy 103.145578 -102.011957) (xy 103.077149 -102.063633)
			(xy 103.004243 -102.108774) (xy 102.927483 -102.146996) (xy 102.847524 -102.177972) (xy 102.765048 -102.201439)
			(xy 102.680758 -102.217195) (xy 102.595375 -102.225107) (xy 102.509625 -102.225107) (xy 102.424242 -102.217195)
			(xy 102.339952 -102.201439) (xy 102.257476 -102.177972) (xy 102.177517 -102.146996) (xy 102.100757 -102.108774)
			(xy 102.027851 -102.063633) (xy 101.959422 -102.011957) (xy 101.896052 -101.954188) (xy 101.838283 -101.890818)
			(xy 101.786607 -101.822389) (xy 101.741466 -101.749483) (xy 101.703244 -101.672723) (xy 101.672268 -101.592764)
			(xy 101.648801 -101.510288) (xy 101.633045 -101.425998) (xy 101.625133 -101.340615) (xy 100.939867 -101.340615)
			(xy 100.931955 -101.425998) (xy 100.916199 -101.510288) (xy 100.892732 -101.592764) (xy 100.861756 -101.672723)
			(xy 100.823534 -101.749483) (xy 100.778393 -101.822389) (xy 100.726717 -101.890818) (xy 100.668948 -101.954188)
			(xy 100.605578 -102.011957) (xy 100.537149 -102.063633) (xy 100.464243 -102.108774) (xy 100.387483 -102.146996)
			(xy 100.307524 -102.177972) (xy 100.225048 -102.201439) (xy 100.140758 -102.217195) (xy 100.055375 -102.225107)
			(xy 99.969625 -102.225107) (xy 99.884242 -102.217195) (xy 99.799952 -102.201439) (xy 99.717476 -102.177972)
			(xy 99.637517 -102.146996) (xy 99.560757 -102.108774) (xy 99.487851 -102.063633) (xy 99.419422 -102.011957)
			(xy 99.356052 -101.954188) (xy 99.298283 -101.890818) (xy 99.246607 -101.822389) (xy 99.201466 -101.749483)
			(xy 99.163244 -101.672723) (xy 99.132268 -101.592764) (xy 99.108801 -101.510288) (xy 99.093045 -101.425998)
			(xy 99.085133 -101.340615) (xy 98.122681 -101.340615) (xy 98.116111 -101.41152) (xy 98.100355 -101.49581)
			(xy 98.076888 -101.578286) (xy 98.045912 -101.658245) (xy 98.00769 -101.735005) (xy 97.962549 -101.807911)
			(xy 97.910873 -101.87634) (xy 97.853104 -101.93971) (xy 97.789734 -101.997479) (xy 97.721305 -102.049155)
			(xy 97.648399 -102.094296) (xy 97.571639 -102.132518) (xy 97.49168 -102.163494) (xy 97.409204 -102.186961)
			(xy 97.324914 -102.202717) (xy 97.239531 -102.210629) (xy 97.153781 -102.210629) (xy 97.068398 -102.202717)
			(xy 96.984108 -102.186961) (xy 96.901632 -102.163494) (xy 96.821673 -102.132518) (xy 96.744913 -102.094296)
			(xy 96.672007 -102.049155) (xy 96.603578 -101.997479) (xy 96.540208 -101.93971) (xy 96.482439 -101.87634)
			(xy 96.430763 -101.807911) (xy 96.385622 -101.735005) (xy 96.3474 -101.658245) (xy 96.316424 -101.578286)
			(xy 96.292957 -101.49581) (xy 96.277201 -101.41152) (xy 96.269289 -101.326137) (xy 95.584023 -101.326137)
			(xy 95.576111 -101.41152) (xy 95.560355 -101.49581) (xy 95.536888 -101.578286) (xy 95.505912 -101.658245)
			(xy 95.46769 -101.735005) (xy 95.422549 -101.807911) (xy 95.370873 -101.87634) (xy 95.313104 -101.93971)
			(xy 95.249734 -101.997479) (xy 95.181305 -102.049155) (xy 95.108399 -102.094296) (xy 95.031639 -102.132518)
			(xy 94.95168 -102.163494) (xy 94.869204 -102.186961) (xy 94.784914 -102.202717) (xy 94.699531 -102.210629)
			(xy 94.613781 -102.210629) (xy 94.528398 -102.202717) (xy 94.444108 -102.186961) (xy 94.361632 -102.163494)
			(xy 94.281673 -102.132518) (xy 94.204913 -102.094296) (xy 94.132007 -102.049155) (xy 94.063578 -101.997479)
			(xy 94.000208 -101.93971) (xy 93.942439 -101.87634) (xy 93.890763 -101.807911) (xy 93.845622 -101.735005)
			(xy 93.8074 -101.658245) (xy 93.776424 -101.578286) (xy 93.752957 -101.49581) (xy 93.737201 -101.41152)
			(xy 93.729289 -101.326137) (xy 92.50807 -101.326137) (xy 92.50807 -107.690615) (xy 99.085133 -107.690615)
			(xy 99.085133 -107.604865) (xy 99.093045 -107.519482) (xy 99.108801 -107.435192) (xy 99.132268 -107.352716)
			(xy 99.163244 -107.272757) (xy 99.201466 -107.195997) (xy 99.246607 -107.123091) (xy 99.298283 -107.054662)
			(xy 99.356052 -106.991292) (xy 99.419422 -106.933523) (xy 99.487851 -106.881847) (xy 99.560757 -106.836706)
			(xy 99.637517 -106.798484) (xy 99.717476 -106.767508) (xy 99.799952 -106.744041) (xy 99.884242 -106.728285)
			(xy 99.969625 -106.720373) (xy 100.055375 -106.720373) (xy 100.140758 -106.728285) (xy 100.225048 -106.744041)
			(xy 100.307524 -106.767508) (xy 100.387483 -106.798484) (xy 100.464243 -106.836706) (xy 100.537149 -106.881847)
			(xy 100.605578 -106.933523) (xy 100.668948 -106.991292) (xy 100.726717 -107.054662) (xy 100.778393 -107.123091)
			(xy 100.823534 -107.195997) (xy 100.861756 -107.272757) (xy 100.892732 -107.352716) (xy 100.916199 -107.435192)
			(xy 100.931955 -107.519482) (xy 100.939867 -107.604865) (xy 100.940362 -107.64774) (xy 100.939867 -107.690615)
			(xy 101.625133 -107.690615) (xy 101.625133 -107.604865) (xy 101.633045 -107.519482) (xy 101.648801 -107.435192)
			(xy 101.672268 -107.352716) (xy 101.703244 -107.272757) (xy 101.741466 -107.195997) (xy 101.786607 -107.123091)
			(xy 101.838283 -107.054662) (xy 101.896052 -106.991292) (xy 101.959422 -106.933523) (xy 102.027851 -106.881847)
			(xy 102.100757 -106.836706) (xy 102.177517 -106.798484) (xy 102.257476 -106.767508) (xy 102.339952 -106.744041)
			(xy 102.424242 -106.728285) (xy 102.509625 -106.720373) (xy 102.595375 -106.720373) (xy 102.680758 -106.728285)
			(xy 102.765048 -106.744041) (xy 102.847524 -106.767508) (xy 102.927483 -106.798484) (xy 103.004243 -106.836706)
			(xy 103.077149 -106.881847) (xy 103.145578 -106.933523) (xy 103.208948 -106.991292) (xy 103.266717 -107.054662)
			(xy 103.318393 -107.123091) (xy 103.363534 -107.195997) (xy 103.401756 -107.272757) (xy 103.432732 -107.352716)
			(xy 103.456199 -107.435192) (xy 103.471955 -107.519482) (xy 103.479867 -107.604865) (xy 103.480362 -107.64774)
			(xy 103.479867 -107.690615) (xy 104.165133 -107.690615) (xy 104.165133 -107.604865) (xy 104.173045 -107.519482)
			(xy 104.188801 -107.435192) (xy 104.212268 -107.352716) (xy 104.243244 -107.272757) (xy 104.281466 -107.195997)
			(xy 104.326607 -107.123091) (xy 104.378283 -107.054662) (xy 104.436052 -106.991292) (xy 104.499422 -106.933523)
			(xy 104.567851 -106.881847) (xy 104.640757 -106.836706) (xy 104.717517 -106.798484) (xy 104.797476 -106.767508)
			(xy 104.879952 -106.744041) (xy 104.964242 -106.728285) (xy 105.049625 -106.720373) (xy 105.135375 -106.720373)
			(xy 105.220758 -106.728285) (xy 105.305048 -106.744041) (xy 105.387524 -106.767508) (xy 105.467483 -106.798484)
			(xy 105.544243 -106.836706) (xy 105.617149 -106.881847) (xy 105.685578 -106.933523) (xy 105.748948 -106.991292)
			(xy 105.806717 -107.054662) (xy 105.858393 -107.123091) (xy 105.903534 -107.195997) (xy 105.941756 -107.272757)
			(xy 105.972732 -107.352716) (xy 105.996199 -107.435192) (xy 106.011955 -107.519482) (xy 106.019867 -107.604865)
			(xy 106.020362 -107.64774) (xy 106.019867 -107.690615) (xy 106.011955 -107.775998) (xy 105.996199 -107.860288)
			(xy 105.972732 -107.942764) (xy 105.941756 -108.022723) (xy 105.903534 -108.099483) (xy 105.858393 -108.172389)
			(xy 105.806717 -108.240818) (xy 105.748948 -108.304188) (xy 105.685578 -108.361957) (xy 105.617149 -108.413633)
			(xy 105.544243 -108.458774) (xy 105.467483 -108.496996) (xy 105.387524 -108.527972) (xy 105.305048 -108.551439)
			(xy 105.220758 -108.567195) (xy 105.135375 -108.575107) (xy 105.049625 -108.575107) (xy 104.964242 -108.567195)
			(xy 104.879952 -108.551439) (xy 104.797476 -108.527972) (xy 104.717517 -108.496996) (xy 104.640757 -108.458774)
			(xy 104.567851 -108.413633) (xy 104.499422 -108.361957) (xy 104.436052 -108.304188) (xy 104.378283 -108.240818)
			(xy 104.326607 -108.172389) (xy 104.281466 -108.099483) (xy 104.243244 -108.022723) (xy 104.212268 -107.942764)
			(xy 104.188801 -107.860288) (xy 104.173045 -107.775998) (xy 104.165133 -107.690615) (xy 103.479867 -107.690615)
			(xy 103.471955 -107.775998) (xy 103.456199 -107.860288) (xy 103.432732 -107.942764) (xy 103.401756 -108.022723)
			(xy 103.363534 -108.099483) (xy 103.318393 -108.172389) (xy 103.266717 -108.240818) (xy 103.208948 -108.304188)
			(xy 103.145578 -108.361957) (xy 103.077149 -108.413633) (xy 103.004243 -108.458774) (xy 102.927483 -108.496996)
			(xy 102.847524 -108.527972) (xy 102.765048 -108.551439) (xy 102.680758 -108.567195) (xy 102.595375 -108.575107)
			(xy 102.509625 -108.575107) (xy 102.424242 -108.567195) (xy 102.339952 -108.551439) (xy 102.257476 -108.527972)
			(xy 102.177517 -108.496996) (xy 102.100757 -108.458774) (xy 102.027851 -108.413633) (xy 101.959422 -108.361957)
			(xy 101.896052 -108.304188) (xy 101.838283 -108.240818) (xy 101.786607 -108.172389) (xy 101.741466 -108.099483)
			(xy 101.703244 -108.022723) (xy 101.672268 -107.942764) (xy 101.648801 -107.860288) (xy 101.633045 -107.775998)
			(xy 101.625133 -107.690615) (xy 100.939867 -107.690615) (xy 100.931955 -107.775998) (xy 100.916199 -107.860288)
			(xy 100.892732 -107.942764) (xy 100.861756 -108.022723) (xy 100.823534 -108.099483) (xy 100.778393 -108.172389)
			(xy 100.726717 -108.240818) (xy 100.668948 -108.304188) (xy 100.605578 -108.361957) (xy 100.537149 -108.413633)
			(xy 100.464243 -108.458774) (xy 100.387483 -108.496996) (xy 100.307524 -108.527972) (xy 100.225048 -108.551439)
			(xy 100.140758 -108.567195) (xy 100.055375 -108.575107) (xy 99.969625 -108.575107) (xy 99.884242 -108.567195)
			(xy 99.799952 -108.551439) (xy 99.717476 -108.527972) (xy 99.637517 -108.496996) (xy 99.560757 -108.458774)
			(xy 99.487851 -108.413633) (xy 99.419422 -108.361957) (xy 99.356052 -108.304188) (xy 99.298283 -108.240818)
			(xy 99.246607 -108.172389) (xy 99.201466 -108.099483) (xy 99.163244 -108.022723) (xy 99.132268 -107.942764)
			(xy 99.108801 -107.860288) (xy 99.093045 -107.775998) (xy 99.085133 -107.690615) (xy 92.50807 -107.690615)
			(xy 92.50807 -115.464644) (xy 115.904253 -115.464644) (xy 115.904253 -115.335504) (xy 115.912203 -115.206609)
			(xy 115.928073 -115.078449) (xy 115.951802 -114.951508) (xy 115.983301 -114.826269) (xy 116.02245 -114.703206)
			(xy 116.069101 -114.582787) (xy 116.123076 -114.465468) (xy 116.184171 -114.351694) (xy 116.252154 -114.241897)
			(xy 116.326768 -114.136494) (xy 116.407729 -114.035884) (xy 116.494729 -113.940449) (xy 116.58744 -113.85055)
			(xy 116.68551 -113.766529) (xy 116.788565 -113.688705) (xy 116.896216 -113.617373) (xy 117.008055 -113.552803)
			(xy 117.123656 -113.495241) (xy 117.242581 -113.444904) (xy 117.36438 -113.401984) (xy 117.48859 -113.366643)
			(xy 117.614739 -113.339016) (xy 117.742351 -113.319207) (xy 117.87094 -113.307291) (xy 118.000018 -113.303315)
			(xy 118.129096 -113.307291) (xy 118.257685 -113.319207) (xy 118.385297 -113.339016) (xy 118.511446 -113.366643)
			(xy 118.635656 -113.401984) (xy 118.757455 -113.444904) (xy 118.87638 -113.495241) (xy 118.991981 -113.552803)
			(xy 119.10382 -113.617373) (xy 119.211471 -113.688705) (xy 119.314526 -113.766529) (xy 119.412596 -113.85055)
			(xy 119.505307 -113.940449) (xy 119.592307 -114.035884) (xy 119.673268 -114.136494) (xy 119.747882 -114.241897)
			(xy 119.815865 -114.351694) (xy 119.87696 -114.465468) (xy 119.930935 -114.582787) (xy 119.977586 -114.703206)
			(xy 120.016735 -114.826269) (xy 120.048234 -114.951508) (xy 120.071963 -115.078449) (xy 120.087833 -115.206609)
			(xy 120.095783 -115.335504) (xy 120.09628 -115.400074) (xy 120.095783 -115.464644) (xy 120.087833 -115.593539)
			(xy 120.071963 -115.721699) (xy 120.048234 -115.84864) (xy 120.016735 -115.973879) (xy 119.977586 -116.096942)
			(xy 119.930935 -116.217361) (xy 119.87696 -116.33468) (xy 119.815865 -116.448454) (xy 119.747882 -116.558251)
			(xy 119.673268 -116.663654) (xy 119.592307 -116.764264) (xy 119.505307 -116.859699) (xy 119.412596 -116.949598)
			(xy 119.314526 -117.033619) (xy 119.211471 -117.111443) (xy 119.10382 -117.182775) (xy 118.991981 -117.247345)
			(xy 118.87638 -117.304907) (xy 118.757455 -117.355244) (xy 118.635656 -117.398164) (xy 118.511446 -117.433505)
			(xy 118.385297 -117.461132) (xy 118.257685 -117.480941) (xy 118.129096 -117.492857) (xy 118.000018 -117.496834)
			(xy 117.87094 -117.492857) (xy 117.742351 -117.480941) (xy 117.614739 -117.461132) (xy 117.48859 -117.433505)
			(xy 117.36438 -117.398164) (xy 117.242581 -117.355244) (xy 117.123656 -117.304907) (xy 117.008055 -117.247345)
			(xy 116.896216 -117.182775) (xy 116.788565 -117.111443) (xy 116.68551 -117.033619) (xy 116.58744 -116.949598)
			(xy 116.494729 -116.859699) (xy 116.407729 -116.764264) (xy 116.326768 -116.663654) (xy 116.252154 -116.558251)
			(xy 116.184171 -116.448454) (xy 116.123076 -116.33468) (xy 116.069101 -116.217361) (xy 116.02245 -116.096942)
			(xy 115.983301 -115.973879) (xy 115.951802 -115.84864) (xy 115.928073 -115.721699) (xy 115.912203 -115.593539)
			(xy 115.904253 -115.464644) (xy 92.50807 -115.464644) (xy 92.50807 -118.400068) (xy 92.508591 -118.455876)
			(xy 92.516929 -118.567181) (xy 92.533562 -118.677551) (xy 92.558397 -118.78637) (xy 92.591294 -118.893028)
			(xy 92.63207 -118.99693) (xy 92.680497 -119.097494) (xy 92.736303 -119.194158) (xy 92.799176 -119.286381)
			(xy 92.868766 -119.373648) (xy 92.944683 -119.45547) (xy 93.026502 -119.531391) (xy 93.113766 -119.600984)
			(xy 93.205986 -119.663862) (xy 93.302648 -119.719673) (xy 93.40321 -119.768103) (xy 93.50711 -119.808884)
			(xy 93.613767 -119.841786) (xy 93.722584 -119.866625) (xy 93.832954 -119.883263) (xy 93.944258 -119.891607)
			(xy 94.000066 -119.892064)
		)
		(stroke
			(width 0)
			(type solid)
		)
		(fill yes)
		(layer "In8.Cu")
		(net "GND_P1")
	)
	(gr_poly
		(pts
			(xy 22.6568 -79.3242) (xy 22.6568 -75.6158) (xy 22.45233 -75.41133) (xy 19.096228 -75.41133) (xy 18.927064 -75.580494)
			(xy 18.927064 -78.769464) (xy 19.67103 -79.51343) (xy 22.46757 -79.51343)
		)
		(stroke
			(width 0)
			(type solid)
		)
		(fill yes)
		(layer "In9.Cu")
		(net "GND")
	)
	(gr_poly
		(pts
			(xy 80.255364 -118.737634) (xy 80.255364 -115.252754) (xy 80.174338 -115.171728) (xy 79.865474 -115.171728)
			(xy 79.748126 -115.289076) (xy 79.748126 -118.718584) (xy 79.85379 -118.824248) (xy 80.16875 -118.824248)
		)
		(stroke
			(width 0)
			(type solid)
		)
		(fill yes)
		(layer "In9.Cu")
		(net "GND")
	)
	(gr_poly
		(pts
			(xy 58.743088 -28.44165)
			(arc
				(start 58.707782 -28.43022)
				(mid 58.442896 -28.067)
				(end 58.707782 -27.70378)
			)
			(xy 58.743088 -27.69235) (xy 58.743088 -26.838148) (xy 55.359808 -26.838148) (xy 55.359808 -29.405326)
			(xy 58.743088 -29.405326)
		)
		(stroke
			(width 0)
			(type solid)
		)
		(fill yes)
		(layer "In9.Cu")
		(net "GND")
	)
	(gr_poly
		(pts
			(xy 76.221844 -117.139466) (xy 76.221844 -113.814098) (xy 76.859892 -113.17605) (xy 83.762342 -113.17605)
			(xy 84.430616 -112.507776)
			(arc
				(start 84.430616 -110.06836)
				(mid 84.427244 -110.00096)
				(end 84.426044 -109.933486)
			)
			(arc
				(start 84.426044 -109.933486)
				(mid 84.427245 -109.866012)
				(end 84.430616 -109.798612)
			)
			(xy 84.430616 -108.609384) (xy 85.68817 -107.35183) (xy 85.68817 -103.115364) (xy 85.536024 -102.963218)
			(xy 80.399382 -102.963218) (xy 79.7687 -103.5939) (xy 79.7687 -109.309662) (xy 78.227174 -110.851188)
			(xy 75.244706 -110.851188) (xy 74.866246 -111.229648) (xy 74.866246 -117.131846) (xy 74.977498 -117.243098)
			(xy 76.118212 -117.243098)
		)
		(stroke
			(width 0)
			(type solid)
		)
		(fill yes)
		(layer "In9.Cu")
		(net "P12V_AUX")
	)
	(gr_poly
		(pts
			(xy 10.257028 -118.783354)
			(arc
				(start 10.257028 -114.799872)
				(mid 10.552301 -114.087273)
				(end 11.2649 -113.792)
			)
			(xy 11.677904 -113.792) (xy 11.769344 -113.70056) (xy 11.769344 -113.376456) (xy 11.677396 -113.284508)
			(arc
				(start 11.2649 -113.284508)
				(mid 10.193376 -113.728348)
				(end 9.749536 -114.799872)
			)
			(xy 9.749536 -118.76532) (xy 9.862312 -118.878096) (xy 10.162286 -118.878096)
		)
		(stroke
			(width 0)
			(type solid)
		)
		(fill yes)
		(layer "In9.Cu")
		(net "GND")
	)
	(gr_poly
		(pts
			(xy 72.55256 -33.2486) (xy 72.55256 -30.69082) (xy 71.8185 -29.95676) (xy 68.16852 -29.95676) (xy 67.59956 -30.52572)
			(xy 67.59956 -30.854904) (xy 67.800472 -30.854904) (xy 67.804543 -30.799282) (xy 67.816669 -30.744845)
			(xy 67.836592 -30.692754) (xy 67.863888 -30.644119) (xy 67.897974 -30.599976) (xy 67.938123 -30.561267)
			(xy 67.983481 -30.528816) (xy 68.033081 -30.503315) (xy 68.085865 -30.485308) (xy 68.140708 -30.475178)
			(xy 68.196442 -30.473141) (xy 68.251879 -30.479241) (xy 68.305836 -30.493347) (xy 68.357165 -30.515159)
			(xy 68.404771 -30.544213) (xy 68.447639 -30.579888) (xy 68.484856 -30.621425) (xy 68.515629 -30.667938)
			(xy 68.539301 -30.718435) (xy 68.555369 -30.771842) (xy 68.563489 -30.827018) (xy 68.563998 -30.854904)
			(xy 68.563489 -30.88279) (xy 68.555369 -30.937966) (xy 68.539301 -30.991373) (xy 68.515629 -31.04187)
			(xy 68.484856 -31.088383) (xy 68.447639 -31.12992) (xy 68.404771 -31.165595) (xy 68.357165 -31.194649)
			(xy 68.305836 -31.216461) (xy 68.251879 -31.230567) (xy 68.196442 -31.236667) (xy 68.140708 -31.23463)
			(xy 68.085865 -31.2245) (xy 68.033081 -31.206493) (xy 67.983481 -31.180992) (xy 67.938123 -31.148541)
			(xy 67.897974 -31.109832) (xy 67.863888 -31.065689) (xy 67.836592 -31.017054) (xy 67.816669 -30.964963)
			(xy 67.804543 -30.910526) (xy 67.800472 -30.854904) (xy 67.59956 -30.854904) (xy 67.59956 -31.789951)
			(xy 69.075278 -31.789951) (xy 69.075278 -31.735449) (xy 69.083034 -31.681501) (xy 69.098389 -31.629206)
			(xy 69.121031 -31.579629) (xy 69.150497 -31.533779) (xy 69.186188 -31.492588) (xy 69.227379 -31.456897)
			(xy 69.273229 -31.427431) (xy 69.322806 -31.404789) (xy 69.375101 -31.389434) (xy 69.429049 -31.381678)
			(xy 69.4563 -31.381192) (xy 69.483731 -31.38164) (xy 69.53803 -31.389486) (xy 69.590644 -31.40503)
			(xy 69.640489 -31.427953) (xy 69.686535 -31.45778) (xy 69.727833 -31.493896) (xy 69.76353 -31.535557)
			(xy 69.792891 -31.581902) (xy 69.804534 -31.606744) (xy 69.810294 -31.618754) (xy 69.827086 -31.639421)
			(xy 69.848654 -31.65504) (xy 69.873529 -31.664546) (xy 69.900017 -31.66729) (xy 69.926313 -31.663088)
			(xy 69.938646 -31.658052) (xy 69.963166 -31.647598) (xy 70.014403 -31.632895) (xy 70.067188 -31.625474)
			(xy 70.09384 -31.625032) (xy 70.121092 -31.625441) (xy 70.175041 -31.633203) (xy 70.227337 -31.648563)
			(xy 70.276914 -31.671209) (xy 70.322764 -31.700679) (xy 70.363954 -31.736374) (xy 70.399645 -31.777568)
			(xy 70.429111 -31.823421) (xy 70.451751 -31.873001) (xy 70.467106 -31.925298) (xy 70.474862 -31.979248)
			(xy 70.474862 -32.004) (xy 70.839582 -32.004) (xy 70.843653 -31.948378) (xy 70.855779 -31.893941)
			(xy 70.875702 -31.84185) (xy 70.902998 -31.793215) (xy 70.937084 -31.749072) (xy 70.977233 -31.710363)
			(xy 71.022591 -31.677912) (xy 71.072191 -31.652411) (xy 71.124975 -31.634404) (xy 71.179818 -31.624274)
			(xy 71.235552 -31.622237) (xy 71.290989 -31.628337) (xy 71.344946 -31.642443) (xy 71.396275 -31.664255)
			(xy 71.443881 -31.693309) (xy 71.486749 -31.728984) (xy 71.523966 -31.770521) (xy 71.554739 -31.817034)
			(xy 71.578411 -31.867531) (xy 71.594479 -31.920938) (xy 71.602599 -31.976114) (xy 71.603108 -32.004)
			(xy 71.602599 -32.031886) (xy 71.594479 -32.087062) (xy 71.578411 -32.140469) (xy 71.554739 -32.190966)
			(xy 71.523966 -32.237479) (xy 71.486749 -32.279016) (xy 71.443881 -32.314691) (xy 71.396275 -32.343745)
			(xy 71.344946 -32.365557) (xy 71.290989 -32.379663) (xy 71.235552 -32.385763) (xy 71.179818 -32.383726)
			(xy 71.124975 -32.373596) (xy 71.072191 -32.355589) (xy 71.022591 -32.330088) (xy 70.977233 -32.297637)
			(xy 70.937084 -32.258928) (xy 70.902998 -32.214785) (xy 70.875702 -32.16615) (xy 70.855779 -32.114059)
			(xy 70.843653 -32.059622) (xy 70.839582 -32.004) (xy 70.474862 -32.004) (xy 70.474862 -32.033752)
			(xy 70.467106 -32.087702) (xy 70.451751 -32.139999) (xy 70.429111 -32.189579) (xy 70.399645 -32.235432)
			(xy 70.363954 -32.276626) (xy 70.322764 -32.312321) (xy 70.276914 -32.341791) (xy 70.227337 -32.364437)
			(xy 70.175041 -32.379797) (xy 70.121092 -32.387559) (xy 70.09384 -32.388048) (xy 70.066408 -32.387602)
			(xy 70.012108 -32.37976) (xy 69.959492 -32.364218) (xy 69.909645 -32.341297) (xy 69.863598 -32.311469)
			(xy 69.822301 -32.275351) (xy 69.786605 -32.233688) (xy 69.757247 -32.18734) (xy 69.745606 -32.162496)
			(xy 69.739787 -32.150517) (xy 69.72301 -32.129848) (xy 69.701455 -32.114226) (xy 69.676591 -32.104714)
			(xy 69.650113 -32.101962) (xy 69.623825 -32.106157) (xy 69.611494 -32.111188) (xy 69.58697 -32.121631)
			(xy 69.535735 -32.136338) (xy 69.482952 -32.143763) (xy 69.4563 -32.144208) (xy 69.429049 -32.143722)
			(xy 69.375101 -32.135966) (xy 69.322806 -32.120611) (xy 69.273229 -32.097969) (xy 69.227379 -32.068503)
			(xy 69.186188 -32.032812) (xy 69.150497 -31.991621) (xy 69.121031 -31.945771) (xy 69.098389 -31.896194)
			(xy 69.083034 -31.843899) (xy 69.075278 -31.789951) (xy 67.59956 -31.789951) (xy 67.59956 -33.433766)
			(xy 69.340982 -33.433766) (xy 69.345053 -33.378144) (xy 69.357179 -33.323707) (xy 69.377102 -33.271616)
			(xy 69.404398 -33.222981) (xy 69.438484 -33.178838) (xy 69.478633 -33.140129) (xy 69.523991 -33.107678)
			(xy 69.573591 -33.082177) (xy 69.626375 -33.06417) (xy 69.681218 -33.05404) (xy 69.736952 -33.052003)
			(xy 69.792389 -33.058103) (xy 69.846346 -33.072209) (xy 69.897675 -33.094021) (xy 69.945281 -33.123075)
			(xy 69.988149 -33.15875) (xy 70.025366 -33.200287) (xy 70.056139 -33.2468) (xy 70.079811 -33.297297)
			(xy 70.095879 -33.350704) (xy 70.099543 -33.3756) (xy 70.636382 -33.3756) (xy 70.640453 -33.319978)
			(xy 70.652579 -33.265541) (xy 70.672502 -33.21345) (xy 70.699798 -33.164815) (xy 70.733884 -33.120672)
			(xy 70.774033 -33.081963) (xy 70.819391 -33.049512) (xy 70.868991 -33.024011) (xy 70.921775 -33.006004)
			(xy 70.976618 -32.995874) (xy 71.032352 -32.993837) (xy 71.087789 -32.999937) (xy 71.141746 -33.014043)
			(xy 71.193075 -33.035855) (xy 71.240681 -33.064909) (xy 71.283549 -33.100584) (xy 71.320766 -33.142121)
			(xy 71.351539 -33.188634) (xy 71.375211 -33.239131) (xy 71.391279 -33.292538) (xy 71.399399 -33.347714)
			(xy 71.399908 -33.3756) (xy 71.399399 -33.403486) (xy 71.391279 -33.458662) (xy 71.375211 -33.512069)
			(xy 71.351539 -33.562566) (xy 71.320766 -33.609079) (xy 71.283549 -33.650616) (xy 71.240681 -33.686291)
			(xy 71.193075 -33.715345) (xy 71.141746 -33.737157) (xy 71.087789 -33.751263) (xy 71.032352 -33.757363)
			(xy 70.976618 -33.755326) (xy 70.921775 -33.745196) (xy 70.868991 -33.727189) (xy 70.819391 -33.701688)
			(xy 70.774033 -33.669237) (xy 70.733884 -33.630528) (xy 70.699798 -33.586385) (xy 70.672502 -33.53775)
			(xy 70.652579 -33.485659) (xy 70.640453 -33.431222) (xy 70.636382 -33.3756) (xy 70.099543 -33.3756)
			(xy 70.103999 -33.40588) (xy 70.104508 -33.433766) (xy 70.103999 -33.461652) (xy 70.095879 -33.516828)
			(xy 70.079811 -33.570235) (xy 70.056139 -33.620732) (xy 70.025366 -33.667245) (xy 69.988149 -33.708782)
			(xy 69.945281 -33.744457) (xy 69.897675 -33.773511) (xy 69.846346 -33.795323) (xy 69.792389 -33.809429)
			(xy 69.736952 -33.815529) (xy 69.681218 -33.813492) (xy 69.626375 -33.803362) (xy 69.573591 -33.785355)
			(xy 69.523991 -33.759854) (xy 69.478633 -33.727403) (xy 69.438484 -33.688694) (xy 69.404398 -33.644551)
			(xy 69.377102 -33.595916) (xy 69.357179 -33.543825) (xy 69.345053 -33.489388) (xy 69.340982 -33.433766)
			(xy 67.59956 -33.433766) (xy 67.59956 -33.88868) (xy 68.00342 -34.29254) (xy 71.50862 -34.29254)
		)
		(stroke
			(width 0)
			(type solid)
		)
		(fill yes)
		(layer "In9.Cu")
		(net "P3V3_AUX")
	)
	(gr_poly
		(pts
			(xy 22.225 -37.338) (xy 22.225 -33.147) (xy 22.733 -32.639) (xy 22.733 -29.972) (xy 22.987 -29.718)
			(xy 22.987 -29.4132) (xy 23.3934 -29.0068) (xy 23.6982 -29.0068) (xy 23.9268 -28.7782) (xy 23.9268 -22.987)
			(xy 24.842216 -22.071584) (xy 24.842216 -20.879816) (xy 24.4856 -20.5232) (xy 16.85544 -20.5232)
			(xy 16.47444 -20.9042) (xy 16.47444 -22.795218) (xy 18.606302 -22.795218) (xy 18.610029 -22.741971)
			(xy 18.621141 -22.689763) (xy 18.639423 -22.639613) (xy 18.664516 -22.592501) (xy 18.695932 -22.549347)
			(xy 18.733056 -22.510994) (xy 18.753836 -22.49424) (xy 18.765509 -22.484402) (xy 18.782931 -22.459356)
			(xy 18.79218 -22.430282) (xy 18.79243 -22.399773) (xy 18.783659 -22.370551) (xy 18.766649 -22.345223)
			(xy 18.755106 -22.335236) (xy 18.731865 -22.316619) (xy 18.690941 -22.273363) (xy 18.657241 -22.224271)
			(xy 18.631584 -22.170535) (xy 18.614594 -22.113463) (xy 18.610072 -22.08403) (xy 18.608505 -22.071389)
			(xy 18.606849 -22.045968) (xy 18.60677 -22.03323) (xy 18.607283 -22.004313) (xy 18.61601 -21.94714)
			(xy 18.633267 -21.89194) (xy 18.658659 -21.839978) (xy 18.691605 -21.792444) (xy 18.731349 -21.750429)
			(xy 18.753836 -21.73224) (xy 18.765616 -21.722313) (xy 18.783143 -21.697) (xy 18.792327 -21.667613)
			(xy 18.792333 -21.636824) (xy 18.783159 -21.607434) (xy 18.765642 -21.582114) (xy 18.753836 -21.57222)
			(xy 18.73137 -21.554009) (xy 18.691632 -21.511994) (xy 18.65869 -21.464464) (xy 18.633298 -21.412506)
			(xy 18.616038 -21.357312) (xy 18.607306 -21.300145) (xy 18.60677 -21.27123) (xy 18.607256 -21.243979)
			(xy 18.615012 -21.190031) (xy 18.630367 -21.137736) (xy 18.653009 -21.088159) (xy 18.682475 -21.042309)
			(xy 18.718166 -21.001118) (xy 18.759357 -20.965427) (xy 18.805207 -20.935961) (xy 18.854784 -20.913319)
			(xy 18.907079 -20.897964) (xy 18.961027 -20.890208) (xy 19.015529 -20.890208) (xy 19.069477 -20.897964)
			(xy 19.121772 -20.913319) (xy 19.171349 -20.935961) (xy 19.217199 -20.965427) (xy 19.25839 -21.001118)
			(xy 19.294081 -21.042309) (xy 19.323547 -21.088159) (xy 19.346189 -21.137736) (xy 19.361544 -21.190031)
			(xy 19.3693 -21.243979) (xy 19.369786 -21.27123) (xy 19.369223 -21.300145) (xy 19.360504 -21.357315)
			(xy 19.343255 -21.412513) (xy 19.317872 -21.464475) (xy 19.284936 -21.51201) (xy 19.245202 -21.554029)
			(xy 19.22272 -21.57222) (xy 19.210884 -21.582084) (xy 19.193366 -21.607417) (xy 19.184193 -21.636819)
			(xy 19.184198 -21.667618) (xy 19.193382 -21.697017) (xy 19.21091 -21.722343) (xy 19.22272 -21.73224)
			(xy 19.243534 -21.748957) (xy 19.280666 -21.787314) (xy 19.312089 -21.830472) (xy 19.337189 -21.87759)
			(xy 19.355475 -21.927747) (xy 19.366591 -21.979963) (xy 19.370318 -22.033218) (xy 19.366585 -22.086474)
			(xy 19.355465 -22.138689) (xy 19.337174 -22.188844) (xy 19.31207 -22.235959) (xy 19.280643 -22.279114)
			(xy 19.243506 -22.317467) (xy 19.22272 -22.33422) (xy 19.210884 -22.344084) (xy 19.193366 -22.369417)
			(xy 19.184193 -22.398819) (xy 19.184198 -22.429618) (xy 19.193382 -22.459017) (xy 19.21091 -22.484343)
			(xy 19.22272 -22.49424) (xy 19.243534 -22.510957) (xy 19.280666 -22.549314) (xy 19.312089 -22.592472)
			(xy 19.337189 -22.63959) (xy 19.355475 -22.689747) (xy 19.366591 -22.741963) (xy 19.370318 -22.795218)
			(xy 22.822936 -22.795218) (xy 22.826663 -22.741969) (xy 22.837777 -22.689759) (xy 22.856062 -22.639609)
			(xy 22.881159 -22.592497) (xy 22.912579 -22.549344) (xy 22.949708 -22.510993) (xy 22.97049 -22.49424)
			(xy 22.982167 -22.484405) (xy 22.999597 -22.45936) (xy 23.00885 -22.430283) (xy 23.0091 -22.399771)
			(xy 23.000325 -22.370547) (xy 22.983307 -22.34522) (xy 22.97176 -22.335236) (xy 22.948509 -22.31663)
			(xy 22.907588 -22.273371) (xy 22.873891 -22.224275) (xy 22.848236 -22.170537) (xy 22.831248 -22.113464)
			(xy 22.826726 -22.08403) (xy 22.825159 -22.071389) (xy 22.823503 -22.045968) (xy 22.823424 -22.03323)
			(xy 22.823955 -22.004313) (xy 22.83268 -21.947142) (xy 22.849935 -21.891943) (xy 22.875324 -21.839982)
			(xy 22.908266 -21.792447) (xy 22.948005 -21.75043) (xy 22.97049 -21.73224) (xy 22.982265 -21.722309)
			(xy 22.999782 -21.696995) (xy 23.008961 -21.667611) (xy 23.008967 -21.636826) (xy 22.999799 -21.607438)
			(xy 22.98229 -21.582118) (xy 22.97049 -21.57222) (xy 22.948014 -21.55402) (xy 22.908279 -21.512002)
			(xy 22.875339 -21.464469) (xy 22.84995 -21.412509) (xy 22.832692 -21.357313) (xy 22.82396 -21.300145)
			(xy 22.823424 -21.27123) (xy 22.82391 -21.243979) (xy 22.831666 -21.190031) (xy 22.847021 -21.137736)
			(xy 22.869663 -21.088159) (xy 22.899129 -21.042309) (xy 22.93482 -21.001118) (xy 22.976011 -20.965427)
			(xy 23.021861 -20.935961) (xy 23.071438 -20.913319) (xy 23.123733 -20.897964) (xy 23.177681 -20.890208)
			(xy 23.232183 -20.890208) (xy 23.286131 -20.897964) (xy 23.338426 -20.913319) (xy 23.388003 -20.935961)
			(xy 23.433853 -20.965427) (xy 23.475044 -21.001118) (xy 23.510735 -21.042309) (xy 23.540201 -21.088159)
			(xy 23.562843 -21.137736) (xy 23.578198 -21.190031) (xy 23.585954 -21.243979) (xy 23.58644 -21.27123)
			(xy 23.585894 -21.300146) (xy 23.577174 -21.357317) (xy 23.559923 -21.412516) (xy 23.534537 -21.464479)
			(xy 23.501597 -21.512013) (xy 23.461858 -21.55403) (xy 23.439374 -21.57222) (xy 23.427543 -21.582087)
			(xy 23.410032 -21.607421) (xy 23.400864 -21.63682) (xy 23.400869 -21.667616) (xy 23.410049 -21.697013)
			(xy 23.427568 -21.72234) (xy 23.439374 -21.73224) (xy 23.460185 -21.748959) (xy 23.497313 -21.787318)
			(xy 23.528731 -21.830477) (xy 23.553827 -21.877595) (xy 23.572111 -21.92775) (xy 23.583224 -21.979965)
			(xy 23.586952 -22.033218) (xy 23.583219 -22.086472) (xy 23.572101 -22.138685) (xy 23.553812 -22.188839)
			(xy 23.528712 -22.235954) (xy 23.497289 -22.279111) (xy 23.460158 -22.317466) (xy 23.439374 -22.33422)
			(xy 23.427543 -22.344087) (xy 23.410032 -22.369421) (xy 23.400864 -22.39882) (xy 23.400869 -22.429616)
			(xy 23.410049 -22.459013) (xy 23.427568 -22.48434) (xy 23.439374 -22.49424) (xy 23.460185 -22.510959)
			(xy 23.497313 -22.549318) (xy 23.528731 -22.592477) (xy 23.553827 -22.639595) (xy 23.572111 -22.68975)
			(xy 23.583224 -22.741965) (xy 23.586952 -22.795218) (xy 23.583219 -22.848472) (xy 23.572101 -22.900685)
			(xy 23.553812 -22.950839) (xy 23.528712 -22.997954) (xy 23.497289 -23.041111) (xy 23.460158 -23.079466)
			(xy 23.439374 -23.09622) (xy 23.427543 -23.106087) (xy 23.410032 -23.131421) (xy 23.400864 -23.16082)
			(xy 23.400869 -23.191616) (xy 23.410049 -23.221013) (xy 23.427568 -23.24634) (xy 23.439374 -23.25624)
			(xy 23.461871 -23.274415) (xy 23.501607 -23.316437) (xy 23.534545 -23.363975) (xy 23.559931 -23.41594)
			(xy 23.577184 -23.471141) (xy 23.585908 -23.528313) (xy 23.58644 -23.55723) (xy 23.585954 -23.584481)
			(xy 23.578198 -23.638429) (xy 23.562843 -23.690724) (xy 23.540201 -23.740301) (xy 23.510735 -23.786151)
			(xy 23.475044 -23.827342) (xy 23.433853 -23.863033) (xy 23.388003 -23.892499) (xy 23.338426 -23.915141)
			(xy 23.286131 -23.930496) (xy 23.232183 -23.938252) (xy 23.177681 -23.938252) (xy 23.123733 -23.930496)
			(xy 23.071438 -23.915141) (xy 23.021861 -23.892499) (xy 22.976011 -23.863033) (xy 22.93482 -23.827342)
			(xy 22.899129 -23.786151) (xy 22.869663 -23.740301) (xy 22.847021 -23.690724) (xy 22.831666 -23.638429)
			(xy 22.82391 -23.584481) (xy 22.823424 -23.55723) (xy 22.823955 -23.528313) (xy 22.83268 -23.471142)
			(xy 22.849935 -23.415943) (xy 22.875324 -23.363982) (xy 22.908266 -23.316447) (xy 22.948005 -23.27443)
			(xy 22.97049 -23.25624) (xy 22.982265 -23.246309) (xy 22.999782 -23.220995) (xy 23.008961 -23.191611)
			(xy 23.008967 -23.160826) (xy 22.999799 -23.131438) (xy 22.98229 -23.106118) (xy 22.97049 -23.09622)
			(xy 22.949735 -23.079432) (xy 22.912603 -23.041084) (xy 22.881179 -22.997934) (xy 22.856077 -22.950825)
			(xy 22.837788 -22.900676) (xy 22.826668 -22.848467) (xy 22.822936 -22.795218) (xy 19.370318 -22.795218)
			(xy 19.366585 -22.848474) (xy 19.355465 -22.900689) (xy 19.337174 -22.950844) (xy 19.31207 -22.997959)
			(xy 19.280643 -23.041114) (xy 19.243506 -23.079467) (xy 19.22272 -23.09622) (xy 19.210884 -23.106084)
			(xy 19.193366 -23.131417) (xy 19.184193 -23.160819) (xy 19.184198 -23.191618) (xy 19.193382 -23.221017)
			(xy 19.21091 -23.246343) (xy 19.22272 -23.25624) (xy 19.245227 -23.274403) (xy 19.28496 -23.316429)
			(xy 19.317895 -23.36397) (xy 19.34328 -23.415937) (xy 19.360531 -23.471139) (xy 19.369254 -23.528312)
			(xy 19.369786 -23.55723) (xy 19.3693 -23.584481) (xy 19.361544 -23.638429) (xy 19.346189 -23.690724)
			(xy 19.323547 -23.740301) (xy 19.294081 -23.786151) (xy 19.25839 -23.827342) (xy 19.217199 -23.863033)
			(xy 19.171349 -23.892499) (xy 19.121772 -23.915141) (xy 19.069477 -23.930496) (xy 19.015529 -23.938252)
			(xy 18.961027 -23.938252) (xy 18.907079 -23.930496) (xy 18.854784 -23.915141) (xy 18.805207 -23.892499)
			(xy 18.759357 -23.863033) (xy 18.718166 -23.827342) (xy 18.682475 -23.786151) (xy 18.653009 -23.740301)
			(xy 18.630367 -23.690724) (xy 18.615012 -23.638429) (xy 18.607256 -23.584481) (xy 18.60677 -23.55723)
			(xy 18.607283 -23.528313) (xy 18.61601 -23.47114) (xy 18.633267 -23.41594) (xy 18.658659 -23.363978)
			(xy 18.691605 -23.316444) (xy 18.731349 -23.274429) (xy 18.753836 -23.25624) (xy 18.765616 -23.246313)
			(xy 18.783143 -23.221) (xy 18.792327 -23.191613) (xy 18.792333 -23.160824) (xy 18.783159 -23.131434)
			(xy 18.765642 -23.106114) (xy 18.753836 -23.09622) (xy 18.733084 -23.079431) (xy 18.695956 -23.041081)
			(xy 18.664536 -22.99793) (xy 18.639438 -22.950821) (xy 18.621152 -22.900673) (xy 18.610034 -22.848466)
			(xy 18.606302 -22.795218) (xy 16.47444 -22.795218) (xy 16.47444 -27.822906) (xy 17.306776 -30.2514)
			(xy 21.639782 -30.2514) (xy 21.643853 -30.195778) (xy 21.655979 -30.141341) (xy 21.675902 -30.08925)
			(xy 21.703198 -30.040615) (xy 21.737284 -29.996472) (xy 21.777433 -29.957763) (xy 21.822791 -29.925312)
			(xy 21.872391 -29.899811) (xy 21.925175 -29.881804) (xy 21.980018 -29.871674) (xy 22.035752 -29.869637)
			(xy 22.091189 -29.875737) (xy 22.145146 -29.889843) (xy 22.196475 -29.911655) (xy 22.244081 -29.940709)
			(xy 22.286949 -29.976384) (xy 22.324166 -30.017921) (xy 22.354939 -30.064434) (xy 22.378611 -30.114931)
			(xy 22.394679 -30.168338) (xy 22.402799 -30.223514) (xy 22.403308 -30.2514) (xy 22.402799 -30.279286)
			(xy 22.394679 -30.334462) (xy 22.378611 -30.387869) (xy 22.354939 -30.438366) (xy 22.324166 -30.484879)
			(xy 22.286949 -30.526416) (xy 22.244081 -30.562091) (xy 22.196475 -30.591145) (xy 22.145146 -30.612957)
			(xy 22.091189 -30.627063) (xy 22.035752 -30.633163) (xy 21.980018 -30.631126) (xy 21.925175 -30.620996)
			(xy 21.872391 -30.602989) (xy 21.822791 -30.577488) (xy 21.777433 -30.545037) (xy 21.737284 -30.506328)
			(xy 21.703198 -30.462185) (xy 21.675902 -30.41355) (xy 21.655979 -30.361459) (xy 21.643853 -30.307022)
			(xy 21.639782 -30.2514) (xy 17.306776 -30.2514) (xy 17.431004 -30.613858) (xy 17.431004 -32.523938)
			(xy 17.431512 -32.5374) (xy 17.431004 -32.550862) (xy 17.431004 -34.790126) (xy 17.098772 -35.122612)
			(xy 17.098772 -38.739572) (xy 17.4117 -39.0525) (xy 20.5105 -39.0525)
		)
		(stroke
			(width 0)
			(type solid)
		)
		(fill yes)
		(layer "In9.Cu")
		(net "GND")
	)
	(gr_poly
		(pts
			(xy 84.492084 -118.78056)
			(arc
				(start 84.492084 -114.799872)
				(mid 84.787357 -114.087273)
				(end 85.499956 -113.792)
			)
			(arc
				(start 88.000078 -113.792)
				(mid 89.055078 -113.355004)
				(end 89.492074 -112.300004)
			)
			(xy 89.492074 -85.508084)
			(arc
				(start 87.749888 -85.508084)
				(mid 87.037379 -85.212795)
				(end 86.742016 -84.500212)
			)
			(arc
				(start 86.742016 -81.999836)
				(mid 87.037289 -81.287237)
				(end 87.749888 -80.991964)
			)
			(xy 89.492074 -80.991964)
			(arc
				(start 89.492074 -1.999996)
				(mid 89.055078 -0.944996)
				(end 88.000078 -0.508)
			)
			(arc
				(start 1.999996 -0.508)
				(mid 0.944996 -0.944996)
				(end 0.508 -1.999996)
			)
			(xy 0.508 -80.991964)
			(arc
				(start 2.249932 -80.991964)
				(mid 2.962785 -81.287237)
				(end 3.258058 -82.00009)
			)
			(arc
				(start 3.258058 -84.499958)
				(mid 2.962785 -85.212811)
				(end 2.249932 -85.508084)
			)
			(xy 0.508 -85.508084)
			(arc
				(start 0.508 -112.300004)
				(mid 0.944996 -113.355004)
				(end 1.999996 -113.792)
			)
			(arc
				(start 4.500118 -113.792)
				(mid 5.212717 -114.087273)
				(end 5.50799 -114.799872)
			)
			(xy 5.50799 -118.71071) (xy 5.621528 -118.824248) (xy 5.936488 -118.824248) (xy 6.015228 -118.745508)
			(arc
				(start 6.015228 -114.799872)
				(mid 5.571478 -113.728438)
				(end 4.500118 -113.284508)
			)
			(arc
				(start 1.999996 -113.284508)
				(mid 1.303847 -112.996153)
				(end 1.015492 -112.300004)
			)
			(xy 1.015492 -86.015576)
			(arc
				(start 2.249932 -86.015576)
				(mid 3.321472 -85.571572)
				(end 3.765296 -84.499958)
			)
			(arc
				(start 3.765296 -81.999582)
				(mid 3.321366 -80.928222)
				(end 2.249932 -80.484472)
			)
			(xy 1.015492 -80.484472)
			(arc
				(start 1.015492 -1.999996)
				(mid 1.303847 -1.303847)
				(end 1.999996 -1.015492)
			)
			(xy 63.724028 -1.015492) (xy 76.606908 -1.015492)
			(arc
				(start 88.000078 -1.015492)
				(mid 88.696317 -1.303831)
				(end 88.984836 -1.999996)
			)
			(xy 88.984836 -80.484472)
			(arc
				(start 87.749888 -80.484472)
				(mid 86.678438 -80.928386)
				(end 86.234524 -81.999836)
			)
			(arc
				(start 86.234524 -84.500212)
				(mid 86.678348 -85.571826)
				(end 87.749888 -86.015576)
			)
			(xy 88.984836 -86.015576)
			(arc
				(start 88.984836 -112.300004)
				(mid 88.696571 -112.996064)
				(end 88.000586 -113.284508)
			)
			(arc
				(start 85.499956 -113.284508)
				(mid 84.428432 -113.728348)
				(end 83.984592 -114.799872)
			)
			(xy 83.984592 -118.768114) (xy 84.094574 -118.878096) (xy 84.394548 -118.878096)
		)
		(stroke
			(width 0)
			(type solid)
		)
		(fill yes)
		(layer "In9.Cu")
		(net "GND")
	)
	(gr_poly
		(pts
			(xy 48.103536 -54.440836) (xy 48.117946 -54.440343) (xy 48.145619 -54.432296) (xy 48.169936 -54.416827)
			(xy 48.188951 -54.395171) (xy 48.201148 -54.36906) (xy 48.205551 -54.340579) (xy 48.201808 -54.312003)
			(xy 48.1965 -54.298596) (xy 48.18781 -54.277674) (xy 48.175585 -54.234051) (xy 48.16942 -54.189168)
			(xy 48.169068 -54.166516) (xy 48.169578 -54.140529) (xy 48.177708 -54.089194) (xy 48.193769 -54.039764)
			(xy 48.217365 -53.993454) (xy 48.247915 -53.951406) (xy 48.284666 -53.914655) (xy 48.326714 -53.884105)
			(xy 48.373024 -53.860509) (xy 48.422454 -53.844448) (xy 48.473789 -53.836318) (xy 48.525763 -53.836318)
			(xy 48.577098 -53.844448) (xy 48.626528 -53.860509) (xy 48.672838 -53.884105) (xy 48.714886 -53.914655)
			(xy 48.751637 -53.951406) (xy 48.782187 -53.993454) (xy 48.805783 -54.039764) (xy 48.821844 -54.089194)
			(xy 48.829974 -54.140529) (xy 48.830484 -54.166516) (xy 48.83013 -54.189168) (xy 48.823974 -54.234052)
			(xy 48.81174 -54.277673) (xy 48.803052 -54.298596) (xy 48.797755 -54.311993) (xy 48.794073 -54.340551)
			(xy 48.798509 -54.369001) (xy 48.810709 -54.395084) (xy 48.829704 -54.416724) (xy 48.853984 -54.432203)
			(xy 48.88162 -54.44029) (xy 48.896016 -54.440836) (xy 52.209192 -54.440836) (xy 52.6288 -54.021228)
			(xy 52.6288 -52.998116) (xy 52.628372 -52.984242) (xy 52.620977 -52.957501) (xy 52.606647 -52.933742)
			(xy 52.586444 -52.914726) (xy 52.561863 -52.901858) (xy 52.534724 -52.896093) (xy 52.52085 -52.896516)
			(xy 52.499768 -52.897278) (xy 52.473785 -52.896766) (xy 52.422459 -52.888632) (xy 52.373037 -52.87257)
			(xy 52.326736 -52.848975) (xy 52.284696 -52.818427) (xy 52.247952 -52.781679) (xy 52.217409 -52.739636)
			(xy 52.193818 -52.693333) (xy 52.17776 -52.64391) (xy 52.169631 -52.592583) (xy 52.169631 -52.540617)
			(xy 52.17776 -52.48929) (xy 52.193818 -52.439867) (xy 52.217409 -52.393564) (xy 52.247952 -52.351521)
			(xy 52.284696 -52.314773) (xy 52.326736 -52.284225) (xy 52.373037 -52.26063) (xy 52.422459 -52.244568)
			(xy 52.473785 -52.236434) (xy 52.499768 -52.235862) (xy 52.52085 -52.236624) (xy 52.534721 -52.237023)
			(xy 52.561849 -52.231241) (xy 52.58642 -52.218371) (xy 52.60662 -52.199363) (xy 52.620959 -52.17562)
			(xy 52.628378 -52.148893) (xy 52.6288 -52.135024) (xy 52.6288 -51.492658) (xy 52.631848 -51.48961)
			(xy 52.631848 -50.121312) (xy 52.4637 -49.953164) (xy 52.117244 -49.953164) (xy 52.103934 -49.953554)
			(xy 52.078219 -49.960437) (xy 52.055163 -49.973744) (xy 52.036341 -49.992568) (xy 52.023035 -50.015624)
			(xy 52.016153 -50.041339) (xy 52.016166 -50.067959) (xy 52.0192 -50.080926) (xy 52.024462 -50.101932)
			(xy 52.030071 -50.144871) (xy 52.030376 -50.166524) (xy 52.029866 -50.192511) (xy 52.021736 -50.243846)
			(xy 52.005675 -50.293276) (xy 51.982079 -50.339586) (xy 51.951529 -50.381634) (xy 51.914778 -50.418385)
			(xy 51.87273 -50.448935) (xy 51.82642 -50.472531) (xy 51.77699 -50.488592) (xy 51.725655 -50.496722)
			(xy 51.673681 -50.496722) (xy 51.622346 -50.488592) (xy 51.572916 -50.472531) (xy 51.526606 -50.448935)
			(xy 51.484558 -50.418385) (xy 51.447807 -50.381634) (xy 51.417257 -50.339586) (xy 51.393661 -50.293276)
			(xy 51.3776 -50.243846) (xy 51.36947 -50.192511) (xy 51.36896 -50.166524) (xy 51.369301 -50.144874)
			(xy 51.374912 -50.101939) (xy 51.380136 -50.080926) (xy 51.383137 -50.067964) (xy 51.383102 -50.041367)
			(xy 51.376198 -50.015683) (xy 51.362894 -49.992653) (xy 51.344092 -49.973841) (xy 51.32107 -49.960524)
			(xy 51.295389 -49.953606) (xy 51.282092 -49.953164) (xy 50.517298 -49.953164) (xy 50.503983 -49.953548)
			(xy 50.478255 -49.960422) (xy 50.455187 -49.973726) (xy 50.436353 -49.992552) (xy 50.423039 -50.015614)
			(xy 50.416153 -50.041338) (xy 50.416168 -50.067968) (xy 50.419254 -50.080926) (xy 50.424516 -50.101932)
			(xy 50.430123 -50.144871) (xy 50.43043 -50.166524) (xy 50.42992 -50.192511) (xy 50.42179 -50.243846)
			(xy 50.405729 -50.293276) (xy 50.382133 -50.339586) (xy 50.351583 -50.381634) (xy 50.314832 -50.418385)
			(xy 50.272784 -50.448935) (xy 50.226474 -50.472531) (xy 50.177044 -50.488592) (xy 50.125709 -50.496722)
			(xy 50.073735 -50.496722) (xy 50.0224 -50.488592) (xy 49.97297 -50.472531) (xy 49.92666 -50.448935)
			(xy 49.884612 -50.418385) (xy 49.847861 -50.381634) (xy 49.817311 -50.339586) (xy 49.793715 -50.293276)
			(xy 49.777654 -50.243846) (xy 49.769524 -50.192511) (xy 49.769014 -50.166524) (xy 49.769355 -50.144874)
			(xy 49.774967 -50.101939) (xy 49.78019 -50.080926) (xy 49.783192 -50.067966) (xy 49.783158 -50.041373)
			(xy 49.776253 -50.015692) (xy 49.762948 -49.992666) (xy 49.744145 -49.973861) (xy 49.721122 -49.960552)
			(xy 49.695442 -49.953644) (xy 49.682146 -49.953164) (xy 48.917352 -49.953164) (xy 48.904041 -49.953553)
			(xy 48.878324 -49.960434) (xy 48.855267 -49.973741) (xy 48.836442 -49.992565) (xy 48.823135 -50.015622)
			(xy 48.816253 -50.041339) (xy 48.816267 -50.06796) (xy 48.819308 -50.080926) (xy 48.82457 -50.101932)
			(xy 48.830178 -50.144871) (xy 48.830484 -50.166524) (xy 48.829974 -50.192511) (xy 48.821844 -50.243846)
			(xy 48.805783 -50.293276) (xy 48.782187 -50.339586) (xy 48.751637 -50.381634) (xy 48.714886 -50.418385)
			(xy 48.672838 -50.448935) (xy 48.626528 -50.472531) (xy 48.577098 -50.488592) (xy 48.525763 -50.496722)
			(xy 48.473789 -50.496722) (xy 48.422454 -50.488592) (xy 48.373024 -50.472531) (xy 48.326714 -50.448935)
			(xy 48.284666 -50.418385) (xy 48.247915 -50.381634) (xy 48.217365 -50.339586) (xy 48.193769 -50.293276)
			(xy 48.177708 -50.243846) (xy 48.169578 -50.192511) (xy 48.169068 -50.166524) (xy 48.169409 -50.144874)
			(xy 48.17502 -50.101939) (xy 48.180244 -50.080926) (xy 48.183245 -50.067963) (xy 48.183209 -50.041366)
			(xy 48.176305 -50.015681) (xy 48.163002 -49.992651) (xy 48.144201 -49.973838) (xy 48.121179 -49.960519)
			(xy 48.095498 -49.953599) (xy 48.0822 -49.953164) (xy 47.53229 -49.953164) (xy 47.410116 -50.075338)
			(xy 47.410116 -50.992357) (xy 48.169578 -50.992357) (xy 48.169578 -50.940383) (xy 48.177708 -50.889048)
			(xy 48.193769 -50.839618) (xy 48.217365 -50.793308) (xy 48.247915 -50.75126) (xy 48.284666 -50.714509)
			(xy 48.326714 -50.683959) (xy 48.373024 -50.660363) (xy 48.422454 -50.644302) (xy 48.473789 -50.636172)
			(xy 48.525763 -50.636172) (xy 48.577098 -50.644302) (xy 48.626528 -50.660363) (xy 48.672838 -50.683959)
			(xy 48.714886 -50.714509) (xy 48.751637 -50.75126) (xy 48.782187 -50.793308) (xy 48.805783 -50.839618)
			(xy 48.821844 -50.889048) (xy 48.829974 -50.940383) (xy 48.830484 -50.96637) (xy 48.829974 -50.992357)
			(xy 49.769524 -50.992357) (xy 49.769524 -50.940383) (xy 49.777654 -50.889048) (xy 49.793715 -50.839618)
			(xy 49.817311 -50.793308) (xy 49.847861 -50.75126) (xy 49.884612 -50.714509) (xy 49.92666 -50.683959)
			(xy 49.97297 -50.660363) (xy 50.0224 -50.644302) (xy 50.073735 -50.636172) (xy 50.125709 -50.636172)
			(xy 50.177044 -50.644302) (xy 50.226474 -50.660363) (xy 50.272784 -50.683959) (xy 50.314832 -50.714509)
			(xy 50.351583 -50.75126) (xy 50.382133 -50.793308) (xy 50.405729 -50.839618) (xy 50.42179 -50.889048)
			(xy 50.42992 -50.940383) (xy 50.43043 -50.96637) (xy 50.42992 -50.992357) (xy 51.36947 -50.992357)
			(xy 51.36947 -50.940383) (xy 51.3776 -50.889048) (xy 51.393661 -50.839618) (xy 51.417257 -50.793308)
			(xy 51.447807 -50.75126) (xy 51.484558 -50.714509) (xy 51.526606 -50.683959) (xy 51.572916 -50.660363)
			(xy 51.622346 -50.644302) (xy 51.673681 -50.636172) (xy 51.725655 -50.636172) (xy 51.77699 -50.644302)
			(xy 51.82642 -50.660363) (xy 51.87273 -50.683959) (xy 51.914778 -50.714509) (xy 51.951529 -50.75126)
			(xy 51.982079 -50.793308) (xy 52.005675 -50.839618) (xy 52.021736 -50.889048) (xy 52.029866 -50.940383)
			(xy 52.030376 -50.96637) (xy 52.029866 -50.992357) (xy 52.021736 -51.043692) (xy 52.005675 -51.093122)
			(xy 51.982079 -51.139432) (xy 51.951529 -51.18148) (xy 51.914778 -51.218231) (xy 51.87273 -51.248781)
			(xy 51.82642 -51.272377) (xy 51.77699 -51.288438) (xy 51.725655 -51.296568) (xy 51.673681 -51.296568)
			(xy 51.622346 -51.288438) (xy 51.572916 -51.272377) (xy 51.526606 -51.248781) (xy 51.484558 -51.218231)
			(xy 51.447807 -51.18148) (xy 51.417257 -51.139432) (xy 51.393661 -51.093122) (xy 51.3776 -51.043692)
			(xy 51.36947 -50.992357) (xy 50.42992 -50.992357) (xy 50.42179 -51.043692) (xy 50.405729 -51.093122)
			(xy 50.382133 -51.139432) (xy 50.351583 -51.18148) (xy 50.314832 -51.218231) (xy 50.272784 -51.248781)
			(xy 50.226474 -51.272377) (xy 50.177044 -51.288438) (xy 50.125709 -51.296568) (xy 50.073735 -51.296568)
			(xy 50.0224 -51.288438) (xy 49.97297 -51.272377) (xy 49.92666 -51.248781) (xy 49.884612 -51.218231)
			(xy 49.847861 -51.18148) (xy 49.817311 -51.139432) (xy 49.793715 -51.093122) (xy 49.777654 -51.043692)
			(xy 49.769524 -50.992357) (xy 48.829974 -50.992357) (xy 48.821844 -51.043692) (xy 48.805783 -51.093122)
			(xy 48.782187 -51.139432) (xy 48.751637 -51.18148) (xy 48.714886 -51.218231) (xy 48.672838 -51.248781)
			(xy 48.626528 -51.272377) (xy 48.577098 -51.288438) (xy 48.525763 -51.296568) (xy 48.473789 -51.296568)
			(xy 48.422454 -51.288438) (xy 48.373024 -51.272377) (xy 48.326714 -51.248781) (xy 48.284666 -51.218231)
			(xy 48.247915 -51.18148) (xy 48.217365 -51.139432) (xy 48.193769 -51.093122) (xy 48.177708 -51.043692)
			(xy 48.169578 -50.992357) (xy 47.410116 -50.992357) (xy 47.410116 -51.207416) (xy 47.55515 -51.35245)
			(xy 47.571294 -51.36923) (xy 47.598633 -51.406921) (xy 47.619737 -51.448426) (xy 47.634086 -51.492722)
			(xy 47.641326 -51.538718) (xy 47.641764 -51.562) (xy 47.641764 -51.792457) (xy 48.169578 -51.792457)
			(xy 48.169578 -51.740483) (xy 48.177708 -51.689148) (xy 48.193769 -51.639718) (xy 48.217365 -51.593408)
			(xy 48.247915 -51.55136) (xy 48.284666 -51.514609) (xy 48.326714 -51.484059) (xy 48.373024 -51.460463)
			(xy 48.422454 -51.444402) (xy 48.473789 -51.436272) (xy 48.525763 -51.436272) (xy 48.577098 -51.444402)
			(xy 48.626528 -51.460463) (xy 48.672838 -51.484059) (xy 48.714886 -51.514609) (xy 48.751637 -51.55136)
			(xy 48.782187 -51.593408) (xy 48.805783 -51.639718) (xy 48.821844 -51.689148) (xy 48.829974 -51.740483)
			(xy 48.830484 -51.76647) (xy 48.829974 -51.792457) (xy 49.769524 -51.792457) (xy 49.769524 -51.740483)
			(xy 49.777654 -51.689148) (xy 49.793715 -51.639718) (xy 49.817311 -51.593408) (xy 49.847861 -51.55136)
			(xy 49.884612 -51.514609) (xy 49.92666 -51.484059) (xy 49.97297 -51.460463) (xy 50.0224 -51.444402)
			(xy 50.073735 -51.436272) (xy 50.125709 -51.436272) (xy 50.177044 -51.444402) (xy 50.226474 -51.460463)
			(xy 50.272784 -51.484059) (xy 50.314832 -51.514609) (xy 50.351583 -51.55136) (xy 50.382133 -51.593408)
			(xy 50.405729 -51.639718) (xy 50.42179 -51.689148) (xy 50.42992 -51.740483) (xy 50.43043 -51.76647)
			(xy 50.42992 -51.792457) (xy 50.42179 -51.843792) (xy 50.405729 -51.893222) (xy 50.382133 -51.939532)
			(xy 50.351583 -51.98158) (xy 50.314832 -52.018331) (xy 50.272784 -52.048881) (xy 50.226474 -52.072477)
			(xy 50.177044 -52.088538) (xy 50.125709 -52.096668) (xy 50.073735 -52.096668) (xy 50.0224 -52.088538)
			(xy 49.97297 -52.072477) (xy 49.92666 -52.048881) (xy 49.884612 -52.018331) (xy 49.847861 -51.98158)
			(xy 49.817311 -51.939532) (xy 49.793715 -51.893222) (xy 49.777654 -51.843792) (xy 49.769524 -51.792457)
			(xy 48.829974 -51.792457) (xy 48.821844 -51.843792) (xy 48.805783 -51.893222) (xy 48.782187 -51.939532)
			(xy 48.751637 -51.98158) (xy 48.714886 -52.018331) (xy 48.672838 -52.048881) (xy 48.626528 -52.072477)
			(xy 48.577098 -52.088538) (xy 48.525763 -52.096668) (xy 48.473789 -52.096668) (xy 48.422454 -52.088538)
			(xy 48.373024 -52.072477) (xy 48.326714 -52.048881) (xy 48.284666 -52.018331) (xy 48.247915 -51.98158)
			(xy 48.217365 -51.939532) (xy 48.193769 -51.893222) (xy 48.177708 -51.843792) (xy 48.169578 -51.792457)
			(xy 47.641764 -51.792457) (xy 47.641764 -52.592557) (xy 50.569624 -52.592557) (xy 50.569624 -52.540583)
			(xy 50.577754 -52.489248) (xy 50.593815 -52.439818) (xy 50.617411 -52.393508) (xy 50.647961 -52.35146)
			(xy 50.684712 -52.314709) (xy 50.72676 -52.284159) (xy 50.77307 -52.260563) (xy 50.8225 -52.244502)
			(xy 50.873835 -52.236372) (xy 50.925809 -52.236372) (xy 50.977144 -52.244502) (xy 51.026574 -52.260563)
			(xy 51.072884 -52.284159) (xy 51.114932 -52.314709) (xy 51.151683 -52.35146) (xy 51.182233 -52.393508)
			(xy 51.205829 -52.439818) (xy 51.22189 -52.489248) (xy 51.23002 -52.540583) (xy 51.23053 -52.56657)
			(xy 51.23002 -52.592557) (xy 51.36947 -52.592557) (xy 51.36947 -52.540583) (xy 51.3776 -52.489248)
			(xy 51.393661 -52.439818) (xy 51.417257 -52.393508) (xy 51.447807 -52.35146) (xy 51.484558 -52.314709)
			(xy 51.526606 -52.284159) (xy 51.572916 -52.260563) (xy 51.622346 -52.244502) (xy 51.673681 -52.236372)
			(xy 51.725655 -52.236372) (xy 51.77699 -52.244502) (xy 51.82642 -52.260563) (xy 51.87273 -52.284159)
			(xy 51.914778 -52.314709) (xy 51.951529 -52.35146) (xy 51.982079 -52.393508) (xy 52.005675 -52.439818)
			(xy 52.021736 -52.489248) (xy 52.029866 -52.540583) (xy 52.030376 -52.56657) (xy 52.029866 -52.592557)
			(xy 52.021736 -52.643892) (xy 52.005675 -52.693322) (xy 51.982079 -52.739632) (xy 51.951529 -52.78168)
			(xy 51.914778 -52.818431) (xy 51.87273 -52.848981) (xy 51.82642 -52.872577) (xy 51.77699 -52.888638)
			(xy 51.725655 -52.896768) (xy 51.673681 -52.896768) (xy 51.622346 -52.888638) (xy 51.572916 -52.872577)
			(xy 51.526606 -52.848981) (xy 51.484558 -52.818431) (xy 51.447807 -52.78168) (xy 51.417257 -52.739632)
			(xy 51.393661 -52.693322) (xy 51.3776 -52.643892) (xy 51.36947 -52.592557) (xy 51.23002 -52.592557)
			(xy 51.22189 -52.643892) (xy 51.205829 -52.693322) (xy 51.182233 -52.739632) (xy 51.151683 -52.78168)
			(xy 51.114932 -52.818431) (xy 51.072884 -52.848981) (xy 51.026574 -52.872577) (xy 50.977144 -52.888638)
			(xy 50.925809 -52.896768) (xy 50.873835 -52.896768) (xy 50.8225 -52.888638) (xy 50.77307 -52.872577)
			(xy 50.72676 -52.848981) (xy 50.684712 -52.818431) (xy 50.647961 -52.78168) (xy 50.617411 -52.739632)
			(xy 50.593815 -52.693322) (xy 50.577754 -52.643892) (xy 50.569624 -52.592557) (xy 47.641764 -52.592557)
			(xy 47.641764 -52.7304) (xy 47.641346 -52.753681) (xy 47.634092 -52.799673) (xy 47.61973 -52.843963)
			(xy 47.598615 -52.885461) (xy 47.571267 -52.923144) (xy 47.55515 -52.93995) (xy 47.480474 -53.014626)
			(xy 47.540418 -53.07457) (xy 47.571914 -53.061362) (xy 47.592225 -53.053243) (xy 47.634447 -53.041819)
			(xy 47.677806 -53.036054) (xy 47.699676 -53.035708) (xy 47.725665 -53.036189) (xy 47.777004 -53.044317)
			(xy 47.82644 -53.060376) (xy 47.872754 -53.083972) (xy 47.914807 -53.114522) (xy 47.951562 -53.151275)
			(xy 47.982116 -53.193326) (xy 48.005714 -53.239638) (xy 48.021777 -53.289072) (xy 48.029909 -53.340411)
			(xy 48.029909 -53.392389) (xy 48.029907 -53.392403) (xy 48.169578 -53.392403) (xy 48.169578 -53.340429)
			(xy 48.177708 -53.289094) (xy 48.193769 -53.239664) (xy 48.217365 -53.193354) (xy 48.247915 -53.151306)
			(xy 48.284666 -53.114555) (xy 48.326714 -53.084005) (xy 48.373024 -53.060409) (xy 48.422454 -53.044348)
			(xy 48.473789 -53.036218) (xy 48.525763 -53.036218) (xy 48.577098 -53.044348) (xy 48.626528 -53.060409)
			(xy 48.672838 -53.084005) (xy 48.714886 -53.114555) (xy 48.751637 -53.151306) (xy 48.782187 -53.193354)
			(xy 48.805783 -53.239664) (xy 48.821844 -53.289094) (xy 48.829974 -53.340429) (xy 48.830484 -53.366416)
			(xy 48.829974 -53.392403) (xy 50.569624 -53.392403) (xy 50.569624 -53.340429) (xy 50.577754 -53.289094)
			(xy 50.593815 -53.239664) (xy 50.617411 -53.193354) (xy 50.647961 -53.151306) (xy 50.684712 -53.114555)
			(xy 50.72676 -53.084005) (xy 50.77307 -53.060409) (xy 50.8225 -53.044348) (xy 50.873835 -53.036218)
			(xy 50.925809 -53.036218) (xy 50.977144 -53.044348) (xy 51.026574 -53.060409) (xy 51.072884 -53.084005)
			(xy 51.114932 -53.114555) (xy 51.151683 -53.151306) (xy 51.182233 -53.193354) (xy 51.205829 -53.239664)
			(xy 51.22189 -53.289094) (xy 51.23002 -53.340429) (xy 51.23053 -53.366416) (xy 51.23002 -53.392403)
			(xy 51.36947 -53.392403) (xy 51.36947 -53.340429) (xy 51.3776 -53.289094) (xy 51.393661 -53.239664)
			(xy 51.417257 -53.193354) (xy 51.447807 -53.151306) (xy 51.484558 -53.114555) (xy 51.526606 -53.084005)
			(xy 51.572916 -53.060409) (xy 51.622346 -53.044348) (xy 51.673681 -53.036218) (xy 51.725655 -53.036218)
			(xy 51.77699 -53.044348) (xy 51.82642 -53.060409) (xy 51.87273 -53.084005) (xy 51.914778 -53.114555)
			(xy 51.951529 -53.151306) (xy 51.982079 -53.193354) (xy 52.005675 -53.239664) (xy 52.021736 -53.289094)
			(xy 52.029866 -53.340429) (xy 52.030376 -53.366416) (xy 52.029866 -53.392403) (xy 52.021736 -53.443738)
			(xy 52.005675 -53.493168) (xy 51.982079 -53.539478) (xy 51.951529 -53.581526) (xy 51.914778 -53.618277)
			(xy 51.87273 -53.648827) (xy 51.82642 -53.672423) (xy 51.77699 -53.688484) (xy 51.725655 -53.696614)
			(xy 51.673681 -53.696614) (xy 51.622346 -53.688484) (xy 51.572916 -53.672423) (xy 51.526606 -53.648827)
			(xy 51.484558 -53.618277) (xy 51.447807 -53.581526) (xy 51.417257 -53.539478) (xy 51.393661 -53.493168)
			(xy 51.3776 -53.443738) (xy 51.36947 -53.392403) (xy 51.23002 -53.392403) (xy 51.22189 -53.443738)
			(xy 51.205829 -53.493168) (xy 51.182233 -53.539478) (xy 51.151683 -53.581526) (xy 51.114932 -53.618277)
			(xy 51.072884 -53.648827) (xy 51.026574 -53.672423) (xy 50.977144 -53.688484) (xy 50.925809 -53.696614)
			(xy 50.873835 -53.696614) (xy 50.8225 -53.688484) (xy 50.77307 -53.672423) (xy 50.72676 -53.648827)
			(xy 50.684712 -53.618277) (xy 50.647961 -53.581526) (xy 50.617411 -53.539478) (xy 50.593815 -53.493168)
			(xy 50.577754 -53.443738) (xy 50.569624 -53.392403) (xy 48.829974 -53.392403) (xy 48.821844 -53.443738)
			(xy 48.805783 -53.493168) (xy 48.782187 -53.539478) (xy 48.751637 -53.581526) (xy 48.714886 -53.618277)
			(xy 48.672838 -53.648827) (xy 48.626528 -53.672423) (xy 48.577098 -53.688484) (xy 48.525763 -53.696614)
			(xy 48.473789 -53.696614) (xy 48.422454 -53.688484) (xy 48.373024 -53.672423) (xy 48.326714 -53.648827)
			(xy 48.284666 -53.618277) (xy 48.247915 -53.581526) (xy 48.217365 -53.539478) (xy 48.193769 -53.493168)
			(xy 48.177708 -53.443738) (xy 48.169578 -53.392403) (xy 48.029907 -53.392403) (xy 48.021777 -53.443728)
			(xy 48.005714 -53.493162) (xy 47.982116 -53.539474) (xy 47.951562 -53.581525) (xy 47.914807 -53.618278)
			(xy 47.872754 -53.648828) (xy 47.82644 -53.672424) (xy 47.777004 -53.688483) (xy 47.725665 -53.696611)
			(xy 47.699676 -53.697124) (xy 47.67487 -53.696662) (xy 47.625819 -53.689211) (xy 47.578434 -53.674511)
			(xy 47.555912 -53.664104) (xy 47.54245 -53.658144) (xy 47.513402 -53.653422) (xy 47.484213 -53.657174)
			(xy 47.457304 -53.669088) (xy 47.434906 -53.688177) (xy 47.418876 -53.712858) (xy 47.410544 -53.741083)
			(xy 47.410116 -53.755798) (xy 47.410116 -53.777134) (xy 47.41057 -53.791852) (xy 47.418887 -53.820085)
			(xy 47.434909 -53.844775) (xy 47.457306 -53.863872) (xy 47.484217 -53.875792) (xy 47.51341 -53.879544)
			(xy 47.542461 -53.874817) (xy 47.555912 -53.868828) (xy 47.578436 -53.858428) (xy 47.625823 -53.843738)
			(xy 47.674871 -53.836286) (xy 47.699676 -53.835808) (xy 47.725666 -53.836289) (xy 47.777007 -53.844418)
			(xy 47.826443 -53.860478) (xy 47.872759 -53.884075) (xy 47.914812 -53.914627) (xy 47.951568 -53.951382)
			(xy 47.982121 -53.993435) (xy 48.005719 -54.039749) (xy 48.02178 -54.089186) (xy 48.02991 -54.140526)
			(xy 48.030384 -54.166516) (xy 48.03003 -54.189168) (xy 48.023874 -54.234052) (xy 48.01164 -54.277673)
			(xy 48.002952 -54.298596) (xy 47.997655 -54.311993) (xy 47.993973 -54.340551) (xy 47.998409 -54.369001)
			(xy 48.010609 -54.395084) (xy 48.029604 -54.416724) (xy 48.053884 -54.432203) (xy 48.08152 -54.44029)
			(xy 48.095916 -54.440836)
		)
		(stroke
			(width 0)
			(type solid)
		)
		(fill yes)
		(layer "In9.Cu")
		(net "P3V3_AUX")
	)
	(gr_poly
		(pts
			(xy 39.454328 -51.938936) (xy 39.436846 -51.918012) (xy 39.407373 -51.87214) (xy 39.384724 -51.822543)
			(xy 39.369358 -51.770229) (xy 39.36159 -51.716262) (xy 39.36111 -51.689) (xy 39.361636 -51.660149)
			(xy 39.370331 -51.603105) (xy 39.387538 -51.548028) (xy 39.399718 -51.521868) (xy 39.405757 -51.508406)
			(xy 39.410619 -51.479316) (xy 39.406966 -51.45005) (xy 39.395104 -51.423047) (xy 39.376021 -51.40056)
			(xy 39.351308 -51.384462) (xy 39.323026 -51.376097) (xy 39.308278 -51.375564) (xy 39.1414 -51.375564)
			(xy 39.118119 -51.375146) (xy 39.072127 -51.367892) (xy 39.027837 -51.35353) (xy 38.986339 -51.332415)
			(xy 38.948656 -51.305067) (xy 38.93185 -51.28895) (xy 38.695884 -51.052984) (xy 38.67912 -51.050444)
			(xy 38.652306 -51.045994) (xy 38.600211 -51.030494) (xy 38.550843 -51.007756) (xy 38.505203 -50.978241)
			(xy 38.464214 -50.942546) (xy 38.428708 -50.901394) (xy 38.399402 -50.855618) (xy 38.376891 -50.806147)
			(xy 38.361631 -50.75398) (xy 38.353929 -50.700176) (xy 38.353492 -50.673) (xy 38.353978 -50.645749)
			(xy 38.361734 -50.591801) (xy 38.377089 -50.539506) (xy 38.399731 -50.489929) (xy 38.429197 -50.444079)
			(xy 38.464888 -50.402888) (xy 38.506079 -50.367197) (xy 38.551929 -50.337731) (xy 38.601506 -50.315089)
			(xy 38.653801 -50.299734) (xy 38.707749 -50.291978) (xy 38.735 -50.291492) (xy 38.762174 -50.291972)
			(xy 38.815972 -50.299683) (xy 38.868131 -50.314948) (xy 38.917597 -50.337459) (xy 38.96337 -50.36676)
			(xy 39.004522 -50.402259) (xy 39.040221 -50.443237) (xy 39.069745 -50.488865) (xy 39.092498 -50.538221)
			(xy 39.108017 -50.590306) (xy 39.112444 -50.61712) (xy 39.114984 -50.633884) (xy 39.264082 -50.783236)
			(xy 39.983918 -50.783236) (xy 40.20185 -50.56505) (xy 40.218176 -50.549293) (xy 40.254771 -50.522471)
			(xy 40.295034 -50.501555) (xy 40.316404 -50.49393) (xy 40.32758 -50.49012) (xy 41.353486 -49.464214)
			(xy 41.370263 -49.448063) (xy 41.407951 -49.42071) (xy 41.449455 -49.399592) (xy 41.493752 -49.385231)
			(xy 41.539752 -49.377979) (xy 41.563036 -49.3776) (xy 42.957496 -49.3776) (xy 42.972515 -49.377053)
			(xy 43.001254 -49.368307) (xy 43.026216 -49.351595) (xy 43.045254 -49.328358) (xy 43.056727 -49.300596)
			(xy 43.059648 -49.270698) (xy 43.053765 -49.24124) (xy 43.047158 -49.22774) (xy 43.032887 -49.199842)
			(xy 43.012647 -49.14054) (xy 43.002364 -49.07873) (xy 43.001692 -49.0474) (xy 43.002178 -49.020149)
			(xy 43.009934 -48.966201) (xy 43.025289 -48.913906) (xy 43.047931 -48.864329) (xy 43.077397 -48.818479)
			(xy 43.113088 -48.777288) (xy 43.154279 -48.741597) (xy 43.200129 -48.712131) (xy 43.249706 -48.689489)
			(xy 43.302001 -48.674134) (xy 43.355949 -48.666378) (xy 43.410451 -48.666378) (xy 43.464399 -48.674134)
			(xy 43.516694 -48.689489) (xy 43.566271 -48.712131) (xy 43.612121 -48.741597) (xy 43.653312 -48.777288)
			(xy 43.689003 -48.818479) (xy 43.718469 -48.864329) (xy 43.741111 -48.913906) (xy 43.756466 -48.966201)
			(xy 43.760921 -48.997187) (xy 43.951146 -48.997187) (xy 43.951146 -48.945213) (xy 43.959276 -48.893878)
			(xy 43.975337 -48.844448) (xy 43.998933 -48.798138) (xy 44.029483 -48.75609) (xy 44.066234 -48.719339)
			(xy 44.108282 -48.688789) (xy 44.154592 -48.665193) (xy 44.204022 -48.649132) (xy 44.255357 -48.641002)
			(xy 44.307331 -48.641002) (xy 44.358666 -48.649132) (xy 44.408096 -48.665193) (xy 44.454406 -48.688789)
			(xy 44.496454 -48.719339) (xy 44.533205 -48.75609) (xy 44.563755 -48.798138) (xy 44.587351 -48.844448)
			(xy 44.603412 -48.893878) (xy 44.611542 -48.945213) (xy 44.612052 -48.9712) (xy 44.611542 -48.997187)
			(xy 44.603412 -49.048522) (xy 44.587351 -49.097952) (xy 44.563755 -49.144262) (xy 44.533205 -49.18631)
			(xy 44.496454 -49.223061) (xy 44.454406 -49.253611) (xy 44.408096 -49.277207) (xy 44.358666 -49.293268)
			(xy 44.307331 -49.301398) (xy 44.255357 -49.301398) (xy 44.204022 -49.293268) (xy 44.154592 -49.277207)
			(xy 44.108282 -49.253611) (xy 44.066234 -49.223061) (xy 44.029483 -49.18631) (xy 43.998933 -49.144262)
			(xy 43.975337 -49.097952) (xy 43.959276 -49.048522) (xy 43.951146 -48.997187) (xy 43.760921 -48.997187)
			(xy 43.764222 -49.020149) (xy 43.764708 -49.0474) (xy 43.764058 -49.078732) (xy 43.753779 -49.140547)
			(xy 43.733532 -49.19985) (xy 43.719242 -49.22774) (xy 43.712571 -49.241228) (xy 43.706606 -49.270708)
			(xy 43.709488 -49.300647) (xy 43.720965 -49.328448) (xy 43.740042 -49.3517) (xy 43.765065 -49.368387)
			(xy 43.793864 -49.377062) (xy 43.808904 -49.3776) (xy 43.933364 -49.3776) (xy 43.957253 -49.378078)
			(xy 44.004412 -49.385736) (xy 44.049733 -49.40086) (xy 44.092041 -49.423058) (xy 44.111418 -49.437036)
			(xy 46.2534 -49.437036) (xy 46.276681 -49.437454) (xy 46.322673 -49.444708) (xy 46.366963 -49.45907)
			(xy 46.408461 -49.480185) (xy 46.446144 -49.507533) (xy 46.46295 -49.52365) (xy 46.697138 -49.757838)
			(xy 47.367952 -49.757838) (xy 47.42688 -49.698656) (xy 52.56911 -49.698656) (xy 52.628038 -49.757838)
			(xy 57.170066 -49.757838) (xy 57.513728 -49.413922) (xy 57.513728 -48.990758) (xy 57.513304 -48.977254)
			(xy 57.506219 -48.951191) (xy 57.492553 -48.927894) (xy 57.473263 -48.90899) (xy 57.449694 -48.895799)
			(xy 57.423493 -48.889242) (xy 57.396489 -48.889778) (xy 57.383426 -48.893222) (xy 57.360638 -48.899517)
			(xy 57.313846 -48.906271) (xy 57.290208 -48.906684) (xy 57.26422 -48.906202) (xy 57.212884 -48.898072)
			(xy 57.163452 -48.882012) (xy 57.117141 -48.858416) (xy 57.075092 -48.827866) (xy 57.038339 -48.791114)
			(xy 57.007788 -48.749065) (xy 56.984192 -48.702755) (xy 56.96813 -48.653323) (xy 56.959999 -48.601988)
			(xy 56.959999 -48.550012) (xy 56.96813 -48.498677) (xy 56.984192 -48.449245) (xy 57.007788 -48.402935)
			(xy 57.038339 -48.360886) (xy 57.075092 -48.324134) (xy 57.117141 -48.293584) (xy 57.163452 -48.269988)
			(xy 57.212884 -48.253928) (xy 57.26422 -48.245798) (xy 57.290208 -48.245268) (xy 57.313844 -48.245709)
			(xy 57.360632 -48.252463) (xy 57.383426 -48.25873) (xy 57.396498 -48.262139) (xy 57.423498 -48.262701)
			(xy 57.449699 -48.256159) (xy 57.473267 -48.242974) (xy 57.49255 -48.224067) (xy 57.506199 -48.200764)
			(xy 57.513256 -48.174697) (xy 57.513728 -48.161194) (xy 57.513728 -48.065436) (xy 57.450736 -48.065436)
			(xy 57.439814 -48.071024) (xy 57.416501 -48.082294) (xy 57.367242 -48.098246) (xy 57.316097 -48.106321)
			(xy 57.290208 -48.106838) (xy 57.264216 -48.106355) (xy 57.212872 -48.098224) (xy 57.163432 -48.082161)
			(xy 57.117113 -48.058562) (xy 57.075057 -48.028007) (xy 57.038298 -47.991249) (xy 57.007742 -47.949194)
			(xy 56.984142 -47.902876) (xy 56.968077 -47.853436) (xy 56.959945 -47.802092) (xy 56.959945 -47.750108)
			(xy 56.968077 -47.698764) (xy 56.984142 -47.649324) (xy 57.007742 -47.603006) (xy 57.038298 -47.560951)
			(xy 57.075057 -47.524193) (xy 57.117113 -47.493638) (xy 57.163432 -47.470039) (xy 57.212872 -47.453976)
			(xy 57.264216 -47.445845) (xy 57.290208 -47.445422) (xy 57.313844 -47.445862) (xy 57.360632 -47.452616)
			(xy 57.383426 -47.458884) (xy 57.3965 -47.462292) (xy 57.423504 -47.462852) (xy 57.449709 -47.456311)
			(xy 57.473283 -47.443127) (xy 57.492573 -47.424222) (xy 57.506231 -47.400921) (xy 57.513301 -47.374853)
			(xy 57.513728 -47.361348) (xy 57.513728 -47.265336) (xy 57.450736 -47.265336) (xy 57.439814 -47.270924)
			(xy 57.416501 -47.282194) (xy 57.367242 -47.298146) (xy 57.316097 -47.306221) (xy 57.290208 -47.306738)
			(xy 57.264216 -47.306255) (xy 57.212872 -47.298124) (xy 57.163432 -47.282061) (xy 57.117113 -47.258462)
			(xy 57.075057 -47.227907) (xy 57.038298 -47.191149) (xy 57.007742 -47.149094) (xy 56.984142 -47.102776)
			(xy 56.968077 -47.053336) (xy 56.959945 -47.001992) (xy 56.959945 -46.950008) (xy 56.968077 -46.898664)
			(xy 56.984142 -46.849224) (xy 57.007742 -46.802906) (xy 57.038298 -46.760851) (xy 57.075057 -46.724093)
			(xy 57.117113 -46.693538) (xy 57.163432 -46.669939) (xy 57.212872 -46.653876) (xy 57.264216 -46.645745)
			(xy 57.290208 -46.645322) (xy 57.313844 -46.645762) (xy 57.360632 -46.652516) (xy 57.383426 -46.658784)
			(xy 57.3965 -46.662192) (xy 57.423504 -46.662752) (xy 57.449709 -46.656211) (xy 57.473283 -46.643027)
			(xy 57.492573 -46.624122) (xy 57.506231 -46.600821) (xy 57.513301 -46.574753) (xy 57.513728 -46.561248)
			(xy 57.513728 -46.143164) (xy 57.29224 -45.921676) (xy 55.745126 -45.921676) (xy 53.926994 -47.739808)
			(xy 53.813456 -47.739808) (xy 53.80101 -47.752508) (xy 48.833024 -47.752508) (xy 48.829722 -47.799498)
			(xy 48.829487 -47.802117) (xy 55.360064 -47.802117) (xy 55.360064 -47.750143) (xy 55.368194 -47.698808)
			(xy 55.384255 -47.649378) (xy 55.407851 -47.603068) (xy 55.438401 -47.56102) (xy 55.475152 -47.524269)
			(xy 55.5172 -47.493719) (xy 55.56351 -47.470123) (xy 55.61294 -47.454062) (xy 55.664275 -47.445932)
			(xy 55.716249 -47.445932) (xy 55.767584 -47.454062) (xy 55.817014 -47.470123) (xy 55.863324 -47.493719)
			(xy 55.905372 -47.524269) (xy 55.942123 -47.56102) (xy 55.972673 -47.603068) (xy 55.996269 -47.649378)
			(xy 56.01233 -47.698808) (xy 56.02046 -47.750143) (xy 56.02097 -47.77613) (xy 56.02046 -47.802117)
			(xy 56.01233 -47.853452) (xy 55.996269 -47.902882) (xy 55.972673 -47.949192) (xy 55.942123 -47.99124)
			(xy 55.905372 -48.027991) (xy 55.863324 -48.058541) (xy 55.817014 -48.082137) (xy 55.767584 -48.098198)
			(xy 55.716249 -48.106328) (xy 55.664275 -48.106328) (xy 55.61294 -48.098198) (xy 55.56351 -48.082137)
			(xy 55.5172 -48.058541) (xy 55.475152 -48.027991) (xy 55.438401 -47.99124) (xy 55.407851 -47.949192)
			(xy 55.384255 -47.902882) (xy 55.368194 -47.853452) (xy 55.360064 -47.802117) (xy 48.829487 -47.802117)
			(xy 48.827383 -47.825528) (xy 48.815539 -47.876429) (xy 48.795839 -47.924835) (xy 48.768772 -47.96954)
			(xy 48.735012 -48.009433) (xy 48.695398 -48.043521) (xy 48.650917 -48.070956) (xy 48.602676 -48.091055)
			(xy 48.551874 -48.103318) (xy 48.499776 -48.10744) (xy 48.447678 -48.103318) (xy 48.396876 -48.091055)
			(xy 48.348635 -48.070956) (xy 48.304154 -48.043521) (xy 48.26454 -48.009433) (xy 48.23078 -47.96954)
			(xy 48.203713 -47.924835) (xy 48.184013 -47.876429) (xy 48.172169 -47.825528) (xy 48.16983 -47.799498)
			(xy 48.166528 -47.752508) (xy 47.233078 -47.752508) (xy 47.229776 -47.799498) (xy 47.227437 -47.825528)
			(xy 47.215593 -47.876429) (xy 47.195893 -47.924835) (xy 47.168826 -47.96954) (xy 47.135066 -48.009433)
			(xy 47.095452 -48.043521) (xy 47.050971 -48.070956) (xy 47.00273 -48.091055) (xy 46.951928 -48.103318)
			(xy 46.89983 -48.10744) (xy 46.847732 -48.103318) (xy 46.79693 -48.091055) (xy 46.748689 -48.070956)
			(xy 46.704208 -48.043521) (xy 46.664594 -48.009433) (xy 46.630834 -47.96954) (xy 46.603767 -47.924835)
			(xy 46.584067 -47.876429) (xy 46.572223 -47.825528) (xy 46.569884 -47.799498) (xy 46.566582 -47.752508)
			(xy 46.432978 -47.752508) (xy 46.429676 -47.799498) (xy 46.427337 -47.825528) (xy 46.415493 -47.876429)
			(xy 46.395793 -47.924835) (xy 46.368726 -47.96954) (xy 46.334966 -48.009433) (xy 46.295352 -48.043521)
			(xy 46.250871 -48.070956) (xy 46.20263 -48.091055) (xy 46.151828 -48.103318) (xy 46.09973 -48.10744)
			(xy 46.047632 -48.103318) (xy 45.99683 -48.091055) (xy 45.948589 -48.070956) (xy 45.904108 -48.043521)
			(xy 45.864494 -48.009433) (xy 45.830734 -47.96954) (xy 45.803667 -47.924835) (xy 45.783967 -47.876429)
			(xy 45.772123 -47.825528) (xy 45.769784 -47.799498) (xy 45.766482 -47.752508) (xy 45.633132 -47.752508)
			(xy 45.62983 -47.799498) (xy 45.627491 -47.825528) (xy 45.615647 -47.876429) (xy 45.595947 -47.924835)
			(xy 45.56888 -47.96954) (xy 45.53512 -48.009433) (xy 45.495506 -48.043521) (xy 45.451025 -48.070956)
			(xy 45.402784 -48.091055) (xy 45.351982 -48.103318) (xy 45.299884 -48.10744) (xy 45.247786 -48.103318)
			(xy 45.196984 -48.091055) (xy 45.148743 -48.070956) (xy 45.104262 -48.043521) (xy 45.064648 -48.009433)
			(xy 45.030888 -47.96954) (xy 45.003821 -47.924835) (xy 44.984121 -47.876429) (xy 44.972277 -47.825528)
			(xy 44.969938 -47.799498) (xy 44.966636 -47.752508) (xy 41.052242 -47.752508) (xy 40.970454 -47.834296)
			(xy 40.961008 -47.84439) (xy 40.947421 -47.868452) (xy 40.940793 -47.895279) (xy 40.941611 -47.922901)
			(xy 40.949814 -47.949289) (xy 40.964801 -47.972506) (xy 40.98547 -47.990847) (xy 41.010304 -48.002966)
			(xy 41.023794 -48.006) (xy 41.049785 -48.011234) (xy 41.100104 -48.027933) (xy 41.147626 -48.051438)
			(xy 41.191437 -48.081296) (xy 41.230692 -48.116931) (xy 41.264636 -48.157658) (xy 41.292615 -48.202692)
			(xy 41.31409 -48.251165) (xy 41.328647 -48.302145) (xy 41.336006 -48.354649) (xy 41.336468 -48.381158)
			(xy 41.336007 -48.408412) (xy 41.328255 -48.462365) (xy 41.312902 -48.514666) (xy 41.290262 -48.564249)
			(xy 41.266026 -48.601963) (xy 44.969686 -48.601963) (xy 44.969686 -48.549989) (xy 44.977816 -48.498654)
			(xy 44.993877 -48.449224) (xy 45.017473 -48.402914) (xy 45.048023 -48.360866) (xy 45.084774 -48.324115)
			(xy 45.126822 -48.293565) (xy 45.173132 -48.269969) (xy 45.222562 -48.253908) (xy 45.273897 -48.245778)
			(xy 45.325871 -48.245778) (xy 45.377206 -48.253908) (xy 45.426636 -48.269969) (xy 45.472946 -48.293565)
			(xy 45.514994 -48.324115) (xy 45.551745 -48.360866) (xy 45.582295 -48.402914) (xy 45.605891 -48.449224)
			(xy 45.621952 -48.498654) (xy 45.630082 -48.549989) (xy 45.630592 -48.575976) (xy 45.630082 -48.601963)
			(xy 45.769532 -48.601963) (xy 45.769532 -48.549989) (xy 45.777662 -48.498654) (xy 45.793723 -48.449224)
			(xy 45.817319 -48.402914) (xy 45.847869 -48.360866) (xy 45.88462 -48.324115) (xy 45.926668 -48.293565)
			(xy 45.972978 -48.269969) (xy 46.022408 -48.253908) (xy 46.073743 -48.245778) (xy 46.125717 -48.245778)
			(xy 46.177052 -48.253908) (xy 46.226482 -48.269969) (xy 46.272792 -48.293565) (xy 46.31484 -48.324115)
			(xy 46.351591 -48.360866) (xy 46.382141 -48.402914) (xy 46.405737 -48.449224) (xy 46.421798 -48.498654)
			(xy 46.429928 -48.549989) (xy 46.430438 -48.575976) (xy 46.429928 -48.601963) (xy 46.569632 -48.601963)
			(xy 46.569632 -48.549989) (xy 46.577762 -48.498654) (xy 46.593823 -48.449224) (xy 46.617419 -48.402914)
			(xy 46.647969 -48.360866) (xy 46.68472 -48.324115) (xy 46.726768 -48.293565) (xy 46.773078 -48.269969)
			(xy 46.822508 -48.253908) (xy 46.873843 -48.245778) (xy 46.925817 -48.245778) (xy 46.977152 -48.253908)
			(xy 47.026582 -48.269969) (xy 47.072892 -48.293565) (xy 47.11494 -48.324115) (xy 47.151691 -48.360866)
			(xy 47.182241 -48.402914) (xy 47.205837 -48.449224) (xy 47.221898 -48.498654) (xy 47.230028 -48.549989)
			(xy 47.230538 -48.575976) (xy 47.230028 -48.601963) (xy 48.169578 -48.601963) (xy 48.169578 -48.549989)
			(xy 48.177708 -48.498654) (xy 48.193769 -48.449224) (xy 48.217365 -48.402914) (xy 48.247915 -48.360866)
			(xy 48.284666 -48.324115) (xy 48.326714 -48.293565) (xy 48.373024 -48.269969) (xy 48.422454 -48.253908)
			(xy 48.473789 -48.245778) (xy 48.525763 -48.245778) (xy 48.577098 -48.253908) (xy 48.626528 -48.269969)
			(xy 48.672838 -48.293565) (xy 48.714886 -48.324115) (xy 48.751637 -48.360866) (xy 48.782187 -48.402914)
			(xy 48.805783 -48.449224) (xy 48.821844 -48.498654) (xy 48.829974 -48.549989) (xy 48.830484 -48.575976)
			(xy 48.829974 -48.601963) (xy 49.769524 -48.601963) (xy 49.769524 -48.549989) (xy 49.777654 -48.498654)
			(xy 49.793715 -48.449224) (xy 49.817311 -48.402914) (xy 49.847861 -48.360866) (xy 49.884612 -48.324115)
			(xy 49.92666 -48.293565) (xy 49.97297 -48.269969) (xy 50.0224 -48.253908) (xy 50.073735 -48.245778)
			(xy 50.125709 -48.245778) (xy 50.177044 -48.253908) (xy 50.226474 -48.269969) (xy 50.272784 -48.293565)
			(xy 50.314832 -48.324115) (xy 50.351583 -48.360866) (xy 50.382133 -48.402914) (xy 50.405729 -48.449224)
			(xy 50.42179 -48.498654) (xy 50.42992 -48.549989) (xy 50.43043 -48.575976) (xy 50.42992 -48.601963)
			(xy 50.569624 -48.601963) (xy 50.569624 -48.549989) (xy 50.577754 -48.498654) (xy 50.593815 -48.449224)
			(xy 50.617411 -48.402914) (xy 50.647961 -48.360866) (xy 50.684712 -48.324115) (xy 50.72676 -48.293565)
			(xy 50.77307 -48.269969) (xy 50.8225 -48.253908) (xy 50.873835 -48.245778) (xy 50.925809 -48.245778)
			(xy 50.977144 -48.253908) (xy 51.026574 -48.269969) (xy 51.072884 -48.293565) (xy 51.114932 -48.324115)
			(xy 51.151683 -48.360866) (xy 51.182233 -48.402914) (xy 51.205829 -48.449224) (xy 51.22189 -48.498654)
			(xy 51.23002 -48.549989) (xy 51.23053 -48.575976) (xy 51.23002 -48.601963) (xy 51.36947 -48.601963)
			(xy 51.36947 -48.549989) (xy 51.3776 -48.498654) (xy 51.393661 -48.449224) (xy 51.417257 -48.402914)
			(xy 51.447807 -48.360866) (xy 51.484558 -48.324115) (xy 51.526606 -48.293565) (xy 51.572916 -48.269969)
			(xy 51.622346 -48.253908) (xy 51.673681 -48.245778) (xy 51.725655 -48.245778) (xy 51.77699 -48.253908)
			(xy 51.82642 -48.269969) (xy 51.87273 -48.293565) (xy 51.914778 -48.324115) (xy 51.951529 -48.360866)
			(xy 51.982079 -48.402914) (xy 52.005675 -48.449224) (xy 52.021736 -48.498654) (xy 52.029866 -48.549989)
			(xy 52.030376 -48.575976) (xy 52.029866 -48.601963) (xy 52.16957 -48.601963) (xy 52.16957 -48.549989)
			(xy 52.1777 -48.498654) (xy 52.193761 -48.449224) (xy 52.217357 -48.402914) (xy 52.247907 -48.360866)
			(xy 52.284658 -48.324115) (xy 52.326706 -48.293565) (xy 52.373016 -48.269969) (xy 52.422446 -48.253908)
			(xy 52.473781 -48.245778) (xy 52.525755 -48.245778) (xy 52.57709 -48.253908) (xy 52.62652 -48.269969)
			(xy 52.67283 -48.293565) (xy 52.714878 -48.324115) (xy 52.751629 -48.360866) (xy 52.782179 -48.402914)
			(xy 52.805775 -48.449224) (xy 52.821836 -48.498654) (xy 52.829966 -48.549989) (xy 52.830476 -48.575976)
			(xy 52.83015 -48.592565) (xy 55.369462 -48.592565) (xy 55.369462 -48.540591) (xy 55.377592 -48.489256)
			(xy 55.393653 -48.439826) (xy 55.417249 -48.393516) (xy 55.447799 -48.351468) (xy 55.48455 -48.314717)
			(xy 55.526598 -48.284167) (xy 55.572908 -48.260571) (xy 55.622338 -48.24451) (xy 55.673673 -48.23638)
			(xy 55.725647 -48.23638) (xy 55.776982 -48.24451) (xy 55.826412 -48.260571) (xy 55.872722 -48.284167)
			(xy 55.91477 -48.314717) (xy 55.951521 -48.351468) (xy 55.982071 -48.393516) (xy 56.005667 -48.439826)
			(xy 56.021728 -48.489256) (xy 56.029858 -48.540591) (xy 56.030368 -48.566578) (xy 56.029858 -48.592565)
			(xy 56.02837 -48.601963) (xy 56.15991 -48.601963) (xy 56.15991 -48.549989) (xy 56.16804 -48.498654)
			(xy 56.184101 -48.449224) (xy 56.207697 -48.402914) (xy 56.238247 -48.360866) (xy 56.274998 -48.324115)
			(xy 56.317046 -48.293565) (xy 56.363356 -48.269969) (xy 56.412786 -48.253908) (xy 56.464121 -48.245778)
			(xy 56.516095 -48.245778) (xy 56.56743 -48.253908) (xy 56.61686 -48.269969) (xy 56.66317 -48.293565)
			(xy 56.705218 -48.324115) (xy 56.741969 -48.360866) (xy 56.772519 -48.402914) (xy 56.796115 -48.449224)
			(xy 56.812176 -48.498654) (xy 56.820306 -48.549989) (xy 56.820816 -48.575976) (xy 56.820306 -48.601963)
			(xy 56.812176 -48.653298) (xy 56.796115 -48.702728) (xy 56.772519 -48.749038) (xy 56.741969 -48.791086)
			(xy 56.705218 -48.827837) (xy 56.66317 -48.858387) (xy 56.61686 -48.881983) (xy 56.56743 -48.898044)
			(xy 56.516095 -48.906174) (xy 56.464121 -48.906174) (xy 56.412786 -48.898044) (xy 56.363356 -48.881983)
			(xy 56.317046 -48.858387) (xy 56.274998 -48.827837) (xy 56.238247 -48.791086) (xy 56.207697 -48.749038)
			(xy 56.184101 -48.702728) (xy 56.16804 -48.653298) (xy 56.15991 -48.601963) (xy 56.02837 -48.601963)
			(xy 56.021728 -48.6439) (xy 56.005667 -48.69333) (xy 55.982071 -48.73964) (xy 55.951521 -48.781688)
			(xy 55.91477 -48.818439) (xy 55.872722 -48.848989) (xy 55.826412 -48.872585) (xy 55.776982 -48.888646)
			(xy 55.725647 -48.896776) (xy 55.673673 -48.896776) (xy 55.622338 -48.888646) (xy 55.572908 -48.872585)
			(xy 55.526598 -48.848989) (xy 55.48455 -48.818439) (xy 55.447799 -48.781688) (xy 55.417249 -48.73964)
			(xy 55.393653 -48.69333) (xy 55.377592 -48.6439) (xy 55.369462 -48.592565) (xy 52.83015 -48.592565)
			(xy 52.829966 -48.601963) (xy 52.821836 -48.653298) (xy 52.805775 -48.702728) (xy 52.782179 -48.749038)
			(xy 52.751629 -48.791086) (xy 52.714878 -48.827837) (xy 52.67283 -48.858387) (xy 52.62652 -48.881983)
			(xy 52.57709 -48.898044) (xy 52.525755 -48.906174) (xy 52.473781 -48.906174) (xy 52.422446 -48.898044)
			(xy 52.373016 -48.881983) (xy 52.326706 -48.858387) (xy 52.284658 -48.827837) (xy 52.247907 -48.791086)
			(xy 52.217357 -48.749038) (xy 52.193761 -48.702728) (xy 52.1777 -48.653298) (xy 52.16957 -48.601963)
			(xy 52.029866 -48.601963) (xy 52.021736 -48.653298) (xy 52.005675 -48.702728) (xy 51.982079 -48.749038)
			(xy 51.951529 -48.791086) (xy 51.914778 -48.827837) (xy 51.87273 -48.858387) (xy 51.82642 -48.881983)
			(xy 51.77699 -48.898044) (xy 51.725655 -48.906174) (xy 51.673681 -48.906174) (xy 51.622346 -48.898044)
			(xy 51.572916 -48.881983) (xy 51.526606 -48.858387) (xy 51.484558 -48.827837) (xy 51.447807 -48.791086)
			(xy 51.417257 -48.749038) (xy 51.393661 -48.702728) (xy 51.3776 -48.653298) (xy 51.36947 -48.601963)
			(xy 51.23002 -48.601963) (xy 51.22189 -48.653298) (xy 51.205829 -48.702728) (xy 51.182233 -48.749038)
			(xy 51.151683 -48.791086) (xy 51.114932 -48.827837) (xy 51.072884 -48.858387) (xy 51.026574 -48.881983)
			(xy 50.977144 -48.898044) (xy 50.925809 -48.906174) (xy 50.873835 -48.906174) (xy 50.8225 -48.898044)
			(xy 50.77307 -48.881983) (xy 50.72676 -48.858387) (xy 50.684712 -48.827837) (xy 50.647961 -48.791086)
			(xy 50.617411 -48.749038) (xy 50.593815 -48.702728) (xy 50.577754 -48.653298) (xy 50.569624 -48.601963)
			(xy 50.42992 -48.601963) (xy 50.42179 -48.653298) (xy 50.405729 -48.702728) (xy 50.382133 -48.749038)
			(xy 50.351583 -48.791086) (xy 50.314832 -48.827837) (xy 50.272784 -48.858387) (xy 50.226474 -48.881983)
			(xy 50.177044 -48.898044) (xy 50.125709 -48.906174) (xy 50.073735 -48.906174) (xy 50.0224 -48.898044)
			(xy 49.97297 -48.881983) (xy 49.92666 -48.858387) (xy 49.884612 -48.827837) (xy 49.847861 -48.791086)
			(xy 49.817311 -48.749038) (xy 49.793715 -48.702728) (xy 49.777654 -48.653298) (xy 49.769524 -48.601963)
			(xy 48.829974 -48.601963) (xy 48.821844 -48.653298) (xy 48.805783 -48.702728) (xy 48.782187 -48.749038)
			(xy 48.751637 -48.791086) (xy 48.714886 -48.827837) (xy 48.672838 -48.858387) (xy 48.626528 -48.881983)
			(xy 48.577098 -48.898044) (xy 48.525763 -48.906174) (xy 48.473789 -48.906174) (xy 48.422454 -48.898044)
			(xy 48.373024 -48.881983) (xy 48.326714 -48.858387) (xy 48.284666 -48.827837) (xy 48.247915 -48.791086)
			(xy 48.217365 -48.749038) (xy 48.193769 -48.702728) (xy 48.177708 -48.653298) (xy 48.169578 -48.601963)
			(xy 47.230028 -48.601963) (xy 47.221898 -48.653298) (xy 47.205837 -48.702728) (xy 47.182241 -48.749038)
			(xy 47.151691 -48.791086) (xy 47.11494 -48.827837) (xy 47.072892 -48.858387) (xy 47.026582 -48.881983)
			(xy 46.977152 -48.898044) (xy 46.925817 -48.906174) (xy 46.873843 -48.906174) (xy 46.822508 -48.898044)
			(xy 46.773078 -48.881983) (xy 46.726768 -48.858387) (xy 46.68472 -48.827837) (xy 46.647969 -48.791086)
			(xy 46.617419 -48.749038) (xy 46.593823 -48.702728) (xy 46.577762 -48.653298) (xy 46.569632 -48.601963)
			(xy 46.429928 -48.601963) (xy 46.421798 -48.653298) (xy 46.405737 -48.702728) (xy 46.382141 -48.749038)
			(xy 46.351591 -48.791086) (xy 46.31484 -48.827837) (xy 46.272792 -48.858387) (xy 46.226482 -48.881983)
			(xy 46.177052 -48.898044) (xy 46.125717 -48.906174) (xy 46.073743 -48.906174) (xy 46.022408 -48.898044)
			(xy 45.972978 -48.881983) (xy 45.926668 -48.858387) (xy 45.88462 -48.827837) (xy 45.847869 -48.791086)
			(xy 45.817319 -48.749038) (xy 45.793723 -48.702728) (xy 45.777662 -48.653298) (xy 45.769532 -48.601963)
			(xy 45.630082 -48.601963) (xy 45.621952 -48.653298) (xy 45.605891 -48.702728) (xy 45.582295 -48.749038)
			(xy 45.551745 -48.791086) (xy 45.514994 -48.827837) (xy 45.472946 -48.858387) (xy 45.426636 -48.881983)
			(xy 45.377206 -48.898044) (xy 45.325871 -48.906174) (xy 45.273897 -48.906174) (xy 45.222562 -48.898044)
			(xy 45.173132 -48.881983) (xy 45.126822 -48.858387) (xy 45.084774 -48.827837) (xy 45.048023 -48.791086)
			(xy 45.017473 -48.749038) (xy 44.993877 -48.702728) (xy 44.977816 -48.653298) (xy 44.969686 -48.601963)
			(xy 41.266026 -48.601963) (xy 41.260794 -48.610104) (xy 41.2251 -48.651299) (xy 41.183906 -48.686993)
			(xy 41.13805 -48.716461) (xy 41.088468 -48.739102) (xy 41.036167 -48.754455) (xy 40.982214 -48.762207)
			(xy 40.95496 -48.762666) (xy 40.928447 -48.762214) (xy 40.875932 -48.754876) (xy 40.82494 -48.740334)
			(xy 40.776454 -48.718868) (xy 40.731409 -48.690892) (xy 40.690674 -48.656945) (xy 40.655036 -48.617682)
			(xy 40.62518 -48.573861) (xy 40.601682 -48.526326) (xy 40.584997 -48.475994) (xy 40.579802 -48.449992)
			(xy 40.57682 -48.436499) (xy 40.564668 -48.411693) (xy 40.546311 -48.391053) (xy 40.523093 -48.376089)
			(xy 40.496714 -48.367896) (xy 40.469104 -48.367075) (xy 40.442285 -48.373684) (xy 40.418218 -48.387241)
			(xy 40.408098 -48.396652) (xy 40.269922 -48.534828) (xy 38.125908 -48.534828) (xy 38.104516 -48.553285)
			(xy 38.057323 -48.584349) (xy 38.006073 -48.608128) (xy 37.95188 -48.624107) (xy 37.923978 -48.628554)
			(xy 37.90696 -48.63084) (xy 37.084 -49.4538) (xy 37.084 -51.74234) (xy 38.210742 -51.74234) (xy 38.214813 -51.686718)
			(xy 38.226939 -51.632281) (xy 38.246862 -51.58019) (xy 38.274158 -51.531555) (xy 38.308244 -51.487412)
			(xy 38.348393 -51.448703) (xy 38.393751 -51.416252) (xy 38.443351 -51.390751) (xy 38.496135 -51.372744)
			(xy 38.550978 -51.362614) (xy 38.606712 -51.360577) (xy 38.662149 -51.366677) (xy 38.716106 -51.380783)
			(xy 38.767435 -51.402595) (xy 38.815041 -51.431649) (xy 38.857909 -51.467324) (xy 38.895126 -51.508861)
			(xy 38.925899 -51.555374) (xy 38.949571 -51.605871) (xy 38.965639 -51.659278) (xy 38.973759 -51.714454)
			(xy 38.974268 -51.74234) (xy 38.973759 -51.770226) (xy 38.965639 -51.825402) (xy 38.949571 -51.878809)
			(xy 38.925899 -51.929306) (xy 38.895126 -51.975819) (xy 38.857909 -52.017356) (xy 38.815041 -52.053031)
			(xy 38.767435 -52.082085) (xy 38.716106 -52.103897) (xy 38.662149 -52.118003) (xy 38.606712 -52.124103)
			(xy 38.550978 -52.122066) (xy 38.496135 -52.111936) (xy 38.443351 -52.093929) (xy 38.393751 -52.068428)
			(xy 38.348393 -52.035977) (xy 38.308244 -51.997268) (xy 38.274158 -51.953125) (xy 38.246862 -51.90449)
			(xy 38.226939 -51.852399) (xy 38.214813 -51.797962) (xy 38.210742 -51.74234) (xy 37.084 -51.74234)
			(xy 37.084 -51.9176) (xy 37.644832 -52.478432) (xy 38.914832 -52.478432)
		)
		(stroke
			(width 0)
			(type solid)
		)
		(fill yes)
		(layer "In9.Cu")
		(net "P3V3_RGM")
	)
	(gr_poly
		(pts
			(xy 7.32536 -80.339946) (xy 7.340481 -80.3394) (xy 7.3694 -80.330554) (xy 7.394461 -80.313626) (xy 7.413465 -80.290101)
			(xy 7.424745 -80.262042) (xy 7.427313 -80.231909) (xy 7.424674 -80.21701) (xy 7.420729 -80.197244)
			(xy 7.416526 -80.157155) (xy 7.416292 -80.137) (xy 7.416778 -80.109749) (xy 7.424534 -80.055801)
			(xy 7.439889 -80.003506) (xy 7.462531 -79.953929) (xy 7.491997 -79.908079) (xy 7.527688 -79.866888)
			(xy 7.568879 -79.831197) (xy 7.614729 -79.801731) (xy 7.664306 -79.779089) (xy 7.716601 -79.763734)
			(xy 7.770549 -79.755978) (xy 7.825051 -79.755978) (xy 7.878999 -79.763734) (xy 7.931294 -79.779089)
			(xy 7.980871 -79.801731) (xy 8.026721 -79.831197) (xy 8.067912 -79.866888) (xy 8.103603 -79.908079)
			(xy 8.133069 -79.953929) (xy 8.155711 -80.003506) (xy 8.171066 -80.055801) (xy 8.178822 -80.109749)
			(xy 8.179308 -80.137) (xy 8.179072 -80.157155) (xy 8.174868 -80.197243) (xy 8.170926 -80.21701) (xy 8.168297 -80.231905)
			(xy 8.170889 -80.262024) (xy 8.182177 -80.290067) (xy 8.201176 -80.313582) (xy 8.226222 -80.33051)
			(xy 8.255125 -80.33937) (xy 8.27024 -80.339946) (xy 9.544558 -80.339946) (xy 9.559798 -80.339692)
			(xy 9.669526 -80.339692) (xy 10.879836 -79.129636) (xy 10.886948 -79.12227) (xy 10.893044 -79.116174)
			(xy 10.923016 -79.086202) (xy 10.923016 -76.081382) (xy 10.923551 -76.054116) (xy 10.932079 -76.000256)
			(xy 10.948924 -75.948391) (xy 10.97367 -75.899797) (xy 11.005708 -75.85567) (xy 11.024616 -75.836018)
			(xy 11.377676 -75.482958) (xy 11.377676 -70.520814) (xy 11.37539 -70.513448) (xy 11.367445 -70.486064)
			(xy 11.358904 -70.429689) (xy 11.358372 -70.40118) (xy 11.358871 -70.37334) (xy 11.366953 -70.318249)
			(xy 11.382957 -70.264919) (xy 11.406543 -70.214481) (xy 11.43721 -70.168007) (xy 11.4554 -70.146926)
			(xy 11.4554 -68.467732) (xy 10.661904 -67.674236) (xy 10.661904 -63.688214) (xy 10.66136 -63.672743)
			(xy 10.652098 -63.643219) (xy 10.63442 -63.617823) (xy 10.609948 -63.598887) (xy 10.580929 -63.588148)
			(xy 10.550025 -63.586592) (xy 10.534904 -63.589916) (xy 10.511441 -63.595618) (xy 10.463543 -63.601731)
			(xy 10.4394 -63.602108) (xy 10.412149 -63.601622) (xy 10.358201 -63.593866) (xy 10.305906 -63.578511)
			(xy 10.256329 -63.555869) (xy 10.210479 -63.526403) (xy 10.169288 -63.490712) (xy 10.133597 -63.449521)
			(xy 10.104131 -63.403671) (xy 10.081489 -63.354094) (xy 10.066134 -63.301799) (xy 10.058378 -63.247851)
			(xy 10.058378 -63.193349) (xy 10.066134 -63.139401) (xy 10.081489 -63.087106) (xy 10.104131 -63.037529)
			(xy 10.133597 -62.991679) (xy 10.169288 -62.950488) (xy 10.210479 -62.914797) (xy 10.256329 -62.885331)
			(xy 10.305906 -62.862689) (xy 10.358201 -62.847334) (xy 10.412149 -62.839578) (xy 10.4394 -62.839092)
			(xy 10.463542 -62.839478) (xy 10.51144 -62.84559) (xy 10.534904 -62.851284) (xy 10.550018 -62.854624)
			(xy 10.580915 -62.853042) (xy 10.609925 -62.842291) (xy 10.634391 -62.823355) (xy 10.652073 -62.797968)
			(xy 10.661352 -62.768455) (xy 10.661904 -62.752986) (xy 10.661904 -58.61685) (xy 8.6868 -56.642254)
			(xy 8.6868 -55.390542) (xy 8.686292 -55.372) (xy 8.6868 -55.353458) (xy 8.6868 -53.271928) (xy 11.087608 -50.870866)
			(xy 11.087608 -50.706528) (xy 11.088046 -50.685239) (xy 11.094745 -50.643191) (xy 11.107935 -50.602707)
			(xy 11.127293 -50.564782) (xy 11.152341 -50.530351) (xy 11.16711 -50.515012) (xy 12.481814 -49.200054)
			(xy 12.481814 -45.775626) (xy 12.786106 -45.471334) (xy 12.786106 -33.66135) (xy 12.785645 -33.647178)
			(xy 12.777853 -33.619927) (xy 12.762859 -33.595875) (xy 12.741821 -33.576882) (xy 12.716366 -33.564416)
			(xy 12.688463 -33.559442) (xy 12.660269 -33.562344) (xy 12.646914 -33.567116) (xy 12.624404 -33.575653)
			(xy 12.577778 -33.587644) (xy 12.530016 -33.593684) (xy 12.505944 -33.59404) (xy 12.478688 -33.59358)
			(xy 12.424731 -33.585828) (xy 12.372426 -33.570477) (xy 12.322838 -33.547837) (xy 12.276977 -33.518371)
			(xy 12.235776 -33.482677) (xy 12.200075 -33.441484) (xy 12.170599 -33.395629) (xy 12.14795 -33.346046)
			(xy 12.132588 -33.293744) (xy 12.124825 -33.239788) (xy 12.124436 -33.212532) (xy 12.124968 -33.183615)
			(xy 12.133691 -33.126442) (xy 12.150943 -33.07124) (xy 12.176328 -33.019274) (xy 12.209265 -32.971734)
			(xy 12.248999 -32.92971) (xy 12.271502 -32.911542) (xy 12.283311 -32.901644) (xy 12.300835 -32.876317)
			(xy 12.310017 -32.846919) (xy 12.310023 -32.81612) (xy 12.300852 -32.786719) (xy 12.283338 -32.761385)
			(xy 12.271502 -32.751522) (xy 12.249019 -32.733331) (xy 12.209282 -32.691314) (xy 12.176344 -32.643779)
			(xy 12.150959 -32.591817) (xy 12.133709 -32.536618) (xy 12.124989 -32.479448) (xy 12.124436 -32.450532)
			(xy 12.124897 -32.423279) (xy 12.132651 -32.369327) (xy 12.148004 -32.317028) (xy 12.170646 -32.267446)
			(xy 12.200114 -32.221592) (xy 12.235808 -32.180399) (xy 12.277002 -32.144706) (xy 12.322857 -32.11524)
			(xy 12.372439 -32.0926) (xy 12.424738 -32.077248) (xy 12.478691 -32.069496) (xy 12.505944 -32.069024)
			(xy 12.530017 -32.06937) (xy 12.577784 -32.075393) (xy 12.624412 -32.087388) (xy 12.646914 -32.095948)
			(xy 12.660249 -32.100755) (xy 12.688439 -32.103599) (xy 12.716327 -32.098591) (xy 12.741768 -32.086117)
			(xy 12.762804 -32.067136) (xy 12.777819 -32.043108) (xy 12.785658 -32.01588) (xy 12.786106 -32.001714)
			(xy 12.786106 -29.711142) (xy 12.18311 -29.108146) (xy 6.85038 -29.108146) (xy 6.679184 -29.279342)
			(xy 6.698454 -29.300669) (xy 6.731019 -29.348032) (xy 6.75611 -29.399743) (xy 6.77316 -29.454634)
			(xy 6.781782 -29.511461) (xy 6.782308 -29.5402) (xy 6.781822 -29.567451) (xy 6.774066 -29.621399)
			(xy 6.758711 -29.673694) (xy 6.736069 -29.723271) (xy 6.706603 -29.769121) (xy 6.670912 -29.810312)
			(xy 6.629721 -29.846003) (xy 6.583871 -29.875469) (xy 6.534294 -29.898111) (xy 6.481999 -29.913466)
			(xy 6.428051 -29.921222) (xy 6.4008 -29.921708) (xy 6.374497 -29.921266) (xy 6.322391 -29.914033)
			(xy 6.271774 -29.899703) (xy 6.223608 -29.87855) (xy 6.178808 -29.850974) (xy 6.15823 -29.834586)
			(xy 3.887216 -32.1056) (xy 3.887216 -33.212532) (xy 5.647436 -33.212532) (xy 5.647964 -33.183615)
			(xy 5.656689 -33.126444) (xy 5.673944 -33.071245) (xy 5.699334 -33.019283) (xy 5.732276 -32.971749)
			(xy 5.772017 -32.929732) (xy 5.794502 -32.911542) (xy 5.806274 -32.901609) (xy 5.823789 -32.876294)
			(xy 5.832967 -32.846911) (xy 5.832973 -32.816128) (xy 5.823806 -32.786741) (xy 5.806301 -32.76142)
			(xy 5.794502 -32.751522) (xy 5.772029 -32.733318) (xy 5.732293 -32.691301) (xy 5.699353 -32.643769)
			(xy 5.673963 -32.59181) (xy 5.656704 -32.536615) (xy 5.647973 -32.479447) (xy 5.647436 -32.450532)
			(xy 5.647922 -32.423281) (xy 5.655678 -32.369333) (xy 5.671033 -32.317038) (xy 5.693675 -32.267461)
			(xy 5.723141 -32.221611) (xy 5.758832 -32.18042) (xy 5.800023 -32.144729) (xy 5.845873 -32.115263)
			(xy 5.89545 -32.092621) (xy 5.947745 -32.077266) (xy 6.001693 -32.06951) (xy 6.056195 -32.06951)
			(xy 6.110143 -32.077266) (xy 6.162438 -32.092621) (xy 6.212015 -32.115263) (xy 6.257865 -32.144729)
			(xy 6.299056 -32.18042) (xy 6.334747 -32.221611) (xy 6.364213 -32.267461) (xy 6.386855 -32.317038)
			(xy 6.40221 -32.369333) (xy 6.409966 -32.423281) (xy 6.410452 -32.450532) (xy 6.409903 -32.479448)
			(xy 6.401183 -32.536619) (xy 6.383932 -32.591817) (xy 6.358546 -32.64378) (xy 6.325607 -32.691314)
			(xy 6.28587 -32.733331) (xy 6.263386 -32.751522) (xy 6.251551 -32.761386) (xy 6.234039 -32.78672)
			(xy 6.224869 -32.816121) (xy 6.224875 -32.846918) (xy 6.234056 -32.876316) (xy 6.251579 -32.901643)
			(xy 6.263386 -32.911542) (xy 6.285867 -32.929736) (xy 6.325602 -32.971755) (xy 6.358541 -33.01929)
			(xy 6.38393 -33.07125) (xy 6.401187 -33.126447) (xy 6.409917 -33.183616) (xy 6.410452 -33.212532)
			(xy 7.806436 -33.212532) (xy 7.806964 -33.183615) (xy 7.815689 -33.126444) (xy 7.832944 -33.071245)
			(xy 7.858334 -33.019283) (xy 7.891276 -32.971749) (xy 7.931017 -32.929732) (xy 7.953502 -32.911542)
			(xy 7.965274 -32.901609) (xy 7.982789 -32.876294) (xy 7.991967 -32.846911) (xy 7.991973 -32.816128)
			(xy 7.982806 -32.786741) (xy 7.965301 -32.76142) (xy 7.953502 -32.751522) (xy 7.931029 -32.733318)
			(xy 7.891293 -32.691301) (xy 7.858353 -32.643769) (xy 7.832963 -32.59181) (xy 7.815704 -32.536615)
			(xy 7.806973 -32.479447) (xy 7.806436 -32.450532) (xy 7.806922 -32.423281) (xy 7.814678 -32.369333)
			(xy 7.830033 -32.317038) (xy 7.852675 -32.267461) (xy 7.882141 -32.221611) (xy 7.917832 -32.18042)
			(xy 7.959023 -32.144729) (xy 8.004873 -32.115263) (xy 8.05445 -32.092621) (xy 8.106745 -32.077266)
			(xy 8.160693 -32.06951) (xy 8.215195 -32.06951) (xy 8.269143 -32.077266) (xy 8.321438 -32.092621)
			(xy 8.371015 -32.115263) (xy 8.416865 -32.144729) (xy 8.458056 -32.18042) (xy 8.493747 -32.221611)
			(xy 8.523213 -32.267461) (xy 8.545855 -32.317038) (xy 8.56121 -32.369333) (xy 8.568966 -32.423281)
			(xy 8.569452 -32.450532) (xy 8.568903 -32.479448) (xy 8.560183 -32.536619) (xy 8.542932 -32.591817)
			(xy 8.517546 -32.64378) (xy 8.484607 -32.691314) (xy 8.44487 -32.733331) (xy 8.422386 -32.751522)
			(xy 8.410551 -32.761386) (xy 8.393039 -32.78672) (xy 8.383869 -32.816121) (xy 8.383875 -32.846918)
			(xy 8.393056 -32.876316) (xy 8.410579 -32.901643) (xy 8.422386 -32.911542) (xy 8.444887 -32.929713)
			(xy 8.484621 -32.971736) (xy 8.517559 -33.019275) (xy 8.542944 -33.071241) (xy 8.560197 -33.126442)
			(xy 8.56892 -33.183615) (xy 8.569452 -33.212532) (xy 9.965436 -33.212532) (xy 9.965964 -33.183615)
			(xy 9.974689 -33.126444) (xy 9.991944 -33.071245) (xy 10.017334 -33.019283) (xy 10.050276 -32.971749)
			(xy 10.090017 -32.929732) (xy 10.112502 -32.911542) (xy 10.124274 -32.901609) (xy 10.141789 -32.876294)
			(xy 10.150967 -32.846911) (xy 10.150973 -32.816128) (xy 10.141806 -32.786741) (xy 10.124301 -32.76142)
			(xy 10.112502 -32.751522) (xy 10.090029 -32.733318) (xy 10.050293 -32.691301) (xy 10.017353 -32.643769)
			(xy 9.991963 -32.59181) (xy 9.974704 -32.536615) (xy 9.965973 -32.479447) (xy 9.965436 -32.450532)
			(xy 9.965922 -32.423281) (xy 9.973678 -32.369333) (xy 9.989033 -32.317038) (xy 10.011675 -32.267461)
			(xy 10.041141 -32.221611) (xy 10.076832 -32.18042) (xy 10.118023 -32.144729) (xy 10.163873 -32.115263)
			(xy 10.21345 -32.092621) (xy 10.265745 -32.077266) (xy 10.319693 -32.06951) (xy 10.374195 -32.06951)
			(xy 10.428143 -32.077266) (xy 10.480438 -32.092621) (xy 10.530015 -32.115263) (xy 10.575865 -32.144729)
			(xy 10.617056 -32.18042) (xy 10.652747 -32.221611) (xy 10.682213 -32.267461) (xy 10.704855 -32.317038)
			(xy 10.72021 -32.369333) (xy 10.727966 -32.423281) (xy 10.728452 -32.450532) (xy 10.727903 -32.479448)
			(xy 10.719183 -32.536619) (xy 10.701932 -32.591817) (xy 10.676546 -32.64378) (xy 10.643607 -32.691314)
			(xy 10.60387 -32.733331) (xy 10.581386 -32.751522) (xy 10.569551 -32.761386) (xy 10.552039 -32.78672)
			(xy 10.542869 -32.816121) (xy 10.542875 -32.846918) (xy 10.552056 -32.876316) (xy 10.569579 -32.901643)
			(xy 10.581386 -32.911542) (xy 10.603887 -32.929713) (xy 10.643621 -32.971736) (xy 10.676559 -33.019275)
			(xy 10.701944 -33.071241) (xy 10.719197 -33.126442) (xy 10.72792 -33.183615) (xy 10.728452 -33.212532)
			(xy 10.727966 -33.239783) (xy 10.72021 -33.293731) (xy 10.704855 -33.346026) (xy 10.682213 -33.395603)
			(xy 10.652747 -33.441453) (xy 10.617056 -33.482644) (xy 10.575865 -33.518335) (xy 10.530015 -33.547801)
			(xy 10.480438 -33.570443) (xy 10.428143 -33.585798) (xy 10.374195 -33.593554) (xy 10.319693 -33.593554)
			(xy 10.265745 -33.585798) (xy 10.21345 -33.570443) (xy 10.163873 -33.547801) (xy 10.118023 -33.518335)
			(xy 10.076832 -33.482644) (xy 10.041141 -33.441453) (xy 10.011675 -33.395603) (xy 9.989033 -33.346026)
			(xy 9.973678 -33.293731) (xy 9.965922 -33.239783) (xy 9.965436 -33.212532) (xy 8.569452 -33.212532)
			(xy 8.568966 -33.239783) (xy 8.56121 -33.293731) (xy 8.545855 -33.346026) (xy 8.523213 -33.395603)
			(xy 8.493747 -33.441453) (xy 8.458056 -33.482644) (xy 8.416865 -33.518335) (xy 8.371015 -33.547801)
			(xy 8.321438 -33.570443) (xy 8.269143 -33.585798) (xy 8.215195 -33.593554) (xy 8.160693 -33.593554)
			(xy 8.106745 -33.585798) (xy 8.05445 -33.570443) (xy 8.004873 -33.547801) (xy 7.959023 -33.518335)
			(xy 7.917832 -33.482644) (xy 7.882141 -33.441453) (xy 7.852675 -33.395603) (xy 7.830033 -33.346026)
			(xy 7.814678 -33.293731) (xy 7.806922 -33.239783) (xy 7.806436 -33.212532) (xy 6.410452 -33.212532)
			(xy 6.409966 -33.239783) (xy 6.40221 -33.293731) (xy 6.386855 -33.346026) (xy 6.364213 -33.395603)
			(xy 6.334747 -33.441453) (xy 6.299056 -33.482644) (xy 6.257865 -33.518335) (xy 6.212015 -33.547801)
			(xy 6.162438 -33.570443) (xy 6.110143 -33.585798) (xy 6.056195 -33.593554) (xy 6.001693 -33.593554)
			(xy 5.947745 -33.585798) (xy 5.89545 -33.570443) (xy 5.845873 -33.547801) (xy 5.800023 -33.518335)
			(xy 5.758832 -33.482644) (xy 5.723141 -33.441453) (xy 5.693675 -33.395603) (xy 5.671033 -33.346026)
			(xy 5.655678 -33.293731) (xy 5.647922 -33.239783) (xy 5.647436 -33.212532) (xy 3.887216 -33.212532)
			(xy 3.887216 -47.60468) (xy 4.469382 -47.60468) (xy 4.473453 -47.549058) (xy 4.485579 -47.494621)
			(xy 4.505502 -47.44253) (xy 4.532798 -47.393895) (xy 4.566884 -47.349752) (xy 4.607033 -47.311043)
			(xy 4.652391 -47.278592) (xy 4.701991 -47.253091) (xy 4.754775 -47.235084) (xy 4.809618 -47.224954)
			(xy 4.865352 -47.222917) (xy 4.920789 -47.229017) (xy 4.974746 -47.243123) (xy 5.026075 -47.264935)
			(xy 5.073681 -47.293989) (xy 5.116549 -47.329664) (xy 5.153766 -47.371201) (xy 5.184539 -47.417714)
			(xy 5.208211 -47.468211) (xy 5.224279 -47.521618) (xy 5.232399 -47.576794) (xy 5.232908 -47.60468)
			(xy 5.232399 -47.632566) (xy 5.224279 -47.687742) (xy 5.208211 -47.741149) (xy 5.184539 -47.791646)
			(xy 5.153766 -47.838159) (xy 5.116549 -47.879696) (xy 5.073681 -47.915371) (xy 5.026075 -47.944425)
			(xy 4.974746 -47.966237) (xy 4.920789 -47.980343) (xy 4.865352 -47.986443) (xy 4.809618 -47.984406)
			(xy 4.754775 -47.974276) (xy 4.701991 -47.956269) (xy 4.652391 -47.930768) (xy 4.607033 -47.898317)
			(xy 4.566884 -47.859608) (xy 4.532798 -47.815465) (xy 4.505502 -47.76683) (xy 4.485579 -47.714739)
			(xy 4.473453 -47.660302) (xy 4.469382 -47.60468) (xy 3.887216 -47.60468) (xy 3.887216 -49.78146)
			(xy 9.627614 -49.78146) (xy 9.631685 -49.725838) (xy 9.643811 -49.671401) (xy 9.663734 -49.61931)
			(xy 9.69103 -49.570675) (xy 9.725116 -49.526532) (xy 9.765265 -49.487823) (xy 9.810623 -49.455372)
			(xy 9.860223 -49.429871) (xy 9.913007 -49.411864) (xy 9.96785 -49.401734) (xy 10.023584 -49.399697)
			(xy 10.079021 -49.405797) (xy 10.132978 -49.419903) (xy 10.184307 -49.441715) (xy 10.231913 -49.470769)
			(xy 10.274781 -49.506444) (xy 10.311998 -49.547981) (xy 10.342771 -49.594494) (xy 10.366443 -49.644991)
			(xy 10.382511 -49.698398) (xy 10.390631 -49.753574) (xy 10.39114 -49.78146) (xy 10.390631 -49.809346)
			(xy 10.382511 -49.864522) (xy 10.366443 -49.917929) (xy 10.342771 -49.968426) (xy 10.311998 -50.014939)
			(xy 10.274781 -50.056476) (xy 10.231913 -50.092151) (xy 10.184307 -50.121205) (xy 10.132978 -50.143017)
			(xy 10.079021 -50.157123) (xy 10.023584 -50.163223) (xy 9.96785 -50.161186) (xy 9.913007 -50.151056)
			(xy 9.860223 -50.133049) (xy 9.810623 -50.107548) (xy 9.765265 -50.075097) (xy 9.725116 -50.036388)
			(xy 9.69103 -49.992245) (xy 9.663734 -49.94361) (xy 9.643811 -49.891519) (xy 9.631685 -49.837082)
			(xy 9.627614 -49.78146) (xy 3.887216 -49.78146) (xy 3.887216 -56.287416) (xy 4.0132 -56.4134) (xy 5.4102 -56.4134)
			(xy 5.9182 -56.9214) (xy 5.9182 -57.8358) (xy 5.5626 -58.1914) (xy 4.217416 -58.1914) (xy 3.887216 -58.5216)
			(xy 3.887216 -61.2648) (xy 8.660892 -61.2648) (xy 8.661375 -61.235881) (xy 8.670107 -61.178707) (xy 8.687369 -61.123506)
			(xy 8.712767 -61.071544) (xy 8.745719 -61.024011) (xy 8.785468 -60.981997) (xy 8.807958 -60.96381)
			(xy 8.819766 -60.953914) (xy 8.837288 -60.928591) (xy 8.846467 -60.899197) (xy 8.846467 -60.868403)
			(xy 8.837288 -60.839009) (xy 8.819766 -60.813686) (xy 8.807958 -60.80379) (xy 8.785461 -60.785615)
			(xy 8.745729 -60.743591) (xy 8.712792 -60.696052) (xy 8.687407 -60.644088) (xy 8.670153 -60.588888)
			(xy 8.661426 -60.531717) (xy 8.660892 -60.5028) (xy 8.661378 -60.475549) (xy 8.669134 -60.421601)
			(xy 8.684489 -60.369306) (xy 8.707131 -60.319729) (xy 8.736597 -60.273879) (xy 8.772288 -60.232688)
			(xy 8.813479 -60.196997) (xy 8.859329 -60.167531) (xy 8.908906 -60.144889) (xy 8.961201 -60.129534)
			(xy 9.015149 -60.121778) (xy 9.069651 -60.121778) (xy 9.123599 -60.129534) (xy 9.175894 -60.144889)
			(xy 9.225471 -60.167531) (xy 9.271321 -60.196997) (xy 9.312512 -60.232688) (xy 9.348203 -60.273879)
			(xy 9.377669 -60.319729) (xy 9.400311 -60.369306) (xy 9.415666 -60.421601) (xy 9.423422 -60.475549)
			(xy 9.423908 -60.5028) (xy 9.423425 -60.531719) (xy 9.414693 -60.588893) (xy 9.397431 -60.644094)
			(xy 9.372033 -60.696056) (xy 9.339081 -60.743589) (xy 9.299332 -60.785603) (xy 9.276842 -60.80379)
			(xy 9.265034 -60.813686) (xy 9.247512 -60.839009) (xy 9.238333 -60.868403) (xy 9.238333 -60.899197)
			(xy 9.247512 -60.928591) (xy 9.265034 -60.953914) (xy 9.276842 -60.96381) (xy 9.299339 -60.981985)
			(xy 9.339071 -61.024009) (xy 9.372008 -61.071548) (xy 9.397393 -61.123512) (xy 9.414647 -61.178712)
			(xy 9.423374 -61.235883) (xy 9.423908 -61.2648) (xy 9.423422 -61.292051) (xy 9.415666 -61.345999)
			(xy 9.400311 -61.398294) (xy 9.377669 -61.447871) (xy 9.348203 -61.493721) (xy 9.312512 -61.534912)
			(xy 9.271321 -61.570603) (xy 9.225471 -61.600069) (xy 9.175894 -61.622711) (xy 9.123599 -61.638066)
			(xy 9.069651 -61.645822) (xy 9.015149 -61.645822) (xy 8.961201 -61.638066) (xy 8.908906 -61.622711)
			(xy 8.859329 -61.600069) (xy 8.813479 -61.570603) (xy 8.772288 -61.534912) (xy 8.736597 -61.493721)
			(xy 8.707131 -61.447871) (xy 8.684489 -61.398294) (xy 8.669134 -61.345999) (xy 8.661378 -61.292051)
			(xy 8.660892 -61.2648) (xy 3.887216 -61.2648) (xy 3.887216 -64.613282) (xy 3.887762 -64.628343) (xy 3.89655 -64.657155)
			(xy 3.913354 -64.682155) (xy 3.936714 -64.701172) (xy 3.964603 -64.712556) (xy 3.994598 -64.715317)
			(xy 4.024096 -64.709217) (xy 4.050536 -64.694784) (xy 4.06146 -64.684402) (xy 4.079475 -64.666535)
			(xy 4.119409 -64.635236) (xy 4.16314 -64.609508) (xy 4.209895 -64.589804) (xy 4.258851 -64.576471)
			(xy 4.309141 -64.569747) (xy 4.33451 -64.56934) (xy 4.361761 -64.569826) (xy 4.415709 -64.577582)
			(xy 4.468004 -64.592938) (xy 4.517582 -64.615579) (xy 4.563433 -64.645045) (xy 4.604623 -64.680737)
			(xy 4.640315 -64.721927) (xy 4.669781 -64.767778) (xy 4.692422 -64.817356) (xy 4.707778 -64.869651)
			(xy 4.715534 -64.923599) (xy 4.715534 -64.978101) (xy 4.707778 -65.032049) (xy 4.692422 -65.084344)
			(xy 4.669781 -65.133922) (xy 4.640315 -65.179773) (xy 4.604623 -65.220963) (xy 4.563433 -65.256655)
			(xy 4.517582 -65.286121) (xy 4.468004 -65.308762) (xy 4.415709 -65.324118) (xy 4.361761 -65.331874)
			(xy 4.33451 -65.332356) (xy 4.309141 -65.33194) (xy 4.25885 -65.325217) (xy 4.209894 -65.311888)
			(xy 4.163137 -65.292188) (xy 4.119403 -65.266465) (xy 4.079464 -65.235172) (xy 4.06146 -65.217294)
			(xy 4.050531 -65.206903) (xy 4.024084 -65.192444) (xy 3.994571 -65.186325) (xy 3.964556 -65.189078)
			(xy 3.936648 -65.200464) (xy 3.913273 -65.219493) (xy 3.896462 -65.244511) (xy 3.887677 -65.273343)
			(xy 3.887216 -65.288414) (xy 3.887216 -65.726818) (xy 5.893052 -65.726818) (xy 5.897123 -65.671196)
			(xy 5.909249 -65.616759) (xy 5.929172 -65.564668) (xy 5.956468 -65.516033) (xy 5.990554 -65.47189)
			(xy 6.030703 -65.433181) (xy 6.076061 -65.40073) (xy 6.125661 -65.375229) (xy 6.178445 -65.357222)
			(xy 6.233288 -65.347092) (xy 6.289022 -65.345055) (xy 6.344459 -65.351155) (xy 6.398416 -65.365261)
			(xy 6.449745 -65.387073) (xy 6.497351 -65.416127) (xy 6.540219 -65.451802) (xy 6.577436 -65.493339)
			(xy 6.608209 -65.539852) (xy 6.631881 -65.590349) (xy 6.647949 -65.643756) (xy 6.656069 -65.698932)
			(xy 6.656578 -65.726818) (xy 6.656393 -65.736978) (xy 9.139172 -65.736978) (xy 9.143243 -65.681356)
			(xy 9.155369 -65.626919) (xy 9.175292 -65.574828) (xy 9.202588 -65.526193) (xy 9.236674 -65.48205)
			(xy 9.276823 -65.443341) (xy 9.322181 -65.41089) (xy 9.371781 -65.385389) (xy 9.424565 -65.367382)
			(xy 9.479408 -65.357252) (xy 9.535142 -65.355215) (xy 9.590579 -65.361315) (xy 9.644536 -65.375421)
			(xy 9.695865 -65.397233) (xy 9.743471 -65.426287) (xy 9.786339 -65.461962) (xy 9.823556 -65.503499)
			(xy 9.854329 -65.550012) (xy 9.878001 -65.600509) (xy 9.894069 -65.653916) (xy 9.902189 -65.709092)
			(xy 9.902698 -65.736978) (xy 9.902189 -65.764864) (xy 9.894069 -65.82004) (xy 9.878001 -65.873447)
			(xy 9.854329 -65.923944) (xy 9.823556 -65.970457) (xy 9.786339 -66.011994) (xy 9.743471 -66.047669)
			(xy 9.695865 -66.076723) (xy 9.644536 -66.098535) (xy 9.590579 -66.112641) (xy 9.535142 -66.118741)
			(xy 9.479408 -66.116704) (xy 9.424565 -66.106574) (xy 9.371781 -66.088567) (xy 9.322181 -66.063066)
			(xy 9.276823 -66.030615) (xy 9.236674 -65.991906) (xy 9.202588 -65.947763) (xy 9.175292 -65.899128)
			(xy 9.155369 -65.847037) (xy 9.143243 -65.7926) (xy 9.139172 -65.736978) (xy 6.656393 -65.736978)
			(xy 6.656069 -65.754704) (xy 6.647949 -65.80988) (xy 6.631881 -65.863287) (xy 6.608209 -65.913784)
			(xy 6.577436 -65.960297) (xy 6.540219 -66.001834) (xy 6.497351 -66.037509) (xy 6.449745 -66.066563)
			(xy 6.398416 -66.088375) (xy 6.344459 -66.102481) (xy 6.289022 -66.108581) (xy 6.233288 -66.106544)
			(xy 6.178445 -66.096414) (xy 6.125661 -66.078407) (xy 6.076061 -66.052906) (xy 6.030703 -66.020455)
			(xy 5.990554 -65.981746) (xy 5.956468 -65.937603) (xy 5.929172 -65.888968) (xy 5.909249 -65.836877)
			(xy 5.897123 -65.78244) (xy 5.893052 -65.726818) (xy 3.887216 -65.726818) (xy 3.887216 -77.375004)
			(xy 5.26669 -77.375004) (xy 5.267155 -77.348782) (xy 5.274351 -77.296833) (xy 5.288592 -77.246359)
			(xy 5.309612 -77.198311) (xy 5.337014 -77.153595) (xy 5.370281 -77.113052) (xy 5.408787 -77.077447)
			(xy 5.451807 -77.047451) (xy 5.47497 -77.035152) (xy 5.487246 -77.028409) (xy 5.507814 -77.009413)
			(xy 5.52245 -76.985545) (xy 5.530054 -76.958599) (xy 5.530054 -76.930601) (xy 5.522451 -76.903656)
			(xy 5.507815 -76.879788) (xy 5.487247 -76.860792) (xy 5.47497 -76.85405) (xy 5.451797 -76.841763)
			(xy 5.408762 -76.811779) (xy 5.370242 -76.77618) (xy 5.336965 -76.735637) (xy 5.309558 -76.690917)
			(xy 5.288539 -76.642862) (xy 5.274304 -76.59238) (xy 5.267123 -76.540423) (xy 5.26669 -76.514198)
			(xy 5.267176 -76.486947) (xy 5.274932 -76.432999) (xy 5.290287 -76.380704) (xy 5.312929 -76.331127)
			(xy 5.342395 -76.285277) (xy 5.378086 -76.244086) (xy 5.419277 -76.208395) (xy 5.465127 -76.178929)
			(xy 5.514704 -76.156287) (xy 5.566999 -76.140932) (xy 5.620947 -76.133176) (xy 5.675449 -76.133176)
			(xy 5.729397 -76.140932) (xy 5.781692 -76.156287) (xy 5.831269 -76.178929) (xy 5.877119 -76.208395)
			(xy 5.91831 -76.244086) (xy 5.954001 -76.285277) (xy 5.983467 -76.331127) (xy 6.006109 -76.380704)
			(xy 6.021464 -76.432999) (xy 6.02922 -76.486947) (xy 6.029706 -76.514198) (xy 6.029244 -76.54042)
			(xy 6.022049 -76.592369) (xy 6.007807 -76.642843) (xy 5.986786 -76.690891) (xy 5.959384 -76.735608)
			(xy 5.926116 -76.776151) (xy 5.88761 -76.811756) (xy 5.84459 -76.841752) (xy 5.821426 -76.85405)
			(xy 5.809187 -76.86082) (xy 5.788698 -76.879844) (xy 5.774124 -76.903705) (xy 5.766554 -76.930621)
			(xy 5.766555 -76.95858) (xy 5.774124 -76.985496) (xy 5.788698 -77.009357) (xy 5.809188 -77.028381)
			(xy 5.821426 -77.035152) (xy 5.844599 -77.04744) (xy 5.887634 -77.077423) (xy 5.926154 -77.113022)
			(xy 5.959432 -77.153564) (xy 5.986839 -77.198285) (xy 6.007858 -77.24634) (xy 6.022092 -77.296822)
			(xy 6.029273 -77.348779) (xy 6.029605 -77.368908) (xy 7.400544 -77.368908) (xy 7.401038 -77.342687)
			(xy 7.408231 -77.290741) (xy 7.422471 -77.240269) (xy 7.443487 -77.192222) (xy 7.470885 -77.147506)
			(xy 7.504147 -77.106962) (xy 7.542649 -77.071356) (xy 7.585663 -77.041357) (xy 7.608824 -77.029056)
			(xy 7.621101 -77.02231) (xy 7.641677 -77.003319) (xy 7.656321 -76.979451) (xy 7.663929 -76.952503)
			(xy 7.663929 -76.924502) (xy 7.656322 -76.897553) (xy 7.64168 -76.873685) (xy 7.621104 -76.854693)
			(xy 7.608824 -76.847954) (xy 7.585654 -76.835662) (xy 7.542618 -76.805679) (xy 7.504098 -76.770081)
			(xy 7.470821 -76.729539) (xy 7.443414 -76.684819) (xy 7.422394 -76.636765) (xy 7.408159 -76.586283)
			(xy 7.400977 -76.534327) (xy 7.400544 -76.508102) (xy 7.40103 -76.480851) (xy 7.408786 -76.426903)
			(xy 7.424141 -76.374608) (xy 7.446783 -76.325031) (xy 7.476249 -76.279181) (xy 7.51194 -76.23799)
			(xy 7.553131 -76.202299) (xy 7.598981 -76.172833) (xy 7.648558 -76.150191) (xy 7.700853 -76.134836)
			(xy 7.754801 -76.12708) (xy 7.809303 -76.12708) (xy 7.863251 -76.134836) (xy 7.915546 -76.150191)
			(xy 7.965123 -76.172833) (xy 8.010973 -76.202299) (xy 8.052164 -76.23799) (xy 8.087855 -76.279181)
			(xy 8.117321 -76.325031) (xy 8.139963 -76.374608) (xy 8.155318 -76.426903) (xy 8.163074 -76.480851)
			(xy 8.16356 -76.508102) (xy 8.163072 -76.534323) (xy 8.155877 -76.58627) (xy 8.141637 -76.636742)
			(xy 8.12062 -76.684788) (xy 8.093221 -76.729505) (xy 8.059958 -76.770048) (xy 8.021456 -76.805654)
			(xy 7.978441 -76.835653) (xy 7.95528 -76.847954) (xy 7.943032 -76.854714) (xy 7.922532 -76.873736)
			(xy 7.90795 -76.897599) (xy 7.900376 -76.924519) (xy 7.900377 -76.952485) (xy 7.907952 -76.979405)
			(xy 7.922535 -77.003268) (xy 7.943036 -77.022288) (xy 7.95528 -77.029056) (xy 7.978451 -77.041346)
			(xy 8.021486 -77.07133) (xy 8.060006 -77.106928) (xy 8.093284 -77.14747) (xy 8.120691 -77.19219)
			(xy 8.14171 -77.240245) (xy 8.154785 -77.286612) (xy 9.534398 -77.286612) (xy 9.534894 -77.257996)
			(xy 9.543435 -77.201406) (xy 9.560341 -77.146729) (xy 9.585234 -77.095195) (xy 9.617552 -77.047962)
			(xy 9.656569 -77.006092) (xy 9.67867 -76.987908) (xy 9.690366 -76.978038) (xy 9.707665 -76.952806)
			(xy 9.716718 -76.923583) (xy 9.716714 -76.892991) (xy 9.707653 -76.863771) (xy 9.690348 -76.838543)
			(xy 9.67867 -76.82865) (xy 9.656589 -76.810445) (xy 9.617585 -76.768571) (xy 9.585275 -76.721339)
			(xy 9.560384 -76.66981) (xy 9.54347 -76.615141) (xy 9.534914 -76.558559) (xy 9.534398 -76.529946)
			(xy 9.534884 -76.502695) (xy 9.54264 -76.448747) (xy 9.557995 -76.396452) (xy 9.580637 -76.346875)
			(xy 9.610103 -76.301025) (xy 9.645794 -76.259834) (xy 9.686985 -76.224143) (xy 9.732835 -76.194677)
			(xy 9.782412 -76.172035) (xy 9.834707 -76.15668) (xy 9.888655 -76.148924) (xy 9.943157 -76.148924)
			(xy 9.997105 -76.15668) (xy 10.0494 -76.172035) (xy 10.098977 -76.194677) (xy 10.144827 -76.224143)
			(xy 10.186018 -76.259834) (xy 10.221709 -76.301025) (xy 10.251175 -76.346875) (xy 10.273817 -76.396452)
			(xy 10.289172 -76.448747) (xy 10.296928 -76.502695) (xy 10.297414 -76.529946) (xy 10.296883 -76.55856)
			(xy 10.288349 -76.615149) (xy 10.271449 -76.669825) (xy 10.246563 -76.721359) (xy 10.214251 -76.768593)
			(xy 10.17524 -76.810464) (xy 10.153142 -76.82865) (xy 10.141588 -76.838638) (xy 10.124398 -76.863859)
			(xy 10.115402 -76.893026) (xy 10.115398 -76.923548) (xy 10.124386 -76.952717) (xy 10.14157 -76.977943)
			(xy 10.153142 -76.987908) (xy 10.175205 -77.006133) (xy 10.21421 -77.048004) (xy 10.246522 -77.095231)
			(xy 10.271416 -77.146756) (xy 10.288334 -77.201421) (xy 10.296895 -77.258) (xy 10.297414 -77.286612)
			(xy 10.296928 -77.313863) (xy 10.289172 -77.367811) (xy 10.273817 -77.420106) (xy 10.251175 -77.469683)
			(xy 10.221709 -77.515533) (xy 10.186018 -77.556724) (xy 10.144827 -77.592415) (xy 10.098977 -77.621881)
			(xy 10.0494 -77.644523) (xy 9.997105 -77.659878) (xy 9.943157 -77.667634) (xy 9.888655 -77.667634)
			(xy 9.834707 -77.659878) (xy 9.782412 -77.644523) (xy 9.732835 -77.621881) (xy 9.686985 -77.592415)
			(xy 9.645794 -77.556724) (xy 9.610103 -77.515533) (xy 9.580637 -77.469683) (xy 9.557995 -77.420106)
			(xy 9.54264 -77.367811) (xy 9.534884 -77.313863) (xy 9.534398 -77.286612) (xy 8.154785 -77.286612)
			(xy 8.155945 -77.290726) (xy 8.163127 -77.342683) (xy 8.16356 -77.368908) (xy 8.163074 -77.396159)
			(xy 8.155318 -77.450107) (xy 8.139963 -77.502402) (xy 8.117321 -77.551979) (xy 8.087855 -77.597829)
			(xy 8.052164 -77.63902) (xy 8.010973 -77.674711) (xy 7.965123 -77.704177) (xy 7.915546 -77.726819)
			(xy 7.863251 -77.742174) (xy 7.809303 -77.74993) (xy 7.754801 -77.74993) (xy 7.700853 -77.742174)
			(xy 7.648558 -77.726819) (xy 7.598981 -77.704177) (xy 7.553131 -77.674711) (xy 7.51194 -77.63902)
			(xy 7.476249 -77.597829) (xy 7.446783 -77.551979) (xy 7.424141 -77.502402) (xy 7.408786 -77.450107)
			(xy 7.40103 -77.396159) (xy 7.400544 -77.368908) (xy 6.029605 -77.368908) (xy 6.029706 -77.375004)
			(xy 6.02922 -77.402255) (xy 6.021464 -77.456203) (xy 6.006109 -77.508498) (xy 5.983467 -77.558075)
			(xy 5.954001 -77.603925) (xy 5.91831 -77.645116) (xy 5.877119 -77.680807) (xy 5.831269 -77.710273)
			(xy 5.781692 -77.732915) (xy 5.729397 -77.74827) (xy 5.675449 -77.756026) (xy 5.620947 -77.756026)
			(xy 5.566999 -77.74827) (xy 5.514704 -77.732915) (xy 5.465127 -77.710273) (xy 5.419277 -77.680807)
			(xy 5.378086 -77.645116) (xy 5.342395 -77.603925) (xy 5.312929 -77.558075) (xy 5.290287 -77.508498)
			(xy 5.274932 -77.456203) (xy 5.267176 -77.402255) (xy 5.26669 -77.375004) (xy 3.887216 -77.375004)
			(xy 3.887216 -78.090522) (xy 6.13664 -80.339946)
		)
		(stroke
			(width 0)
			(type solid)
		)
		(fill yes)
		(layer "In9.Cu")
		(net "GND")
	)
	(gr_poly
		(pts
			(xy 48.026574 -44.62653) (xy 48.024933 -44.639883) (xy 48.027928 -44.666611) (xy 48.037811 -44.691623)
			(xy 48.053895 -44.713178) (xy 48.075059 -44.729774) (xy 48.099828 -44.740254) (xy 48.126476 -44.743889)
			(xy 48.153146 -44.740424) (xy 48.165766 -44.73575) (xy 48.229012 -44.709588) (xy 48.256167 -44.699171)
			(xy 48.313219 -44.687907) (xy 48.342296 -44.687236) (xy 48.80991 -44.687236) (xy 48.80991 -43.43781)
			(xy 48.71085 -43.33875) (xy 48.695222 -43.322573) (xy 48.668563 -43.286346) (xy 48.657764 -43.266614)
			(xy 48.633369 -43.279252) (xy 48.581428 -43.297148) (xy 48.527245 -43.306218) (xy 48.499776 -43.306746)
			(xy 48.473789 -43.306235) (xy 48.422455 -43.298101) (xy 48.373025 -43.282039) (xy 48.326716 -43.258442)
			(xy 48.284668 -43.227893) (xy 48.247916 -43.191142) (xy 48.217365 -43.149095) (xy 48.193767 -43.102788)
			(xy 48.177702 -43.053358) (xy 48.169566 -43.002025) (xy 48.169068 -42.976038) (xy 48.169666 -42.947485)
			(xy 48.179464 -42.891227) (xy 48.198776 -42.837486) (xy 48.227028 -42.787859) (xy 48.24476 -42.765472)
			(xy 48.27397 -42.729912) (xy 47.945802 -42.401744) (xy 47.910242 -42.430954) (xy 47.887844 -42.448671)
			(xy 47.838222 -42.47693) (xy 47.784485 -42.496248) (xy 47.728228 -42.506051) (xy 47.699676 -42.506646)
			(xy 47.673689 -42.506135) (xy 47.622355 -42.498001) (xy 47.572925 -42.481939) (xy 47.526616 -42.458342)
			(xy 47.484568 -42.427793) (xy 47.447816 -42.391042) (xy 47.417265 -42.348995) (xy 47.393667 -42.302688)
			(xy 47.377602 -42.253258) (xy 47.369466 -42.201925) (xy 47.368968 -42.175938) (xy 47.36945 -42.150005)
			(xy 47.37751 -42.09877) (xy 47.393486 -42.049427) (xy 47.404782 -42.026078) (xy 47.394112 -42.018489)
			(xy 47.374017 -42.001699) (xy 47.36465 -41.99255) (xy 47.08525 -41.71315) (xy 47.075637 -41.703277)
			(xy 47.058083 -41.682033) (xy 47.050198 -41.670732) (xy 47.026775 -41.682087) (xy 46.977268 -41.698162)
			(xy 46.925856 -41.706293) (xy 46.89983 -41.7068) (xy 46.873839 -41.706319) (xy 46.822498 -41.698192)
			(xy 46.77306 -41.682132) (xy 46.726743 -41.658536) (xy 46.684688 -41.627984) (xy 46.647931 -41.591229)
			(xy 46.617376 -41.549176) (xy 46.593777 -41.502861) (xy 46.577714 -41.453424) (xy 46.569583 -41.402083)
			(xy 46.569122 -41.376092) (xy 46.569316 -41.359468) (xy 46.572628 -41.326386) (xy 46.575726 -41.310052)
			(xy 46.57718 -41.300907) (xy 46.574201 -41.282646) (xy 46.564936 -41.266631) (xy 46.550592 -41.254944)
			(xy 46.541944 -41.251632) (xy 46.52902 -41.247249) (xy 46.503961 -41.236438) (xy 46.491906 -41.230042)
			(xy 46.482968 -41.225686) (xy 46.463227 -41.223477) (xy 46.444127 -41.228932) (xy 46.428531 -41.241234)
			(xy 46.418777 -41.258539) (xy 46.416328 -41.278252) (xy 46.4185 -41.287954) (xy 46.424093 -41.309557)
			(xy 46.430078 -41.353779) (xy 46.430438 -41.376092) (xy 46.429955 -41.402084) (xy 46.421824 -41.453429)
			(xy 46.405761 -41.502869) (xy 46.382161 -41.549188) (xy 46.351606 -41.591245) (xy 46.314847 -41.628004)
			(xy 46.272791 -41.658559) (xy 46.226472 -41.68216) (xy 46.177032 -41.698223) (xy 46.125688 -41.706355)
			(xy 46.073703 -41.706354) (xy 46.022359 -41.698221) (xy 45.972919 -41.682156) (xy 45.926601 -41.658554)
			(xy 45.884546 -41.627998) (xy 45.847788 -41.591238) (xy 45.817234 -41.54918) (xy 45.793635 -41.502861)
			(xy 45.777574 -41.45342) (xy 45.769444 -41.402075) (xy 45.769447 -41.35009) (xy 45.777582 -41.298746)
			(xy 45.793649 -41.249307) (xy 45.817252 -41.20299) (xy 45.847811 -41.160936) (xy 45.884572 -41.12418)
			(xy 45.926631 -41.093627) (xy 45.972951 -41.070031) (xy 46.022393 -41.053971) (xy 46.073738 -41.045843)
			(xy 46.09973 -41.045384) (xy 46.119482 -41.04567) (xy 46.158705 -41.050379) (xy 46.177962 -41.054782)
			(xy 46.187879 -41.056711) (xy 46.207809 -41.053492) (xy 46.224966 -41.042852) (xy 46.236707 -41.02643)
			(xy 46.241226 -41.006754) (xy 46.237827 -40.986855) (xy 46.232826 -40.978074) (xy 46.226 -40.967178)
			(xy 46.214047 -40.944412) (xy 46.20895 -40.932608) (xy 46.20395 -40.922406) (xy 46.186949 -40.907379)
			(xy 46.16513 -40.901152) (xy 46.153832 -40.902382) (xy 46.140402 -40.904437) (xy 46.113316 -40.906597)
			(xy 46.09973 -40.9067) (xy 46.073739 -40.906219) (xy 46.022398 -40.898092) (xy 45.97296 -40.882032)
			(xy 45.926643 -40.858436) (xy 45.884588 -40.827884) (xy 45.847831 -40.791129) (xy 45.817276 -40.749076)
			(xy 45.793677 -40.702761) (xy 45.777614 -40.653324) (xy 45.769483 -40.601983) (xy 45.769022 -40.575992)
			(xy 45.769463 -40.552361) (xy 45.776217 -40.505585) (xy 45.789545 -40.460241) (xy 45.798994 -40.438578)
			(xy 45.782762 -40.428732) (xy 45.752698 -40.405547) (xy 45.73905 -40.39235) (xy 45.48505 -40.13835)
			(xy 45.471493 -40.124337) (xy 45.447793 -40.093375) (xy 45.437806 -40.076628) (xy 45.416079 -40.08617)
			(xy 45.370573 -40.099625) (xy 45.32361 -40.106429) (xy 45.299884 -40.106854) (xy 45.273896 -40.106343)
			(xy 45.222561 -40.098211) (xy 45.17313 -40.082149) (xy 45.126819 -40.058553) (xy 45.084769 -40.028004)
			(xy 45.048016 -39.991254) (xy 45.017462 -39.949207) (xy 44.993862 -39.902898) (xy 44.977796 -39.853468)
			(xy 44.969659 -39.802134) (xy 44.969176 -39.776146) (xy 44.969781 -39.747596) (xy 44.979594 -39.691345)
			(xy 44.998917 -39.637614) (xy 45.027179 -39.587999) (xy 45.044868 -39.56558) (xy 45.074332 -39.53002)
			(xy 44.74337 -39.199312) (xy 44.709588 -39.219378) (xy 44.683889 -39.233799) (xy 44.628646 -39.254296)
			(xy 44.570648 -39.264699) (xy 44.541186 -39.265352) (xy 44.517882 -39.264952) (xy 44.471738 -39.258403)
			(xy 44.426971 -39.245437) (xy 44.384468 -39.226312) (xy 44.345074 -39.201405) (xy 44.327064 -39.186612)
			(xy 44.315016 -39.177087) (xy 44.286765 -39.165075) (xy 44.256222 -39.161983) (xy 44.226136 -39.168087)
			(xy 44.199214 -39.18284) (xy 44.188126 -39.19347) (xy 44.170091 -39.211489) (xy 44.130068 -39.243069)
			(xy 44.086194 -39.269034) (xy 44.039252 -39.288923) (xy 43.990079 -39.302381) (xy 43.939551 -39.309168)
			(xy 43.91406 -39.309548) (xy 43.88681 -39.30906) (xy 43.832864 -39.301299) (xy 43.780572 -39.28594)
			(xy 43.730997 -39.263298) (xy 43.685149 -39.233831) (xy 43.64396 -39.19814) (xy 43.608269 -39.156951)
			(xy 43.578802 -39.111103) (xy 43.55616 -39.061528) (xy 43.540801 -39.009236) (xy 43.53304 -38.95529)
			(xy 43.532552 -38.92804) (xy 43.533007 -38.900906) (xy 43.540656 -38.847181) (xy 43.555848 -38.795083)
			(xy 43.578276 -38.745667) (xy 43.592496 -38.722554) (xy 43.599446 -38.710853) (xy 43.607499 -38.684868)
			(xy 43.608406 -38.657679) (xy 43.602102 -38.631215) (xy 43.589034 -38.607354) (xy 43.57013 -38.587791)
			(xy 43.546732 -38.573912) (xy 43.5205 -38.566704) (xy 43.506898 -38.566344) (xy 41.47058 -38.566344)
			(xy 41.396666 -38.49243) (xy 41.378629 -38.510444) (xy 41.338602 -38.542012) (xy 41.294727 -38.567967)
			(xy 41.247785 -38.587845) (xy 41.198613 -38.601293) (xy 41.148089 -38.608071) (xy 41.1226 -38.608508)
			(xy 41.095349 -38.608022) (xy 41.041401 -38.600266) (xy 40.989106 -38.584911) (xy 40.939529 -38.562269)
			(xy 40.893679 -38.532803) (xy 40.852488 -38.497112) (xy 40.816797 -38.455921) (xy 40.787331 -38.410071)
			(xy 40.764689 -38.360494) (xy 40.749334 -38.308199) (xy 40.741578 -38.254251) (xy 40.741092 -38.227)
			(xy 40.741516 -38.201511) (xy 40.748303 -38.150988) (xy 40.761757 -38.101817) (xy 40.781637 -38.054876)
			(xy 40.80759 -38.010999) (xy 40.839153 -37.970969) (xy 40.85717 -37.952934) (xy 38.9382 -36.033964)
			(xy 38.13302 -36.033964) (xy 37.880036 -36.286948) (xy 37.880036 -37.174424) (xy 37.905824 -37.188763)
			(xy 37.953031 -37.224157) (xy 37.99423 -37.266394) (xy 38.028438 -37.314467) (xy 38.054841 -37.367232)
			(xy 38.072809 -37.423432) (xy 38.081915 -37.481727) (xy 38.082474 -37.511228) (xy 38.08247 -37.511482)
			(xy 38.367206 -37.511482) (xy 38.371277 -37.45586) (xy 38.383403 -37.401423) (xy 38.403326 -37.349332)
			(xy 38.430622 -37.300697) (xy 38.464708 -37.256554) (xy 38.504857 -37.217845) (xy 38.550215 -37.185394)
			(xy 38.599815 -37.159893) (xy 38.652599 -37.141886) (xy 38.707442 -37.131756) (xy 38.763176 -37.129719)
			(xy 38.818613 -37.135819) (xy 38.87257 -37.149925) (xy 38.923899 -37.171737) (xy 38.971505 -37.200791)
			(xy 39.014373 -37.236466) (xy 39.05159 -37.278003) (xy 39.082363 -37.324516) (xy 39.106035 -37.375013)
			(xy 39.122103 -37.42842) (xy 39.130223 -37.483596) (xy 39.130732 -37.511482) (xy 39.130223 -37.539368)
			(xy 39.122103 -37.594544) (xy 39.106035 -37.647951) (xy 39.082363 -37.698448) (xy 39.05159 -37.744961)
			(xy 39.014373 -37.786498) (xy 38.971505 -37.822173) (xy 38.923899 -37.851227) (xy 38.87257 -37.873039)
			(xy 38.818613 -37.887145) (xy 38.763176 -37.893245) (xy 38.707442 -37.891208) (xy 38.652599 -37.881078)
			(xy 38.599815 -37.863071) (xy 38.550215 -37.83757) (xy 38.504857 -37.805119) (xy 38.464708 -37.76641)
			(xy 38.430622 -37.722267) (xy 38.403326 -37.673632) (xy 38.383403 -37.621541) (xy 38.371277 -37.567104)
			(xy 38.367206 -37.511482) (xy 38.08247 -37.511482) (xy 38.082036 -37.537461) (xy 38.074844 -37.589432)
			(xy 38.0606 -37.639927) (xy 38.039571 -37.687994) (xy 38.012156 -37.732727) (xy 37.99586 -37.75329)
			(xy 37.96665 -37.78885) (xy 39.494714 -39.316914) (xy 39.529512 -39.293038) (xy 39.553528 -39.277099)
			(xy 39.605347 -39.251862) (xy 39.660374 -39.23471) (xy 39.717355 -39.226034) (xy 39.746174 -39.225474)
			(xy 39.773429 -39.225935) (xy 39.827383 -39.233689) (xy 39.879685 -39.249043) (xy 39.92927 -39.271683)
			(xy 39.975128 -39.30115) (xy 40.016325 -39.336844) (xy 40.052023 -39.378037) (xy 40.081496 -39.423891)
			(xy 40.104142 -39.473473) (xy 40.119502 -39.525774) (xy 40.127262 -39.579727) (xy 40.127682 -39.606982)
			(xy 40.127178 -39.634218) (xy 40.119395 -39.688133) (xy 40.104028 -39.740394) (xy 40.081389 -39.78994)
			(xy 40.051938 -39.835766) (xy 40.034464 -39.856664) (xy 40.144954 -39.967154) (xy 40.155934 -39.97738)
			(xy 40.182384 -39.991515) (xy 40.211799 -39.997363) (xy 40.241644 -39.994419) (xy 40.269349 -39.982938)
			(xy 40.292528 -39.963908) (xy 40.309185 -39.938968) (xy 40.317883 -39.910267) (xy 40.318436 -39.895272)
			(xy 40.318436 -39.763446) (xy 40.308276 -39.74973) (xy 40.29059 -39.72492) (xy 40.2625 -39.670856)
			(xy 40.243366 -39.613013) (xy 40.233676 -39.552863) (xy 40.233092 -39.5224) (xy 40.233578 -39.495149)
			(xy 40.241334 -39.441201) (xy 40.256689 -39.388906) (xy 40.279331 -39.339329) (xy 40.308797 -39.293479)
			(xy 40.344488 -39.252288) (xy 40.385679 -39.216597) (xy 40.431529 -39.187131) (xy 40.481106 -39.164489)
			(xy 40.533401 -39.149134) (xy 40.587349 -39.141378) (xy 40.641851 -39.141378) (xy 40.695799 -39.149134)
			(xy 40.748094 -39.164489) (xy 40.797671 -39.187131) (xy 40.843521 -39.216597) (xy 40.884712 -39.252288)
			(xy 40.920403 -39.293479) (xy 40.949869 -39.339329) (xy 40.972511 -39.388906) (xy 40.987866 -39.441201)
			(xy 40.995622 -39.495149) (xy 40.996108 -39.5224) (xy 40.995511 -39.552862) (xy 40.985824 -39.613012)
			(xy 40.966695 -39.670856) (xy 40.938612 -39.724922) (xy 40.920924 -39.74973) (xy 40.910764 -39.763446)
			(xy 40.910764 -39.821358) (xy 40.911291 -39.832363) (xy 40.920466 -39.85237) (xy 40.937157 -39.866718)
			(xy 40.958314 -39.872785) (xy 40.980072 -39.869462) (xy 40.989504 -39.863776) (xy 41.012943 -39.849)
			(xy 41.063183 -39.825639) (xy 41.116273 -39.809787) (xy 41.171097 -39.801777) (xy 41.1988 -39.801292)
			(xy 41.226051 -39.801778) (xy 41.279999 -39.809534) (xy 41.332294 -39.824889) (xy 41.381871 -39.847531)
			(xy 41.389759 -39.8526) (xy 43.229782 -39.8526) (xy 43.233853 -39.796978) (xy 43.245979 -39.742541)
			(xy 43.265902 -39.69045) (xy 43.293198 -39.641815) (xy 43.327284 -39.597672) (xy 43.367433 -39.558963)
			(xy 43.412791 -39.526512) (xy 43.462391 -39.501011) (xy 43.515175 -39.483004) (xy 43.570018 -39.472874)
			(xy 43.625752 -39.470837) (xy 43.681189 -39.476937) (xy 43.735146 -39.491043) (xy 43.786475 -39.512855)
			(xy 43.834081 -39.541909) (xy 43.876949 -39.577584) (xy 43.914166 -39.619121) (xy 43.944939 -39.665634)
			(xy 43.968611 -39.716131) (xy 43.984679 -39.769538) (xy 43.989476 -39.802133) (xy 44.169586 -39.802133)
			(xy 44.169586 -39.750159) (xy 44.177716 -39.698824) (xy 44.193777 -39.649394) (xy 44.217373 -39.603084)
			(xy 44.247923 -39.561036) (xy 44.284674 -39.524285) (xy 44.326722 -39.493735) (xy 44.373032 -39.470139)
			(xy 44.422462 -39.454078) (xy 44.473797 -39.445948) (xy 44.525771 -39.445948) (xy 44.577106 -39.454078)
			(xy 44.626536 -39.470139) (xy 44.672846 -39.493735) (xy 44.714894 -39.524285) (xy 44.751645 -39.561036)
			(xy 44.782195 -39.603084) (xy 44.805791 -39.649394) (xy 44.821852 -39.698824) (xy 44.829982 -39.750159)
			(xy 44.830492 -39.776146) (xy 44.829982 -39.802133) (xy 44.821852 -39.853468) (xy 44.805791 -39.902898)
			(xy 44.782195 -39.949208) (xy 44.751645 -39.991256) (xy 44.714894 -40.028007) (xy 44.672846 -40.058557)
			(xy 44.626536 -40.082153) (xy 44.577106 -40.098214) (xy 44.525771 -40.106344) (xy 44.473797 -40.106344)
			(xy 44.422462 -40.098214) (xy 44.373032 -40.082153) (xy 44.326722 -40.058557) (xy 44.284674 -40.028007)
			(xy 44.247923 -39.991256) (xy 44.217373 -39.949208) (xy 44.193777 -39.902898) (xy 44.177716 -39.853468)
			(xy 44.169586 -39.802133) (xy 43.989476 -39.802133) (xy 43.992799 -39.824714) (xy 43.993308 -39.8526)
			(xy 43.992799 -39.880486) (xy 43.984679 -39.935662) (xy 43.968611 -39.989069) (xy 43.944939 -40.039566)
			(xy 43.914166 -40.086079) (xy 43.876949 -40.127616) (xy 43.834081 -40.163291) (xy 43.786475 -40.192345)
			(xy 43.735146 -40.214157) (xy 43.681189 -40.228263) (xy 43.625752 -40.234363) (xy 43.570018 -40.232326)
			(xy 43.515175 -40.222196) (xy 43.462391 -40.204189) (xy 43.412791 -40.178688) (xy 43.367433 -40.146237)
			(xy 43.327284 -40.107528) (xy 43.293198 -40.063385) (xy 43.265902 -40.01475) (xy 43.245979 -39.962659)
			(xy 43.233853 -39.908222) (xy 43.229782 -39.8526) (xy 41.389759 -39.8526) (xy 41.427721 -39.876997)
			(xy 41.468912 -39.912688) (xy 41.504603 -39.953879) (xy 41.534069 -39.999729) (xy 41.556711 -40.049306)
			(xy 41.572066 -40.101601) (xy 41.579822 -40.155549) (xy 41.580308 -40.1828) (xy 41.579828 -40.209974)
			(xy 41.572117 -40.263772) (xy 41.556852 -40.315931) (xy 41.534341 -40.365397) (xy 41.50504 -40.41117)
			(xy 41.469541 -40.452322) (xy 41.428563 -40.488021) (xy 41.382935 -40.517545) (xy 41.333579 -40.540298)
			(xy 41.281494 -40.555817) (xy 41.25468 -40.560244) (xy 41.244757 -40.56212) (xy 41.227455 -40.572501)
			(xy 41.215515 -40.588767) (xy 41.212338 -40.601979) (xy 44.169586 -40.601979) (xy 44.169586 -40.550005)
			(xy 44.177716 -40.49867) (xy 44.193777 -40.44924) (xy 44.217373 -40.40293) (xy 44.247923 -40.360882)
			(xy 44.284674 -40.324131) (xy 44.326722 -40.293581) (xy 44.373032 -40.269985) (xy 44.422462 -40.253924)
			(xy 44.473797 -40.245794) (xy 44.525771 -40.245794) (xy 44.577106 -40.253924) (xy 44.626536 -40.269985)
			(xy 44.672846 -40.293581) (xy 44.714894 -40.324131) (xy 44.751645 -40.360882) (xy 44.782195 -40.40293)
			(xy 44.805791 -40.44924) (xy 44.821852 -40.49867) (xy 44.829982 -40.550005) (xy 44.830492 -40.575992)
			(xy 44.829982 -40.601979) (xy 44.969686 -40.601979) (xy 44.969686 -40.550005) (xy 44.977816 -40.49867)
			(xy 44.993877 -40.44924) (xy 45.017473 -40.40293) (xy 45.048023 -40.360882) (xy 45.084774 -40.324131)
			(xy 45.126822 -40.293581) (xy 45.173132 -40.269985) (xy 45.222562 -40.253924) (xy 45.273897 -40.245794)
			(xy 45.325871 -40.245794) (xy 45.377206 -40.253924) (xy 45.426636 -40.269985) (xy 45.472946 -40.293581)
			(xy 45.514994 -40.324131) (xy 45.551745 -40.360882) (xy 45.582295 -40.40293) (xy 45.605891 -40.44924)
			(xy 45.621952 -40.49867) (xy 45.630082 -40.550005) (xy 45.630592 -40.575992) (xy 45.630082 -40.601979)
			(xy 45.621952 -40.653314) (xy 45.605891 -40.702744) (xy 45.582295 -40.749054) (xy 45.551745 -40.791102)
			(xy 45.514994 -40.827853) (xy 45.472946 -40.858403) (xy 45.426636 -40.881999) (xy 45.377206 -40.89806)
			(xy 45.325871 -40.90619) (xy 45.273897 -40.90619) (xy 45.222562 -40.89806) (xy 45.173132 -40.881999)
			(xy 45.126822 -40.858403) (xy 45.084774 -40.827853) (xy 45.048023 -40.791102) (xy 45.017473 -40.749054)
			(xy 44.993877 -40.702744) (xy 44.977816 -40.653314) (xy 44.969686 -40.601979) (xy 44.829982 -40.601979)
			(xy 44.821852 -40.653314) (xy 44.805791 -40.702744) (xy 44.782195 -40.749054) (xy 44.751645 -40.791102)
			(xy 44.714894 -40.827853) (xy 44.672846 -40.858403) (xy 44.626536 -40.881999) (xy 44.577106 -40.89806)
			(xy 44.525771 -40.90619) (xy 44.473797 -40.90619) (xy 44.422462 -40.89806) (xy 44.373032 -40.881999)
			(xy 44.326722 -40.858403) (xy 44.284674 -40.827853) (xy 44.247923 -40.791102) (xy 44.217373 -40.749054)
			(xy 44.193777 -40.702744) (xy 44.177716 -40.653314) (xy 44.169586 -40.601979) (xy 41.212338 -40.601979)
			(xy 41.210797 -40.608386) (xy 41.212008 -40.61841) (xy 41.213713 -40.630082) (xy 41.215494 -40.653605)
			(xy 41.215564 -40.6654) (xy 41.215564 -40.923718) (xy 41.69398 -41.402079) (xy 44.969686 -41.402079)
			(xy 44.969686 -41.350105) (xy 44.977816 -41.29877) (xy 44.993877 -41.24934) (xy 45.017473 -41.20303)
			(xy 45.048023 -41.160982) (xy 45.084774 -41.124231) (xy 45.126822 -41.093681) (xy 45.173132 -41.070085)
			(xy 45.222562 -41.054024) (xy 45.273897 -41.045894) (xy 45.325871 -41.045894) (xy 45.377206 -41.054024)
			(xy 45.426636 -41.070085) (xy 45.472946 -41.093681) (xy 45.514994 -41.124231) (xy 45.551745 -41.160982)
			(xy 45.582295 -41.20303) (xy 45.605891 -41.24934) (xy 45.621952 -41.29877) (xy 45.630082 -41.350105)
			(xy 45.630592 -41.376092) (xy 45.630082 -41.402079) (xy 45.621952 -41.453414) (xy 45.605891 -41.502844)
			(xy 45.582295 -41.549154) (xy 45.551745 -41.591202) (xy 45.514994 -41.627953) (xy 45.472946 -41.658503)
			(xy 45.426636 -41.682099) (xy 45.377206 -41.69816) (xy 45.325871 -41.70629) (xy 45.273897 -41.70629)
			(xy 45.222562 -41.69816) (xy 45.173132 -41.682099) (xy 45.126822 -41.658503) (xy 45.084774 -41.627953)
			(xy 45.048023 -41.591202) (xy 45.017473 -41.549154) (xy 44.993877 -41.502844) (xy 44.977816 -41.453414)
			(xy 44.969686 -41.402079) (xy 41.69398 -41.402079) (xy 42.493917 -42.201925) (xy 45.769532 -42.201925)
			(xy 45.769532 -42.149951) (xy 45.777662 -42.098616) (xy 45.793723 -42.049186) (xy 45.817319 -42.002876)
			(xy 45.847869 -41.960828) (xy 45.88462 -41.924077) (xy 45.926668 -41.893527) (xy 45.972978 -41.869931)
			(xy 46.022408 -41.85387) (xy 46.073743 -41.84574) (xy 46.125717 -41.84574) (xy 46.177052 -41.85387)
			(xy 46.226482 -41.869931) (xy 46.272792 -41.893527) (xy 46.31484 -41.924077) (xy 46.351591 -41.960828)
			(xy 46.382141 -42.002876) (xy 46.405737 -42.049186) (xy 46.421798 -42.098616) (xy 46.429928 -42.149951)
			(xy 46.430438 -42.175938) (xy 46.429928 -42.201925) (xy 46.569632 -42.201925) (xy 46.569632 -42.149951)
			(xy 46.577762 -42.098616) (xy 46.593823 -42.049186) (xy 46.617419 -42.002876) (xy 46.647969 -41.960828)
			(xy 46.68472 -41.924077) (xy 46.726768 -41.893527) (xy 46.773078 -41.869931) (xy 46.822508 -41.85387)
			(xy 46.873843 -41.84574) (xy 46.925817 -41.84574) (xy 46.977152 -41.85387) (xy 47.026582 -41.869931)
			(xy 47.072892 -41.893527) (xy 47.11494 -41.924077) (xy 47.151691 -41.960828) (xy 47.182241 -42.002876)
			(xy 47.205837 -42.049186) (xy 47.221898 -42.098616) (xy 47.230028 -42.149951) (xy 47.230538 -42.175938)
			(xy 47.230028 -42.201925) (xy 47.221898 -42.25326) (xy 47.205837 -42.30269) (xy 47.182241 -42.349)
			(xy 47.151691 -42.391048) (xy 47.11494 -42.427799) (xy 47.072892 -42.458349) (xy 47.026582 -42.481945)
			(xy 46.977152 -42.498006) (xy 46.925817 -42.506136) (xy 46.873843 -42.506136) (xy 46.822508 -42.498006)
			(xy 46.773078 -42.481945) (xy 46.726768 -42.458349) (xy 46.68472 -42.427799) (xy 46.647969 -42.391048)
			(xy 46.617419 -42.349) (xy 46.593823 -42.30269) (xy 46.577762 -42.25326) (xy 46.569632 -42.201925)
			(xy 46.429928 -42.201925) (xy 46.421798 -42.25326) (xy 46.405737 -42.30269) (xy 46.382141 -42.349)
			(xy 46.351591 -42.391048) (xy 46.31484 -42.427799) (xy 46.272792 -42.458349) (xy 46.226482 -42.481945)
			(xy 46.177052 -42.498006) (xy 46.125717 -42.506136) (xy 46.073743 -42.506136) (xy 46.022408 -42.498006)
			(xy 45.972978 -42.481945) (xy 45.926668 -42.458349) (xy 45.88462 -42.427799) (xy 45.847869 -42.391048)
			(xy 45.817319 -42.349) (xy 45.793723 -42.30269) (xy 45.777662 -42.25326) (xy 45.769532 -42.201925)
			(xy 42.493917 -42.201925) (xy 43.439588 -43.147488) (xy 43.450257 -43.157485) (xy 43.475929 -43.171455)
			(xy 43.504506 -43.177581) (xy 43.533648 -43.175361) (xy 43.560968 -43.164977) (xy 43.584227 -43.147279)
			(xy 43.60152 -43.123718) (xy 43.606974 -43.11015) (xy 43.616707 -43.084661) (xy 43.642807 -43.036749)
			(xy 43.675909 -42.99338) (xy 43.71524 -42.955569) (xy 43.759879 -42.924199) (xy 43.808781 -42.900006)
			(xy 43.8608 -42.883555) (xy 43.914721 -42.875233) (xy 43.942 -42.874692) (xy 43.969983 -42.875241)
			(xy 44.02526 -42.883996) (xy 44.078487 -42.901291) (xy 44.128354 -42.926699) (xy 44.173631 -42.959595)
			(xy 44.213205 -42.999169) (xy 44.21528 -43.002025) (xy 45.769532 -43.002025) (xy 45.769532 -42.950051)
			(xy 45.777662 -42.898716) (xy 45.793723 -42.849286) (xy 45.817319 -42.802976) (xy 45.847869 -42.760928)
			(xy 45.88462 -42.724177) (xy 45.926668 -42.693627) (xy 45.972978 -42.670031) (xy 46.022408 -42.65397)
			(xy 46.073743 -42.64584) (xy 46.125717 -42.64584) (xy 46.177052 -42.65397) (xy 46.226482 -42.670031)
			(xy 46.272792 -42.693627) (xy 46.31484 -42.724177) (xy 46.351591 -42.760928) (xy 46.382141 -42.802976)
			(xy 46.405737 -42.849286) (xy 46.421798 -42.898716) (xy 46.429928 -42.950051) (xy 46.430438 -42.976038)
			(xy 46.429928 -43.002025) (xy 46.569632 -43.002025) (xy 46.569632 -42.950051) (xy 46.577762 -42.898716)
			(xy 46.593823 -42.849286) (xy 46.617419 -42.802976) (xy 46.647969 -42.760928) (xy 46.68472 -42.724177)
			(xy 46.726768 -42.693627) (xy 46.773078 -42.670031) (xy 46.822508 -42.65397) (xy 46.873843 -42.64584)
			(xy 46.925817 -42.64584) (xy 46.977152 -42.65397) (xy 47.026582 -42.670031) (xy 47.072892 -42.693627)
			(xy 47.11494 -42.724177) (xy 47.151691 -42.760928) (xy 47.182241 -42.802976) (xy 47.205837 -42.849286)
			(xy 47.221898 -42.898716) (xy 47.230028 -42.950051) (xy 47.230538 -42.976038) (xy 47.230028 -43.002025)
			(xy 47.369478 -43.002025) (xy 47.369478 -42.950051) (xy 47.377608 -42.898716) (xy 47.393669 -42.849286)
			(xy 47.417265 -42.802976) (xy 47.447815 -42.760928) (xy 47.484566 -42.724177) (xy 47.526614 -42.693627)
			(xy 47.572924 -42.670031) (xy 47.622354 -42.65397) (xy 47.673689 -42.64584) (xy 47.725663 -42.64584)
			(xy 47.776998 -42.65397) (xy 47.826428 -42.670031) (xy 47.872738 -42.693627) (xy 47.914786 -42.724177)
			(xy 47.951537 -42.760928) (xy 47.982087 -42.802976) (xy 48.005683 -42.849286) (xy 48.021744 -42.898716)
			(xy 48.029874 -42.950051) (xy 48.030384 -42.976038) (xy 48.029874 -43.002025) (xy 48.021744 -43.05336)
			(xy 48.005683 -43.10279) (xy 47.982087 -43.1491) (xy 47.951537 -43.191148) (xy 47.914786 -43.227899)
			(xy 47.872738 -43.258449) (xy 47.826428 -43.282045) (xy 47.776998 -43.298106) (xy 47.725663 -43.306236)
			(xy 47.673689 -43.306236) (xy 47.622354 -43.298106) (xy 47.572924 -43.282045) (xy 47.526614 -43.258449)
			(xy 47.484566 -43.227899) (xy 47.447815 -43.191148) (xy 47.417265 -43.1491) (xy 47.393669 -43.10279)
			(xy 47.377608 -43.05336) (xy 47.369478 -43.002025) (xy 47.230028 -43.002025) (xy 47.221898 -43.05336)
			(xy 47.205837 -43.10279) (xy 47.182241 -43.1491) (xy 47.151691 -43.191148) (xy 47.11494 -43.227899)
			(xy 47.072892 -43.258449) (xy 47.026582 -43.282045) (xy 46.977152 -43.298106) (xy 46.925817 -43.306236)
			(xy 46.873843 -43.306236) (xy 46.822508 -43.298106) (xy 46.773078 -43.282045) (xy 46.726768 -43.258449)
			(xy 46.68472 -43.227899) (xy 46.647969 -43.191148) (xy 46.617419 -43.1491) (xy 46.593823 -43.10279)
			(xy 46.577762 -43.05336) (xy 46.569632 -43.002025) (xy 46.429928 -43.002025) (xy 46.421798 -43.05336)
			(xy 46.405737 -43.10279) (xy 46.382141 -43.1491) (xy 46.351591 -43.191148) (xy 46.31484 -43.227899)
			(xy 46.272792 -43.258449) (xy 46.226482 -43.282045) (xy 46.177052 -43.298106) (xy 46.125717 -43.306236)
			(xy 46.073743 -43.306236) (xy 46.022408 -43.298106) (xy 45.972978 -43.282045) (xy 45.926668 -43.258449)
			(xy 45.88462 -43.227899) (xy 45.847869 -43.191148) (xy 45.817319 -43.1491) (xy 45.793723 -43.10279)
			(xy 45.777662 -43.05336) (xy 45.769532 -43.002025) (xy 44.21528 -43.002025) (xy 44.246101 -43.044446)
			(xy 44.271509 -43.094313) (xy 44.288804 -43.14754) (xy 44.297559 -43.202817) (xy 44.298108 -43.2308)
			(xy 44.297685 -43.256368) (xy 44.290419 -43.306984) (xy 44.28363 -43.331638) (xy 44.280166 -43.344789)
			(xy 44.279569 -43.371969) (xy 44.286174 -43.39834) (xy 44.299514 -43.422029) (xy 44.318638 -43.441351)
			(xy 44.342188 -43.454933) (xy 44.368491 -43.461809) (xy 44.395675 -43.461491) (xy 44.408852 -43.45813)
			(xy 44.431116 -43.452197) (xy 44.476747 -43.445824) (xy 44.499784 -43.44543) (xy 44.525773 -43.445912)
			(xy 44.577111 -43.454041) (xy 44.626546 -43.470103) (xy 44.672858 -43.4937) (xy 44.714909 -43.524253)
			(xy 44.751661 -43.561008) (xy 44.782211 -43.603061) (xy 44.805806 -43.649375) (xy 44.821864 -43.69881)
			(xy 44.82999 -43.750149) (xy 44.830492 -43.776138) (xy 44.829991 -43.802125) (xy 44.969686 -43.802125)
			(xy 44.969686 -43.750151) (xy 44.977816 -43.698816) (xy 44.993877 -43.649386) (xy 45.017473 -43.603076)
			(xy 45.048023 -43.561028) (xy 45.084774 -43.524277) (xy 45.126822 -43.493727) (xy 45.173132 -43.470131)
			(xy 45.222562 -43.45407) (xy 45.273897 -43.44594) (xy 45.325871 -43.44594) (xy 45.377206 -43.45407)
			(xy 45.426636 -43.470131) (xy 45.472946 -43.493727) (xy 45.514994 -43.524277) (xy 45.551745 -43.561028)
			(xy 45.582295 -43.603076) (xy 45.605891 -43.649386) (xy 45.621952 -43.698816) (xy 45.630082 -43.750151)
			(xy 45.630592 -43.776138) (xy 45.630082 -43.802125) (xy 45.769532 -43.802125) (xy 45.769532 -43.750151)
			(xy 45.777662 -43.698816) (xy 45.793723 -43.649386) (xy 45.817319 -43.603076) (xy 45.847869 -43.561028)
			(xy 45.88462 -43.524277) (xy 45.926668 -43.493727) (xy 45.972978 -43.470131) (xy 46.022408 -43.45407)
			(xy 46.073743 -43.44594) (xy 46.125717 -43.44594) (xy 46.177052 -43.45407) (xy 46.226482 -43.470131)
			(xy 46.272792 -43.493727) (xy 46.31484 -43.524277) (xy 46.351591 -43.561028) (xy 46.382141 -43.603076)
			(xy 46.405737 -43.649386) (xy 46.421798 -43.698816) (xy 46.429928 -43.750151) (xy 46.430438 -43.776138)
			(xy 46.429928 -43.802125) (xy 46.569632 -43.802125) (xy 46.569632 -43.750151) (xy 46.577762 -43.698816)
			(xy 46.593823 -43.649386) (xy 46.617419 -43.603076) (xy 46.647969 -43.561028) (xy 46.68472 -43.524277)
			(xy 46.726768 -43.493727) (xy 46.773078 -43.470131) (xy 46.822508 -43.45407) (xy 46.873843 -43.44594)
			(xy 46.925817 -43.44594) (xy 46.977152 -43.45407) (xy 47.026582 -43.470131) (xy 47.072892 -43.493727)
			(xy 47.11494 -43.524277) (xy 47.151691 -43.561028) (xy 47.182241 -43.603076) (xy 47.205837 -43.649386)
			(xy 47.221898 -43.698816) (xy 47.230028 -43.750151) (xy 47.230538 -43.776138) (xy 47.230028 -43.802125)
			(xy 47.369478 -43.802125) (xy 47.369478 -43.750151) (xy 47.377608 -43.698816) (xy 47.393669 -43.649386)
			(xy 47.417265 -43.603076) (xy 47.447815 -43.561028) (xy 47.484566 -43.524277) (xy 47.526614 -43.493727)
			(xy 47.572924 -43.470131) (xy 47.622354 -43.45407) (xy 47.673689 -43.44594) (xy 47.725663 -43.44594)
			(xy 47.776998 -43.45407) (xy 47.826428 -43.470131) (xy 47.872738 -43.493727) (xy 47.914786 -43.524277)
			(xy 47.951537 -43.561028) (xy 47.982087 -43.603076) (xy 48.005683 -43.649386) (xy 48.021744 -43.698816)
			(xy 48.029874 -43.750151) (xy 48.030384 -43.776138) (xy 48.029874 -43.802125) (xy 48.021744 -43.85346)
			(xy 48.005683 -43.90289) (xy 47.982087 -43.9492) (xy 47.951537 -43.991248) (xy 47.914786 -44.027999)
			(xy 47.872738 -44.058549) (xy 47.826428 -44.082145) (xy 47.776998 -44.098206) (xy 47.725663 -44.106336)
			(xy 47.673689 -44.106336) (xy 47.622354 -44.098206) (xy 47.572924 -44.082145) (xy 47.526614 -44.058549)
			(xy 47.484566 -44.027999) (xy 47.447815 -43.991248) (xy 47.417265 -43.9492) (xy 47.393669 -43.90289)
			(xy 47.377608 -43.85346) (xy 47.369478 -43.802125) (xy 47.230028 -43.802125) (xy 47.221898 -43.85346)
			(xy 47.205837 -43.90289) (xy 47.182241 -43.9492) (xy 47.151691 -43.991248) (xy 47.11494 -44.027999)
			(xy 47.072892 -44.058549) (xy 47.026582 -44.082145) (xy 46.977152 -44.098206) (xy 46.925817 -44.106336)
			(xy 46.873843 -44.106336) (xy 46.822508 -44.098206) (xy 46.773078 -44.082145) (xy 46.726768 -44.058549)
			(xy 46.68472 -44.027999) (xy 46.647969 -43.991248) (xy 46.617419 -43.9492) (xy 46.593823 -43.90289)
			(xy 46.577762 -43.85346) (xy 46.569632 -43.802125) (xy 46.429928 -43.802125) (xy 46.421798 -43.85346)
			(xy 46.405737 -43.90289) (xy 46.382141 -43.9492) (xy 46.351591 -43.991248) (xy 46.31484 -44.027999)
			(xy 46.272792 -44.058549) (xy 46.226482 -44.082145) (xy 46.177052 -44.098206) (xy 46.125717 -44.106336)
			(xy 46.073743 -44.106336) (xy 46.022408 -44.098206) (xy 45.972978 -44.082145) (xy 45.926668 -44.058549)
			(xy 45.88462 -44.027999) (xy 45.847869 -43.991248) (xy 45.817319 -43.9492) (xy 45.793723 -43.90289)
			(xy 45.777662 -43.85346) (xy 45.769532 -43.802125) (xy 45.630082 -43.802125) (xy 45.621952 -43.85346)
			(xy 45.605891 -43.90289) (xy 45.582295 -43.9492) (xy 45.551745 -43.991248) (xy 45.514994 -44.027999)
			(xy 45.472946 -44.058549) (xy 45.426636 -44.082145) (xy 45.377206 -44.098206) (xy 45.325871 -44.106336)
			(xy 45.273897 -44.106336) (xy 45.222562 -44.098206) (xy 45.173132 -44.082145) (xy 45.126822 -44.058549)
			(xy 45.084774 -44.027999) (xy 45.048023 -43.991248) (xy 45.017473 -43.9492) (xy 44.993877 -43.90289)
			(xy 44.977816 -43.85346) (xy 44.969686 -43.802125) (xy 44.829991 -43.802125) (xy 44.829983 -43.802519)
			(xy 44.821614 -43.854614) (xy 44.80508 -43.904719) (xy 44.7808 -43.951563) (xy 44.74939 -43.993957)
			(xy 44.711646 -44.030826) (xy 44.668527 -44.061234) (xy 44.621127 -44.08441) (xy 44.59605 -44.092622)
			(xy 44.581858 -44.097465) (xy 44.556919 -44.11409) (xy 44.537883 -44.137241) (xy 44.526391 -44.164922)
			(xy 44.523433 -44.194749) (xy 44.529265 -44.224148) (xy 44.543384 -44.250587) (xy 44.553632 -44.261532)
			(xy 44.814236 -44.52239) (xy 44.825222 -44.532619) (xy 44.851684 -44.546756) (xy 44.881111 -44.552602)
			(xy 44.910968 -44.549653) (xy 44.938682 -44.538163) (xy 44.961867 -44.519122) (xy 44.978526 -44.49417)
			(xy 44.9834 -44.479972) (xy 44.991558 -44.454867) (xy 45.014717 -44.407434) (xy 45.045119 -44.364284)
			(xy 45.081989 -44.326511) (xy 45.124392 -44.295076) (xy 45.171251 -44.270776) (xy 45.221375 -44.25423)
			(xy 45.273492 -44.245857) (xy 45.299884 -44.245276) (xy 45.325872 -44.245784) (xy 45.37721 -44.253913)
			(xy 45.426644 -44.269972) (xy 45.472956 -44.293567) (xy 45.515008 -44.324116) (xy 45.551763 -44.360868)
			(xy 45.582316 -44.402916) (xy 45.605916 -44.449227) (xy 45.62198 -44.498659) (xy 45.630113 -44.549996)
			(xy 45.630592 -44.575984) (xy 45.630482 -44.58912) (xy 45.628449 -44.615313) (xy 45.626528 -44.628308)
			(xy 45.625766 -44.632372) (xy 45.625766 -44.687236) (xy 45.773848 -44.687236) (xy 45.773848 -44.632372)
			(xy 45.773086 -44.628308) (xy 45.77115 -44.615314) (xy 45.769112 -44.589121) (xy 45.769022 -44.575984)
			(xy 45.769532 -44.549997) (xy 45.777662 -44.498662) (xy 45.793723 -44.449232) (xy 45.817319 -44.402922)
			(xy 45.847869 -44.360874) (xy 45.88462 -44.324123) (xy 45.926668 -44.293573) (xy 45.972978 -44.269977)
			(xy 46.022408 -44.253916) (xy 46.073743 -44.245786) (xy 46.125717 -44.245786) (xy 46.177052 -44.253916)
			(xy 46.226482 -44.269977) (xy 46.272792 -44.293573) (xy 46.31484 -44.324123) (xy 46.351591 -44.360874)
			(xy 46.382141 -44.402922) (xy 46.405737 -44.449232) (xy 46.421798 -44.498662) (xy 46.429928 -44.549997)
			(xy 46.430438 -44.575984) (xy 46.430328 -44.58912) (xy 46.428295 -44.615313) (xy 46.426374 -44.628308)
			(xy 46.425612 -44.632372) (xy 46.425612 -44.687236) (xy 46.573948 -44.687236) (xy 46.573948 -44.632372)
			(xy 46.573186 -44.628308) (xy 46.57125 -44.615314) (xy 46.569212 -44.589121) (xy 46.569122 -44.575984)
			(xy 46.569606 -44.549996) (xy 46.57774 -44.498662) (xy 46.593804 -44.449231) (xy 46.617403 -44.402922)
			(xy 46.647956 -44.360875) (xy 46.68471 -44.324126) (xy 46.726762 -44.293579) (xy 46.773074 -44.269986)
			(xy 46.822506 -44.253929) (xy 46.873842 -44.245803) (xy 46.89983 -44.245276) (xy 46.924318 -44.245721)
			(xy 46.972759 -44.252946) (xy 47.019605 -44.267234) (xy 47.063833 -44.288272) (xy 47.104476 -44.315601)
			(xy 47.140645 -44.348624) (xy 47.171551 -44.386618) (xy 47.196517 -44.428754) (xy 47.206154 -44.45127)
			(xy 47.212038 -44.464312) (xy 47.229818 -44.486715) (xy 47.253108 -44.503314) (xy 47.280086 -44.51281)
			(xy 47.308638 -44.51446) (xy 47.33653 -44.508134) (xy 47.361577 -44.494328) (xy 47.372016 -44.484544)
			(xy 47.385986 -44.470574) (xy 47.389796 -44.460414) (xy 47.399002 -44.437054) (xy 47.42345 -44.393202)
			(xy 47.454247 -44.35355) (xy 47.490686 -44.31901) (xy 47.531928 -44.290377) (xy 47.577025 -44.268308)
			(xy 47.62494 -44.253311) (xy 47.674572 -44.245732) (xy 47.699676 -44.245276) (xy 47.725667 -44.245757)
			(xy 47.777009 -44.253885) (xy 47.826448 -44.269945) (xy 47.872766 -44.293542) (xy 47.914822 -44.324093)
			(xy 47.951581 -44.360848) (xy 47.982137 -44.4029) (xy 48.005739 -44.449215) (xy 48.021805 -44.498652)
			(xy 48.02994 -44.549993) (xy 48.030384 -44.575984) (xy 48.030285 -44.588671) (xy 48.028377 -44.613972)
		)
		(stroke
			(width 0)
			(type solid)
		)
		(fill yes)
		(layer "In9.Cu")
		(net "P3V3_P1V8_SD1VDD")
	)
	(gr_poly
		(pts
			(xy 37.43706 -48.041052) (xy 37.45666 -48.022309) (xy 37.501336 -47.991578) (xy 37.550856 -47.969482)
			(xy 37.603567 -47.956759) (xy 37.630608 -47.954692) (xy 37.651111 -47.938587) (xy 37.695658 -47.9115)
			(xy 37.743478 -47.89073) (xy 37.793681 -47.876665) (xy 37.845332 -47.869567) (xy 37.8714 -47.869094)
			(xy 37.897805 -47.869542) (xy 37.95011 -47.876828) (xy 38.00091 -47.89126) (xy 38.049233 -47.912563)
			(xy 38.094155 -47.940329) (xy 38.134816 -47.974026) (xy 38.17044 -48.013011) (xy 38.200345 -48.056539)
			(xy 38.223959 -48.103775) (xy 38.24083 -48.153818) (xy 38.250636 -48.205709) (xy 38.2524 -48.23206)
			(xy 38.254686 -48.28032) (xy 40.164512 -48.28032) (xy 40.767762 -47.67707) (xy 40.778117 -47.665919)
			(xy 40.792344 -47.639038) (xy 40.798031 -47.609161) (xy 40.794675 -47.578933) (xy 40.782573 -47.551031)
			(xy 40.762796 -47.527926) (xy 40.750236 -47.519336) (xy 40.727288 -47.504274) (xy 40.685567 -47.468604)
			(xy 40.649395 -47.427319) (xy 40.619518 -47.381272) (xy 40.596557 -47.331415) (xy 40.580984 -47.27878)
			(xy 40.573123 -47.224455) (xy 40.57269 -47.19701) (xy 40.573176 -47.169759) (xy 40.580932 -47.115811)
			(xy 40.596287 -47.063516) (xy 40.618929 -47.013939) (xy 40.648395 -46.968089) (xy 40.684086 -46.926898)
			(xy 40.725277 -46.891207) (xy 40.771127 -46.861741) (xy 40.820704 -46.839099) (xy 40.872999 -46.823744)
			(xy 40.926947 -46.815988) (xy 40.981449 -46.815988) (xy 41.035397 -46.823744) (xy 41.087692 -46.839099)
			(xy 41.137269 -46.861741) (xy 41.183119 -46.891207) (xy 41.22431 -46.926898) (xy 41.260001 -46.968089)
			(xy 41.281805 -47.002017) (xy 44.969686 -47.002017) (xy 44.969686 -46.950043) (xy 44.977816 -46.898708)
			(xy 44.993877 -46.849278) (xy 45.017473 -46.802968) (xy 45.048023 -46.76092) (xy 45.084774 -46.724169)
			(xy 45.126822 -46.693619) (xy 45.173132 -46.670023) (xy 45.222562 -46.653962) (xy 45.273897 -46.645832)
			(xy 45.325871 -46.645832) (xy 45.377206 -46.653962) (xy 45.426636 -46.670023) (xy 45.472946 -46.693619)
			(xy 45.514994 -46.724169) (xy 45.551745 -46.76092) (xy 45.582295 -46.802968) (xy 45.605891 -46.849278)
			(xy 45.621952 -46.898708) (xy 45.630082 -46.950043) (xy 45.630592 -46.97603) (xy 45.630082 -47.002017)
			(xy 45.769532 -47.002017) (xy 45.769532 -46.950043) (xy 45.777662 -46.898708) (xy 45.793723 -46.849278)
			(xy 45.817319 -46.802968) (xy 45.847869 -46.76092) (xy 45.88462 -46.724169) (xy 45.926668 -46.693619)
			(xy 45.972978 -46.670023) (xy 46.022408 -46.653962) (xy 46.073743 -46.645832) (xy 46.125717 -46.645832)
			(xy 46.177052 -46.653962) (xy 46.226482 -46.670023) (xy 46.272792 -46.693619) (xy 46.31484 -46.724169)
			(xy 46.351591 -46.76092) (xy 46.382141 -46.802968) (xy 46.405737 -46.849278) (xy 46.421798 -46.898708)
			(xy 46.429928 -46.950043) (xy 46.430438 -46.97603) (xy 46.429928 -47.002017) (xy 46.569632 -47.002017)
			(xy 46.569632 -46.950043) (xy 46.577762 -46.898708) (xy 46.593823 -46.849278) (xy 46.617419 -46.802968)
			(xy 46.647969 -46.76092) (xy 46.68472 -46.724169) (xy 46.726768 -46.693619) (xy 46.773078 -46.670023)
			(xy 46.822508 -46.653962) (xy 46.873843 -46.645832) (xy 46.925817 -46.645832) (xy 46.977152 -46.653962)
			(xy 47.026582 -46.670023) (xy 47.072892 -46.693619) (xy 47.11494 -46.724169) (xy 47.151691 -46.76092)
			(xy 47.182241 -46.802968) (xy 47.205837 -46.849278) (xy 47.221898 -46.898708) (xy 47.230028 -46.950043)
			(xy 47.230538 -46.97603) (xy 47.230028 -47.002017) (xy 47.369478 -47.002017) (xy 47.369478 -46.950043)
			(xy 47.377608 -46.898708) (xy 47.393669 -46.849278) (xy 47.417265 -46.802968) (xy 47.447815 -46.76092)
			(xy 47.484566 -46.724169) (xy 47.526614 -46.693619) (xy 47.572924 -46.670023) (xy 47.622354 -46.653962)
			(xy 47.673689 -46.645832) (xy 47.725663 -46.645832) (xy 47.776998 -46.653962) (xy 47.826428 -46.670023)
			(xy 47.872738 -46.693619) (xy 47.914786 -46.724169) (xy 47.951537 -46.76092) (xy 47.982087 -46.802968)
			(xy 48.005683 -46.849278) (xy 48.021744 -46.898708) (xy 48.029874 -46.950043) (xy 48.030384 -46.97603)
			(xy 48.029874 -47.002017) (xy 48.169578 -47.002017) (xy 48.169578 -46.950043) (xy 48.177708 -46.898708)
			(xy 48.193769 -46.849278) (xy 48.217365 -46.802968) (xy 48.247915 -46.76092) (xy 48.284666 -46.724169)
			(xy 48.326714 -46.693619) (xy 48.373024 -46.670023) (xy 48.422454 -46.653962) (xy 48.473789 -46.645832)
			(xy 48.525763 -46.645832) (xy 48.577098 -46.653962) (xy 48.626528 -46.670023) (xy 48.672838 -46.693619)
			(xy 48.714886 -46.724169) (xy 48.751637 -46.76092) (xy 48.782187 -46.802968) (xy 48.805783 -46.849278)
			(xy 48.821844 -46.898708) (xy 48.829974 -46.950043) (xy 48.830484 -46.97603) (xy 48.829974 -47.002017)
			(xy 49.769524 -47.002017) (xy 49.769524 -46.950043) (xy 49.777654 -46.898708) (xy 49.793715 -46.849278)
			(xy 49.817311 -46.802968) (xy 49.847861 -46.76092) (xy 49.884612 -46.724169) (xy 49.92666 -46.693619)
			(xy 49.97297 -46.670023) (xy 50.0224 -46.653962) (xy 50.073735 -46.645832) (xy 50.125709 -46.645832)
			(xy 50.177044 -46.653962) (xy 50.226474 -46.670023) (xy 50.272784 -46.693619) (xy 50.314832 -46.724169)
			(xy 50.351583 -46.76092) (xy 50.382133 -46.802968) (xy 50.405729 -46.849278) (xy 50.42179 -46.898708)
			(xy 50.42992 -46.950043) (xy 50.43043 -46.97603) (xy 50.42992 -47.002017) (xy 52.96967 -47.002017)
			(xy 52.96967 -46.950043) (xy 52.9778 -46.898708) (xy 52.993861 -46.849278) (xy 53.017457 -46.802968)
			(xy 53.048007 -46.76092) (xy 53.084758 -46.724169) (xy 53.126806 -46.693619) (xy 53.173116 -46.670023)
			(xy 53.222546 -46.653962) (xy 53.273881 -46.645832) (xy 53.325855 -46.645832) (xy 53.37719 -46.653962)
			(xy 53.42662 -46.670023) (xy 53.47293 -46.693619) (xy 53.514978 -46.724169) (xy 53.551729 -46.76092)
			(xy 53.582279 -46.802968) (xy 53.605875 -46.849278) (xy 53.621936 -46.898708) (xy 53.630066 -46.950043)
			(xy 53.630576 -46.97603) (xy 53.630066 -47.002017) (xy 53.621936 -47.053352) (xy 53.605875 -47.102782)
			(xy 53.582279 -47.149092) (xy 53.551729 -47.19114) (xy 53.514978 -47.227891) (xy 53.47293 -47.258441)
			(xy 53.42662 -47.282037) (xy 53.37719 -47.298098) (xy 53.325855 -47.306228) (xy 53.273881 -47.306228)
			(xy 53.222546 -47.298098) (xy 53.173116 -47.282037) (xy 53.126806 -47.258441) (xy 53.084758 -47.227891)
			(xy 53.048007 -47.19114) (xy 53.017457 -47.149092) (xy 52.993861 -47.102782) (xy 52.9778 -47.053352)
			(xy 52.96967 -47.002017) (xy 50.42992 -47.002017) (xy 50.42179 -47.053352) (xy 50.405729 -47.102782)
			(xy 50.382133 -47.149092) (xy 50.351583 -47.19114) (xy 50.314832 -47.227891) (xy 50.272784 -47.258441)
			(xy 50.226474 -47.282037) (xy 50.177044 -47.298098) (xy 50.125709 -47.306228) (xy 50.073735 -47.306228)
			(xy 50.0224 -47.298098) (xy 49.97297 -47.282037) (xy 49.92666 -47.258441) (xy 49.884612 -47.227891)
			(xy 49.847861 -47.19114) (xy 49.817311 -47.149092) (xy 49.793715 -47.102782) (xy 49.777654 -47.053352)
			(xy 49.769524 -47.002017) (xy 48.829974 -47.002017) (xy 48.821844 -47.053352) (xy 48.805783 -47.102782)
			(xy 48.782187 -47.149092) (xy 48.751637 -47.19114) (xy 48.714886 -47.227891) (xy 48.672838 -47.258441)
			(xy 48.626528 -47.282037) (xy 48.577098 -47.298098) (xy 48.525763 -47.306228) (xy 48.473789 -47.306228)
			(xy 48.422454 -47.298098) (xy 48.373024 -47.282037) (xy 48.326714 -47.258441) (xy 48.284666 -47.227891)
			(xy 48.247915 -47.19114) (xy 48.217365 -47.149092) (xy 48.193769 -47.102782) (xy 48.177708 -47.053352)
			(xy 48.169578 -47.002017) (xy 48.029874 -47.002017) (xy 48.021744 -47.053352) (xy 48.005683 -47.102782)
			(xy 47.982087 -47.149092) (xy 47.951537 -47.19114) (xy 47.914786 -47.227891) (xy 47.872738 -47.258441)
			(xy 47.826428 -47.282037) (xy 47.776998 -47.298098) (xy 47.725663 -47.306228) (xy 47.673689 -47.306228)
			(xy 47.622354 -47.298098) (xy 47.572924 -47.282037) (xy 47.526614 -47.258441) (xy 47.484566 -47.227891)
			(xy 47.447815 -47.19114) (xy 47.417265 -47.149092) (xy 47.393669 -47.102782) (xy 47.377608 -47.053352)
			(xy 47.369478 -47.002017) (xy 47.230028 -47.002017) (xy 47.221898 -47.053352) (xy 47.205837 -47.102782)
			(xy 47.182241 -47.149092) (xy 47.151691 -47.19114) (xy 47.11494 -47.227891) (xy 47.072892 -47.258441)
			(xy 47.026582 -47.282037) (xy 46.977152 -47.298098) (xy 46.925817 -47.306228) (xy 46.873843 -47.306228)
			(xy 46.822508 -47.298098) (xy 46.773078 -47.282037) (xy 46.726768 -47.258441) (xy 46.68472 -47.227891)
			(xy 46.647969 -47.19114) (xy 46.617419 -47.149092) (xy 46.593823 -47.102782) (xy 46.577762 -47.053352)
			(xy 46.569632 -47.002017) (xy 46.429928 -47.002017) (xy 46.421798 -47.053352) (xy 46.405737 -47.102782)
			(xy 46.382141 -47.149092) (xy 46.351591 -47.19114) (xy 46.31484 -47.227891) (xy 46.272792 -47.258441)
			(xy 46.226482 -47.282037) (xy 46.177052 -47.298098) (xy 46.125717 -47.306228) (xy 46.073743 -47.306228)
			(xy 46.022408 -47.298098) (xy 45.972978 -47.282037) (xy 45.926668 -47.258441) (xy 45.88462 -47.227891)
			(xy 45.847869 -47.19114) (xy 45.817319 -47.149092) (xy 45.793723 -47.102782) (xy 45.777662 -47.053352)
			(xy 45.769532 -47.002017) (xy 45.630082 -47.002017) (xy 45.621952 -47.053352) (xy 45.605891 -47.102782)
			(xy 45.582295 -47.149092) (xy 45.551745 -47.19114) (xy 45.514994 -47.227891) (xy 45.472946 -47.258441)
			(xy 45.426636 -47.282037) (xy 45.377206 -47.298098) (xy 45.325871 -47.306228) (xy 45.273897 -47.306228)
			(xy 45.222562 -47.298098) (xy 45.173132 -47.282037) (xy 45.126822 -47.258441) (xy 45.084774 -47.227891)
			(xy 45.048023 -47.19114) (xy 45.017473 -47.149092) (xy 44.993877 -47.102782) (xy 44.977816 -47.053352)
			(xy 44.969686 -47.002017) (xy 41.281805 -47.002017) (xy 41.289467 -47.013939) (xy 41.312109 -47.063516)
			(xy 41.327464 -47.115811) (xy 41.33522 -47.169759) (xy 41.335706 -47.19701) (xy 41.335232 -47.224078)
			(xy 41.327575 -47.277671) (xy 41.312418 -47.329642) (xy 41.30167 -47.35449) (xy 41.296153 -47.367912)
			(xy 41.292099 -47.396633) (xy 41.296285 -47.425335) (xy 41.308373 -47.451702) (xy 41.327387 -47.473606)
			(xy 41.351794 -47.489279) (xy 41.379624 -47.497455) (xy 41.394126 -47.498) (xy 45.121068 -47.498)
			(xy 45.144071 -47.483837) (xy 45.193645 -47.462383) (xy 45.246048 -47.449278) (xy 45.299884 -47.444871)
			(xy 45.35372 -47.449278) (xy 45.406123 -47.462383) (xy 45.455697 -47.483837) (xy 45.4787 -47.498)
			(xy 45.920914 -47.498) (xy 45.943917 -47.483837) (xy 45.993491 -47.462383) (xy 46.045894 -47.449278)
			(xy 46.09973 -47.444871) (xy 46.153566 -47.449278) (xy 46.205969 -47.462383) (xy 46.255543 -47.483837)
			(xy 46.278546 -47.498) (xy 46.721014 -47.498) (xy 46.744017 -47.483837) (xy 46.793591 -47.462383)
			(xy 46.845994 -47.449278) (xy 46.89983 -47.444871) (xy 46.953666 -47.449278) (xy 47.006069 -47.462383)
			(xy 47.055643 -47.483837) (xy 47.078646 -47.498) (xy 48.32096 -47.498) (xy 48.343963 -47.483837)
			(xy 48.393537 -47.462383) (xy 48.44594 -47.449278) (xy 48.499776 -47.444871) (xy 48.553612 -47.449278)
			(xy 48.606015 -47.462383) (xy 48.655589 -47.483837) (xy 48.678592 -47.498) (xy 53.6956 -47.498) (xy 53.853334 -47.340266)
			(xy 53.863904 -47.328855) (xy 53.878194 -47.301244) (xy 53.883525 -47.270615) (xy 53.879405 -47.239799)
			(xy 53.866214 -47.211647) (xy 53.856128 -47.199804) (xy 53.839835 -47.181386) (xy 53.812313 -47.140637)
			(xy 53.791122 -47.096265) (xy 53.776729 -47.049247) (xy 53.76945 -47.000616) (xy 53.769006 -46.97603)
			(xy 53.769505 -46.949812) (xy 53.777775 -46.898033) (xy 53.794113 -46.848207) (xy 53.818109 -46.801584)
			(xy 53.849161 -46.759332) (xy 53.886493 -46.72251) (xy 53.929167 -46.69204) (xy 53.952394 -46.679866)
			(xy 53.95976 -46.67631) (xy 54.01564 -46.619922) (xy 54.01564 -46.497748) (xy 53.982874 -46.485302)
			(xy 53.959631 -46.476034) (xy 53.916017 -46.451509) (xy 53.876595 -46.420694) (xy 53.842265 -46.384292)
			(xy 53.813811 -46.343134) (xy 53.791881 -46.298159) (xy 53.776976 -46.250394) (xy 53.769437 -46.200929)
			(xy 53.769436 -46.150892) (xy 53.776972 -46.101427) (xy 53.791873 -46.05366) (xy 53.8138 -46.008684)
			(xy 53.842252 -45.967524) (xy 53.87658 -45.93112) (xy 53.915999 -45.900302) (xy 53.959612 -45.875775)
			(xy 53.982874 -45.866558) (xy 54.01564 -45.854112) (xy 54.01564 -44.96943) (xy 53.580792 -44.534582)
			(xy 53.580792 -44.530772) (xy 53.250338 -44.200572) (xy 52.288186 -44.200572) (xy 52.15382 -44.334938)
			(xy 52.15382 -44.910502) (xy 51.894232 -45.17009) (xy 50.51933 -45.17009) (xy 50.503899 -45.170593)
			(xy 50.474424 -45.179733) (xy 50.449019 -45.197252) (xy 50.429999 -45.221553) (xy 50.419095 -45.250422)
			(xy 50.417301 -45.281229) (xy 50.420524 -45.296328) (xy 50.425122 -45.315947) (xy 50.430086 -45.355936)
			(xy 50.43043 -45.376084) (xy 50.42992 -45.402071) (xy 52.16957 -45.402071) (xy 52.16957 -45.350097)
			(xy 52.1777 -45.298762) (xy 52.193761 -45.249332) (xy 52.217357 -45.203022) (xy 52.247907 -45.160974)
			(xy 52.284658 -45.124223) (xy 52.326706 -45.093673) (xy 52.373016 -45.070077) (xy 52.422446 -45.054016)
			(xy 52.473781 -45.045886) (xy 52.525755 -45.045886) (xy 52.57709 -45.054016) (xy 52.62652 -45.070077)
			(xy 52.67283 -45.093673) (xy 52.714878 -45.124223) (xy 52.751629 -45.160974) (xy 52.782179 -45.203022)
			(xy 52.805775 -45.249332) (xy 52.821836 -45.298762) (xy 52.829966 -45.350097) (xy 52.830476 -45.376084)
			(xy 52.829966 -45.402071) (xy 52.821836 -45.453406) (xy 52.805775 -45.502836) (xy 52.782179 -45.549146)
			(xy 52.751629 -45.591194) (xy 52.714878 -45.627945) (xy 52.67283 -45.658495) (xy 52.62652 -45.682091)
			(xy 52.57709 -45.698152) (xy 52.525755 -45.706282) (xy 52.473781 -45.706282) (xy 52.422446 -45.698152)
			(xy 52.373016 -45.682091) (xy 52.326706 -45.658495) (xy 52.284658 -45.627945) (xy 52.247907 -45.591194)
			(xy 52.217357 -45.549146) (xy 52.193761 -45.502836) (xy 52.1777 -45.453406) (xy 52.16957 -45.402071)
			(xy 50.42992 -45.402071) (xy 50.42179 -45.453406) (xy 50.405729 -45.502836) (xy 50.382133 -45.549146)
			(xy 50.351583 -45.591194) (xy 50.314832 -45.627945) (xy 50.272784 -45.658495) (xy 50.226474 -45.682091)
			(xy 50.177044 -45.698152) (xy 50.125709 -45.706282) (xy 50.073735 -45.706282) (xy 50.0224 -45.698152)
			(xy 49.97297 -45.682091) (xy 49.92666 -45.658495) (xy 49.884612 -45.627945) (xy 49.847861 -45.591194)
			(xy 49.817311 -45.549146) (xy 49.793715 -45.502836) (xy 49.777654 -45.453406) (xy 49.769524 -45.402071)
			(xy 49.769014 -45.376084) (xy 49.769343 -45.355935) (xy 49.774308 -45.315944) (xy 49.77892 -45.296328)
			(xy 49.782138 -45.281227) (xy 49.780343 -45.250417) (xy 49.769441 -45.221545) (xy 49.750422 -45.197239)
			(xy 49.72502 -45.179712) (xy 49.695546 -45.170561) (xy 49.680114 -45.17009) (xy 49.33061 -45.17009)
			(xy 49.30775 -45.19295) (xy 49.29097 -45.209094) (xy 49.253279 -45.236433) (xy 49.211774 -45.257537)
			(xy 49.167478 -45.271886) (xy 49.121482 -45.279126) (xy 49.0982 -45.279564) (xy 48.932084 -45.279564)
			(xy 48.918849 -45.279989) (xy 48.893271 -45.286799) (xy 48.870303 -45.299957) (xy 48.851491 -45.318578)
			(xy 48.8381 -45.34141) (xy 48.83103 -45.366918) (xy 48.830484 -45.380148) (xy 48.829675 -45.405926)
			(xy 48.821046 -45.456772) (xy 48.804629 -45.505662) (xy 48.780821 -45.551411) (xy 48.750201 -45.592909)
			(xy 48.71351 -45.629151) (xy 48.671637 -45.659259) (xy 48.625599 -45.682501) (xy 48.57651 -45.698315)
			(xy 48.525562 -45.706317) (xy 48.499776 -45.706792) (xy 48.474441 -45.706306) (xy 48.424363 -45.698573)
			(xy 48.376052 -45.68329) (xy 48.330638 -45.660816) (xy 48.289184 -45.631678) (xy 48.25266 -45.596556)
			(xy 48.221921 -45.556273) (xy 48.197688 -45.511773) (xy 48.180526 -45.464097) (xy 48.175164 -45.43933)
			(xy 48.174148 -45.43425) (xy 48.152812 -45.382688) (xy 48.08347 -45.41139) (xy 48.013366 -45.481494)
			(xy 48.009556 -45.491654) (xy 48.000348 -45.515012) (xy 47.975895 -45.558861) (xy 47.945096 -45.59851)
			(xy 47.908657 -45.633048) (xy 47.867417 -45.661681) (xy 47.822322 -45.683751) (xy 47.774409 -45.698752)
			(xy 47.724779 -45.706337) (xy 47.699676 -45.706792) (xy 47.673691 -45.706281) (xy 47.62236 -45.698147)
			(xy 47.572934 -45.682084) (xy 47.526629 -45.658486) (xy 47.484585 -45.627936) (xy 47.447838 -45.591185)
			(xy 47.417293 -45.549137) (xy 47.393701 -45.502829) (xy 47.377644 -45.453401) (xy 47.369516 -45.40207)
			(xy 47.368968 -45.376084) (xy 47.369052 -45.365897) (xy 47.370321 -45.345562) (xy 47.371508 -45.335444)
			(xy 47.372254 -45.324135) (xy 47.365065 -45.302673) (xy 47.349386 -45.286348) (xy 47.328231 -45.2783)
			(xy 47.316898 -45.278548) (xy 47.29226 -45.279564) (xy 47.227744 -45.279564) (xy 47.227744 -45.333412)
			(xy 47.228252 -45.33646) (xy 47.229345 -45.346329) (xy 47.230487 -45.366155) (xy 47.230538 -45.376084)
			(xy 47.230028 -45.402071) (xy 47.221898 -45.453406) (xy 47.205837 -45.502836) (xy 47.182241 -45.549146)
			(xy 47.151691 -45.591194) (xy 47.11494 -45.627945) (xy 47.072892 -45.658495) (xy 47.026582 -45.682091)
			(xy 46.977152 -45.698152) (xy 46.925817 -45.706282) (xy 46.873843 -45.706282) (xy 46.822508 -45.698152)
			(xy 46.773078 -45.682091) (xy 46.726768 -45.658495) (xy 46.68472 -45.627945) (xy 46.647969 -45.591194)
			(xy 46.617419 -45.549146) (xy 46.593823 -45.502836) (xy 46.577762 -45.453406) (xy 46.569632 -45.402071)
			(xy 46.569122 -45.376084) (xy 46.569172 -45.366155) (xy 46.570313 -45.346329) (xy 46.571408 -45.33646)
			(xy 46.571916 -45.333412) (xy 46.571916 -45.279564) (xy 46.427644 -45.279564) (xy 46.427644 -45.333412)
			(xy 46.428152 -45.33646) (xy 46.429245 -45.346329) (xy 46.430387 -45.366155) (xy 46.430438 -45.376084)
			(xy 46.42993 -45.402073) (xy 46.421801 -45.453411) (xy 46.405742 -45.502846) (xy 46.382148 -45.54916)
			(xy 46.351599 -45.591212) (xy 46.314847 -45.627969) (xy 46.272799 -45.658523) (xy 46.226488 -45.682124)
			(xy 46.177056 -45.698191) (xy 46.125719 -45.706326) (xy 46.09973 -45.706792) (xy 46.073942 -45.706301)
			(xy 46.02299 -45.6983) (xy 45.973897 -45.682489) (xy 45.927853 -45.65925) (xy 45.885974 -45.629146)
			(xy 45.849274 -45.592907) (xy 45.818644 -45.551412) (xy 45.794825 -45.505665) (xy 45.778394 -45.456776)
			(xy 45.769751 -45.405929) (xy 45.769022 -45.380148) (xy 45.768462 -45.36692) (xy 45.761393 -45.341415)
			(xy 45.748003 -45.318586) (xy 45.729194 -45.299966) (xy 45.70623 -45.286809) (xy 45.680655 -45.279998)
			(xy 45.667422 -45.279564) (xy 44.8564 -45.279564) (xy 44.833119 -45.279146) (xy 44.787127 -45.271892)
			(xy 44.742837 -45.25753) (xy 44.701339 -45.236415) (xy 44.663656 -45.209067) (xy 44.64685 -45.19295)
			(xy 40.70985 -41.25595) (xy 40.702055 -41.247997) (xy 40.68756 -41.231089) (xy 40.680894 -41.222168)
			(xy 40.673611 -41.213368) (xy 40.653458 -41.20268) (xy 40.630666 -41.201743) (xy 40.619934 -41.205658)
			(xy 40.596047 -41.215462) (xy 40.546292 -41.22927) (xy 40.495129 -41.236239) (xy 40.469312 -41.236646)
			(xy 40.442059 -41.236161) (xy 40.388108 -41.228406) (xy 40.33581 -41.213052) (xy 40.286229 -41.190413)
			(xy 40.240374 -41.160947) (xy 40.199179 -41.125256) (xy 40.163483 -41.084066) (xy 40.134011 -41.038215)
			(xy 40.111365 -40.988637) (xy 40.096004 -40.936341) (xy 40.088243 -40.882391) (xy 40.087804 -40.855138)
			(xy 40.088349 -40.825769) (xy 40.097356 -40.767726) (xy 40.11515 -40.711748) (xy 40.141309 -40.659157)
			(xy 40.175216 -40.611193) (xy 40.195246 -40.589708) (xy 40.201801 -40.582254) (xy 40.209164 -40.563841)
			(xy 40.209017 -40.544012) (xy 40.201383 -40.52571) (xy 40.194738 -40.518334) (xy 39.653718 -39.977314)
			(xy 39.641018 -39.973758) (xy 39.61462 -39.96568) (xy 39.564301 -39.942972) (xy 39.51778 -39.91325)
			(xy 39.476028 -39.877133) (xy 39.439918 -39.835376) (xy 39.410202 -39.788851) (xy 39.387502 -39.738529)
			(xy 39.379398 -39.712138) (xy 39.375842 -39.699438) (xy 37.52723 -37.850826) (xy 37.500946 -37.836732)
			(xy 37.452728 -37.801637) (xy 37.410558 -37.759466) (xy 37.375464 -37.711247) (xy 37.361368 -37.684964)
			(xy 37.133022 -37.456618) (xy 36.187634 -37.456618) (xy 35.920426 -37.723826) (xy 35.920426 -39.56431)
			(xy 37.311582 -39.56431) (xy 37.315653 -39.508688) (xy 37.327779 -39.454251) (xy 37.347702 -39.40216)
			(xy 37.374998 -39.353525) (xy 37.409084 -39.309382) (xy 37.449233 -39.270673) (xy 37.494591 -39.238222)
			(xy 37.544191 -39.212721) (xy 37.596975 -39.194714) (xy 37.651818 -39.184584) (xy 37.707552 -39.182547)
			(xy 37.762989 -39.188647) (xy 37.816946 -39.202753) (xy 37.868275 -39.224565) (xy 37.915881 -39.253619)
			(xy 37.958749 -39.289294) (xy 37.995966 -39.330831) (xy 38.026739 -39.377344) (xy 38.050411 -39.427841)
			(xy 38.066479 -39.481248) (xy 38.074599 -39.536424) (xy 38.075108 -39.56431) (xy 38.074599 -39.592196)
			(xy 38.066479 -39.647372) (xy 38.050411 -39.700779) (xy 38.026739 -39.751276) (xy 37.995966 -39.797789)
			(xy 37.958749 -39.839326) (xy 37.915881 -39.875001) (xy 37.868275 -39.904055) (xy 37.816946 -39.925867)
			(xy 37.762989 -39.939973) (xy 37.707552 -39.946073) (xy 37.651818 -39.944036) (xy 37.596975 -39.933906)
			(xy 37.544191 -39.915899) (xy 37.494591 -39.890398) (xy 37.449233 -39.857947) (xy 37.409084 -39.819238)
			(xy 37.374998 -39.775095) (xy 37.347702 -39.72646) (xy 37.327779 -39.674369) (xy 37.315653 -39.619932)
			(xy 37.311582 -39.56431) (xy 35.920426 -39.56431) (xy 35.920426 -39.645844) (xy 36.338764 -40.064436)
			(xy 37.4904 -40.064436) (xy 37.517666 -40.06497) (xy 37.571528 -40.073497) (xy 37.623394 -40.09034)
			(xy 37.671988 -40.115085) (xy 37.716116 -40.147124) (xy 37.735764 -40.166036) (xy 37.938964 -40.369236)
			(xy 38.4556 -40.369236) (xy 38.482866 -40.36977) (xy 38.536728 -40.378297) (xy 38.588594 -40.39514)
			(xy 38.637188 -40.419885) (xy 38.681316 -40.451924) (xy 38.700964 -40.470836) (xy 39.539164 -41.309036)
			(xy 39.558091 -41.328674) (xy 39.590153 -41.372794) (xy 39.614914 -41.421389) (xy 39.631763 -41.473261)
			(xy 39.640285 -41.52713) (xy 39.640764 -41.5544) (xy 39.640764 -41.867836) (xy 43.186096 -45.413168)
			(xy 43.195748 -45.416978) (xy 43.22182 -45.428057) (xy 43.270638 -45.456791) (xy 43.314669 -45.49243)
			(xy 43.352945 -45.534189) (xy 43.384625 -45.581149) (xy 43.409011 -45.632277) (xy 43.425568 -45.68645)
			(xy 43.433931 -45.742476) (xy 43.434508 -45.7708) (xy 43.434035 -45.797295) (xy 44.010328 -45.797295)
			(xy 44.010328 -45.745321) (xy 44.018458 -45.693986) (xy 44.034519 -45.644556) (xy 44.058115 -45.598246)
			(xy 44.088665 -45.556198) (xy 44.125416 -45.519447) (xy 44.167464 -45.488897) (xy 44.213774 -45.465301)
			(xy 44.263204 -45.44924) (xy 44.314539 -45.44111) (xy 44.366513 -45.44111) (xy 44.417848 -45.44924)
			(xy 44.467278 -45.465301) (xy 44.513588 -45.488897) (xy 44.555636 -45.519447) (xy 44.592387 -45.556198)
			(xy 44.622937 -45.598246) (xy 44.646533 -45.644556) (xy 44.662594 -45.693986) (xy 44.670724 -45.745321)
			(xy 44.671234 -45.771308) (xy 44.670724 -45.797295) (xy 44.662594 -45.84863) (xy 44.646533 -45.89806)
			(xy 44.622937 -45.94437) (xy 44.592387 -45.986418) (xy 44.555636 -46.023169) (xy 44.513588 -46.053719)
			(xy 44.467278 -46.077315) (xy 44.417848 -46.093376) (xy 44.366513 -46.101506) (xy 44.314539 -46.101506)
			(xy 44.263204 -46.093376) (xy 44.213774 -46.077315) (xy 44.167464 -46.053719) (xy 44.125416 -46.023169)
			(xy 44.088665 -45.986418) (xy 44.058115 -45.94437) (xy 44.034519 -45.89806) (xy 44.018458 -45.84863)
			(xy 44.010328 -45.797295) (xy 43.434035 -45.797295) (xy 43.434022 -45.798051) (xy 43.426266 -45.851999)
			(xy 43.410911 -45.904294) (xy 43.388269 -45.953871) (xy 43.358803 -45.999721) (xy 43.323112 -46.040912)
			(xy 43.281921 -46.076603) (xy 43.236071 -46.106069) (xy 43.186494 -46.128711) (xy 43.134199 -46.144066)
			(xy 43.080251 -46.151822) (xy 43.053 -46.152308) (xy 43.024674 -46.151792) (xy 42.968644 -46.143416)
			(xy 42.914468 -46.126849) (xy 42.863337 -46.102455) (xy 42.816374 -46.070769) (xy 42.774612 -46.032489)
			(xy 42.738968 -45.988455) (xy 42.710226 -45.939635) (xy 42.699178 -45.913548) (xy 42.695368 -45.903896)
			(xy 39.048436 -42.256964) (xy 39.029509 -42.237326) (xy 38.997447 -42.193206) (xy 38.972686 -42.144611)
			(xy 38.955837 -42.092739) (xy 38.947315 -42.03887) (xy 38.946836 -42.0116) (xy 38.946836 -41.698164)
			(xy 38.311836 -41.063164) (xy 37.7952 -41.063164) (xy 37.767801 -41.062667) (xy 37.71368 -41.054083)
			(xy 37.661586 -41.037082) (xy 37.636958 -41.025064) (xy 37.624905 -41.019335) (xy 37.59882 -41.013746)
			(xy 37.572178 -41.015119) (xy 37.546806 -41.023362) (xy 37.524444 -41.037909) (xy 37.506625 -41.057762)
			(xy 37.500306 -41.069514) (xy 37.487484 -41.093693) (xy 37.45596 -41.138432) (xy 37.418364 -41.178204)
			(xy 37.375468 -41.212193) (xy 37.328154 -41.239699) (xy 37.302948 -41.250362) (xy 37.293296 -41.254172)
			(xy 37.230304 -41.317164) (xy 37.210665 -41.336088) (xy 37.166543 -41.368142) (xy 37.117948 -41.392895)
			(xy 37.066076 -41.409735) (xy 37.012208 -41.418247) (xy 36.98494 -41.418764) (xy 35.0139 -41.418764)
			(xy 35.0139 -43.07078) (xy 36.320982 -43.07078) (xy 36.325053 -43.015158) (xy 36.337179 -42.960721)
			(xy 36.357102 -42.90863) (xy 36.384398 -42.859995) (xy 36.418484 -42.815852) (xy 36.458633 -42.777143)
			(xy 36.503991 -42.744692) (xy 36.553591 -42.719191) (xy 36.606375 -42.701184) (xy 36.661218 -42.691054)
			(xy 36.716952 -42.689017) (xy 36.772389 -42.695117) (xy 36.826346 -42.709223) (xy 36.877675 -42.731035)
			(xy 36.925281 -42.760089) (xy 36.968149 -42.795764) (xy 37.005366 -42.837301) (xy 37.036139 -42.883814)
			(xy 37.059811 -42.934311) (xy 37.075879 -42.987718) (xy 37.083999 -43.042894) (xy 37.084508 -43.07078)
			(xy 37.083999 -43.098666) (xy 37.075879 -43.153842) (xy 37.059811 -43.207249) (xy 37.036139 -43.257746)
			(xy 37.005366 -43.304259) (xy 36.968149 -43.345796) (xy 36.925281 -43.381471) (xy 36.877675 -43.410525)
			(xy 36.826346 -43.432337) (xy 36.772389 -43.446443) (xy 36.716952 -43.452543) (xy 36.661218 -43.450506)
			(xy 36.606375 -43.440376) (xy 36.553591 -43.422369) (xy 36.503991 -43.396868) (xy 36.458633 -43.364417)
			(xy 36.418484 -43.325708) (xy 36.384398 -43.281565) (xy 36.357102 -43.23293) (xy 36.337179 -43.180839)
			(xy 36.325053 -43.126402) (xy 36.320982 -43.07078) (xy 35.0139 -43.07078) (xy 35.0139 -43.9928) (xy 35.34918 -44.32808)
			(xy 37.83838 -44.32808) (xy 38.31844 -44.80814) (xy 38.31844 -44.997624) (xy 38.356032 -45.00753)
			(xy 38.382419 -45.015119) (xy 38.43285 -45.036824) (xy 38.479652 -45.06553) (xy 38.501066 -45.082714)
			(xy 38.512719 -45.091705) (xy 38.539793 -45.103214) (xy 38.569023 -45.10655) (xy 38.597994 -45.101438)
			(xy 38.624317 -45.0883) (xy 38.635432 -45.07865) (xy 38.656749 -45.05942) (xy 38.704077 -45.026928)
			(xy 38.75574 -45.001896) (xy 38.810571 -44.984888) (xy 38.867332 -44.97629) (xy 38.896036 -44.97578)
			(xy 38.923286 -44.976268) (xy 38.977232 -44.984029) (xy 39.029524 -44.999388) (xy 39.079098 -45.022032)
			(xy 39.124946 -45.0515) (xy 39.166133 -45.087193) (xy 39.201822 -45.128383) (xy 39.231285 -45.174233)
			(xy 39.253925 -45.22381) (xy 39.269278 -45.276103) (xy 39.277034 -45.33005) (xy 39.277034 -45.38455)
			(xy 39.269278 -45.438497) (xy 39.253925 -45.49079) (xy 39.231285 -45.540367) (xy 39.201822 -45.586217)
			(xy 39.166133 -45.627407) (xy 39.124946 -45.6631) (xy 39.079098 -45.692568) (xy 39.029524 -45.715212)
			(xy 38.977232 -45.730571) (xy 38.923286 -45.738332) (xy 38.896036 -45.738796) (xy 38.86957 -45.73834)
			(xy 38.817149 -45.731013) (xy 38.766243 -45.716511) (xy 38.717831 -45.69511) (xy 38.672843 -45.667221)
			(xy 38.652196 -45.650658) (xy 38.640542 -45.64166) (xy 38.613462 -45.630137) (xy 38.584223 -45.626787)
			(xy 38.555238 -45.631886) (xy 38.528898 -45.645015) (xy 38.51783 -45.654722) (xy 38.494633 -45.675565)
			(xy 38.442774 -45.710195) (xy 38.385983 -45.735951) (xy 38.356032 -45.744638) (xy 38.31844 -45.754544)
			(xy 38.31844 -46.16069) (xy 40.57218 -46.16069) (xy 40.576251 -46.105068) (xy 40.588377 -46.050631)
			(xy 40.6083 -45.99854) (xy 40.635596 -45.949905) (xy 40.669682 -45.905762) (xy 40.709831 -45.867053)
			(xy 40.755189 -45.834602) (xy 40.804789 -45.809101) (xy 40.857573 -45.791094) (xy 40.912416 -45.780964)
			(xy 40.96815 -45.778927) (xy 41.023587 -45.785027) (xy 41.077544 -45.799133) (xy 41.128873 -45.820945)
			(xy 41.176479 -45.849999) (xy 41.219347 -45.885674) (xy 41.256564 -45.927211) (xy 41.287337 -45.973724)
			(xy 41.311009 -46.024221) (xy 41.327077 -46.077628) (xy 41.335197 -46.132804) (xy 41.335706 -46.16069)
			(xy 41.335197 -46.188576) (xy 41.333234 -46.201917) (xy 45.769532 -46.201917) (xy 45.769532 -46.149943)
			(xy 45.777662 -46.098608) (xy 45.793723 -46.049178) (xy 45.817319 -46.002868) (xy 45.847869 -45.96082)
			(xy 45.88462 -45.924069) (xy 45.926668 -45.893519) (xy 45.972978 -45.869923) (xy 46.022408 -45.853862)
			(xy 46.073743 -45.845732) (xy 46.125717 -45.845732) (xy 46.177052 -45.853862) (xy 46.226482 -45.869923)
			(xy 46.272792 -45.893519) (xy 46.31484 -45.924069) (xy 46.351591 -45.96082) (xy 46.382141 -46.002868)
			(xy 46.405737 -46.049178) (xy 46.421798 -46.098608) (xy 46.429928 -46.149943) (xy 46.430438 -46.17593)
			(xy 46.429928 -46.201917) (xy 46.569632 -46.201917) (xy 46.569632 -46.149943) (xy 46.577762 -46.098608)
			(xy 46.593823 -46.049178) (xy 46.617419 -46.002868) (xy 46.647969 -45.96082) (xy 46.68472 -45.924069)
			(xy 46.726768 -45.893519) (xy 46.773078 -45.869923) (xy 46.822508 -45.853862) (xy 46.873843 -45.845732)
			(xy 46.925817 -45.845732) (xy 46.977152 -45.853862) (xy 47.026582 -45.869923) (xy 47.072892 -45.893519)
			(xy 47.11494 -45.924069) (xy 47.151691 -45.96082) (xy 47.182241 -46.002868) (xy 47.205837 -46.049178)
			(xy 47.221898 -46.098608) (xy 47.230028 -46.149943) (xy 47.230538 -46.17593) (xy 47.230028 -46.201917)
			(xy 47.369478 -46.201917) (xy 47.369478 -46.149943) (xy 47.377608 -46.098608) (xy 47.393669 -46.049178)
			(xy 47.417265 -46.002868) (xy 47.447815 -45.96082) (xy 47.484566 -45.924069) (xy 47.526614 -45.893519)
			(xy 47.572924 -45.869923) (xy 47.622354 -45.853862) (xy 47.673689 -45.845732) (xy 47.725663 -45.845732)
			(xy 47.776998 -45.853862) (xy 47.826428 -45.869923) (xy 47.872738 -45.893519) (xy 47.914786 -45.924069)
			(xy 47.951537 -45.96082) (xy 47.982087 -46.002868) (xy 48.005683 -46.049178) (xy 48.021744 -46.098608)
			(xy 48.029874 -46.149943) (xy 48.030384 -46.17593) (xy 48.029874 -46.201917) (xy 48.169578 -46.201917)
			(xy 48.169578 -46.149943) (xy 48.177708 -46.098608) (xy 48.193769 -46.049178) (xy 48.217365 -46.002868)
			(xy 48.247915 -45.96082) (xy 48.284666 -45.924069) (xy 48.326714 -45.893519) (xy 48.373024 -45.869923)
			(xy 48.422454 -45.853862) (xy 48.473789 -45.845732) (xy 48.525763 -45.845732) (xy 48.577098 -45.853862)
			(xy 48.626528 -45.869923) (xy 48.672838 -45.893519) (xy 48.714886 -45.924069) (xy 48.751637 -45.96082)
			(xy 48.782187 -46.002868) (xy 48.805783 -46.049178) (xy 48.821844 -46.098608) (xy 48.829974 -46.149943)
			(xy 48.830484 -46.17593) (xy 48.829974 -46.201917) (xy 52.16957 -46.201917) (xy 52.16957 -46.149943)
			(xy 52.1777 -46.098608) (xy 52.193761 -46.049178) (xy 52.217357 -46.002868) (xy 52.247907 -45.96082)
			(xy 52.284658 -45.924069) (xy 52.326706 -45.893519) (xy 52.373016 -45.869923) (xy 52.422446 -45.853862)
			(xy 52.473781 -45.845732) (xy 52.525755 -45.845732) (xy 52.57709 -45.853862) (xy 52.62652 -45.869923)
			(xy 52.67283 -45.893519) (xy 52.714878 -45.924069) (xy 52.751629 -45.96082) (xy 52.782179 -46.002868)
			(xy 52.805775 -46.049178) (xy 52.821836 -46.098608) (xy 52.829966 -46.149943) (xy 52.830476 -46.17593)
			(xy 52.829966 -46.201917) (xy 52.96967 -46.201917) (xy 52.96967 -46.149943) (xy 52.9778 -46.098608)
			(xy 52.993861 -46.049178) (xy 53.017457 -46.002868) (xy 53.048007 -45.96082) (xy 53.084758 -45.924069)
			(xy 53.126806 -45.893519) (xy 53.173116 -45.869923) (xy 53.222546 -45.853862) (xy 53.273881 -45.845732)
			(xy 53.325855 -45.845732) (xy 53.37719 -45.853862) (xy 53.42662 -45.869923) (xy 53.47293 -45.893519)
			(xy 53.514978 -45.924069) (xy 53.551729 -45.96082) (xy 53.582279 -46.002868) (xy 53.605875 -46.049178)
			(xy 53.621936 -46.098608) (xy 53.630066 -46.149943) (xy 53.630576 -46.17593) (xy 53.630066 -46.201917)
			(xy 53.621936 -46.253252) (xy 53.605875 -46.302682) (xy 53.582279 -46.348992) (xy 53.551729 -46.39104)
			(xy 53.514978 -46.427791) (xy 53.47293 -46.458341) (xy 53.42662 -46.481937) (xy 53.37719 -46.497998)
			(xy 53.325855 -46.506128) (xy 53.273881 -46.506128) (xy 53.222546 -46.497998) (xy 53.173116 -46.481937)
			(xy 53.126806 -46.458341) (xy 53.084758 -46.427791) (xy 53.048007 -46.39104) (xy 53.017457 -46.348992)
			(xy 52.993861 -46.302682) (xy 52.9778 -46.253252) (xy 52.96967 -46.201917) (xy 52.829966 -46.201917)
			(xy 52.821836 -46.253252) (xy 52.805775 -46.302682) (xy 52.782179 -46.348992) (xy 52.751629 -46.39104)
			(xy 52.714878 -46.427791) (xy 52.67283 -46.458341) (xy 52.62652 -46.481937) (xy 52.57709 -46.497998)
			(xy 52.525755 -46.506128) (xy 52.473781 -46.506128) (xy 52.422446 -46.497998) (xy 52.373016 -46.481937)
			(xy 52.326706 -46.458341) (xy 52.284658 -46.427791) (xy 52.247907 -46.39104) (xy 52.217357 -46.348992)
			(xy 52.193761 -46.302682) (xy 52.1777 -46.253252) (xy 52.16957 -46.201917) (xy 48.829974 -46.201917)
			(xy 48.821844 -46.253252) (xy 48.805783 -46.302682) (xy 48.782187 -46.348992) (xy 48.751637 -46.39104)
			(xy 48.714886 -46.427791) (xy 48.672838 -46.458341) (xy 48.626528 -46.481937) (xy 48.577098 -46.497998)
			(xy 48.525763 -46.506128) (xy 48.473789 -46.506128) (xy 48.422454 -46.497998) (xy 48.373024 -46.481937)
			(xy 48.326714 -46.458341) (xy 48.284666 -46.427791) (xy 48.247915 -46.39104) (xy 48.217365 -46.348992)
			(xy 48.193769 -46.302682) (xy 48.177708 -46.253252) (xy 48.169578 -46.201917) (xy 48.029874 -46.201917)
			(xy 48.021744 -46.253252) (xy 48.005683 -46.302682) (xy 47.982087 -46.348992) (xy 47.951537 -46.39104)
			(xy 47.914786 -46.427791) (xy 47.872738 -46.458341) (xy 47.826428 -46.481937) (xy 47.776998 -46.497998)
			(xy 47.725663 -46.506128) (xy 47.673689 -46.506128) (xy 47.622354 -46.497998) (xy 47.572924 -46.481937)
			(xy 47.526614 -46.458341) (xy 47.484566 -46.427791) (xy 47.447815 -46.39104) (xy 47.417265 -46.348992)
			(xy 47.393669 -46.302682) (xy 47.377608 -46.253252) (xy 47.369478 -46.201917) (xy 47.230028 -46.201917)
			(xy 47.221898 -46.253252) (xy 47.205837 -46.302682) (xy 47.182241 -46.348992) (xy 47.151691 -46.39104)
			(xy 47.11494 -46.427791) (xy 47.072892 -46.458341) (xy 47.026582 -46.481937) (xy 46.977152 -46.497998)
			(xy 46.925817 -46.506128) (xy 46.873843 -46.506128) (xy 46.822508 -46.497998) (xy 46.773078 -46.481937)
			(xy 46.726768 -46.458341) (xy 46.68472 -46.427791) (xy 46.647969 -46.39104) (xy 46.617419 -46.348992)
			(xy 46.593823 -46.302682) (xy 46.577762 -46.253252) (xy 46.569632 -46.201917) (xy 46.429928 -46.201917)
			(xy 46.421798 -46.253252) (xy 46.405737 -46.302682) (xy 46.382141 -46.348992) (xy 46.351591 -46.39104)
			(xy 46.31484 -46.427791) (xy 46.272792 -46.458341) (xy 46.226482 -46.481937) (xy 46.177052 -46.497998)
			(xy 46.125717 -46.506128) (xy 46.073743 -46.506128) (xy 46.022408 -46.497998) (xy 45.972978 -46.481937)
			(xy 45.926668 -46.458341) (xy 45.88462 -46.427791) (xy 45.847869 -46.39104) (xy 45.817319 -46.348992)
			(xy 45.793723 -46.302682) (xy 45.777662 -46.253252) (xy 45.769532 -46.201917) (xy 41.333234 -46.201917)
			(xy 41.327077 -46.243752) (xy 41.311009 -46.297159) (xy 41.287337 -46.347656) (xy 41.256564 -46.394169)
			(xy 41.219347 -46.435706) (xy 41.176479 -46.471381) (xy 41.128873 -46.500435) (xy 41.077544 -46.522247)
			(xy 41.023587 -46.536353) (xy 40.96815 -46.542453) (xy 40.912416 -46.540416) (xy 40.857573 -46.530286)
			(xy 40.804789 -46.512279) (xy 40.755189 -46.486778) (xy 40.709831 -46.454327) (xy 40.669682 -46.415618)
			(xy 40.635596 -46.371475) (xy 40.6083 -46.32284) (xy 40.588377 -46.270749) (xy 40.576251 -46.216312)
			(xy 40.57218 -46.16069) (xy 38.31844 -46.16069) (xy 38.31844 -46.669452) (xy 38.339825 -46.684794)
			(xy 38.378569 -46.720417) (xy 38.412049 -46.761028) (xy 38.439627 -46.805856) (xy 38.460781 -46.854049)
			(xy 38.475109 -46.904693) (xy 38.482338 -46.956826) (xy 38.482778 -46.983142) (xy 38.482289 -47.01039)
			(xy 38.474527 -47.064332) (xy 38.459168 -47.11662) (xy 38.436524 -47.16619) (xy 38.407056 -47.212033)
			(xy 38.371365 -47.253216) (xy 38.330175 -47.2889) (xy 38.284327 -47.318359) (xy 38.234752 -47.340993)
			(xy 38.182462 -47.356343) (xy 38.128519 -47.364094) (xy 38.10127 -47.36465) (xy 38.074537 -47.364198)
			(xy 38.021595 -47.356723) (xy 37.970216 -47.341925) (xy 37.92141 -47.320094) (xy 37.876132 -47.291657)
			(xy 37.835271 -47.257173) (xy 37.79963 -47.217319) (xy 37.769906 -47.172876) (xy 37.757862 -47.149004)
			(xy 36.587176 -47.149004) (xy 36.37788 -47.3583) (xy 36.37788 -47.587916) (xy 38.492936 -47.587916)
			(xy 38.497007 -47.532294) (xy 38.509133 -47.477857) (xy 38.529056 -47.425766) (xy 38.556352 -47.377131)
			(xy 38.590438 -47.332988) (xy 38.630587 -47.294279) (xy 38.675945 -47.261828) (xy 38.725545 -47.236327)
			(xy 38.778329 -47.21832) (xy 38.833172 -47.20819) (xy 38.888906 -47.206153) (xy 38.944343 -47.212253)
			(xy 38.9983 -47.226359) (xy 39.049629 -47.248171) (xy 39.097235 -47.277225) (xy 39.140103 -47.3129)
			(xy 39.17732 -47.354437) (xy 39.208093 -47.40095) (xy 39.231765 -47.451447) (xy 39.247833 -47.504854)
			(xy 39.255953 -47.56003) (xy 39.256462 -47.587916) (xy 39.255953 -47.615802) (xy 39.247833 -47.670978)
			(xy 39.231765 -47.724385) (xy 39.208093 -47.774882) (xy 39.17732 -47.821395) (xy 39.140103 -47.862932)
			(xy 39.097235 -47.898607) (xy 39.049629 -47.927661) (xy 38.9983 -47.949473) (xy 38.944343 -47.963579)
			(xy 38.888906 -47.969679) (xy 38.833172 -47.967642) (xy 38.778329 -47.957512) (xy 38.725545 -47.939505)
			(xy 38.675945 -47.914004) (xy 38.630587 -47.881553) (xy 38.590438 -47.842844) (xy 38.556352 -47.798701)
			(xy 38.529056 -47.750066) (xy 38.509133 -47.697975) (xy 38.497007 -47.643538) (xy 38.492936 -47.587916)
			(xy 36.37788 -47.587916) (xy 36.37788 -48.17364) (xy 36.61664 -48.4124) (xy 37.065712 -48.4124)
		)
		(stroke
			(width 0)
			(type solid)
		)
		(fill yes)
		(layer "In9.Cu")
		(net "P3V3_AUX")
	)
	(gr_poly
		(pts
			(xy 51.396138 -44.710858) (xy 51.385978 -44.68114) (xy 51.378002 -44.655588) (xy 51.369456 -44.602748)
			(xy 51.36896 -44.575984) (xy 51.369408 -44.551136) (xy 51.376848 -44.502) (xy 51.391558 -44.454531)
			(xy 51.413206 -44.409798) (xy 51.426872 -44.38904) (xy 51.426872 -43.162982) (xy 51.413193 -43.142231)
			(xy 51.391546 -43.097494) (xy 51.376837 -43.050021) (xy 51.369397 -43.000881) (xy 51.369392 -42.951182)
			(xy 51.376823 -42.902041) (xy 51.391523 -42.854565) (xy 51.413161 -42.809823) (xy 51.426872 -42.789094)
			(xy 51.426872 -42.362882) (xy 51.413193 -42.342131) (xy 51.391546 -42.297394) (xy 51.376837 -42.249921)
			(xy 51.369397 -42.200781) (xy 51.369392 -42.151082) (xy 51.376823 -42.101941) (xy 51.391523 -42.054465)
			(xy 51.413161 -42.009723) (xy 51.426872 -41.988994) (xy 51.426872 -41.563036) (xy 51.413196 -41.542285)
			(xy 51.391556 -41.497548) (xy 51.376854 -41.450077) (xy 51.36942 -41.40094) (xy 51.36896 -41.376092)
			(xy 51.369346 -41.35299) (xy 51.375781 -41.307238) (xy 51.388526 -41.262827) (xy 51.407331 -41.220624)
			(xy 51.419252 -41.200832) (xy 51.426872 -41.18864) (xy 51.426872 -41.040558) (xy 51.200812 -40.814498)
			(xy 51.193521 -40.807797) (xy 51.175304 -40.80008) (xy 51.155522 -40.799877) (xy 51.137151 -40.807219)
			(xy 51.129692 -40.813736) (xy 51.111084 -40.831075) (xy 51.069536 -40.860408) (xy 51.023987 -40.883036)
			(xy 50.975512 -40.898426) (xy 50.925252 -40.906214) (xy 50.899822 -40.9067) (xy 50.873832 -40.906219)
			(xy 50.822491 -40.89809) (xy 50.773054 -40.88203) (xy 50.726738 -40.858433) (xy 50.684685 -40.827881)
			(xy 50.647928 -40.791126) (xy 50.617374 -40.749074) (xy 50.593776 -40.702759) (xy 50.577713 -40.653323)
			(xy 50.569583 -40.601982) (xy 50.569114 -40.575992) (xy 50.569581 -40.550561) (xy 50.57737 -40.5003)
			(xy 50.592763 -40.451823) (xy 50.615397 -40.406275) (xy 50.644738 -40.36473) (xy 50.662078 -40.346122)
			(xy 50.668553 -40.338661) (xy 50.675779 -40.320294) (xy 50.675555 -40.300558) (xy 50.667913 -40.28236)
			(xy 50.661316 -40.275002) (xy 50.400712 -40.014398) (xy 50.393374 -40.007769) (xy 50.375133 -40.000181)
			(xy 50.355376 -40.000042) (xy 50.33703 -40.007372) (xy 50.329592 -40.01389) (xy 50.310985 -40.031231)
			(xy 50.269438 -40.060568) (xy 50.223889 -40.083199) (xy 50.175413 -40.098591) (xy 50.125152 -40.10638)
			(xy 50.099722 -40.106854) (xy 50.073732 -40.106346) (xy 50.022393 -40.098219) (xy 49.972956 -40.08216)
			(xy 49.92664 -40.058566) (xy 49.884585 -40.028018) (xy 49.847827 -39.991267) (xy 49.817269 -39.949218)
			(xy 49.793666 -39.902907) (xy 49.777597 -39.853474) (xy 49.769459 -39.802136) (xy 49.769014 -39.776146)
			(xy 49.769477 -39.750714) (xy 49.777258 -39.700448) (xy 49.792645 -39.651966) (xy 49.815274 -39.606413)
			(xy 49.844612 -39.564861) (xy 49.861978 -39.546276) (xy 49.868502 -39.538846) (xy 49.875828 -39.5205)
			(xy 49.87568 -39.500746) (xy 49.868081 -39.482512) (xy 49.86147 -39.475156) (xy 49.344072 -38.957758)
			(xy 49.334203 -38.948532) (xy 49.310733 -38.93517) (xy 49.28458 -38.92843) (xy 49.257576 -38.928783)
			(xy 49.231608 -38.936204) (xy 49.208495 -38.950174) (xy 49.189853 -38.969715) (xy 49.183036 -38.98138)
			(xy 49.169591 -39.005243) (xy 49.136508 -39.048895) (xy 49.097129 -39.086963) (xy 49.052382 -39.118548)
			(xy 49.003325 -39.142906) (xy 48.951116 -39.15946) (xy 48.896986 -39.167821) (xy 48.8696 -39.168324)
			(xy 48.841616 -39.167775) (xy 48.786338 -39.15902) (xy 48.73311 -39.141726) (xy 48.683243 -39.116318)
			(xy 48.637964 -39.083422) (xy 48.598388 -39.043848) (xy 48.56549 -38.998571) (xy 48.54008 -38.948705)
			(xy 48.522784 -38.895477) (xy 48.514026 -38.8402) (xy 48.513492 -38.812216) (xy 48.513999 -38.784834)
			(xy 48.522391 -38.730718) (xy 48.538965 -38.678523) (xy 48.563329 -38.629478) (xy 48.594911 -38.584738)
			(xy 48.632966 -38.545358) (xy 48.676599 -38.512264) (xy 48.700436 -38.49878) (xy 48.712128 -38.491996)
			(xy 48.731708 -38.47337) (xy 48.745703 -38.450254) (xy 48.75313 -38.424272) (xy 48.753468 -38.397251)
			(xy 48.746691 -38.371091) (xy 48.733278 -38.347632) (xy 48.724058 -38.337744) (xy 44.388024 -34.00171)
			(xy 44.362624 -34.00552) (xy 44.348734 -34.007441) (xy 44.320765 -34.009473) (xy 44.306744 -34.009584)
			(xy 44.27949 -34.009124) (xy 44.225535 -34.001372) (xy 44.173234 -33.986019) (xy 44.123649 -33.963379)
			(xy 44.077792 -33.933912) (xy 44.036597 -33.898218) (xy 44.0009 -33.857024) (xy 43.971431 -33.811168)
			(xy 43.948788 -33.761585) (xy 43.933433 -33.709284) (xy 43.925678 -33.65533) (xy 43.925236 -33.628076)
			(xy 43.925358 -33.614055) (xy 43.927391 -33.586087) (xy 43.9293 -33.572196) (xy 43.93311 -33.546796)
			(xy 43.885104 -33.49879) (xy 43.874824 -33.48914) (xy 43.850215 -33.475399) (xy 43.822788 -33.468907)
			(xy 43.79463 -33.470159) (xy 43.767887 -33.479058) (xy 43.744593 -33.494927) (xy 43.726524 -33.516558)
			(xy 43.715054 -33.542304) (xy 43.712638 -33.556194) (xy 43.708344 -33.583145) (xy 43.693057 -33.635535)
			(xy 43.670461 -33.685212) (xy 43.641017 -33.731162) (xy 43.605326 -33.772448) (xy 43.564116 -33.808227)
			(xy 43.518229 -33.837769) (xy 43.468601 -33.860472) (xy 43.416244 -33.875871) (xy 43.362227 -33.883653)
			(xy 43.33494 -33.884108) (xy 43.307685 -33.883647) (xy 43.25373 -33.875895) (xy 43.201427 -33.860542)
			(xy 43.151842 -33.837902) (xy 43.105984 -33.808435) (xy 43.064787 -33.772742) (xy 43.029089 -33.731548)
			(xy 42.999617 -33.685693) (xy 42.976972 -33.63611) (xy 42.961613 -33.583809) (xy 42.953855 -33.529855)
			(xy 42.953432 -33.5026) (xy 42.953898 -33.475313) (xy 42.961675 -33.421296) (xy 42.977071 -33.368938)
			(xy 42.999771 -33.319309) (xy 43.029312 -33.273421) (xy 43.06509 -33.232212) (xy 43.106376 -33.196521)
			(xy 43.152327 -33.167079) (xy 43.202005 -33.144485) (xy 43.254396 -33.129202) (xy 43.281346 -33.124902)
			(xy 43.295217 -33.122439) (xy 43.320928 -33.110954) (xy 43.342528 -33.092886) (xy 43.358375 -33.069608)
			(xy 43.367266 -33.042888) (xy 43.368524 -33.014756) (xy 43.362055 -32.987349) (xy 43.348349 -32.962749)
			(xy 43.33875 -32.952436) (xy 43.326558 -32.940244) (xy 43.312588 -32.936942) (xy 43.286979 -32.930439)
			(xy 43.237722 -32.911328) (xy 43.191573 -32.885602) (xy 43.149415 -32.853755) (xy 43.112054 -32.816396)
			(xy 43.080206 -32.774239) (xy 43.054479 -32.728091) (xy 43.035365 -32.678834) (xy 43.02887 -32.653224)
			(xy 43.025568 -32.639254) (xy 42.965116 -32.578802) (xy 42.939208 -32.583374) (xy 42.923326 -32.585884)
			(xy 42.891279 -32.588554) (xy 42.8752 -32.588708) (xy 42.84218 -32.587184) (xy 42.828111 -32.586391)
			(xy 42.800442 -32.591665) (xy 42.775269 -32.604304) (xy 42.754511 -32.623344) (xy 42.739749 -32.647334)
			(xy 42.732109 -32.674445) (xy 42.73169 -32.68853) (xy 42.73169 -32.688784) (xy 42.731296 -32.716084)
			(xy 42.723657 -32.770144) (xy 42.708389 -32.822563) (xy 42.685804 -32.87227) (xy 42.656363 -32.918249)
			(xy 42.620669 -32.959562) (xy 42.579449 -32.995365) (xy 42.533547 -33.024925) (xy 42.483899 -33.04764)
			(xy 42.431521 -33.063045) (xy 42.377481 -33.070826) (xy 42.350182 -33.071308) (xy 42.322932 -33.070821)
			(xy 42.268986 -33.063062) (xy 42.216693 -33.047706) (xy 42.167118 -33.025064) (xy 42.12127 -32.995597)
			(xy 42.080082 -32.959905) (xy 42.044392 -32.918715) (xy 42.014928 -32.872866) (xy 41.992288 -32.82329)
			(xy 41.976934 -32.770997) (xy 41.969178 -32.71705) (xy 41.968674 -32.6898) (xy 41.968854 -32.673525)
			(xy 41.97165 -32.641095) (xy 41.974262 -32.62503) (xy 41.976274 -32.610388) (xy 41.972747 -32.581058)
			(xy 41.960978 -32.553962) (xy 41.941952 -32.531364) (xy 41.917257 -32.515151) (xy 41.888956 -32.506678)
			(xy 41.874186 -32.506158) (xy 39.57193 -32.506158) (xy 39.314374 -32.763714) (xy 39.314374 -33.282128)
			(xy 40.872408 -33.282128) (xy 40.876479 -33.226506) (xy 40.888605 -33.172069) (xy 40.908528 -33.119978)
			(xy 40.935824 -33.071343) (xy 40.96991 -33.0272) (xy 41.010059 -32.988491) (xy 41.055417 -32.95604)
			(xy 41.105017 -32.930539) (xy 41.157801 -32.912532) (xy 41.212644 -32.902402) (xy 41.268378 -32.900365)
			(xy 41.323815 -32.906465) (xy 41.377772 -32.920571) (xy 41.429101 -32.942383) (xy 41.476707 -32.971437)
			(xy 41.519575 -33.007112) (xy 41.556792 -33.048649) (xy 41.587565 -33.095162) (xy 41.611237 -33.145659)
			(xy 41.627305 -33.199066) (xy 41.635425 -33.254242) (xy 41.635934 -33.282128) (xy 41.635425 -33.310014)
			(xy 41.627305 -33.36519) (xy 41.611237 -33.418597) (xy 41.587565 -33.469094) (xy 41.556792 -33.515607)
			(xy 41.519575 -33.557144) (xy 41.476707 -33.592819) (xy 41.433088 -33.61944) (xy 41.959782 -33.61944)
			(xy 41.963853 -33.563818) (xy 41.975979 -33.509381) (xy 41.995902 -33.45729) (xy 42.023198 -33.408655)
			(xy 42.057284 -33.364512) (xy 42.097433 -33.325803) (xy 42.142791 -33.293352) (xy 42.192391 -33.267851)
			(xy 42.245175 -33.249844) (xy 42.300018 -33.239714) (xy 42.355752 -33.237677) (xy 42.411189 -33.243777)
			(xy 42.465146 -33.257883) (xy 42.516475 -33.279695) (xy 42.564081 -33.308749) (xy 42.606949 -33.344424)
			(xy 42.644166 -33.385961) (xy 42.674939 -33.432474) (xy 42.698611 -33.482971) (xy 42.714679 -33.536378)
			(xy 42.722799 -33.591554) (xy 42.723308 -33.61944) (xy 42.722799 -33.647326) (xy 42.714679 -33.702502)
			(xy 42.698611 -33.755909) (xy 42.674939 -33.806406) (xy 42.644166 -33.852919) (xy 42.606949 -33.894456)
			(xy 42.564081 -33.930131) (xy 42.516475 -33.959185) (xy 42.465146 -33.980997) (xy 42.411189 -33.995103)
			(xy 42.355752 -34.001203) (xy 42.300018 -33.999166) (xy 42.245175 -33.989036) (xy 42.192391 -33.971029)
			(xy 42.142791 -33.945528) (xy 42.097433 -33.913077) (xy 42.057284 -33.874368) (xy 42.023198 -33.830225)
			(xy 41.995902 -33.78159) (xy 41.975979 -33.729499) (xy 41.963853 -33.675062) (xy 41.959782 -33.61944)
			(xy 41.433088 -33.61944) (xy 41.429101 -33.621873) (xy 41.377772 -33.643685) (xy 41.323815 -33.657791)
			(xy 41.268378 -33.663891) (xy 41.212644 -33.661854) (xy 41.157801 -33.651724) (xy 41.105017 -33.633717)
			(xy 41.055417 -33.608216) (xy 41.010059 -33.575765) (xy 40.96991 -33.537056) (xy 40.935824 -33.492913)
			(xy 40.908528 -33.444278) (xy 40.888605 -33.392187) (xy 40.876479 -33.33775) (xy 40.872408 -33.282128)
			(xy 39.314374 -33.282128) (xy 39.314374 -34.29) (xy 40.003982 -34.29) (xy 40.008053 -34.234378) (xy 40.020179 -34.179941)
			(xy 40.040102 -34.12785) (xy 40.067398 -34.079215) (xy 40.101484 -34.035072) (xy 40.141633 -33.996363)
			(xy 40.186991 -33.963912) (xy 40.236591 -33.938411) (xy 40.289375 -33.920404) (xy 40.344218 -33.910274)
			(xy 40.399952 -33.908237) (xy 40.455389 -33.914337) (xy 40.509346 -33.928443) (xy 40.560675 -33.950255)
			(xy 40.608281 -33.979309) (xy 40.651149 -34.014984) (xy 40.688366 -34.056521) (xy 40.719139 -34.103034)
			(xy 40.742811 -34.153531) (xy 40.758879 -34.206938) (xy 40.766999 -34.262114) (xy 40.767508 -34.29)
			(xy 40.766999 -34.317886) (xy 40.758879 -34.373062) (xy 40.742811 -34.426469) (xy 40.719139 -34.476966)
			(xy 40.688366 -34.523479) (xy 40.651149 -34.565016) (xy 40.608281 -34.600691) (xy 40.560675 -34.629745)
			(xy 40.509346 -34.651557) (xy 40.455389 -34.665663) (xy 40.399952 -34.671763) (xy 40.344218 -34.669726)
			(xy 40.289375 -34.659596) (xy 40.236591 -34.641589) (xy 40.186991 -34.616088) (xy 40.141633 -34.583637)
			(xy 40.101484 -34.544928) (xy 40.067398 -34.500785) (xy 40.040102 -34.45215) (xy 40.020179 -34.400059)
			(xy 40.008053 -34.345622) (xy 40.003982 -34.29) (xy 39.314374 -34.29) (xy 39.314374 -34.490152) (xy 39.339414 -34.504723)
			(xy 39.385175 -34.540249) (xy 39.42504 -34.582284) (xy 39.458093 -34.629862) (xy 39.483576 -34.681889)
			(xy 39.500902 -34.737169) (xy 39.509673 -34.794434) (xy 39.510208 -34.8234) (xy 39.509773 -34.849844)
			(xy 39.502507 -34.90223) (xy 39.49573 -34.927794) (xy 39.492508 -34.940563) (xy 39.491992 -34.966882)
			(xy 39.498241 -34.992454) (xy 39.510837 -35.01557) (xy 39.528938 -35.034684) (xy 39.551334 -35.048519)
			(xy 39.563802 -35.052762) (xy 39.589531 -35.06109) (xy 39.63852 -35.083994) (xy 39.683782 -35.113588)
			(xy 39.72441 -35.149279) (xy 39.759588 -35.190352) (xy 39.788612 -35.235982) (xy 39.810899 -35.285254)
			(xy 39.826003 -35.337181) (xy 39.833619 -35.390721) (xy 39.834058 -35.41776) (xy 39.833296 -35.440366)
			(xy 39.832026 -35.463226) (xy 40.0558 -35.687) (xy 44.321982 -35.687) (xy 44.326053 -35.631378) (xy 44.338179 -35.576941)
			(xy 44.358102 -35.52485) (xy 44.385398 -35.476215) (xy 44.419484 -35.432072) (xy 44.459633 -35.393363)
			(xy 44.504991 -35.360912) (xy 44.554591 -35.335411) (xy 44.607375 -35.317404) (xy 44.662218 -35.307274)
			(xy 44.717952 -35.305237) (xy 44.773389 -35.311337) (xy 44.827346 -35.325443) (xy 44.878675 -35.347255)
			(xy 44.926281 -35.376309) (xy 44.969149 -35.411984) (xy 45.006366 -35.453521) (xy 45.037139 -35.500034)
			(xy 45.060811 -35.550531) (xy 45.076879 -35.603938) (xy 45.084999 -35.659114) (xy 45.085508 -35.687)
			(xy 45.084999 -35.714886) (xy 45.076879 -35.770062) (xy 45.060811 -35.823469) (xy 45.037139 -35.873966)
			(xy 45.006366 -35.920479) (xy 44.969149 -35.962016) (xy 44.926281 -35.997691) (xy 44.878675 -36.026745)
			(xy 44.827346 -36.048557) (xy 44.773389 -36.062663) (xy 44.717952 -36.068763) (xy 44.662218 -36.066726)
			(xy 44.607375 -36.056596) (xy 44.554591 -36.038589) (xy 44.504991 -36.013088) (xy 44.459633 -35.980637)
			(xy 44.419484 -35.941928) (xy 44.385398 -35.897785) (xy 44.358102 -35.84915) (xy 44.338179 -35.797059)
			(xy 44.326053 -35.742622) (xy 44.321982 -35.687) (xy 40.0558 -35.687) (xy 41.529 -37.1602) (xy 43.331382 -37.1602)
			(xy 43.335453 -37.104578) (xy 43.347579 -37.050141) (xy 43.367502 -36.99805) (xy 43.394798 -36.949415)
			(xy 43.428884 -36.905272) (xy 43.469033 -36.866563) (xy 43.514391 -36.834112) (xy 43.563991 -36.808611)
			(xy 43.616775 -36.790604) (xy 43.671618 -36.780474) (xy 43.727352 -36.778437) (xy 43.782789 -36.784537)
			(xy 43.836746 -36.798643) (xy 43.888075 -36.820455) (xy 43.935681 -36.849509) (xy 43.978549 -36.885184)
			(xy 44.015766 -36.926721) (xy 44.046539 -36.973234) (xy 44.070211 -37.023731) (xy 44.086279 -37.077138)
			(xy 44.094399 -37.132314) (xy 44.094908 -37.1602) (xy 44.094399 -37.188086) (xy 44.086279 -37.243262)
			(xy 44.070211 -37.296669) (xy 44.046539 -37.347166) (xy 44.015766 -37.393679) (xy 43.978549 -37.435216)
			(xy 43.935681 -37.470891) (xy 43.888075 -37.499945) (xy 43.836746 -37.521757) (xy 43.782789 -37.535863)
			(xy 43.727352 -37.541963) (xy 43.671618 -37.539926) (xy 43.616775 -37.529796) (xy 43.563991 -37.511789)
			(xy 43.514391 -37.486288) (xy 43.469033 -37.453837) (xy 43.428884 -37.415128) (xy 43.394798 -37.370985)
			(xy 43.367502 -37.32235) (xy 43.347579 -37.270259) (xy 43.335453 -37.215822) (xy 43.331382 -37.1602)
			(xy 41.529 -37.1602) (xy 41.548304 -37.179504) (xy 42.413682 -37.179504) (xy 42.436975 -37.179936)
			(xy 42.482988 -37.187226) (xy 42.527292 -37.201629) (xy 42.568795 -37.22279) (xy 42.606474 -37.250188)
			(xy 42.623232 -37.266372) (xy 43.22826 -37.8714) (xy 43.794426 -37.8714) (xy 43.896788 -37.973508)
			(xy 44.558966 -37.973508) (xy 44.58226 -37.973939) (xy 44.628274 -37.981227) (xy 44.672579 -37.995628)
			(xy 44.714084 -38.016788) (xy 44.751765 -38.044185) (xy 44.768516 -38.060376) (xy 45.618146 -38.910006)
			(xy 45.628942 -38.920102) (xy 45.654934 -38.93415) (xy 45.683859 -38.940172) (xy 45.713297 -38.937664)
			(xy 45.740787 -38.926838) (xy 45.764029 -38.908597) (xy 45.781078 -38.884467) (xy 45.786294 -38.870636)
			(xy 45.794979 -38.846364) (xy 45.818795 -38.800648) (xy 45.849415 -38.759179) (xy 45.886097 -38.722963)
			(xy 45.927953 -38.692876) (xy 45.97397 -38.669646) (xy 46.023034 -38.653836) (xy 46.073956 -38.645828)
			(xy 46.09973 -38.645338) (xy 46.125712 -38.64585) (xy 46.177036 -38.653983) (xy 46.226455 -38.670045)
			(xy 46.272754 -38.693639) (xy 46.314792 -38.724185) (xy 46.351535 -38.760931) (xy 46.382077 -38.802972)
			(xy 46.405667 -38.849273) (xy 46.421724 -38.898694) (xy 46.429852 -38.950018) (xy 46.429852 -39.001982)
			(xy 46.429844 -39.002033) (xy 46.569632 -39.002033) (xy 46.569632 -38.950059) (xy 46.577762 -38.898724)
			(xy 46.593823 -38.849294) (xy 46.617419 -38.802984) (xy 46.647969 -38.760936) (xy 46.68472 -38.724185)
			(xy 46.726768 -38.693635) (xy 46.773078 -38.670039) (xy 46.822508 -38.653978) (xy 46.873843 -38.645848)
			(xy 46.925817 -38.645848) (xy 46.977152 -38.653978) (xy 47.026582 -38.670039) (xy 47.072892 -38.693635)
			(xy 47.11494 -38.724185) (xy 47.151691 -38.760936) (xy 47.182241 -38.802984) (xy 47.205837 -38.849294)
			(xy 47.221898 -38.898724) (xy 47.230028 -38.950059) (xy 47.230538 -38.976046) (xy 47.230028 -39.002033)
			(xy 47.369478 -39.002033) (xy 47.369478 -38.950059) (xy 47.377608 -38.898724) (xy 47.393669 -38.849294)
			(xy 47.417265 -38.802984) (xy 47.447815 -38.760936) (xy 47.484566 -38.724185) (xy 47.526614 -38.693635)
			(xy 47.572924 -38.670039) (xy 47.622354 -38.653978) (xy 47.673689 -38.645848) (xy 47.725663 -38.645848)
			(xy 47.776998 -38.653978) (xy 47.826428 -38.670039) (xy 47.872738 -38.693635) (xy 47.914786 -38.724185)
			(xy 47.951537 -38.760936) (xy 47.982087 -38.802984) (xy 48.005683 -38.849294) (xy 48.021744 -38.898724)
			(xy 48.029874 -38.950059) (xy 48.030384 -38.976046) (xy 48.029874 -39.002033) (xy 48.021744 -39.053368)
			(xy 48.005683 -39.102798) (xy 47.982087 -39.149108) (xy 47.951537 -39.191156) (xy 47.914786 -39.227907)
			(xy 47.872738 -39.258457) (xy 47.826428 -39.282053) (xy 47.776998 -39.298114) (xy 47.725663 -39.306244)
			(xy 47.673689 -39.306244) (xy 47.622354 -39.298114) (xy 47.572924 -39.282053) (xy 47.526614 -39.258457)
			(xy 47.484566 -39.227907) (xy 47.447815 -39.191156) (xy 47.417265 -39.149108) (xy 47.393669 -39.102798)
			(xy 47.377608 -39.053368) (xy 47.369478 -39.002033) (xy 47.230028 -39.002033) (xy 47.221898 -39.053368)
			(xy 47.205837 -39.102798) (xy 47.182241 -39.149108) (xy 47.151691 -39.191156) (xy 47.11494 -39.227907)
			(xy 47.072892 -39.258457) (xy 47.026582 -39.282053) (xy 46.977152 -39.298114) (xy 46.925817 -39.306244)
			(xy 46.873843 -39.306244) (xy 46.822508 -39.298114) (xy 46.773078 -39.282053) (xy 46.726768 -39.258457)
			(xy 46.68472 -39.227907) (xy 46.647969 -39.191156) (xy 46.617419 -39.149108) (xy 46.593823 -39.102798)
			(xy 46.577762 -39.053368) (xy 46.569632 -39.002033) (xy 46.429844 -39.002033) (xy 46.421724 -39.053306)
			(xy 46.405667 -39.102727) (xy 46.382077 -39.149028) (xy 46.351535 -39.191069) (xy 46.314792 -39.227815)
			(xy 46.272754 -39.258361) (xy 46.226455 -39.281955) (xy 46.177036 -39.298017) (xy 46.125712 -39.30615)
			(xy 46.09973 -39.306754) (xy 46.086208 -39.306635) (xy 46.059251 -39.304472) (xy 46.045882 -39.302436)
			(xy 46.036311 -39.301255) (xy 46.017477 -39.305323) (xy 46.001483 -39.316068) (xy 45.990598 -39.331968)
			(xy 45.986367 -39.350767) (xy 45.987462 -39.360348) (xy 45.988877 -39.370196) (xy 45.990531 -39.390025)
			(xy 45.990764 -39.399972) (xy 45.991502 -39.410856) (xy 46.000915 -39.430513) (xy 46.017604 -39.444531)
			(xy 46.038591 -39.450409) (xy 46.049438 -39.449248) (xy 46.061934 -39.447457) (xy 46.087107 -39.445551)
			(xy 46.09973 -39.445438) (xy 46.125716 -39.445923) (xy 46.177049 -39.454059) (xy 46.226476 -39.470124)
			(xy 46.272782 -39.493724) (xy 46.314826 -39.524278) (xy 46.351572 -39.561032) (xy 46.382116 -39.603083)
			(xy 46.405705 -39.649394) (xy 46.421759 -39.698825) (xy 46.429883 -39.750159) (xy 46.430438 -39.776146)
			(xy 46.43007 -39.798195) (xy 46.424202 -39.8419) (xy 46.418754 -39.863268) (xy 46.416203 -39.874491)
			(xy 46.420347 -39.897107) (xy 46.433961 -39.915636) (xy 46.4439 -39.921434) (xy 46.46297 -39.93207)
			(xy 46.498035 -39.95809) (xy 46.51375 -39.97325) (xy 46.5582 -40.0177) (xy 46.619922 -39.955978)
			(xy 46.603666 -39.923212) (xy 46.592782 -39.90024) (xy 46.577403 -39.851791) (xy 46.569603 -39.801561)
			(xy 46.569122 -39.776146) (xy 46.569601 -39.750159) (xy 46.577725 -39.698823) (xy 46.593779 -39.64939)
			(xy 46.617369 -39.603078) (xy 46.647913 -39.561026) (xy 46.68466 -39.524269) (xy 46.726704 -39.493714)
			(xy 46.77301 -39.470112) (xy 46.822439 -39.454045) (xy 46.873772 -39.445908) (xy 46.925747 -39.445902)
			(xy 46.977082 -39.454026) (xy 47.026514 -39.470081) (xy 47.072827 -39.493672) (xy 47.114878 -39.524216)
			(xy 47.151634 -39.560964) (xy 47.182189 -39.603008) (xy 47.20579 -39.649315) (xy 47.221856 -39.698744)
			(xy 47.229992 -39.750078) (xy 47.229998 -39.802052) (xy 47.229985 -39.802133) (xy 47.369478 -39.802133)
			(xy 47.369478 -39.750159) (xy 47.377608 -39.698824) (xy 47.393669 -39.649394) (xy 47.417265 -39.603084)
			(xy 47.447815 -39.561036) (xy 47.484566 -39.524285) (xy 47.526614 -39.493735) (xy 47.572924 -39.470139)
			(xy 47.622354 -39.454078) (xy 47.673689 -39.445948) (xy 47.725663 -39.445948) (xy 47.776998 -39.454078)
			(xy 47.826428 -39.470139) (xy 47.872738 -39.493735) (xy 47.914786 -39.524285) (xy 47.951537 -39.561036)
			(xy 47.982087 -39.603084) (xy 48.005683 -39.649394) (xy 48.021744 -39.698824) (xy 48.029874 -39.750159)
			(xy 48.030384 -39.776146) (xy 48.029874 -39.802133) (xy 48.021744 -39.853468) (xy 48.005683 -39.902898)
			(xy 47.982087 -39.949208) (xy 47.951537 -39.991256) (xy 47.914786 -40.028007) (xy 47.872738 -40.058557)
			(xy 47.826428 -40.082153) (xy 47.776998 -40.098214) (xy 47.725663 -40.106344) (xy 47.673689 -40.106344)
			(xy 47.622354 -40.098214) (xy 47.572924 -40.082153) (xy 47.526614 -40.058557) (xy 47.484566 -40.028007)
			(xy 47.447815 -39.991256) (xy 47.417265 -39.949208) (xy 47.393669 -39.902898) (xy 47.377608 -39.853468)
			(xy 47.369478 -39.802133) (xy 47.229985 -39.802133) (xy 47.221873 -39.853387) (xy 47.205817 -39.902819)
			(xy 47.182226 -39.949131) (xy 47.15168 -39.991183) (xy 47.114932 -40.027938) (xy 47.072887 -40.058491)
			(xy 47.02658 -40.082092) (xy 46.977151 -40.098157) (xy 46.925817 -40.106293) (xy 46.89983 -40.106854)
			(xy 46.87437 -40.106407) (xy 46.824047 -40.098635) (xy 46.775516 -40.083224) (xy 46.75251 -40.07231)
			(xy 46.743145 -40.06817) (xy 46.722725 -40.066937) (xy 46.703443 -40.073771) (xy 46.688357 -40.087588)
			(xy 46.679861 -40.106198) (xy 46.679301 -40.126647) (xy 46.686767 -40.145694) (xy 46.693582 -40.153336)
			(xy 46.710095 -40.170821) (xy 46.737789 -40.210136) (xy 46.7487 -40.231568) (xy 46.75288 -40.239448)
			(xy 46.765666 -40.251869) (xy 46.781943 -40.259136) (xy 46.799727 -40.260365) (xy 46.80839 -40.258238)
			(xy 46.830764 -40.252183) (xy 46.876655 -40.245676) (xy 46.89983 -40.245284) (xy 46.925816 -40.245796)
			(xy 46.977147 -40.25393) (xy 47.026574 -40.269994) (xy 47.07288 -40.293591) (xy 47.114925 -40.324141)
			(xy 47.151673 -40.360892) (xy 47.182221 -40.402939) (xy 47.205815 -40.449246) (xy 47.221875 -40.498674)
			(xy 47.230006 -40.550006) (xy 47.230538 -40.575992) (xy 47.368968 -40.575992) (xy 47.369484 -40.550003)
			(xy 47.377616 -40.498665) (xy 47.39368 -40.449232) (xy 47.417278 -40.40292) (xy 47.447831 -40.36087)
			(xy 47.484586 -40.324118) (xy 47.526638 -40.293567) (xy 47.572952 -40.269971) (xy 47.622386 -40.253911)
			(xy 47.673724 -40.245782) (xy 47.725702 -40.245784) (xy 47.77704 -40.253917) (xy 47.826473 -40.269982)
			(xy 47.872784 -40.293581) (xy 47.914834 -40.324135) (xy 47.951586 -40.360891) (xy 47.982136 -40.402943)
			(xy 48.005731 -40.449257) (xy 48.02179 -40.498691) (xy 48.029918 -40.55003) (xy 48.029915 -40.601979)
			(xy 48.169578 -40.601979) (xy 48.169578 -40.550005) (xy 48.177708 -40.49867) (xy 48.193769 -40.44924)
			(xy 48.217365 -40.40293) (xy 48.247915 -40.360882) (xy 48.284666 -40.324131) (xy 48.326714 -40.293581)
			(xy 48.373024 -40.269985) (xy 48.422454 -40.253924) (xy 48.473789 -40.245794) (xy 48.525763 -40.245794)
			(xy 48.577098 -40.253924) (xy 48.626528 -40.269985) (xy 48.672838 -40.293581) (xy 48.714886 -40.324131)
			(xy 48.751637 -40.360882) (xy 48.782187 -40.40293) (xy 48.805783 -40.44924) (xy 48.821844 -40.49867)
			(xy 48.829974 -40.550005) (xy 48.830484 -40.575992) (xy 48.829974 -40.601979) (xy 48.969678 -40.601979)
			(xy 48.969678 -40.550005) (xy 48.977808 -40.49867) (xy 48.993869 -40.44924) (xy 49.017465 -40.40293)
			(xy 49.048015 -40.360882) (xy 49.084766 -40.324131) (xy 49.126814 -40.293581) (xy 49.173124 -40.269985)
			(xy 49.222554 -40.253924) (xy 49.273889 -40.245794) (xy 49.325863 -40.245794) (xy 49.377198 -40.253924)
			(xy 49.426628 -40.269985) (xy 49.472938 -40.293581) (xy 49.514986 -40.324131) (xy 49.551737 -40.360882)
			(xy 49.582287 -40.40293) (xy 49.605883 -40.44924) (xy 49.621944 -40.49867) (xy 49.630074 -40.550005)
			(xy 49.630584 -40.575992) (xy 49.630074 -40.601979) (xy 49.769524 -40.601979) (xy 49.769524 -40.550005)
			(xy 49.777654 -40.49867) (xy 49.793715 -40.44924) (xy 49.817311 -40.40293) (xy 49.847861 -40.360882)
			(xy 49.884612 -40.324131) (xy 49.92666 -40.293581) (xy 49.97297 -40.269985) (xy 50.0224 -40.253924)
			(xy 50.073735 -40.245794) (xy 50.125709 -40.245794) (xy 50.177044 -40.253924) (xy 50.226474 -40.269985)
			(xy 50.272784 -40.293581) (xy 50.314832 -40.324131) (xy 50.351583 -40.360882) (xy 50.382133 -40.40293)
			(xy 50.405729 -40.44924) (xy 50.42179 -40.49867) (xy 50.42992 -40.550005) (xy 50.43043 -40.575992)
			(xy 50.42992 -40.601979) (xy 50.42179 -40.653314) (xy 50.405729 -40.702744) (xy 50.382133 -40.749054)
			(xy 50.351583 -40.791102) (xy 50.314832 -40.827853) (xy 50.272784 -40.858403) (xy 50.226474 -40.881999)
			(xy 50.177044 -40.89806) (xy 50.125709 -40.90619) (xy 50.073735 -40.90619) (xy 50.0224 -40.89806)
			(xy 49.97297 -40.881999) (xy 49.92666 -40.858403) (xy 49.884612 -40.827853) (xy 49.847861 -40.791102)
			(xy 49.817311 -40.749054) (xy 49.793715 -40.702744) (xy 49.777654 -40.653314) (xy 49.769524 -40.601979)
			(xy 49.630074 -40.601979) (xy 49.621944 -40.653314) (xy 49.605883 -40.702744) (xy 49.582287 -40.749054)
			(xy 49.551737 -40.791102) (xy 49.514986 -40.827853) (xy 49.472938 -40.858403) (xy 49.426628 -40.881999)
			(xy 49.377198 -40.89806) (xy 49.325863 -40.90619) (xy 49.273889 -40.90619) (xy 49.222554 -40.89806)
			(xy 49.173124 -40.881999) (xy 49.126814 -40.858403) (xy 49.084766 -40.827853) (xy 49.048015 -40.791102)
			(xy 49.017465 -40.749054) (xy 48.993869 -40.702744) (xy 48.977808 -40.653314) (xy 48.969678 -40.601979)
			(xy 48.829974 -40.601979) (xy 48.821844 -40.653314) (xy 48.805783 -40.702744) (xy 48.782187 -40.749054)
			(xy 48.751637 -40.791102) (xy 48.714886 -40.827853) (xy 48.672838 -40.858403) (xy 48.626528 -40.881999)
			(xy 48.577098 -40.89806) (xy 48.525763 -40.90619) (xy 48.473789 -40.90619) (xy 48.422454 -40.89806)
			(xy 48.373024 -40.881999) (xy 48.326714 -40.858403) (xy 48.284666 -40.827853) (xy 48.247915 -40.791102)
			(xy 48.217365 -40.749054) (xy 48.193769 -40.702744) (xy 48.177708 -40.653314) (xy 48.169578 -40.601979)
			(xy 48.029915 -40.601979) (xy 48.029915 -40.602008) (xy 48.021781 -40.653345) (xy 48.005716 -40.702778)
			(xy 47.982116 -40.749089) (xy 47.951562 -40.791138) (xy 47.914805 -40.827889) (xy 47.872752 -40.858438)
			(xy 47.826438 -40.882033) (xy 47.777003 -40.898091) (xy 47.725665 -40.906219) (xy 47.699676 -40.9067)
			(xy 47.671329 -40.906094) (xy 47.615466 -40.896427) (xy 47.562068 -40.87738) (xy 47.512698 -40.849511)
			(xy 47.49038 -40.832024) (xy 47.464726 -40.810942) (xy 47.443644 -40.785288) (xy 47.426162 -40.762965)
			(xy 47.398277 -40.713601) (xy 47.379221 -40.660204) (xy 47.369551 -40.60434) (xy 47.368968 -40.575992)
			(xy 47.230538 -40.575992) (xy 47.23017 -40.598549) (xy 47.22407 -40.643248) (xy 47.211953 -40.686705)
			(xy 47.20336 -40.707564) (xy 47.223155 -40.718354) (xy 47.259514 -40.745008) (xy 47.27575 -40.76065)
			(xy 47.50435 -40.98925) (xy 47.522438 -41.008149) (xy 47.552329 -41.051076) (xy 47.563786 -41.074594)
			(xy 47.585239 -41.065364) (xy 47.63009 -41.052352) (xy 47.676326 -41.045779) (xy 47.699676 -41.045384)
			(xy 47.725667 -41.045865) (xy 47.777009 -41.053994) (xy 47.826447 -41.070054) (xy 47.872764 -41.09365)
			(xy 47.914819 -41.124202) (xy 47.951578 -41.160956) (xy 47.982133 -41.203009) (xy 48.005734 -41.249323)
			(xy 48.021799 -41.29876) (xy 48.029932 -41.350101) (xy 48.030384 -41.376092) (xy 48.030271 -41.389101)
			(xy 48.02824 -41.415041) (xy 48.02632 -41.427908) (xy 48.025558 -41.431972) (xy 48.025558 -41.486836)
			(xy 48.173894 -41.486836) (xy 48.173894 -41.431972) (xy 48.173132 -41.427908) (xy 48.171232 -41.415038)
			(xy 48.1692 -41.389101) (xy 48.169068 -41.376092) (xy 48.169578 -41.350105) (xy 48.177708 -41.29877)
			(xy 48.193769 -41.24934) (xy 48.217365 -41.20303) (xy 48.247915 -41.160982) (xy 48.284666 -41.124231)
			(xy 48.326714 -41.093681) (xy 48.373024 -41.070085) (xy 48.422454 -41.054024) (xy 48.473789 -41.045894)
			(xy 48.525763 -41.045894) (xy 48.577098 -41.054024) (xy 48.626528 -41.070085) (xy 48.672838 -41.093681)
			(xy 48.714886 -41.124231) (xy 48.751637 -41.160982) (xy 48.782187 -41.20303) (xy 48.805783 -41.24934)
			(xy 48.821844 -41.29877) (xy 48.829974 -41.350105) (xy 48.830484 -41.376092) (xy 48.83008 -41.39953)
			(xy 48.823455 -41.445936) (xy 48.817276 -41.468548) (xy 48.81468 -41.47958) (xy 48.818276 -41.501925)
			(xy 48.831134 -41.520551) (xy 48.840644 -41.526714) (xy 48.857107 -41.536626) (xy 48.887557 -41.560069)
			(xy 48.90135 -41.57345) (xy 48.97374 -41.646094) (xy 49.038002 -41.581832) (xy 49.017174 -41.547796)
			(xy 49.005765 -41.528312) (xy 48.987794 -41.48689) (xy 48.975639 -41.443405) (xy 48.969525 -41.398668)
			(xy 48.969168 -41.376092) (xy 48.969652 -41.350101) (xy 48.977785 -41.298758) (xy 48.99385 -41.24932)
			(xy 49.017451 -41.203003) (xy 49.048007 -41.160949) (xy 49.084766 -41.124193) (xy 49.126822 -41.09364)
			(xy 49.17314 -41.070042) (xy 49.222579 -41.05398) (xy 49.273922 -41.04585) (xy 49.325905 -41.045852)
			(xy 49.377247 -41.053986) (xy 49.426685 -41.070052) (xy 49.473001 -41.093654) (xy 49.515055 -41.124211)
			(xy 49.55181 -41.16097) (xy 49.582363 -41.203026) (xy 49.60596 -41.249345) (xy 49.622021 -41.298784)
			(xy 49.63015 -41.350127) (xy 49.630147 -41.402079) (xy 49.769524 -41.402079) (xy 49.769524 -41.350105)
			(xy 49.777654 -41.29877) (xy 49.793715 -41.24934) (xy 49.817311 -41.20303) (xy 49.847861 -41.160982)
			(xy 49.884612 -41.124231) (xy 49.92666 -41.093681) (xy 49.97297 -41.070085) (xy 50.0224 -41.054024)
			(xy 50.073735 -41.045894) (xy 50.125709 -41.045894) (xy 50.177044 -41.054024) (xy 50.226474 -41.070085)
			(xy 50.272784 -41.093681) (xy 50.314832 -41.124231) (xy 50.351583 -41.160982) (xy 50.382133 -41.20303)
			(xy 50.405729 -41.24934) (xy 50.42179 -41.29877) (xy 50.42992 -41.350105) (xy 50.43043 -41.376092)
			(xy 50.42992 -41.402079) (xy 50.569624 -41.402079) (xy 50.569624 -41.350105) (xy 50.577754 -41.29877)
			(xy 50.593815 -41.24934) (xy 50.617411 -41.20303) (xy 50.647961 -41.160982) (xy 50.684712 -41.124231)
			(xy 50.72676 -41.093681) (xy 50.77307 -41.070085) (xy 50.8225 -41.054024) (xy 50.873835 -41.045894)
			(xy 50.925809 -41.045894) (xy 50.977144 -41.054024) (xy 51.026574 -41.070085) (xy 51.072884 -41.093681)
			(xy 51.114932 -41.124231) (xy 51.151683 -41.160982) (xy 51.182233 -41.20303) (xy 51.205829 -41.24934)
			(xy 51.22189 -41.29877) (xy 51.23002 -41.350105) (xy 51.23053 -41.376092) (xy 51.23002 -41.402079)
			(xy 51.22189 -41.453414) (xy 51.205829 -41.502844) (xy 51.182233 -41.549154) (xy 51.151683 -41.591202)
			(xy 51.114932 -41.627953) (xy 51.072884 -41.658503) (xy 51.026574 -41.682099) (xy 50.977144 -41.69816)
			(xy 50.925809 -41.70629) (xy 50.873835 -41.70629) (xy 50.8225 -41.69816) (xy 50.77307 -41.682099)
			(xy 50.72676 -41.658503) (xy 50.684712 -41.627953) (xy 50.647961 -41.591202) (xy 50.617411 -41.549154)
			(xy 50.593815 -41.502844) (xy 50.577754 -41.453414) (xy 50.569624 -41.402079) (xy 50.42992 -41.402079)
			(xy 50.42179 -41.453414) (xy 50.405729 -41.502844) (xy 50.382133 -41.549154) (xy 50.351583 -41.591202)
			(xy 50.314832 -41.627953) (xy 50.272784 -41.658503) (xy 50.226474 -41.682099) (xy 50.177044 -41.69816)
			(xy 50.125709 -41.70629) (xy 50.073735 -41.70629) (xy 50.0224 -41.69816) (xy 49.97297 -41.682099)
			(xy 49.92666 -41.658503) (xy 49.884612 -41.627953) (xy 49.847861 -41.591202) (xy 49.817311 -41.549154)
			(xy 49.793715 -41.502844) (xy 49.777654 -41.453414) (xy 49.769524 -41.402079) (xy 49.630147 -41.402079)
			(xy 49.630147 -41.40211) (xy 49.622012 -41.453452) (xy 49.605946 -41.50289) (xy 49.582343 -41.549206)
			(xy 49.551786 -41.591259) (xy 49.515026 -41.628014) (xy 49.472969 -41.658566) (xy 49.426651 -41.682162)
			(xy 49.377211 -41.698222) (xy 49.325867 -41.706351) (xy 49.299876 -41.7068) (xy 49.277304 -41.70641)
			(xy 49.232579 -41.700265) (xy 49.189103 -41.688105) (xy 49.14768 -41.670156) (xy 49.128172 -41.658794)
			(xy 49.094136 -41.637966) (xy 49.029874 -41.702228) (xy 49.12995 -41.80205) (xy 49.1443 -41.816921)
			(xy 49.169162 -41.849931) (xy 49.17948 -41.867836) (xy 49.208451 -41.857275) (xy 49.269048 -41.845897)
			(xy 49.299876 -41.84523) (xy 49.325864 -41.845711) (xy 49.377199 -41.853839) (xy 49.426631 -41.869897)
			(xy 49.472942 -41.893491) (xy 49.514992 -41.924039) (xy 49.551746 -41.960789) (xy 49.582297 -42.002837)
			(xy 49.605894 -42.049147) (xy 49.621956 -42.098578) (xy 49.630087 -42.149913) (xy 49.630087 -42.201887)
			(xy 49.630081 -42.201925) (xy 49.769524 -42.201925) (xy 49.769524 -42.149951) (xy 49.777654 -42.098616)
			(xy 49.793715 -42.049186) (xy 49.817311 -42.002876) (xy 49.847861 -41.960828) (xy 49.884612 -41.924077)
			(xy 49.92666 -41.893527) (xy 49.97297 -41.869931) (xy 50.0224 -41.85387) (xy 50.073735 -41.84574)
			(xy 50.125709 -41.84574) (xy 50.177044 -41.85387) (xy 50.226474 -41.869931) (xy 50.272784 -41.893527)
			(xy 50.314832 -41.924077) (xy 50.351583 -41.960828) (xy 50.382133 -42.002876) (xy 50.405729 -42.049186)
			(xy 50.42179 -42.098616) (xy 50.42992 -42.149951) (xy 50.43043 -42.175938) (xy 50.42992 -42.201925)
			(xy 50.569624 -42.201925) (xy 50.569624 -42.149951) (xy 50.577754 -42.098616) (xy 50.593815 -42.049186)
			(xy 50.617411 -42.002876) (xy 50.647961 -41.960828) (xy 50.684712 -41.924077) (xy 50.72676 -41.893527)
			(xy 50.77307 -41.869931) (xy 50.8225 -41.85387) (xy 50.873835 -41.84574) (xy 50.925809 -41.84574)
			(xy 50.977144 -41.85387) (xy 51.026574 -41.869931) (xy 51.072884 -41.893527) (xy 51.114932 -41.924077)
			(xy 51.151683 -41.960828) (xy 51.182233 -42.002876) (xy 51.205829 -42.049186) (xy 51.22189 -42.098616)
			(xy 51.23002 -42.149951) (xy 51.23053 -42.175938) (xy 51.23002 -42.201925) (xy 51.22189 -42.25326)
			(xy 51.205829 -42.30269) (xy 51.182233 -42.349) (xy 51.151683 -42.391048) (xy 51.114932 -42.427799)
			(xy 51.072884 -42.458349) (xy 51.026574 -42.481945) (xy 50.977144 -42.498006) (xy 50.925809 -42.506136)
			(xy 50.873835 -42.506136) (xy 50.8225 -42.498006) (xy 50.77307 -42.481945) (xy 50.72676 -42.458349)
			(xy 50.684712 -42.427799) (xy 50.647961 -42.391048) (xy 50.617411 -42.349) (xy 50.593815 -42.30269)
			(xy 50.577754 -42.25326) (xy 50.569624 -42.201925) (xy 50.42992 -42.201925) (xy 50.42179 -42.25326)
			(xy 50.405729 -42.30269) (xy 50.382133 -42.349) (xy 50.351583 -42.391048) (xy 50.314832 -42.427799)
			(xy 50.272784 -42.458349) (xy 50.226474 -42.481945) (xy 50.177044 -42.498006) (xy 50.125709 -42.506136)
			(xy 50.073735 -42.506136) (xy 50.0224 -42.498006) (xy 49.97297 -42.481945) (xy 49.92666 -42.458349)
			(xy 49.884612 -42.427799) (xy 49.847861 -42.391048) (xy 49.817311 -42.349) (xy 49.793715 -42.30269)
			(xy 49.777654 -42.25326) (xy 49.769524 -42.201925) (xy 49.630081 -42.201925) (xy 49.621956 -42.253222)
			(xy 49.605894 -42.302653) (xy 49.582297 -42.348963) (xy 49.551746 -42.391011) (xy 49.514992 -42.427761)
			(xy 49.472942 -42.458309) (xy 49.426631 -42.481903) (xy 49.377199 -42.497961) (xy 49.325864 -42.506089)
			(xy 49.299876 -42.506646) (xy 49.271682 -42.505376) (xy 49.261093 -42.504997) (xy 49.241066 -42.511838)
			(xy 49.225507 -42.526184) (xy 49.217067 -42.545591) (xy 49.216564 -42.556176) (xy 49.216564 -42.5958)
			(xy 49.217107 -42.60636) (xy 49.225607 -42.625697) (xy 49.241143 -42.640008) (xy 49.261111 -42.646896)
			(xy 49.271682 -42.6466) (xy 49.299876 -42.64533) (xy 49.325865 -42.645811) (xy 49.377205 -42.65394)
			(xy 49.42664 -42.67) (xy 49.472954 -42.693598) (xy 49.515005 -42.72415) (xy 49.551759 -42.760905)
			(xy 49.58231 -42.802958) (xy 49.605905 -42.849273) (xy 49.621963 -42.898709) (xy 49.63009 -42.950049)
			(xy 49.630584 -42.976038) (xy 49.630148 -43.000388) (xy 49.629905 -43.002025) (xy 50.569624 -43.002025)
			(xy 50.569624 -42.950051) (xy 50.577754 -42.898716) (xy 50.593815 -42.849286) (xy 50.617411 -42.802976)
			(xy 50.647961 -42.760928) (xy 50.684712 -42.724177) (xy 50.72676 -42.693627) (xy 50.77307 -42.670031)
			(xy 50.8225 -42.65397) (xy 50.873835 -42.64584) (xy 50.925809 -42.64584) (xy 50.977144 -42.65397)
			(xy 51.026574 -42.670031) (xy 51.072884 -42.693627) (xy 51.114932 -42.724177) (xy 51.151683 -42.760928)
			(xy 51.182233 -42.802976) (xy 51.205829 -42.849286) (xy 51.22189 -42.898716) (xy 51.23002 -42.950051)
			(xy 51.23053 -42.976038) (xy 51.23002 -43.002025) (xy 51.22189 -43.05336) (xy 51.205829 -43.10279)
			(xy 51.182233 -43.1491) (xy 51.151683 -43.191148) (xy 51.114932 -43.227899) (xy 51.072884 -43.258449)
			(xy 51.026574 -43.282045) (xy 50.977144 -43.298106) (xy 50.925809 -43.306236) (xy 50.873835 -43.306236)
			(xy 50.8225 -43.298106) (xy 50.77307 -43.282045) (xy 50.72676 -43.258449) (xy 50.684712 -43.227899)
			(xy 50.647961 -43.191148) (xy 50.617411 -43.1491) (xy 50.593815 -43.10279) (xy 50.577754 -43.05336)
			(xy 50.569624 -43.002025) (xy 49.629905 -43.002025) (xy 49.623 -43.048559) (xy 49.608865 -43.095162)
			(xy 49.588047 -43.139187) (xy 49.560997 -43.179683) (xy 49.544986 -43.198034) (xy 49.534967 -43.209887)
			(xy 49.521956 -43.238047) (xy 49.517979 -43.268812) (xy 49.523401 -43.299355) (xy 49.537725 -43.326871)
			(xy 49.548288 -43.338242) (xy 49.73955 -43.52925) (xy 49.755694 -43.54603) (xy 49.783033 -43.583721)
			(xy 49.804137 -43.625226) (xy 49.818486 -43.669522) (xy 49.825726 -43.715518) (xy 49.826164 -43.7388)
			(xy 49.826164 -43.903392) (xy 49.845468 -43.922442) (xy 49.845468 -44.729146) (xy 49.945798 -44.829476)
			(xy 51.27752 -44.829476)
		)
		(stroke
			(width 0)
			(type solid)
		)
		(fill yes)
		(layer "In9.Cu")
		(net "P3V3_P1V8_SD2VDD")
	)
	(gr_poly
		(pts
			(xy 55.03291 -44.758864) (xy 55.043149 -44.747877) (xy 55.0573 -44.721404) (xy 55.063146 -44.691962)
			(xy 55.060184 -44.662091) (xy 55.048668 -44.63437) (xy 55.039514 -44.622466) (xy 55.021908 -44.600092)
			(xy 54.99384 -44.550564) (xy 54.974661 -44.496964) (xy 54.964935 -44.440872) (xy 54.96433 -44.412408)
			(xy 54.964864 -44.385768) (xy 54.973403 -44.333178) (xy 54.990262 -44.282637) (xy 55.015003 -44.235451)
			(xy 55.046989 -44.192841) (xy 55.085391 -44.15591) (xy 55.129216 -44.125612) (xy 55.153052 -44.113704)
			(xy 55.153052 -43.74515) (xy 54.914292 -43.50639) (xy 54.892774 -43.484243) (xy 54.854291 -43.435948)
			(xy 54.821456 -43.38365) (xy 54.794682 -43.328004) (xy 54.774306 -43.269711) (xy 54.760582 -43.209503)
			(xy 54.753685 -43.148138) (xy 54.753256 -43.117262) (xy 54.753256 -39.49954) (xy 54.753704 -39.466661)
			(xy 54.761483 -39.401367) (xy 54.776993 -39.337466) (xy 54.788054 -39.3065) (xy 54.799484 -39.275766)
			(xy 48.734218 -33.2105) (xy 48.707802 -33.21558) (xy 48.690123 -33.218693) (xy 48.654378 -33.221999)
			(xy 48.636428 -33.222184) (xy 48.609174 -33.221723) (xy 48.555222 -33.213969) (xy 48.502922 -33.198615)
			(xy 48.45334 -33.175974) (xy 48.407485 -33.146506) (xy 48.366291 -33.110812) (xy 48.330596 -33.069618)
			(xy 48.301128 -33.023764) (xy 48.278487 -32.974182) (xy 48.263132 -32.921882) (xy 48.255378 -32.86793)
			(xy 48.25492 -32.840676) (xy 48.255092 -32.822726) (xy 48.258403 -32.78698) (xy 48.261524 -32.769302)
			(xy 48.266604 -32.742886) (xy 47.701962 -32.178244) (xy 47.692375 -32.16922) (xy 47.669635 -32.155972)
			(xy 47.644258 -32.148997) (xy 47.617941 -32.148763) (xy 47.592443 -32.155284) (xy 47.569471 -32.168125)
			(xy 47.559722 -32.176974) (xy 47.538267 -32.196937) (xy 47.490373 -32.230704) (xy 47.437877 -32.256746)
			(xy 47.382014 -32.274451) (xy 47.324101 -32.283401) (xy 47.2948 -32.283908) (xy 47.267549 -32.283422)
			(xy 47.213601 -32.275666) (xy 47.161306 -32.260311) (xy 47.111729 -32.237669) (xy 47.065879 -32.208203)
			(xy 47.024688 -32.172512) (xy 46.988997 -32.131321) (xy 46.959531 -32.085471) (xy 46.936889 -32.035894)
			(xy 46.921534 -31.983599) (xy 46.913778 -31.929651) (xy 46.913292 -31.9024) (xy 46.913792 -31.874311)
			(xy 46.922035 -31.81874) (xy 46.938342 -31.76498) (xy 46.962361 -31.714195) (xy 46.977554 -31.690564)
			(xy 46.985076 -31.678427) (xy 46.993727 -31.651226) (xy 46.994506 -31.622694) (xy 46.987354 -31.595061)
			(xy 46.972829 -31.57049) (xy 46.952068 -31.550903) (xy 46.926695 -31.537831) (xy 46.912784 -31.534608)
			(xy 44.157392 -30.986222) (xy 44.140747 -30.982731) (xy 44.108179 -30.97293) (xy 44.092368 -30.966664)
			(xy 43.63212 -30.776164) (xy 43.61127 -30.7671) (xy 43.571935 -30.7443) (xy 43.535914 -30.716559)
			(xy 43.519598 -30.700726) (xy 42.762678 -29.94406) (xy 41.666668 -29.94406) (xy 41.652444 -29.971238)
			(xy 41.639131 -29.995461) (xy 41.606587 -30.040135) (xy 41.567937 -30.079645) (xy 41.52399 -30.113165)
			(xy 41.475666 -30.139993) (xy 41.423977 -30.159568) (xy 41.370004 -30.171478) (xy 41.314878 -30.175477)
			(xy 41.259752 -30.171478) (xy 41.205779 -30.159568) (xy 41.15409 -30.139993) (xy 41.105766 -30.113165)
			(xy 41.061819 -30.079645) (xy 41.023169 -30.040135) (xy 40.990625 -29.995461) (xy 40.977312 -29.971238)
			(xy 40.963088 -29.94406) (xy 40.438324 -29.94406) (xy 40.415705 -29.957435) (xy 40.367575 -29.978527)
			(xy 40.317006 -29.992814) (xy 40.264954 -30.000025) (xy 40.212406 -30.000025) (xy 40.160354 -29.992814)
			(xy 40.109785 -29.978527) (xy 40.061655 -29.957435) (xy 40.039036 -29.94406) (xy 39.716202 -29.94406)
			(xy 39.692583 -29.959192) (xy 39.641847 -29.983114) (xy 39.588156 -29.999354) (xy 39.532667 -30.007563)
			(xy 39.476573 -30.007563) (xy 39.421084 -29.999354) (xy 39.367393 -29.983114) (xy 39.316657 -29.959192)
			(xy 39.293038 -29.94406) (xy 38.70198 -29.94406) (xy 38.693344 -29.947362) (xy 38.671539 -29.955322)
			(xy 38.626486 -29.966508) (xy 38.58041 -29.972154) (xy 38.5572 -29.972508) (xy 38.526897 -29.971921)
			(xy 38.467051 -29.962346) (xy 38.438074 -29.953458) (xy 38.430454 -29.950918) (xy 37.843714 -29.950918)
			(xy 36.795202 -30.99943) (xy 36.791646 -31.012384) (xy 36.783695 -31.03953) (xy 36.760892 -31.091293)
			(xy 36.730696 -31.139123) (xy 36.69377 -31.18197) (xy 36.650923 -31.218896) (xy 36.603093 -31.249092)
			(xy 36.55133 -31.271895) (xy 36.524184 -31.279846) (xy 36.51123 -31.283402) (xy 35.957002 -31.83763)
			(xy 35.957002 -31.927038) (xy 37.418518 -31.927038) (xy 37.419002 -31.899668) (xy 37.426815 -31.84549)
			(xy 37.442299 -31.792987) (xy 37.465137 -31.74324) (xy 37.494858 -31.697272) (xy 37.512498 -31.67634)
			(xy 37.521698 -31.664986) (xy 37.533881 -31.638438) (xy 37.53806 -31.609529) (xy 37.533897 -31.580618)
			(xy 37.52173 -31.554063) (xy 37.512498 -31.542736) (xy 37.494862 -31.521801) (xy 37.46515 -31.475829)
			(xy 37.442313 -31.426082) (xy 37.426821 -31.373582) (xy 37.418992 -31.319407) (xy 37.418518 -31.292038)
			(xy 37.419004 -31.264787) (xy 37.42676 -31.210839) (xy 37.442115 -31.158544) (xy 37.464757 -31.108967)
			(xy 37.494223 -31.063117) (xy 37.529914 -31.021926) (xy 37.571105 -30.986235) (xy 37.616955 -30.956769)
			(xy 37.666532 -30.934127) (xy 37.718827 -30.918772) (xy 37.772775 -30.911016) (xy 37.827277 -30.911016)
			(xy 37.881225 -30.918772) (xy 37.93352 -30.934127) (xy 37.983097 -30.956769) (xy 38.028947 -30.986235)
			(xy 38.070138 -31.021926) (xy 38.105829 -31.063117) (xy 38.135295 -31.108967) (xy 38.157937 -31.158544)
			(xy 38.173292 -31.210839) (xy 38.181048 -31.264787) (xy 38.181534 -31.292038) (xy 38.181048 -31.319408)
			(xy 38.173237 -31.373587) (xy 38.157754 -31.42609) (xy 38.134916 -31.475837) (xy 38.105194 -31.521804)
			(xy 38.087554 -31.542736) (xy 38.078284 -31.554037) (xy 38.066116 -31.580605) (xy 38.061953 -31.609529)
			(xy 38.066133 -31.63845) (xy 38.078315 -31.665011) (xy 38.087554 -31.67634) (xy 38.105171 -31.69729)
			(xy 38.123319 -31.725362) (xy 39.314626 -31.725362) (xy 39.318697 -31.66974) (xy 39.330823 -31.615303)
			(xy 39.350746 -31.563212) (xy 39.378042 -31.514577) (xy 39.412128 -31.470434) (xy 39.452277 -31.431725)
			(xy 39.497635 -31.399274) (xy 39.547235 -31.373773) (xy 39.600019 -31.355766) (xy 39.654862 -31.345636)
			(xy 39.710596 -31.343599) (xy 39.766033 -31.349699) (xy 39.81999 -31.363805) (xy 39.871319 -31.385617)
			(xy 39.918925 -31.414671) (xy 39.961793 -31.450346) (xy 39.99901 -31.491883) (xy 40.029783 -31.538396)
			(xy 40.053455 -31.588893) (xy 40.069523 -31.6423) (xy 40.077643 -31.697476) (xy 40.078152 -31.725362)
			(xy 40.077643 -31.753248) (xy 40.070271 -31.80334) (xy 44.461682 -31.80334) (xy 44.465753 -31.747718)
			(xy 44.477879 -31.693281) (xy 44.497802 -31.64119) (xy 44.525098 -31.592555) (xy 44.559184 -31.548412)
			(xy 44.599333 -31.509703) (xy 44.644691 -31.477252) (xy 44.694291 -31.451751) (xy 44.747075 -31.433744)
			(xy 44.801918 -31.423614) (xy 44.857652 -31.421577) (xy 44.913089 -31.427677) (xy 44.967046 -31.441783)
			(xy 45.018375 -31.463595) (xy 45.065981 -31.492649) (xy 45.108849 -31.528324) (xy 45.146066 -31.569861)
			(xy 45.176839 -31.616374) (xy 45.200511 -31.666871) (xy 45.216579 -31.720278) (xy 45.224699 -31.775454)
			(xy 45.225208 -31.80334) (xy 45.224699 -31.831226) (xy 45.216579 -31.886402) (xy 45.200511 -31.939809)
			(xy 45.176839 -31.990306) (xy 45.146066 -32.036819) (xy 45.108849 -32.078356) (xy 45.065981 -32.114031)
			(xy 45.018375 -32.143085) (xy 44.967046 -32.164897) (xy 44.913089 -32.179003) (xy 44.857652 -32.185103)
			(xy 44.801918 -32.183066) (xy 44.747075 -32.172936) (xy 44.694291 -32.154929) (xy 44.644691 -32.129428)
			(xy 44.599333 -32.096977) (xy 44.559184 -32.058268) (xy 44.525098 -32.014125) (xy 44.497802 -31.96549)
			(xy 44.477879 -31.913399) (xy 44.465753 -31.858962) (xy 44.461682 -31.80334) (xy 40.070271 -31.80334)
			(xy 40.069523 -31.808424) (xy 40.053455 -31.861831) (xy 40.029783 -31.912328) (xy 39.99901 -31.958841)
			(xy 39.961793 -32.000378) (xy 39.918925 -32.036053) (xy 39.871319 -32.065107) (xy 39.81999 -32.086919)
			(xy 39.766033 -32.101025) (xy 39.710596 -32.107125) (xy 39.654862 -32.105088) (xy 39.600019 -32.094958)
			(xy 39.547235 -32.076951) (xy 39.497635 -32.05145) (xy 39.452277 -32.018999) (xy 39.412128 -31.98029)
			(xy 39.378042 -31.936147) (xy 39.350746 -31.887512) (xy 39.330823 -31.835421) (xy 39.318697 -31.780984)
			(xy 39.314626 -31.725362) (xy 38.123319 -31.725362) (xy 38.134888 -31.743257) (xy 38.157729 -31.793)
			(xy 38.173225 -31.845497) (xy 38.181058 -31.89967) (xy 38.181534 -31.927038) (xy 38.181048 -31.954289)
			(xy 38.173292 -32.008237) (xy 38.157937 -32.060532) (xy 38.135295 -32.110109) (xy 38.105829 -32.155959)
			(xy 38.070138 -32.19715) (xy 38.028947 -32.232841) (xy 37.983097 -32.262307) (xy 37.93352 -32.284949)
			(xy 37.881225 -32.300304) (xy 37.827277 -32.30806) (xy 37.772775 -32.30806) (xy 37.718827 -32.300304)
			(xy 37.666532 -32.284949) (xy 37.616955 -32.262307) (xy 37.571105 -32.232841) (xy 37.529914 -32.19715)
			(xy 37.494223 -32.155959) (xy 37.464757 -32.110109) (xy 37.442115 -32.060532) (xy 37.42676 -32.008237)
			(xy 37.419004 -31.954289) (xy 37.418518 -31.927038) (xy 35.957002 -31.927038) (xy 35.957002 -34.84118)
			(xy 36.093908 -34.978086) (xy 36.564062 -34.978086) (xy 36.572698 -34.96945) (xy 37.681662 -34.96945)
			(xy 37.694362 -34.937192) (xy 37.704092 -34.913708) (xy 37.728887 -34.86933) (xy 37.759358 -34.828641)
			(xy 37.794965 -34.792361) (xy 37.814758 -34.77641) (xy 37.826566 -34.766514) (xy 37.844088 -34.741191)
			(xy 37.853267 -34.711797) (xy 37.853267 -34.681003) (xy 37.844088 -34.651609) (xy 37.826566 -34.626286)
			(xy 37.814758 -34.61639) (xy 37.792268 -34.598203) (xy 37.752519 -34.556189) (xy 37.719567 -34.508656)
			(xy 37.694169 -34.456694) (xy 37.676907 -34.401493) (xy 37.668175 -34.344319) (xy 37.667692 -34.3154)
			(xy 37.668178 -34.288149) (xy 37.675934 -34.234201) (xy 37.691289 -34.181906) (xy 37.713931 -34.132329)
			(xy 37.743397 -34.086479) (xy 37.779088 -34.045288) (xy 37.820279 -34.009597) (xy 37.866129 -33.980131)
			(xy 37.915706 -33.957489) (xy 37.968001 -33.942134) (xy 38.021949 -33.934378) (xy 38.076451 -33.934378)
			(xy 38.130399 -33.942134) (xy 38.182694 -33.957489) (xy 38.232271 -33.980131) (xy 38.278121 -34.009597)
			(xy 38.319312 -34.045288) (xy 38.355003 -34.086479) (xy 38.384469 -34.132329) (xy 38.407111 -34.181906)
			(xy 38.422466 -34.234201) (xy 38.430222 -34.288149) (xy 38.430708 -34.3154) (xy 38.430174 -34.344317)
			(xy 38.421447 -34.401488) (xy 38.404193 -34.456688) (xy 38.378808 -34.508652) (xy 38.345871 -34.556191)
			(xy 38.306139 -34.598215) (xy 38.283642 -34.61639) (xy 38.271834 -34.626286) (xy 38.254312 -34.651609)
			(xy 38.245133 -34.681003) (xy 38.245133 -34.711797) (xy 38.254312 -34.741191) (xy 38.271834 -34.766514)
			(xy 38.283642 -34.77641) (xy 38.2972 -34.787196) (xy 38.322514 -34.810853) (xy 38.334188 -34.823654)
			(xy 38.34372 -34.83367) (xy 38.366959 -34.848633) (xy 38.393359 -34.856813) (xy 38.420986 -34.857613)
			(xy 38.447816 -34.850973) (xy 38.471881 -34.837381) (xy 38.482016 -34.827972) (xy 39.033704 -34.276284)
			(xy 39.033704 -32.665416) (xy 39.46779 -32.23133) (xy 42.491406 -32.23133) (xy 42.494454 -32.183578)
			(xy 42.496761 -32.154869) (xy 42.508925 -32.098573) (xy 42.529411 -32.044745) (xy 42.557755 -31.994608)
			(xy 42.593311 -31.949299) (xy 42.635273 -31.909849) (xy 42.682687 -31.877153) (xy 42.734477 -31.851955)
			(xy 42.789465 -31.834825) (xy 42.846403 -31.826155) (xy 42.8752 -31.825692) (xy 42.903132 -31.826179)
			(xy 42.958399 -31.834324) (xy 43.011888 -31.850439) (xy 43.062456 -31.87418) (xy 43.109022 -31.905041)
			(xy 43.150591 -31.94236) (xy 43.186275 -31.985342) (xy 43.215312 -32.033067) (xy 43.23708 -32.084515)
			(xy 43.244516 -32.111442) (xy 43.248645 -32.125492) (xy 43.263707 -32.150593) (xy 43.285268 -32.170393)
			(xy 43.311557 -32.183269) (xy 43.340418 -32.188164) (xy 43.355006 -32.18688) (xy 43.366266 -32.185598)
			(xy 43.388886 -32.184199) (xy 43.400218 -32.184086) (xy 43.427469 -32.184573) (xy 43.481415 -32.192332)
			(xy 43.533708 -32.207688) (xy 43.583283 -32.23033) (xy 43.629132 -32.259797) (xy 43.67032 -32.295488)
			(xy 43.70601 -32.336678) (xy 43.735475 -32.382528) (xy 43.758116 -32.432104) (xy 43.773471 -32.484397)
			(xy 43.781228 -32.538343) (xy 43.781726 -32.565594) (xy 43.781194 -32.594856) (xy 43.772258 -32.652694)
			(xy 43.75826 -32.696912) (xy 43.954444 -32.696912) (xy 43.958515 -32.64129) (xy 43.970641 -32.586853)
			(xy 43.990564 -32.534762) (xy 44.01786 -32.486127) (xy 44.051946 -32.441984) (xy 44.092095 -32.403275)
			(xy 44.137453 -32.370824) (xy 44.187053 -32.345323) (xy 44.239837 -32.327316) (xy 44.29468 -32.317186)
			(xy 44.350414 -32.315149) (xy 44.405851 -32.321249) (xy 44.459808 -32.335355) (xy 44.511137 -32.357167)
			(xy 44.558743 -32.386221) (xy 44.601611 -32.421896) (xy 44.638828 -32.463433) (xy 44.669601 -32.509946)
			(xy 44.693273 -32.560443) (xy 44.709341 -32.61385) (xy 44.717461 -32.669026) (xy 44.71797 -32.696912)
			(xy 44.717525 -32.721296) (xy 44.903642 -32.721296) (xy 44.907713 -32.665674) (xy 44.919839 -32.611237)
			(xy 44.939762 -32.559146) (xy 44.967058 -32.510511) (xy 45.001144 -32.466368) (xy 45.041293 -32.427659)
			(xy 45.086651 -32.395208) (xy 45.136251 -32.369707) (xy 45.189035 -32.3517) (xy 45.243878 -32.34157)
			(xy 45.299612 -32.339533) (xy 45.355049 -32.345633) (xy 45.409006 -32.359739) (xy 45.460335 -32.381551)
			(xy 45.507941 -32.410605) (xy 45.550809 -32.44628) (xy 45.588026 -32.487817) (xy 45.618799 -32.53433)
			(xy 45.642471 -32.584827) (xy 45.658539 -32.638234) (xy 45.666659 -32.69341) (xy 45.667168 -32.721296)
			(xy 45.666659 -32.749182) (xy 45.658539 -32.804358) (xy 45.642471 -32.857765) (xy 45.618799 -32.908262)
			(xy 45.588026 -32.954775) (xy 45.550809 -32.996312) (xy 45.507941 -33.031987) (xy 45.460335 -33.061041)
			(xy 45.409006 -33.082853) (xy 45.355049 -33.096959) (xy 45.299612 -33.103059) (xy 45.243878 -33.101022)
			(xy 45.189035 -33.090892) (xy 45.136251 -33.072885) (xy 45.086651 -33.047384) (xy 45.041293 -33.014933)
			(xy 45.001144 -32.976224) (xy 44.967058 -32.932081) (xy 44.939762 -32.883446) (xy 44.919839 -32.831355)
			(xy 44.907713 -32.776918) (xy 44.903642 -32.721296) (xy 44.717525 -32.721296) (xy 44.717461 -32.724798)
			(xy 44.709341 -32.779974) (xy 44.693273 -32.833381) (xy 44.669601 -32.883878) (xy 44.638828 -32.930391)
			(xy 44.601611 -32.971928) (xy 44.558743 -33.007603) (xy 44.511137 -33.036657) (xy 44.459808 -33.058469)
			(xy 44.405851 -33.072575) (xy 44.350414 -33.078675) (xy 44.29468 -33.076638) (xy 44.239837 -33.066508)
			(xy 44.187053 -33.048501) (xy 44.137453 -33.023) (xy 44.092095 -32.990549) (xy 44.051946 -32.95184)
			(xy 44.01786 -32.907697) (xy 43.990564 -32.859062) (xy 43.970641 -32.806971) (xy 43.958515 -32.752534)
			(xy 43.954444 -32.696912) (xy 43.75826 -32.696912) (xy 43.754595 -32.708489) (xy 43.728618 -32.760932)
			(xy 43.694937 -32.808793) (xy 43.675046 -32.830262) (xy 43.640248 -32.86633) (xy 44.087542 -33.31337)
			(xy 44.12107 -33.294828) (xy 44.142434 -33.283348) (xy 44.187446 -33.265291) (xy 44.234386 -33.25309)
			(xy 44.282494 -33.246943) (xy 44.306744 -33.246568) (xy 44.333994 -33.247057) (xy 44.387938 -33.254818)
			(xy 44.440229 -33.270177) (xy 44.489802 -33.29282) (xy 44.535649 -33.322287) (xy 44.576836 -33.357978)
			(xy 44.612525 -33.399167) (xy 44.641989 -33.445015) (xy 44.66463 -33.49459) (xy 44.679986 -33.546882)
			(xy 44.687745 -33.600826) (xy 44.688252 -33.628076) (xy 44.902118 -33.628076) (xy 44.906189 -33.572454)
			(xy 44.918315 -33.518017) (xy 44.938238 -33.465926) (xy 44.965534 -33.417291) (xy 44.99962 -33.373148)
			(xy 45.039769 -33.334439) (xy 45.085127 -33.301988) (xy 45.134727 -33.276487) (xy 45.187511 -33.25848)
			(xy 45.242354 -33.24835) (xy 45.298088 -33.246313) (xy 45.353525 -33.252413) (xy 45.407482 -33.266519)
			(xy 45.458811 -33.288331) (xy 45.506417 -33.317385) (xy 45.549285 -33.35306) (xy 45.586502 -33.394597)
			(xy 45.617275 -33.44111) (xy 45.640947 -33.491607) (xy 45.657015 -33.545014) (xy 45.665135 -33.60019)
			(xy 45.66518 -33.602676) (xy 45.872654 -33.602676) (xy 45.873124 -33.575377) (xy 45.880898 -33.521334)
			(xy 45.896298 -33.468953) (xy 45.919009 -33.419302) (xy 45.948568 -33.373397) (xy 45.98437 -33.332175)
			(xy 46.025683 -33.296479) (xy 46.048422 -33.281366) (xy 46.060357 -33.273067) (xy 46.079401 -33.251125)
			(xy 46.091501 -33.224711) (xy 46.095676 -33.195959) (xy 46.09159 -33.167194) (xy 46.079573 -33.140742)
			(xy 46.060597 -33.118742) (xy 46.048676 -33.110424) (xy 46.026082 -33.095265) (xy 45.985009 -33.059586)
			(xy 45.949421 -33.018433) (xy 45.920042 -32.972641) (xy 45.897466 -32.923139) (xy 45.882153 -32.870932)
			(xy 45.874412 -32.817079) (xy 45.873924 -32.789876) (xy 45.87441 -32.762625) (xy 45.882166 -32.708677)
			(xy 45.897521 -32.656382) (xy 45.920163 -32.606805) (xy 45.949629 -32.560955) (xy 45.98532 -32.519764)
			(xy 46.026511 -32.484073) (xy 46.072361 -32.454607) (xy 46.121938 -32.431965) (xy 46.174233 -32.41661)
			(xy 46.228181 -32.408854) (xy 46.282683 -32.408854) (xy 46.336631 -32.41661) (xy 46.388926 -32.431965)
			(xy 46.438503 -32.454607) (xy 46.484353 -32.484073) (xy 46.525544 -32.519764) (xy 46.561235 -32.560955)
			(xy 46.590701 -32.606805) (xy 46.613343 -32.656382) (xy 46.628698 -32.708677) (xy 46.636454 -32.762625)
			(xy 46.63694 -32.789876) (xy 46.636436 -32.817174) (xy 46.628669 -32.871215) (xy 46.613275 -32.923596)
			(xy 46.590569 -32.973247) (xy 46.561016 -33.019153) (xy 46.525218 -33.060375) (xy 46.483909 -33.096072)
			(xy 46.461172 -33.111186) (xy 46.449188 -33.119419) (xy 46.430142 -33.141375) (xy 46.418046 -33.167804)
			(xy 46.413877 -33.196569) (xy 46.417972 -33.225345) (xy 46.430001 -33.251805) (xy 46.44899 -33.27381)
			(xy 46.460918 -33.282128) (xy 46.483534 -33.297255) (xy 46.524608 -33.332939) (xy 46.560194 -33.374098)
			(xy 46.589571 -33.419895) (xy 46.612143 -33.469402) (xy 46.627451 -33.521614) (xy 46.635185 -33.575471)
			(xy 46.63567 -33.602676) (xy 46.635184 -33.629927) (xy 46.634318 -33.63595) (xy 47.207932 -33.63595)
			(xy 47.208421 -33.608736) (xy 47.21615 -33.554861) (xy 47.231459 -33.502631) (xy 47.254035 -33.453107)
			(xy 47.283422 -33.407295) (xy 47.319022 -33.366125) (xy 47.33925 -33.347914) (xy 47.349591 -33.338384)
			(xy 47.364959 -33.314844) (xy 47.373315 -33.288002) (xy 47.374025 -33.259898) (xy 47.367034 -33.232668)
			(xy 47.352873 -33.208382) (xy 47.34306 -33.198308) (xy 47.325062 -33.180256) (xy 47.293497 -33.140229)
			(xy 47.267542 -33.096356) (xy 47.247658 -33.049418) (xy 47.234201 -33.000251) (xy 47.227409 -32.94973)
			(xy 47.226982 -32.924242) (xy 47.227468 -32.896991) (xy 47.235224 -32.843043) (xy 47.250579 -32.790748)
			(xy 47.273221 -32.741171) (xy 47.302687 -32.695321) (xy 47.338378 -32.65413) (xy 47.379569 -32.618439)
			(xy 47.425419 -32.588973) (xy 47.474996 -32.566331) (xy 47.527291 -32.550976) (xy 47.581239 -32.54322)
			(xy 47.635741 -32.54322) (xy 47.689689 -32.550976) (xy 47.741984 -32.566331) (xy 47.791561 -32.588973)
			(xy 47.837411 -32.618439) (xy 47.878602 -32.65413) (xy 47.914293 -32.695321) (xy 47.943759 -32.741171)
			(xy 47.966401 -32.790748) (xy 47.981756 -32.843043) (xy 47.989512 -32.896991) (xy 47.989998 -32.924242)
			(xy 47.989527 -32.951457) (xy 47.981798 -33.005334) (xy 47.966487 -33.057565) (xy 47.943907 -33.10709)
			(xy 47.914516 -33.152901) (xy 47.878911 -33.194069) (xy 47.85868 -33.212278) (xy 47.848351 -33.221817)
			(xy 47.832993 -33.245358) (xy 47.824641 -33.272196) (xy 47.823931 -33.300294) (xy 47.830915 -33.32752)
			(xy 47.845063 -33.351807) (xy 47.85487 -33.361884) (xy 47.87287 -33.379935) (xy 47.904434 -33.419963)
			(xy 47.930388 -33.463836) (xy 47.950271 -33.510774) (xy 47.963728 -33.559941) (xy 47.970521 -33.610462)
			(xy 47.970948 -33.63595) (xy 47.970462 -33.663201) (xy 47.962706 -33.717149) (xy 47.947351 -33.769444)
			(xy 47.924709 -33.819021) (xy 47.895243 -33.864871) (xy 47.859552 -33.906062) (xy 47.818361 -33.941753)
			(xy 47.772511 -33.971219) (xy 47.722934 -33.993861) (xy 47.670639 -34.009216) (xy 47.616691 -34.016972)
			(xy 47.562189 -34.016972) (xy 47.508241 -34.009216) (xy 47.455946 -33.993861) (xy 47.406369 -33.971219)
			(xy 47.360519 -33.941753) (xy 47.319328 -33.906062) (xy 47.283637 -33.864871) (xy 47.254171 -33.819021)
			(xy 47.231529 -33.769444) (xy 47.216174 -33.717149) (xy 47.208418 -33.663201) (xy 47.207932 -33.63595)
			(xy 46.634318 -33.63595) (xy 46.627428 -33.683875) (xy 46.612073 -33.73617) (xy 46.589431 -33.785747)
			(xy 46.559965 -33.831597) (xy 46.524274 -33.872788) (xy 46.483083 -33.908479) (xy 46.437233 -33.937945)
			(xy 46.387656 -33.960587) (xy 46.335361 -33.975942) (xy 46.281413 -33.983698) (xy 46.226911 -33.983698)
			(xy 46.172963 -33.975942) (xy 46.120668 -33.960587) (xy 46.071091 -33.937945) (xy 46.025241 -33.908479)
			(xy 45.98405 -33.872788) (xy 45.948359 -33.831597) (xy 45.918893 -33.785747) (xy 45.896251 -33.73617)
			(xy 45.880896 -33.683875) (xy 45.87314 -33.629927) (xy 45.872654 -33.602676) (xy 45.66518 -33.602676)
			(xy 45.665644 -33.628076) (xy 45.665135 -33.655962) (xy 45.657015 -33.711138) (xy 45.640947 -33.764545)
			(xy 45.617275 -33.815042) (xy 45.586502 -33.861555) (xy 45.549285 -33.903092) (xy 45.506417 -33.938767)
			(xy 45.458811 -33.967821) (xy 45.407482 -33.989633) (xy 45.353525 -34.003739) (xy 45.298088 -34.009839)
			(xy 45.242354 -34.007802) (xy 45.187511 -33.997672) (xy 45.134727 -33.979665) (xy 45.085127 -33.954164)
			(xy 45.039769 -33.921713) (xy 44.99962 -33.883004) (xy 44.965534 -33.838861) (xy 44.938238 -33.790226)
			(xy 44.918315 -33.738135) (xy 44.906189 -33.683698) (xy 44.902118 -33.628076) (xy 44.688252 -33.628076)
			(xy 44.687875 -33.652326) (xy 44.681729 -33.700435) (xy 44.669532 -33.747376) (xy 44.651482 -33.792392)
			(xy 44.639992 -33.81375) (xy 44.62145 -33.847278) (xy 46.263306 -35.489134) (xy 46.274252 -35.499356)
			(xy 46.300631 -35.513506) (xy 46.32998 -35.5194) (xy 46.359777 -35.516533) (xy 46.387462 -35.505149)
			(xy 46.410659 -35.486228) (xy 46.419516 -35.474148) (xy 46.434763 -35.452247) (xy 46.470402 -35.412529)
			(xy 46.511233 -35.378169) (xy 46.556455 -35.349838) (xy 46.605187 -35.328092) (xy 46.656476 -35.313353)
			(xy 46.709318 -35.305911) (xy 46.736 -35.305492) (xy 46.763251 -35.305978) (xy 46.817199 -35.313734)
			(xy 46.869494 -35.329089) (xy 46.919071 -35.351731) (xy 46.964921 -35.381197) (xy 47.006112 -35.416888)
			(xy 47.041803 -35.458079) (xy 47.071269 -35.503929) (xy 47.093911 -35.553506) (xy 47.109266 -35.605801)
			(xy 47.117022 -35.659749) (xy 47.117055 -35.6616) (xy 47.801782 -35.6616) (xy 47.805853 -35.605978)
			(xy 47.817979 -35.551541) (xy 47.837902 -35.49945) (xy 47.865198 -35.450815) (xy 47.899284 -35.406672)
			(xy 47.939433 -35.367963) (xy 47.984791 -35.335512) (xy 48.034391 -35.310011) (xy 48.087175 -35.292004)
			(xy 48.142018 -35.281874) (xy 48.197752 -35.279837) (xy 48.253189 -35.285937) (xy 48.307146 -35.300043)
			(xy 48.358475 -35.321855) (xy 48.406081 -35.350909) (xy 48.448949 -35.386584) (xy 48.486166 -35.428121)
			(xy 48.516939 -35.474634) (xy 48.540611 -35.525131) (xy 48.556679 -35.578538) (xy 48.564799 -35.633714)
			(xy 48.565308 -35.6616) (xy 48.564799 -35.689486) (xy 48.556679 -35.744662) (xy 48.540611 -35.798069)
			(xy 48.516939 -35.848566) (xy 48.508719 -35.86099) (xy 49.54854 -35.86099) (xy 49.552611 -35.805368)
			(xy 49.564737 -35.750931) (xy 49.58466 -35.69884) (xy 49.611956 -35.650205) (xy 49.646042 -35.606062)
			(xy 49.686191 -35.567353) (xy 49.731549 -35.534902) (xy 49.781149 -35.509401) (xy 49.833933 -35.491394)
			(xy 49.888776 -35.481264) (xy 49.94451 -35.479227) (xy 49.999947 -35.485327) (xy 50.053904 -35.499433)
			(xy 50.105233 -35.521245) (xy 50.152839 -35.550299) (xy 50.195707 -35.585974) (xy 50.232924 -35.627511)
			(xy 50.263697 -35.674024) (xy 50.287369 -35.724521) (xy 50.303437 -35.777928) (xy 50.311557 -35.833104)
			(xy 50.312066 -35.86099) (xy 50.311557 -35.888876) (xy 50.303437 -35.944052) (xy 50.287369 -35.997459)
			(xy 50.263697 -36.047956) (xy 50.232924 -36.094469) (xy 50.195707 -36.136006) (xy 50.152839 -36.171681)
			(xy 50.105233 -36.200735) (xy 50.053904 -36.222547) (xy 49.999947 -36.236653) (xy 49.94451 -36.242753)
			(xy 49.888776 -36.240716) (xy 49.833933 -36.230586) (xy 49.781149 -36.212579) (xy 49.731549 -36.187078)
			(xy 49.686191 -36.154627) (xy 49.646042 -36.115918) (xy 49.611956 -36.071775) (xy 49.58466 -36.02314)
			(xy 49.564737 -35.971049) (xy 49.552611 -35.916612) (xy 49.54854 -35.86099) (xy 48.508719 -35.86099)
			(xy 48.486166 -35.895079) (xy 48.448949 -35.936616) (xy 48.406081 -35.972291) (xy 48.358475 -36.001345)
			(xy 48.307146 -36.023157) (xy 48.253189 -36.037263) (xy 48.197752 -36.043363) (xy 48.142018 -36.041326)
			(xy 48.087175 -36.031196) (xy 48.034391 -36.013189) (xy 47.984791 -35.987688) (xy 47.939433 -35.955237)
			(xy 47.899284 -35.916528) (xy 47.865198 -35.872385) (xy 47.837902 -35.82375) (xy 47.817979 -35.771659)
			(xy 47.805853 -35.717222) (xy 47.801782 -35.6616) (xy 47.117055 -35.6616) (xy 47.117508 -35.687)
			(xy 47.117062 -35.713681) (xy 47.109622 -35.766522) (xy 47.094887 -35.81781) (xy 47.073145 -35.866542)
			(xy 47.044821 -35.911767) (xy 47.010469 -35.952601) (xy 46.970759 -35.988247) (xy 46.948852 -36.003484)
			(xy 46.936715 -36.012274) (xy 46.91777 -36.035474) (xy 46.906379 -36.063176) (xy 46.903525 -36.092992)
			(xy 46.909453 -36.122352) (xy 46.923653 -36.148725) (xy 46.933866 -36.159694) (xy 49.775988 -39.002033)
			(xy 52.96967 -39.002033) (xy 52.96967 -38.950059) (xy 52.9778 -38.898724) (xy 52.993861 -38.849294)
			(xy 53.017457 -38.802984) (xy 53.048007 -38.760936) (xy 53.084758 -38.724185) (xy 53.126806 -38.693635)
			(xy 53.173116 -38.670039) (xy 53.222546 -38.653978) (xy 53.273881 -38.645848) (xy 53.325855 -38.645848)
			(xy 53.37719 -38.653978) (xy 53.42662 -38.670039) (xy 53.47293 -38.693635) (xy 53.514978 -38.724185)
			(xy 53.551729 -38.760936) (xy 53.582279 -38.802984) (xy 53.605875 -38.849294) (xy 53.621936 -38.898724)
			(xy 53.630066 -38.950059) (xy 53.630576 -38.976046) (xy 53.630066 -39.002033) (xy 53.621936 -39.053368)
			(xy 53.605875 -39.102798) (xy 53.582279 -39.149108) (xy 53.551729 -39.191156) (xy 53.514978 -39.227907)
			(xy 53.47293 -39.258457) (xy 53.42662 -39.282053) (xy 53.37719 -39.298114) (xy 53.325855 -39.306244)
			(xy 53.273881 -39.306244) (xy 53.222546 -39.298114) (xy 53.173116 -39.282053) (xy 53.126806 -39.258457)
			(xy 53.084758 -39.227907) (xy 53.048007 -39.191156) (xy 53.017457 -39.149108) (xy 52.993861 -39.102798)
			(xy 52.9778 -39.053368) (xy 52.96967 -39.002033) (xy 49.775988 -39.002033) (xy 50.261774 -39.487856)
			(xy 50.267362 -39.491158) (xy 50.291179 -39.505846) (xy 50.333944 -39.541925) (xy 50.370029 -39.584685)
			(xy 50.38471 -39.608506) (xy 50.388012 -39.614094) (xy 50.576051 -39.802133) (xy 52.16957 -39.802133)
			(xy 52.16957 -39.750159) (xy 52.1777 -39.698824) (xy 52.193761 -39.649394) (xy 52.217357 -39.603084)
			(xy 52.247907 -39.561036) (xy 52.284658 -39.524285) (xy 52.326706 -39.493735) (xy 52.373016 -39.470139)
			(xy 52.422446 -39.454078) (xy 52.473781 -39.445948) (xy 52.525755 -39.445948) (xy 52.57709 -39.454078)
			(xy 52.62652 -39.470139) (xy 52.67283 -39.493735) (xy 52.714878 -39.524285) (xy 52.751629 -39.561036)
			(xy 52.782179 -39.603084) (xy 52.805775 -39.649394) (xy 52.821836 -39.698824) (xy 52.829966 -39.750159)
			(xy 52.830476 -39.776146) (xy 52.829966 -39.802133) (xy 52.96967 -39.802133) (xy 52.96967 -39.750159)
			(xy 52.9778 -39.698824) (xy 52.993861 -39.649394) (xy 53.017457 -39.603084) (xy 53.048007 -39.561036)
			(xy 53.084758 -39.524285) (xy 53.126806 -39.493735) (xy 53.173116 -39.470139) (xy 53.222546 -39.454078)
			(xy 53.273881 -39.445948) (xy 53.325855 -39.445948) (xy 53.37719 -39.454078) (xy 53.42662 -39.470139)
			(xy 53.47293 -39.493735) (xy 53.514978 -39.524285) (xy 53.551729 -39.561036) (xy 53.582279 -39.603084)
			(xy 53.605875 -39.649394) (xy 53.621936 -39.698824) (xy 53.630066 -39.750159) (xy 53.630576 -39.776146)
			(xy 53.630066 -39.802133) (xy 53.621936 -39.853468) (xy 53.605875 -39.902898) (xy 53.582279 -39.949208)
			(xy 53.551729 -39.991256) (xy 53.514978 -40.028007) (xy 53.47293 -40.058557) (xy 53.42662 -40.082153)
			(xy 53.37719 -40.098214) (xy 53.325855 -40.106344) (xy 53.273881 -40.106344) (xy 53.222546 -40.098214)
			(xy 53.173116 -40.082153) (xy 53.126806 -40.058557) (xy 53.084758 -40.028007) (xy 53.048007 -39.991256)
			(xy 53.017457 -39.949208) (xy 52.993861 -39.902898) (xy 52.9778 -39.853468) (xy 52.96967 -39.802133)
			(xy 52.829966 -39.802133) (xy 52.821836 -39.853468) (xy 52.805775 -39.902898) (xy 52.782179 -39.949208)
			(xy 52.751629 -39.991256) (xy 52.714878 -40.028007) (xy 52.67283 -40.058557) (xy 52.62652 -40.082153)
			(xy 52.57709 -40.098214) (xy 52.525755 -40.106344) (xy 52.473781 -40.106344) (xy 52.422446 -40.098214)
			(xy 52.373016 -40.082153) (xy 52.326706 -40.058557) (xy 52.284658 -40.028007) (xy 52.247907 -39.991256)
			(xy 52.217357 -39.949208) (xy 52.193761 -39.902898) (xy 52.1777 -39.853468) (xy 52.16957 -39.802133)
			(xy 50.576051 -39.802133) (xy 51.061112 -40.287194) (xy 51.066954 -40.290496) (xy 51.091031 -40.305294)
			(xy 51.134209 -40.341751) (xy 51.170581 -40.385) (xy 51.185318 -40.409114) (xy 51.18862 -40.414702)
			(xy 51.23688 -40.462962) (xy 51.247024 -40.472505) (xy 51.271288 -40.486158) (xy 51.298337 -40.492755)
			(xy 51.326162 -40.491806) (xy 51.352699 -40.483382) (xy 51.375977 -40.468109) (xy 51.394269 -40.44712)
			(xy 51.40071 -40.434768) (xy 51.412578 -40.410853) (xy 51.442845 -40.366877) (xy 51.479779 -40.328329)
			(xy 51.522421 -40.29621) (xy 51.569666 -40.271352) (xy 51.620288 -40.2544) (xy 51.672976 -40.245794)
			(xy 51.699668 -40.245284) (xy 51.725659 -40.245765) (xy 51.777002 -40.253892) (xy 51.826441 -40.269951)
			(xy 51.87276 -40.293547) (xy 51.914816 -40.324099) (xy 51.951575 -40.360853) (xy 51.982132 -40.402906)
			(xy 52.005733 -40.449222) (xy 52.021799 -40.498659) (xy 52.029932 -40.550001) (xy 52.030376 -40.575992)
			(xy 52.029948 -40.600373) (xy 52.02971 -40.601979) (xy 52.16957 -40.601979) (xy 52.16957 -40.550005)
			(xy 52.1777 -40.49867) (xy 52.193761 -40.44924) (xy 52.217357 -40.40293) (xy 52.247907 -40.360882)
			(xy 52.284658 -40.324131) (xy 52.326706 -40.293581) (xy 52.373016 -40.269985) (xy 52.422446 -40.253924)
			(xy 52.473781 -40.245794) (xy 52.525755 -40.245794) (xy 52.57709 -40.253924) (xy 52.62652 -40.269985)
			(xy 52.67283 -40.293581) (xy 52.714878 -40.324131) (xy 52.751629 -40.360882) (xy 52.782179 -40.40293)
			(xy 52.805775 -40.44924) (xy 52.821836 -40.49867) (xy 52.829966 -40.550005) (xy 52.830476 -40.575992)
			(xy 52.829966 -40.601979) (xy 52.96967 -40.601979) (xy 52.96967 -40.550005) (xy 52.9778 -40.49867)
			(xy 52.993861 -40.44924) (xy 53.017457 -40.40293) (xy 53.048007 -40.360882) (xy 53.084758 -40.324131)
			(xy 53.126806 -40.293581) (xy 53.173116 -40.269985) (xy 53.222546 -40.253924) (xy 53.273881 -40.245794)
			(xy 53.325855 -40.245794) (xy 53.37719 -40.253924) (xy 53.42662 -40.269985) (xy 53.47293 -40.293581)
			(xy 53.514978 -40.324131) (xy 53.551729 -40.360882) (xy 53.582279 -40.40293) (xy 53.605875 -40.44924)
			(xy 53.621936 -40.49867) (xy 53.630066 -40.550005) (xy 53.630576 -40.575992) (xy 53.630066 -40.601979)
			(xy 53.621936 -40.653314) (xy 53.605875 -40.702744) (xy 53.582279 -40.749054) (xy 53.551729 -40.791102)
			(xy 53.514978 -40.827853) (xy 53.47293 -40.858403) (xy 53.42662 -40.881999) (xy 53.37719 -40.89806)
			(xy 53.325855 -40.90619) (xy 53.273881 -40.90619) (xy 53.222546 -40.89806) (xy 53.173116 -40.881999)
			(xy 53.126806 -40.858403) (xy 53.084758 -40.827853) (xy 53.048007 -40.791102) (xy 53.017457 -40.749054)
			(xy 52.993861 -40.702744) (xy 52.9778 -40.653314) (xy 52.96967 -40.601979) (xy 52.829966 -40.601979)
			(xy 52.821836 -40.653314) (xy 52.805775 -40.702744) (xy 52.782179 -40.749054) (xy 52.751629 -40.791102)
			(xy 52.714878 -40.827853) (xy 52.67283 -40.858403) (xy 52.62652 -40.881999) (xy 52.57709 -40.89806)
			(xy 52.525755 -40.90619) (xy 52.473781 -40.90619) (xy 52.422446 -40.89806) (xy 52.373016 -40.881999)
			(xy 52.326706 -40.858403) (xy 52.284658 -40.827853) (xy 52.247907 -40.791102) (xy 52.217357 -40.749054)
			(xy 52.193761 -40.702744) (xy 52.1777 -40.653314) (xy 52.16957 -40.601979) (xy 52.02971 -40.601979)
			(xy 52.022799 -40.648608) (xy 52.008639 -40.695269) (xy 51.987776 -40.739343) (xy 51.960663 -40.779873)
			(xy 51.927889 -40.815979) (xy 51.890166 -40.846877) (xy 51.848311 -40.871896) (xy 51.803235 -40.890493)
			(xy 51.779678 -40.896794) (xy 51.765962 -40.90035) (xy 51.719988 -40.94607) (xy 51.77028 -40.996362)
			(xy 51.751484 -41.015158) (xy 51.79568 -41.059354) (xy 51.806856 -41.063164) (xy 51.83098 -41.071935)
			(xy 51.876388 -41.095865) (xy 51.917551 -41.126526) (xy 51.95348 -41.163182) (xy 51.983312 -41.20495)
			(xy 52.006329 -41.250828) (xy 52.021977 -41.299712) (xy 52.029882 -41.350428) (xy 52.030376 -41.376092)
			(xy 52.029891 -41.402079) (xy 52.16957 -41.402079) (xy 52.16957 -41.350105) (xy 52.1777 -41.29877)
			(xy 52.193761 -41.24934) (xy 52.217357 -41.20303) (xy 52.247907 -41.160982) (xy 52.284658 -41.124231)
			(xy 52.326706 -41.093681) (xy 52.373016 -41.070085) (xy 52.422446 -41.054024) (xy 52.473781 -41.045894)
			(xy 52.525755 -41.045894) (xy 52.57709 -41.054024) (xy 52.62652 -41.070085) (xy 52.67283 -41.093681)
			(xy 52.714878 -41.124231) (xy 52.751629 -41.160982) (xy 52.782179 -41.20303) (xy 52.805775 -41.24934)
			(xy 52.821836 -41.29877) (xy 52.829966 -41.350105) (xy 52.830476 -41.376092) (xy 52.829966 -41.402079)
			(xy 52.96967 -41.402079) (xy 52.96967 -41.350105) (xy 52.9778 -41.29877) (xy 52.993861 -41.24934)
			(xy 53.017457 -41.20303) (xy 53.048007 -41.160982) (xy 53.084758 -41.124231) (xy 53.126806 -41.093681)
			(xy 53.173116 -41.070085) (xy 53.222546 -41.054024) (xy 53.273881 -41.045894) (xy 53.325855 -41.045894)
			(xy 53.37719 -41.054024) (xy 53.42662 -41.070085) (xy 53.47293 -41.093681) (xy 53.514978 -41.124231)
			(xy 53.551729 -41.160982) (xy 53.582279 -41.20303) (xy 53.605875 -41.24934) (xy 53.621936 -41.29877)
			(xy 53.630066 -41.350105) (xy 53.630576 -41.376092) (xy 53.630066 -41.402079) (xy 53.769516 -41.402079)
			(xy 53.769516 -41.350105) (xy 53.777646 -41.29877) (xy 53.793707 -41.24934) (xy 53.817303 -41.20303)
			(xy 53.847853 -41.160982) (xy 53.884604 -41.124231) (xy 53.926652 -41.093681) (xy 53.972962 -41.070085)
			(xy 54.022392 -41.054024) (xy 54.073727 -41.045894) (xy 54.125701 -41.045894) (xy 54.177036 -41.054024)
			(xy 54.226466 -41.070085) (xy 54.272776 -41.093681) (xy 54.314824 -41.124231) (xy 54.351575 -41.160982)
			(xy 54.382125 -41.20303) (xy 54.405721 -41.24934) (xy 54.421782 -41.29877) (xy 54.429912 -41.350105)
			(xy 54.430422 -41.376092) (xy 54.429912 -41.402079) (xy 54.421782 -41.453414) (xy 54.405721 -41.502844)
			(xy 54.382125 -41.549154) (xy 54.351575 -41.591202) (xy 54.314824 -41.627953) (xy 54.272776 -41.658503)
			(xy 54.226466 -41.682099) (xy 54.177036 -41.69816) (xy 54.125701 -41.70629) (xy 54.073727 -41.70629)
			(xy 54.022392 -41.69816) (xy 53.972962 -41.682099) (xy 53.926652 -41.658503) (xy 53.884604 -41.627953)
			(xy 53.847853 -41.591202) (xy 53.817303 -41.549154) (xy 53.793707 -41.502844) (xy 53.777646 -41.453414)
			(xy 53.769516 -41.402079) (xy 53.630066 -41.402079) (xy 53.621936 -41.453414) (xy 53.605875 -41.502844)
			(xy 53.582279 -41.549154) (xy 53.551729 -41.591202) (xy 53.514978 -41.627953) (xy 53.47293 -41.658503)
			(xy 53.42662 -41.682099) (xy 53.37719 -41.69816) (xy 53.325855 -41.70629) (xy 53.273881 -41.70629)
			(xy 53.222546 -41.69816) (xy 53.173116 -41.682099) (xy 53.126806 -41.658503) (xy 53.084758 -41.627953)
			(xy 53.048007 -41.591202) (xy 53.017457 -41.549154) (xy 52.993861 -41.502844) (xy 52.9778 -41.453414)
			(xy 52.96967 -41.402079) (xy 52.829966 -41.402079) (xy 52.821836 -41.453414) (xy 52.805775 -41.502844)
			(xy 52.782179 -41.549154) (xy 52.751629 -41.591202) (xy 52.714878 -41.627953) (xy 52.67283 -41.658503)
			(xy 52.62652 -41.682099) (xy 52.57709 -41.69816) (xy 52.525755 -41.70629) (xy 52.473781 -41.70629)
			(xy 52.422446 -41.69816) (xy 52.373016 -41.682099) (xy 52.326706 -41.658503) (xy 52.284658 -41.627953)
			(xy 52.247907 -41.591202) (xy 52.217357 -41.549154) (xy 52.193761 -41.502844) (xy 52.1777 -41.453414)
			(xy 52.16957 -41.402079) (xy 52.029891 -41.402079) (xy 52.02989 -41.40212) (xy 52.021736 -41.453533)
			(xy 52.005626 -41.503033) (xy 51.98196 -41.549398) (xy 51.951321 -41.591482) (xy 51.914468 -41.628246)
			(xy 51.872309 -41.658782) (xy 51.825886 -41.682335) (xy 51.801268 -41.690798) (xy 51.766216 -41.702228)
			(xy 51.766216 -41.849802) (xy 51.801268 -41.861232) (xy 51.825886 -41.869689) (xy 51.872304 -41.893241)
			(xy 51.914459 -41.923776) (xy 51.951309 -41.960538) (xy 51.981944 -42.002619) (xy 52.005608 -42.04898)
			(xy 52.021715 -42.098477) (xy 52.029869 -42.149886) (xy 52.029867 -42.201925) (xy 52.16957 -42.201925)
			(xy 52.16957 -42.149951) (xy 52.1777 -42.098616) (xy 52.193761 -42.049186) (xy 52.217357 -42.002876)
			(xy 52.247907 -41.960828) (xy 52.284658 -41.924077) (xy 52.326706 -41.893527) (xy 52.373016 -41.869931)
			(xy 52.422446 -41.85387) (xy 52.473781 -41.84574) (xy 52.525755 -41.84574) (xy 52.57709 -41.85387)
			(xy 52.62652 -41.869931) (xy 52.67283 -41.893527) (xy 52.714878 -41.924077) (xy 52.751629 -41.960828)
			(xy 52.782179 -42.002876) (xy 52.805775 -42.049186) (xy 52.821836 -42.098616) (xy 52.829966 -42.149951)
			(xy 52.830476 -42.175938) (xy 52.829966 -42.201925) (xy 52.96967 -42.201925) (xy 52.96967 -42.149951)
			(xy 52.9778 -42.098616) (xy 52.993861 -42.049186) (xy 53.017457 -42.002876) (xy 53.048007 -41.960828)
			(xy 53.084758 -41.924077) (xy 53.126806 -41.893527) (xy 53.173116 -41.869931) (xy 53.222546 -41.85387)
			(xy 53.273881 -41.84574) (xy 53.325855 -41.84574) (xy 53.37719 -41.85387) (xy 53.42662 -41.869931)
			(xy 53.47293 -41.893527) (xy 53.514978 -41.924077) (xy 53.551729 -41.960828) (xy 53.582279 -42.002876)
			(xy 53.605875 -42.049186) (xy 53.621936 -42.098616) (xy 53.630066 -42.149951) (xy 53.630576 -42.175938)
			(xy 53.630066 -42.201925) (xy 53.769516 -42.201925) (xy 53.769516 -42.149951) (xy 53.777646 -42.098616)
			(xy 53.793707 -42.049186) (xy 53.817303 -42.002876) (xy 53.847853 -41.960828) (xy 53.884604 -41.924077)
			(xy 53.926652 -41.893527) (xy 53.972962 -41.869931) (xy 54.022392 -41.85387) (xy 54.073727 -41.84574)
			(xy 54.125701 -41.84574) (xy 54.177036 -41.85387) (xy 54.226466 -41.869931) (xy 54.272776 -41.893527)
			(xy 54.314824 -41.924077) (xy 54.351575 -41.960828) (xy 54.382125 -42.002876) (xy 54.405721 -42.049186)
			(xy 54.421782 -42.098616) (xy 54.429912 -42.149951) (xy 54.430422 -42.175938) (xy 54.429912 -42.201925)
			(xy 54.421782 -42.25326) (xy 54.405721 -42.30269) (xy 54.382125 -42.349) (xy 54.351575 -42.391048)
			(xy 54.314824 -42.427799) (xy 54.272776 -42.458349) (xy 54.226466 -42.481945) (xy 54.177036 -42.498006)
			(xy 54.125701 -42.506136) (xy 54.073727 -42.506136) (xy 54.022392 -42.498006) (xy 53.972962 -42.481945)
			(xy 53.926652 -42.458349) (xy 53.884604 -42.427799) (xy 53.847853 -42.391048) (xy 53.817303 -42.349)
			(xy 53.793707 -42.30269) (xy 53.777646 -42.25326) (xy 53.769516 -42.201925) (xy 53.630066 -42.201925)
			(xy 53.621936 -42.25326) (xy 53.605875 -42.30269) (xy 53.582279 -42.349) (xy 53.551729 -42.391048)
			(xy 53.514978 -42.427799) (xy 53.47293 -42.458349) (xy 53.42662 -42.481945) (xy 53.37719 -42.498006)
			(xy 53.325855 -42.506136) (xy 53.273881 -42.506136) (xy 53.222546 -42.498006) (xy 53.173116 -42.481945)
			(xy 53.126806 -42.458349) (xy 53.084758 -42.427799) (xy 53.048007 -42.391048) (xy 53.017457 -42.349)
			(xy 52.993861 -42.30269) (xy 52.9778 -42.25326) (xy 52.96967 -42.201925) (xy 52.829966 -42.201925)
			(xy 52.821836 -42.25326) (xy 52.805775 -42.30269) (xy 52.782179 -42.349) (xy 52.751629 -42.391048)
			(xy 52.714878 -42.427799) (xy 52.67283 -42.458349) (xy 52.62652 -42.481945) (xy 52.57709 -42.498006)
			(xy 52.525755 -42.506136) (xy 52.473781 -42.506136) (xy 52.422446 -42.498006) (xy 52.373016 -42.481945)
			(xy 52.326706 -42.458349) (xy 52.284658 -42.427799) (xy 52.247907 -42.391048) (xy 52.217357 -42.349)
			(xy 52.193761 -42.30269) (xy 52.1777 -42.25326) (xy 52.16957 -42.201925) (xy 52.029867 -42.201925)
			(xy 52.029867 -42.201937) (xy 52.02171 -42.253346) (xy 52.005599 -42.302841) (xy 51.981932 -42.349201)
			(xy 51.951294 -42.39128) (xy 51.914441 -42.428039) (xy 51.872284 -42.458571) (xy 51.825865 -42.48212)
			(xy 51.801268 -42.490644) (xy 51.766216 -42.502074) (xy 51.766216 -42.649902) (xy 51.801268 -42.661332)
			(xy 51.825886 -42.669789) (xy 51.872304 -42.693341) (xy 51.914459 -42.723876) (xy 51.951309 -42.760638)
			(xy 51.981944 -42.802719) (xy 52.005608 -42.84908) (xy 52.021715 -42.898577) (xy 52.029869 -42.949986)
			(xy 52.029867 -43.002025) (xy 52.16957 -43.002025) (xy 52.16957 -42.950051) (xy 52.1777 -42.898716)
			(xy 52.193761 -42.849286) (xy 52.217357 -42.802976) (xy 52.247907 -42.760928) (xy 52.284658 -42.724177)
			(xy 52.326706 -42.693627) (xy 52.373016 -42.670031) (xy 52.422446 -42.65397) (xy 52.473781 -42.64584)
			(xy 52.525755 -42.64584) (xy 52.57709 -42.65397) (xy 52.62652 -42.670031) (xy 52.67283 -42.693627)
			(xy 52.714878 -42.724177) (xy 52.751629 -42.760928) (xy 52.782179 -42.802976) (xy 52.805775 -42.849286)
			(xy 52.821836 -42.898716) (xy 52.829966 -42.950051) (xy 52.830476 -42.976038) (xy 52.829966 -43.002025)
			(xy 52.96967 -43.002025) (xy 52.96967 -42.950051) (xy 52.9778 -42.898716) (xy 52.993861 -42.849286)
			(xy 53.017457 -42.802976) (xy 53.048007 -42.760928) (xy 53.084758 -42.724177) (xy 53.126806 -42.693627)
			(xy 53.173116 -42.670031) (xy 53.222546 -42.65397) (xy 53.273881 -42.64584) (xy 53.325855 -42.64584)
			(xy 53.37719 -42.65397) (xy 53.42662 -42.670031) (xy 53.47293 -42.693627) (xy 53.514978 -42.724177)
			(xy 53.551729 -42.760928) (xy 53.582279 -42.802976) (xy 53.605875 -42.849286) (xy 53.621936 -42.898716)
			(xy 53.630066 -42.950051) (xy 53.630576 -42.976038) (xy 53.630066 -43.002025) (xy 53.769516 -43.002025)
			(xy 53.769516 -42.950051) (xy 53.777646 -42.898716) (xy 53.793707 -42.849286) (xy 53.817303 -42.802976)
			(xy 53.847853 -42.760928) (xy 53.884604 -42.724177) (xy 53.926652 -42.693627) (xy 53.972962 -42.670031)
			(xy 54.022392 -42.65397) (xy 54.073727 -42.64584) (xy 54.125701 -42.64584) (xy 54.177036 -42.65397)
			(xy 54.226466 -42.670031) (xy 54.272776 -42.693627) (xy 54.314824 -42.724177) (xy 54.351575 -42.760928)
			(xy 54.382125 -42.802976) (xy 54.405721 -42.849286) (xy 54.421782 -42.898716) (xy 54.429912 -42.950051)
			(xy 54.430422 -42.976038) (xy 54.429912 -43.002025) (xy 54.421782 -43.05336) (xy 54.405721 -43.10279)
			(xy 54.382125 -43.1491) (xy 54.351575 -43.191148) (xy 54.314824 -43.227899) (xy 54.272776 -43.258449)
			(xy 54.226466 -43.282045) (xy 54.177036 -43.298106) (xy 54.125701 -43.306236) (xy 54.073727 -43.306236)
			(xy 54.022392 -43.298106) (xy 53.972962 -43.282045) (xy 53.926652 -43.258449) (xy 53.884604 -43.227899)
			(xy 53.847853 -43.191148) (xy 53.817303 -43.1491) (xy 53.793707 -43.10279) (xy 53.777646 -43.05336)
			(xy 53.769516 -43.002025) (xy 53.630066 -43.002025) (xy 53.621936 -43.05336) (xy 53.605875 -43.10279)
			(xy 53.582279 -43.1491) (xy 53.551729 -43.191148) (xy 53.514978 -43.227899) (xy 53.47293 -43.258449)
			(xy 53.42662 -43.282045) (xy 53.37719 -43.298106) (xy 53.325855 -43.306236) (xy 53.273881 -43.306236)
			(xy 53.222546 -43.298106) (xy 53.173116 -43.282045) (xy 53.126806 -43.258449) (xy 53.084758 -43.227899)
			(xy 53.048007 -43.191148) (xy 53.017457 -43.1491) (xy 52.993861 -43.10279) (xy 52.9778 -43.05336)
			(xy 52.96967 -43.002025) (xy 52.829966 -43.002025) (xy 52.821836 -43.05336) (xy 52.805775 -43.10279)
			(xy 52.782179 -43.1491) (xy 52.751629 -43.191148) (xy 52.714878 -43.227899) (xy 52.67283 -43.258449)
			(xy 52.62652 -43.282045) (xy 52.57709 -43.298106) (xy 52.525755 -43.306236) (xy 52.473781 -43.306236)
			(xy 52.422446 -43.298106) (xy 52.373016 -43.282045) (xy 52.326706 -43.258449) (xy 52.284658 -43.227899)
			(xy 52.247907 -43.191148) (xy 52.217357 -43.1491) (xy 52.193761 -43.10279) (xy 52.1777 -43.05336)
			(xy 52.16957 -43.002025) (xy 52.029867 -43.002025) (xy 52.029867 -43.002037) (xy 52.02171 -43.053446)
			(xy 52.005599 -43.102941) (xy 51.981932 -43.149301) (xy 51.951294 -43.19138) (xy 51.914441 -43.228139)
			(xy 51.872284 -43.258671) (xy 51.825865 -43.28222) (xy 51.801268 -43.290744) (xy 51.766216 -43.302174)
			(xy 51.766216 -43.756072) (xy 51.94427 -43.934126) (xy 53.65877 -43.934126) (xy 53.835046 -44.110402)
			(xy 53.835046 -44.429172) (xy 54.240176 -44.834302) (xy 54.957472 -44.834302)
		)
		(stroke
			(width 0)
			(type solid)
		)
		(fill yes)
		(layer "In9.Cu")
		(net "P3V3_STBY_PLLAHVDD")
	)
	(gr_poly
		(pts
			(xy 60.536328 -45.953934) (xy 60.53709 -45.934122) (xy 60.539 -45.902512) (xy 60.550277 -45.840199)
			(xy 60.569855 -45.779975) (xy 60.597376 -45.722942) (xy 60.632337 -45.670141) (xy 60.674098 -45.622538)
			(xy 60.721898 -45.581001) (xy 60.774863 -45.546289) (xy 60.832026 -45.519037) (xy 60.892341 -45.499743)
			(xy 60.923424 -45.493686) (xy 60.933285 -45.491538) (xy 60.950304 -45.48072) (xy 60.961866 -45.464198)
			(xy 60.966198 -45.444502) (xy 60.964826 -45.434504) (xy 60.962355 -45.420025) (xy 60.959685 -45.390771)
			(xy 60.959492 -45.376084) (xy 60.960097 -45.347761) (xy 60.969809 -45.291952) (xy 60.978796 -45.265086)
			(xy 60.981468 -45.256466) (xy 60.981236 -45.238433) (xy 60.974783 -45.221592) (xy 60.962906 -45.20802)
			(xy 60.955174 -45.203364) (xy 60.923464 -45.185535) (xy 60.863678 -45.144081) (xy 60.80867 -45.096469)
			(xy 60.759071 -45.043247) (xy 60.715449 -44.985024) (xy 60.678305 -44.92247) (xy 60.648066 -44.856301)
			(xy 60.625078 -44.787277) (xy 60.609605 -44.71619) (xy 60.601825 -44.643856) (xy 60.601352 -44.60748)
			(xy 60.601352 -43.68419) (xy 60.601883 -43.642025) (xy 60.61029 -43.558116) (xy 60.627009 -43.47546)
			(xy 60.638944 -43.435016) (xy 60.642687 -43.421058) (xy 60.643063 -43.392175) (xy 60.635336 -43.364343)
			(xy 60.620124 -43.339788) (xy 60.598644 -43.320475) (xy 60.572615 -43.307951) (xy 60.544121 -43.303216)
			(xy 60.529724 -43.30446) (xy 60.519855 -43.305552) (xy 60.500029 -43.306694) (xy 60.4901 -43.306746)
			(xy 60.464107 -43.306263) (xy 60.412761 -43.29813) (xy 60.36332 -43.282065) (xy 60.317001 -43.258464)
			(xy 60.274944 -43.227907) (xy 60.238185 -43.191146) (xy 60.20763 -43.149088) (xy 60.18403 -43.102768)
			(xy 60.167967 -43.053326) (xy 60.159836 -43.00198) (xy 60.159838 -42.949994) (xy 60.167973 -42.898649)
			(xy 60.18404 -42.849208) (xy 60.207643 -42.80289) (xy 60.238202 -42.760834) (xy 60.274963 -42.724077)
			(xy 60.317022 -42.693523) (xy 60.363344 -42.669925) (xy 60.412786 -42.653864) (xy 60.464132 -42.645735)
			(xy 60.516118 -42.645739) (xy 60.567463 -42.653876) (xy 60.616903 -42.669944) (xy 60.663221 -42.69355)
			(xy 60.705275 -42.72411) (xy 60.742031 -42.760873) (xy 60.772584 -42.802933) (xy 60.79618 -42.849255)
			(xy 60.812239 -42.898698) (xy 60.820366 -42.950045) (xy 60.820808 -42.976038) (xy 60.820554 -42.9895)
			(xy 60.819792 -43.011852) (xy 60.871608 -43.063414) (xy 60.915296 -43.019472) (xy 60.936863 -42.997174)
			(xy 60.974613 -42.947946) (xy 61.005617 -42.894214) (xy 61.029344 -42.836895) (xy 61.045389 -42.77697)
			(xy 61.053477 -42.715464) (xy 61.05398 -42.684446) (xy 61.05398 -42.005504) (xy 61.054138 -41.991249)
			(xy 61.055788 -41.962785) (xy 61.057282 -41.948608) (xy 61.057536 -41.945814) (xy 61.057536 -41.7322)
			(xy 61.392816 -41.39692) (xy 61.392816 -41.297352) (xy 61.393247 -41.264902) (xy 61.40018 -41.200373)
			(xy 61.413939 -41.136949) (xy 61.43437 -41.075349) (xy 61.447426 -41.045638) (xy 61.452688 -41.033009)
			(xy 61.457008 -41.006004) (xy 61.454015 -40.978819) (xy 61.443923 -40.953401) (xy 61.427453 -40.931567)
			(xy 61.405785 -40.914881) (xy 61.380468 -40.904536) (xy 61.353315 -40.901272) (xy 61.33973 -40.90289)
			(xy 61.327423 -40.904658) (xy 61.302632 -40.906568) (xy 61.2902 -40.9067) (xy 61.264214 -40.90619)
			(xy 61.212881 -40.89806) (xy 61.163451 -40.882) (xy 61.117143 -40.858405) (xy 61.075096 -40.827856)
			(xy 61.038346 -40.791106) (xy 61.007797 -40.749059) (xy 60.984201 -40.702751) (xy 60.96814 -40.653322)
			(xy 60.96001 -40.601989) (xy 60.960009 -40.550016) (xy 60.968139 -40.498683) (xy 60.984199 -40.449254)
			(xy 61.007794 -40.402946) (xy 61.038342 -40.360898) (xy 61.075092 -40.324147) (xy 61.117139 -40.293598)
			(xy 61.163447 -40.270002) (xy 61.212875 -40.253941) (xy 61.264208 -40.24581) (xy 61.316181 -40.245809)
			(xy 61.367514 -40.253939) (xy 61.416944 -40.269998) (xy 61.463252 -40.293592) (xy 61.5053 -40.324141)
			(xy 61.542051 -40.36089) (xy 61.572601 -40.402936) (xy 61.596197 -40.449244) (xy 61.612258 -40.498673)
			(xy 61.62039 -40.550006) (xy 61.620908 -40.575992) (xy 61.620385 -40.602888) (xy 61.61167 -40.65597)
			(xy 61.594454 -40.706933) (xy 61.5823 -40.730932) (xy 61.578124 -40.739697) (xy 61.576023 -40.758983)
			(xy 61.581228 -40.777672) (xy 61.592995 -40.793096) (xy 61.609645 -40.803054) (xy 61.628801 -40.806123)
			(xy 61.647728 -40.801866) (xy 61.65596 -40.796718) (xy 61.67833 -40.781652) (xy 61.725262 -40.755071)
			(xy 61.749686 -40.743632) (xy 61.758018 -40.739357) (xy 61.77112 -40.725999) (xy 61.778588 -40.708843)
			(xy 61.779437 -40.690151) (xy 61.776864 -40.681148) (xy 61.768818 -40.655606) (xy 61.760133 -40.602766)
			(xy 61.759592 -40.575992) (xy 61.760102 -40.550005) (xy 61.768234 -40.498672) (xy 61.784295 -40.449242)
			(xy 61.807892 -40.402934) (xy 61.838442 -40.360887) (xy 61.875193 -40.324136) (xy 61.917241 -40.293587)
			(xy 61.96355 -40.269992) (xy 62.01298 -40.253932) (xy 62.064313 -40.245802) (xy 62.0903 -40.245284)
			(xy 62.111695 -40.245675) (xy 62.154118 -40.251286) (xy 62.174882 -40.25646) (xy 62.196726 -40.262302)
			(xy 62.244986 -40.230552) (xy 62.251082 -40.217344) (xy 62.258837 -40.200704) (xy 62.275864 -40.168175)
			(xy 62.285118 -40.15232) (xy 62.221364 -40.079676) (xy 62.200589 -40.088256) (xy 62.157301 -40.100353)
			(xy 62.112773 -40.106472) (xy 62.0903 -40.106854) (xy 62.064306 -40.106371) (xy 62.012959 -40.098238)
			(xy 61.963516 -40.082172) (xy 61.917196 -40.05857) (xy 61.875138 -40.028012) (xy 61.838378 -39.991251)
			(xy 61.807822 -39.949191) (xy 61.784222 -39.902869) (xy 61.768159 -39.853426) (xy 61.760028 -39.802078)
			(xy 61.760031 -39.750091) (xy 61.768166 -39.698744) (xy 61.784233 -39.649302) (xy 61.807838 -39.602983)
			(xy 61.838398 -39.560926) (xy 61.875161 -39.524168) (xy 61.917222 -39.493614) (xy 61.963545 -39.470016)
			(xy 62.012989 -39.453955) (xy 62.064337 -39.445827) (xy 62.116324 -39.445832) (xy 62.167671 -39.453969)
			(xy 62.217112 -39.470039) (xy 62.26343 -39.493646) (xy 62.305486 -39.524208) (xy 62.342242 -39.560973)
			(xy 62.372794 -39.603035) (xy 62.39639 -39.649359) (xy 62.412449 -39.698804) (xy 62.420574 -39.750152)
			(xy 62.421008 -39.776146) (xy 62.420754 -39.791386) (xy 62.420638 -39.806561) (xy 62.428249 -39.83592)
			(xy 62.444146 -39.861749) (xy 62.466929 -39.88177) (xy 62.494588 -39.894216) (xy 62.524682 -39.89799)
			(xy 62.554557 -39.892758) (xy 62.568328 -39.886382) (xy 62.605143 -39.868301) (xy 62.682095 -39.83991)
			(xy 62.761845 -39.820739) (xy 62.843293 -39.811052) (xy 62.884304 -39.810436) (xy 62.9793 -39.810436)
			(xy 63.560198 -39.229538) (xy 63.570782 -39.218128) (xy 63.585098 -39.190511) (xy 63.590449 -39.159868)
			(xy 63.586341 -39.129034) (xy 63.573154 -39.100861) (xy 63.562992 -39.089076) (xy 63.544191 -39.06784)
			(xy 63.512426 -39.020853) (xy 63.487963 -38.969683) (xy 63.471337 -38.915458) (xy 63.462916 -38.85937)
			(xy 63.462408 -38.831012) (xy 63.462408 -38.830758) (xy 63.462897 -38.803509) (xy 63.470659 -38.749567)
			(xy 63.486018 -38.697278) (xy 63.508661 -38.647707) (xy 63.538129 -38.601863) (xy 63.573821 -38.56068)
			(xy 63.61501 -38.524994) (xy 63.660858 -38.495533) (xy 63.710433 -38.472897) (xy 63.762724 -38.457546)
			(xy 63.816667 -38.449793) (xy 63.843916 -38.44925) (xy 63.870025 -38.449671) (xy 63.921756 -38.456781)
			(xy 63.972035 -38.470879) (xy 64.019921 -38.491701) (xy 64.064521 -38.518859) (xy 64.105 -38.551846)
			(xy 64.140602 -38.590044) (xy 64.170663 -38.632741) (xy 64.183006 -38.655752) (xy 64.19723 -38.683184)
			(xy 64.574166 -38.683184) (xy 64.586184 -38.659403) (xy 64.616218 -38.615393) (xy 64.652472 -38.576349)
			(xy 64.694139 -38.543141) (xy 64.740288 -38.516511) (xy 64.789889 -38.497054) (xy 64.841836 -38.485203)
			(xy 64.894968 -38.481223) (xy 64.9481 -38.485203) (xy 65.000047 -38.497054) (xy 65.049648 -38.516511)
			(xy 65.095797 -38.543141) (xy 65.137464 -38.576349) (xy 65.173718 -38.615393) (xy 65.203752 -38.659403)
			(xy 65.21577 -38.683184) (xy 66.40703 -38.683184) (xy 66.422347 -38.682615) (xy 66.45158 -38.67345)
			(xy 66.47679 -38.656042) (xy 66.495716 -38.63195) (xy 66.506662 -38.603335) (xy 66.508645 -38.572763)
			(xy 66.501488 -38.542974) (xy 66.494152 -38.529514) (xy 66.478562 -38.505644) (xy 66.453876 -38.454255)
			(xy 66.437108 -38.399766) (xy 66.428631 -38.343389) (xy 66.428112 -38.314884) (xy 66.428576 -38.287632)
			(xy 66.436335 -38.233684) (xy 66.451693 -38.18139) (xy 66.474337 -38.131813) (xy 66.503805 -38.085963)
			(xy 66.539499 -38.044774) (xy 66.580692 -38.009084) (xy 66.626544 -37.979619) (xy 66.676123 -37.95698)
			(xy 66.72842 -37.941628) (xy 66.782368 -37.933874) (xy 66.80962 -37.933376) (xy 66.80962 -37.933122)
			(xy 66.836455 -37.933593) (xy 66.889592 -37.94114) (xy 66.941149 -37.956056) (xy 66.990108 -37.978045)
			(xy 67.035505 -38.006674) (xy 67.076445 -38.041379) (xy 67.094608 -38.061138) (xy 67.104478 -38.072724)
			(xy 67.129522 -38.08999) (xy 67.158537 -38.099125) (xy 67.188956 -38.099322) (xy 67.218086 -38.090562)
			(xy 67.243351 -38.073621) (xy 67.253358 -38.062154) (xy 67.271577 -38.040575) (xy 67.31329 -38.002507)
			(xy 67.360158 -37.971002) (xy 67.411158 -37.94675) (xy 67.465176 -37.93028) (xy 67.521032 -37.921952)
			(xy 67.549268 -37.921438) (xy 67.576636 -37.921915) (xy 67.630809 -37.929748) (xy 67.683306 -37.945244)
			(xy 67.73305 -37.968084) (xy 67.779018 -37.997799) (xy 67.799966 -38.015418) (xy 67.811294 -38.024654)
			(xy 67.837851 -38.03683) (xy 67.866768 -38.041003) (xy 67.895685 -38.03683) (xy 67.922242 -38.024654)
			(xy 67.93357 -38.015418) (xy 67.9545 -37.997774) (xy 68.000466 -37.968043) (xy 68.050212 -37.945194)
			(xy 68.102716 -37.929699) (xy 68.156897 -37.921876) (xy 68.184268 -37.921438) (xy 68.211521 -37.921899)
			(xy 68.265473 -37.929653) (xy 68.317772 -37.945006) (xy 68.367353 -37.967648) (xy 68.413207 -37.997116)
			(xy 68.4544 -38.03281) (xy 68.490093 -38.074004) (xy 68.519559 -38.119859) (xy 68.542198 -38.169441)
			(xy 68.55755 -38.221741) (xy 68.565302 -38.275693) (xy 68.565776 -38.302946) (xy 68.565342 -38.329184)
			(xy 68.558151 -38.381164) (xy 68.543898 -38.431667) (xy 68.522852 -38.479737) (xy 68.49541 -38.524466)
			(xy 68.462093 -38.565007) (xy 68.443094 -38.583108) (xy 68.435727 -38.590634) (xy 68.427307 -38.609912)
			(xy 68.42732 -38.630949) (xy 68.435764 -38.650217) (xy 68.443094 -38.657784) (xy 68.46824 -38.683184)
			(xy 71.77024 -38.683184) (xy 71.793986 -38.667825) (xy 71.845049 -38.643524) (xy 71.899138 -38.627022)
			(xy 71.955071 -38.618679) (xy 72.011621 -38.618679) (xy 72.067554 -38.627022) (xy 72.121643 -38.643524)
			(xy 72.172706 -38.667825) (xy 72.196452 -38.683184) (xy 72.40524 -38.683184) (xy 72.428986 -38.667825)
			(xy 72.480049 -38.643524) (xy 72.534138 -38.627022) (xy 72.590071 -38.618679) (xy 72.646621 -38.618679)
			(xy 72.702554 -38.627022) (xy 72.756643 -38.643524) (xy 72.807706 -38.667825) (xy 72.831452 -38.683184)
			(xy 73.501758 -38.683184) (xy 73.5076 -38.638988) (xy 73.511662 -38.611807) (xy 73.526579 -38.558913)
			(xy 73.548931 -38.508706) (xy 73.578254 -38.462226) (xy 73.613942 -38.420433) (xy 73.655257 -38.384192)
			(xy 73.701344 -38.354254) (xy 73.75125 -38.331237) (xy 73.803941 -38.315618) (xy 73.858327 -38.30772)
			(xy 73.885806 -38.307264) (xy 73.911204 -38.307683) (xy 73.961552 -38.314424) (xy 74.01056 -38.327787)
			(xy 74.057361 -38.347534) (xy 74.101128 -38.373317) (xy 74.141087 -38.40468) (xy 74.15911 -38.42258)
			(xy 74.169245 -38.432378) (xy 74.193645 -38.446471) (xy 74.220969 -38.453355) (xy 74.249133 -38.452505)
			(xy 74.275992 -38.443985) (xy 74.299497 -38.428444) (xy 74.30897 -38.418008) (xy 74.327162 -38.397579)
			(xy 74.368393 -38.361633) (xy 74.414341 -38.33195) (xy 74.46406 -38.309143) (xy 74.51653 -38.293678)
			(xy 74.570671 -38.285874) (xy 74.598022 -38.28542) (xy 74.626474 -38.285941) (xy 74.682747 -38.294384)
			(xy 74.737141 -38.311095) (xy 74.788449 -38.335702) (xy 74.835531 -38.367659) (xy 74.877342 -38.406257)
			(xy 74.912954 -38.450639) (xy 74.941577 -38.49982) (xy 74.962574 -38.552707) (xy 74.975481 -38.608128)
			(xy 74.97826 -38.636448) (xy 74.98207 -38.683184) (xy 75.25258 -38.683184) (xy 75.267054 -38.682637)
			(xy 75.294821 -38.674443) (xy 75.319176 -38.658791) (xy 75.338166 -38.636939) (xy 75.350266 -38.610638)
			(xy 75.354506 -38.582) (xy 75.350546 -38.553321) (xy 75.345036 -38.539928) (xy 75.334507 -38.515337)
			(xy 75.319674 -38.46394) (xy 75.312189 -38.410973) (xy 75.311762 -38.384226) (xy 75.311762 -38.383972)
			(xy 75.312236 -38.356603) (xy 75.320064 -38.302428) (xy 75.335556 -38.249928) (xy 75.358394 -38.200181)
			(xy 75.388108 -38.15421) (xy 75.405742 -38.133274) (xy 75.414972 -38.121945) (xy 75.427136 -38.09539)
			(xy 75.4313 -38.066479) (xy 75.427124 -38.03757) (xy 75.414949 -38.011019) (xy 75.405742 -37.99967)
			(xy 75.388103 -37.978738) (xy 75.358381 -37.932771) (xy 75.335538 -37.883026) (xy 75.320045 -37.830525)
			(xy 75.312219 -37.776348) (xy 75.312223 -37.721609) (xy 75.320054 -37.667434) (xy 75.335553 -37.614935)
			(xy 75.358401 -37.565192) (xy 75.388128 -37.519229) (xy 75.405742 -37.498274) (xy 75.414972 -37.486945)
			(xy 75.427136 -37.46039) (xy 75.4313 -37.431479) (xy 75.427124 -37.40257) (xy 75.414949 -37.376019)
			(xy 75.405742 -37.36467) (xy 75.3881 -37.343739) (xy 75.358374 -37.297773) (xy 75.335532 -37.248026)
			(xy 75.320045 -37.195522) (xy 75.312229 -37.141342) (xy 75.311762 -37.113972) (xy 75.312248 -37.086721)
			(xy 75.320004 -37.032773) (xy 75.335359 -36.980478) (xy 75.358001 -36.930901) (xy 75.387467 -36.885051)
			(xy 75.423158 -36.84386) (xy 75.464349 -36.808169) (xy 75.510199 -36.778703) (xy 75.559776 -36.756061)
			(xy 75.612071 -36.740706) (xy 75.666019 -36.73295) (xy 75.720521 -36.73295) (xy 75.774469 -36.740706)
			(xy 75.826764 -36.756061) (xy 75.876341 -36.778703) (xy 75.922191 -36.808169) (xy 75.963382 -36.84386)
			(xy 75.999073 -36.885051) (xy 76.028539 -36.930901) (xy 76.051181 -36.980478) (xy 76.066536 -37.032773)
			(xy 76.074292 -37.086721) (xy 76.074778 -37.113972) (xy 76.074301 -37.14134) (xy 76.066468 -37.195513)
			(xy 76.050972 -37.24801) (xy 76.028132 -37.297754) (xy 75.998417 -37.343722) (xy 75.980798 -37.36467)
			(xy 75.971557 -37.375997) (xy 75.959373 -37.402558) (xy 75.955193 -37.431479) (xy 75.959361 -37.460402)
			(xy 75.971534 -37.486967) (xy 75.980798 -37.498274) (xy 75.99844 -37.519207) (xy 76.028167 -37.565176)
			(xy 76.051014 -37.614924) (xy 76.066513 -37.667427) (xy 76.074344 -37.721607) (xy 76.074348 -37.776351)
			(xy 76.066522 -37.830532) (xy 76.051029 -37.883037) (xy 76.028187 -37.932787) (xy 75.998465 -37.978759)
			(xy 75.980798 -37.99967) (xy 75.971557 -38.010997) (xy 75.959373 -38.037558) (xy 75.955193 -38.066479)
			(xy 75.959361 -38.095402) (xy 75.971534 -38.121967) (xy 75.980798 -38.133274) (xy 75.998442 -38.154205)
			(xy 76.028171 -38.200171) (xy 76.051018 -38.249917) (xy 76.066511 -38.302421) (xy 76.074334 -38.356601)
			(xy 76.074778 -38.383972) (xy 76.074778 -38.384226) (xy 76.074303 -38.410969) (xy 76.066796 -38.463925)
			(xy 76.051988 -38.515321) (xy 76.041504 -38.539928) (xy 76.036031 -38.553342) (xy 76.032046 -38.582023)
			(xy 76.036269 -38.61067) (xy 76.04836 -38.636982) (xy 76.067349 -38.658843) (xy 76.091709 -38.674498)
			(xy 76.119483 -38.682689) (xy 76.13396 -38.683184) (xy 76.642468 -38.683184) (xy 77.206094 -38.119558)
			(xy 77.206094 -34.881312) (xy 77.17536 -34.868104) (xy 77.145009 -34.854203) (xy 77.089313 -34.817412)
			(xy 77.064616 -34.794952) (xy 77.053671 -34.785239) (xy 77.027606 -34.771963) (xy 76.998846 -34.766627)
			(xy 76.969754 -34.769668) (xy 76.942719 -34.780836) (xy 76.931012 -34.789618) (xy 76.91059 -34.80551)
			(xy 76.86627 -34.832221) (xy 76.818746 -34.852693) (xy 76.76889 -34.866551) (xy 76.717617 -34.87354)
			(xy 76.691744 -34.873946) (xy 76.664486 -34.873486) (xy 76.610525 -34.865733) (xy 76.558217 -34.85038)
			(xy 76.508626 -34.827737) (xy 76.462763 -34.798268) (xy 76.421561 -34.76257) (xy 76.385859 -34.721372)
			(xy 76.356384 -34.675512) (xy 76.333736 -34.625924) (xy 76.318376 -34.573618) (xy 76.310617 -34.519658)
			(xy 76.310617 -34.465142) (xy 76.318376 -34.411182) (xy 76.333736 -34.358876) (xy 76.356384 -34.309287)
			(xy 76.385859 -34.263428) (xy 76.421561 -34.22223) (xy 76.462763 -34.186532) (xy 76.508626 -34.157063)
			(xy 76.558217 -34.13442) (xy 76.610525 -34.119067) (xy 76.664486 -34.111314) (xy 76.691744 -34.11093)
			(xy 76.72066 -34.111469) (xy 76.777829 -34.120207) (xy 76.833022 -34.137477) (xy 76.884976 -34.162883)
			(xy 76.932498 -34.195841) (xy 76.953872 -34.215324) (xy 76.964816 -34.225041) (xy 76.990881 -34.238323)
			(xy 77.019644 -34.243664) (xy 77.04874 -34.240624) (xy 77.075779 -34.229455) (xy 77.087476 -34.220658)
			(xy 77.107794 -34.204822) (xy 77.151886 -34.178183) (xy 77.17536 -34.167572) (xy 77.206094 -34.154364)
			(xy 77.206094 -34.018474) (xy 76.55179 -33.36417) (xy 76.525374 -33.36925) (xy 76.507703 -33.372445)
			(xy 76.471956 -33.37588) (xy 76.454 -33.376108) (xy 76.425983 -33.375613) (xy 76.370551 -33.367412)
			(xy 76.316917 -33.351187) (xy 76.266234 -33.327287) (xy 76.219595 -33.296227) (xy 76.198476 -33.27781)
			(xy 73.582276 -33.27781) (xy 73.568385 -33.278285) (xy 73.541635 -33.285783) (xy 73.517897 -33.300217)
			(xy 73.49893 -33.320516) (xy 73.48614 -33.345179) (xy 73.480474 -33.372376) (xy 73.48093 -33.386268)
			(xy 73.481692 -33.411668) (xy 73.481231 -33.438922) (xy 73.473477 -33.492875) (xy 73.458124 -33.545176)
			(xy 73.435483 -33.594759) (xy 73.406016 -33.640615) (xy 73.370322 -33.681811) (xy 73.329128 -33.717506)
			(xy 73.283273 -33.746975) (xy 73.233691 -33.769618) (xy 73.181391 -33.784974) (xy 73.127438 -33.79273)
			(xy 73.100184 -33.793176) (xy 73.074102 -33.792749) (xy 73.022426 -33.785637) (xy 72.972201 -33.771549)
			(xy 72.924364 -33.750747) (xy 72.87981 -33.723619) (xy 72.839368 -33.690672) (xy 72.803794 -33.652521)
			(xy 72.773752 -33.609877) (xy 72.761348 -33.586928) (xy 72.754669 -33.575018) (xy 72.736124 -33.55499)
			(xy 72.712938 -33.540587) (xy 72.686766 -33.532836) (xy 72.659475 -33.532291) (xy 72.633015 -33.538992)
			(xy 72.609272 -33.552458) (xy 72.599296 -33.561782) (xy 71.61403 -34.547048) (xy 67.89801 -34.547048)
			(xy 67.345052 -33.99409) (xy 67.345052 -33.27781) (xy 66.50482 -33.27781) (xy 66.491386 -33.278218)
			(xy 66.465447 -33.285224) (xy 66.442236 -33.298756) (xy 66.42336 -33.317876) (xy 66.410127 -33.341259)
			(xy 66.403454 -33.367285) (xy 66.403804 -33.394151) (xy 66.411152 -33.419994) (xy 66.417698 -33.431734)
			(xy 66.430649 -33.454087) (xy 66.451068 -33.50154) (xy 66.464895 -33.551315) (xy 66.471877 -33.6025)
			(xy 66.472308 -33.62833) (xy 66.471822 -33.655581) (xy 66.464066 -33.709529) (xy 66.448711 -33.761824)
			(xy 66.426069 -33.811401) (xy 66.396603 -33.857251) (xy 66.360912 -33.898442) (xy 66.319721 -33.934133)
			(xy 66.273871 -33.963599) (xy 66.224294 -33.986241) (xy 66.171999 -34.001596) (xy 66.118051 -34.009352)
			(xy 66.063549 -34.009352) (xy 66.009601 -34.001596) (xy 65.957306 -33.986241) (xy 65.907729 -33.963599)
			(xy 65.861879 -33.934133) (xy 65.820688 -33.898442) (xy 65.784997 -33.857251) (xy 65.755531 -33.811401)
			(xy 65.732889 -33.761824) (xy 65.717534 -33.709529) (xy 65.709778 -33.655581) (xy 65.709292 -33.62833)
			(xy 65.70972 -33.6025) (xy 65.716694 -33.551312) (xy 65.73052 -33.501535) (xy 65.750943 -33.454082)
			(xy 65.763902 -33.431734) (xy 65.77047 -33.420004) (xy 65.777821 -33.394154) (xy 65.778171 -33.367282)
			(xy 65.771496 -33.34125) (xy 65.75826 -33.317861) (xy 65.739379 -33.298736) (xy 65.716162 -33.285201)
			(xy 65.690217 -33.278193) (xy 65.67678 -33.27781) (xy 64.547496 -33.27781) (xy 64.533169 -33.2783)
			(xy 64.505647 -33.286269) (xy 64.481426 -33.301578) (xy 64.462418 -33.323019) (xy 64.450123 -33.3489)
			(xy 64.44551 -33.37718) (xy 64.448944 -33.405626) (xy 64.454024 -33.419034) (xy 64.463663 -33.44274)
			(xy 64.477225 -33.492084) (xy 64.484068 -33.542799) (xy 64.484504 -33.568386) (xy 64.484042 -33.595639)
			(xy 64.476286 -33.649592) (xy 64.460931 -33.701891) (xy 64.43829 -33.751473) (xy 64.408822 -33.797327)
			(xy 64.373128 -33.838521) (xy 64.331935 -33.874216) (xy 64.286081 -33.903685) (xy 64.2365 -33.926328)
			(xy 64.184201 -33.941684) (xy 64.130249 -33.949441) (xy 64.102996 -33.949894) (xy 64.0744 -33.949384)
			(xy 64.017848 -33.940848) (xy 63.963203 -33.923968) (xy 63.911689 -33.899122) (xy 63.864461 -33.866866)
			(xy 63.843154 -33.847786) (xy 63.831326 -33.837524) (xy 63.803065 -33.824075) (xy 63.772063 -33.819788)
			(xy 63.741213 -33.825064) (xy 63.713396 -33.839409) (xy 63.70193 -33.850072) (xy 62.067948 -35.484308)
			(xy 62.067948 -35.814762) (xy 62.067468 -35.848029) (xy 62.059453 -35.914079) (xy 62.043534 -35.978681)
			(xy 62.019945 -36.040893) (xy 61.989029 -36.099808) (xy 61.951237 -36.154567) (xy 61.907119 -36.204371)
			(xy 61.857321 -36.248495) (xy 61.802566 -36.286294) (xy 61.743655 -36.317217) (xy 61.681446 -36.340814)
			(xy 61.616846 -36.35674) (xy 61.550797 -36.364764) (xy 61.51753 -36.36518) (xy 61.485081 -36.364691)
			(xy 61.420635 -36.357027) (xy 61.357539 -36.341837) (xy 61.296667 -36.319331) (xy 61.238864 -36.289822)
			(xy 61.184933 -36.25372) (xy 61.135622 -36.211526) (xy 61.091616 -36.163825) (xy 61.053525 -36.111279)
			(xy 61.021878 -36.054619) (xy 61.009022 -36.02482) (xy 60.932314 -36.02482) (xy 60.266834 -36.6903)
			(xy 67.945508 -36.6903) (xy 67.945972 -36.66293) (xy 67.95379 -36.60875) (xy 67.96928 -36.556247)
			(xy 67.992122 -36.5065) (xy 68.021847 -36.460534) (xy 68.039488 -36.439602) (xy 68.048726 -36.428275)
			(xy 68.060905 -36.401717) (xy 68.065078 -36.3728) (xy 68.060905 -36.343883) (xy 68.048726 -36.317325)
			(xy 68.039488 -36.305998) (xy 68.021833 -36.285079) (xy 67.992124 -36.239102) (xy 67.969291 -36.189352)
			(xy 67.953804 -36.136848) (xy 67.94598 -36.08267) (xy 67.945508 -36.0553) (xy 67.946002 -36.029008)
			(xy 67.953231 -35.976923) (xy 67.967539 -35.926323) (xy 67.988654 -35.878164) (xy 68.016178 -35.833359)
			(xy 68.04959 -35.792754) (xy 68.088258 -35.757118) (xy 68.131449 -35.727125) (xy 68.178348 -35.703342)
			(xy 68.203064 -35.694366) (xy 68.216064 -35.689377) (xy 68.238967 -35.673567) (xy 68.256745 -35.652155)
			(xy 68.268075 -35.626736) (xy 68.272114 -35.599201) (xy 68.268562 -35.571598) (xy 68.257682 -35.545983)
			(xy 68.240285 -35.524261) (xy 68.229226 -35.515804) (xy 68.20844 -35.500349) (xy 68.170785 -35.464784)
			(xy 68.138286 -35.424453) (xy 68.111539 -35.380098) (xy 68.091036 -35.332533) (xy 68.077154 -35.282633)
			(xy 68.070148 -35.231314) (xy 68.069714 -35.205416) (xy 68.0702 -35.178165) (xy 68.077956 -35.124217)
			(xy 68.093311 -35.071922) (xy 68.115953 -35.022345) (xy 68.145419 -34.976495) (xy 68.18111 -34.935304)
			(xy 68.222301 -34.899613) (xy 68.268151 -34.870147) (xy 68.317728 -34.847505) (xy 68.370023 -34.83215)
			(xy 68.423971 -34.824394) (xy 68.478473 -34.824394) (xy 68.532421 -34.83215) (xy 68.584716 -34.847505)
			(xy 68.634293 -34.870147) (xy 68.680143 -34.899613) (xy 68.721334 -34.935304) (xy 68.757025 -34.976495)
			(xy 68.786491 -35.022345) (xy 68.809133 -35.071922) (xy 68.824488 -35.124217) (xy 68.832244 -35.178165)
			(xy 68.83273 -35.205416) (xy 68.832292 -35.23171) (xy 68.825059 -35.283799) (xy 68.810747 -35.334403)
			(xy 68.789625 -35.382564) (xy 68.762094 -35.427371) (xy 68.728675 -35.467975) (xy 68.69 -35.503609)
			(xy 68.6468 -35.533599) (xy 68.599894 -35.557377) (xy 68.575174 -35.56635) (xy 68.562163 -35.571305)
			(xy 68.539267 -35.587127) (xy 68.521497 -35.608545) (xy 68.510173 -35.633968) (xy 68.506137 -35.661504)
			(xy 68.509689 -35.689107) (xy 68.520565 -35.714724) (xy 68.537956 -35.736451) (xy 68.549012 -35.744912)
			(xy 68.569814 -35.760346) (xy 68.607467 -35.795916) (xy 68.639963 -35.836251) (xy 68.666708 -35.880609)
			(xy 68.687208 -35.928177) (xy 68.701087 -35.97808) (xy 68.708091 -36.029401) (xy 68.708524 -36.0553)
			(xy 68.708076 -36.082671) (xy 68.703692 -36.113052) (xy 70.927958 -36.113052) (xy 70.927958 -36.058548)
			(xy 70.935714 -36.0046) (xy 70.951069 -35.952304) (xy 70.973709 -35.902726) (xy 71.003175 -35.856875)
			(xy 71.038866 -35.815683) (xy 71.080055 -35.779989) (xy 71.125905 -35.750521) (xy 71.175482 -35.727877)
			(xy 71.227776 -35.712519) (xy 71.281724 -35.704759) (xy 71.308976 -35.704272) (xy 71.33604 -35.704733)
			(xy 71.389625 -35.712381) (xy 71.44159 -35.727528) (xy 71.490892 -35.749869) (xy 71.536541 -35.778955)
			(xy 71.557388 -35.79622) (xy 71.568823 -35.80533) (xy 71.595485 -35.817285) (xy 71.624442 -35.821199)
			(xy 71.653322 -35.816751) (xy 71.67976 -35.804306) (xy 71.690992 -35.79495) (xy 71.712083 -35.776827)
			(xy 71.758521 -35.74624) (xy 71.808906 -35.722714) (xy 71.862171 -35.706748) (xy 71.917189 -35.698679)
			(xy 71.944992 -35.698176) (xy 71.972244 -35.698671) (xy 72.026194 -35.706426) (xy 72.07849 -35.721781)
			(xy 72.128069 -35.744422) (xy 72.173921 -35.773889) (xy 72.215113 -35.809581) (xy 72.250806 -35.850772)
			(xy 72.280274 -35.896624) (xy 72.302916 -35.946202) (xy 72.318272 -35.998499) (xy 72.326029 -36.052448)
			(xy 72.326029 -36.106952) (xy 72.318272 -36.160901) (xy 72.314301 -36.174426) (xy 72.656952 -36.174426)
			(xy 72.661023 -36.118804) (xy 72.673149 -36.064367) (xy 72.693072 -36.012276) (xy 72.720368 -35.963641)
			(xy 72.754454 -35.919498) (xy 72.794603 -35.880789) (xy 72.839961 -35.848338) (xy 72.889561 -35.822837)
			(xy 72.942345 -35.80483) (xy 72.997188 -35.7947) (xy 73.052922 -35.792663) (xy 73.108359 -35.798763)
			(xy 73.162316 -35.812869) (xy 73.213645 -35.834681) (xy 73.261251 -35.863735) (xy 73.304119 -35.89941)
			(xy 73.341336 -35.940947) (xy 73.372109 -35.98746) (xy 73.395781 -36.037957) (xy 73.411849 -36.091364)
			(xy 73.419969 -36.14654) (xy 73.420478 -36.174426) (xy 73.419969 -36.202312) (xy 73.416933 -36.22294)
			(xy 73.837798 -36.22294) (xy 73.841869 -36.167318) (xy 73.853995 -36.112881) (xy 73.873918 -36.06079)
			(xy 73.901214 -36.012155) (xy 73.9353 -35.968012) (xy 73.975449 -35.929303) (xy 74.020807 -35.896852)
			(xy 74.070407 -35.871351) (xy 74.123191 -35.853344) (xy 74.178034 -35.843214) (xy 74.233768 -35.841177)
			(xy 74.289205 -35.847277) (xy 74.343162 -35.861383) (xy 74.394491 -35.883195) (xy 74.442097 -35.912249)
			(xy 74.484965 -35.947924) (xy 74.522182 -35.989461) (xy 74.552955 -36.035974) (xy 74.576627 -36.086471)
			(xy 74.592695 -36.139878) (xy 74.600815 -36.195054) (xy 74.601324 -36.22294) (xy 74.600815 -36.250826)
			(xy 74.592695 -36.306002) (xy 74.576627 -36.359409) (xy 74.552955 -36.409906) (xy 74.522182 -36.456419)
			(xy 74.484965 -36.497956) (xy 74.442097 -36.533631) (xy 74.415541 -36.549838) (xy 76.309726 -36.549838)
			(xy 76.313797 -36.494216) (xy 76.325923 -36.439779) (xy 76.345846 -36.387688) (xy 76.373142 -36.339053)
			(xy 76.407228 -36.29491) (xy 76.447377 -36.256201) (xy 76.492735 -36.22375) (xy 76.542335 -36.198249)
			(xy 76.595119 -36.180242) (xy 76.649962 -36.170112) (xy 76.705696 -36.168075) (xy 76.761133 -36.174175)
			(xy 76.81509 -36.188281) (xy 76.866419 -36.210093) (xy 76.914025 -36.239147) (xy 76.956893 -36.274822)
			(xy 76.99411 -36.316359) (xy 77.024883 -36.362872) (xy 77.048555 -36.413369) (xy 77.064623 -36.466776)
			(xy 77.072743 -36.521952) (xy 77.073252 -36.549838) (xy 77.072743 -36.577724) (xy 77.064623 -36.6329)
			(xy 77.048555 -36.686307) (xy 77.024883 -36.736804) (xy 76.99411 -36.783317) (xy 76.956893 -36.824854)
			(xy 76.914025 -36.860529) (xy 76.866419 -36.889583) (xy 76.81509 -36.911395) (xy 76.761133 -36.925501)
			(xy 76.705696 -36.931601) (xy 76.649962 -36.929564) (xy 76.595119 -36.919434) (xy 76.542335 -36.901427)
			(xy 76.492735 -36.875926) (xy 76.447377 -36.843475) (xy 76.407228 -36.804766) (xy 76.373142 -36.760623)
			(xy 76.345846 -36.711988) (xy 76.325923 -36.659897) (xy 76.313797 -36.60546) (xy 76.309726 -36.549838)
			(xy 74.415541 -36.549838) (xy 74.394491 -36.562685) (xy 74.343162 -36.584497) (xy 74.289205 -36.598603)
			(xy 74.233768 -36.604703) (xy 74.178034 -36.602666) (xy 74.123191 -36.592536) (xy 74.070407 -36.574529)
			(xy 74.020807 -36.549028) (xy 73.975449 -36.516577) (xy 73.9353 -36.477868) (xy 73.901214 -36.433725)
			(xy 73.873918 -36.38509) (xy 73.853995 -36.332999) (xy 73.841869 -36.278562) (xy 73.837798 -36.22294)
			(xy 73.416933 -36.22294) (xy 73.411849 -36.257488) (xy 73.395781 -36.310895) (xy 73.372109 -36.361392)
			(xy 73.341336 -36.407905) (xy 73.304119 -36.449442) (xy 73.261251 -36.485117) (xy 73.213645 -36.514171)
			(xy 73.162316 -36.535983) (xy 73.108359 -36.550089) (xy 73.052922 -36.556189) (xy 72.997188 -36.554152)
			(xy 72.942345 -36.544022) (xy 72.889561 -36.526015) (xy 72.839961 -36.500514) (xy 72.794603 -36.468063)
			(xy 72.754454 -36.429354) (xy 72.720368 -36.385211) (xy 72.693072 -36.336576) (xy 72.673149 -36.284485)
			(xy 72.661023 -36.230048) (xy 72.656952 -36.174426) (xy 72.314301 -36.174426) (xy 72.302916 -36.213198)
			(xy 72.280274 -36.262776) (xy 72.250806 -36.308628) (xy 72.215113 -36.349819) (xy 72.173921 -36.385511)
			(xy 72.128069 -36.414978) (xy 72.07849 -36.437619) (xy 72.026194 -36.452974) (xy 71.972244 -36.460729)
			(xy 71.944992 -36.461192) (xy 71.917928 -36.460735) (xy 71.864344 -36.453083) (xy 71.812379 -36.437935)
			(xy 71.763077 -36.415594) (xy 71.717428 -36.386508) (xy 71.69658 -36.369244) (xy 71.685167 -36.360107)
			(xy 71.658496 -36.348159) (xy 71.629533 -36.344253) (xy 71.60065 -36.348707) (xy 71.57421 -36.361157)
			(xy 71.562976 -36.370514) (xy 71.541892 -36.388646) (xy 71.495453 -36.419233) (xy 71.445066 -36.442758)
			(xy 71.391799 -36.458722) (xy 71.33678 -36.466788) (xy 71.308976 -36.467288) (xy 71.281724 -36.466841)
			(xy 71.227776 -36.459081) (xy 71.175482 -36.443723) (xy 71.125905 -36.421079) (xy 71.080055 -36.391611)
			(xy 71.038866 -36.355917) (xy 71.003175 -36.314725) (xy 70.973709 -36.268874) (xy 70.951069 -36.219296)
			(xy 70.935714 -36.167) (xy 70.927958 -36.113052) (xy 68.703692 -36.113052) (xy 68.700257 -36.136852)
			(xy 68.684765 -36.189356) (xy 68.661918 -36.239102) (xy 68.632188 -36.285068) (xy 68.614544 -36.305998)
			(xy 68.605312 -36.317327) (xy 68.593141 -36.343885) (xy 68.588971 -36.3728) (xy 68.593141 -36.401715)
			(xy 68.605312 -36.428273) (xy 68.614544 -36.439602) (xy 68.632205 -36.460517) (xy 68.661912 -36.506495)
			(xy 68.684743 -36.556247) (xy 68.700229 -36.608751) (xy 68.708053 -36.66293) (xy 68.708524 -36.6903)
			(xy 68.708038 -36.717551) (xy 68.700282 -36.771499) (xy 68.684927 -36.823794) (xy 68.662285 -36.873371)
			(xy 68.632819 -36.919221) (xy 68.597128 -36.960412) (xy 68.555937 -36.996103) (xy 68.510087 -37.025569)
			(xy 68.46051 -37.048211) (xy 68.408215 -37.063566) (xy 68.354267 -37.071322) (xy 68.299765 -37.071322)
			(xy 68.245817 -37.063566) (xy 68.193522 -37.048211) (xy 68.143945 -37.025569) (xy 68.098095 -36.996103)
			(xy 68.056904 -36.960412) (xy 68.021213 -36.919221) (xy 67.991747 -36.873371) (xy 67.969105 -36.823794)
			(xy 67.95375 -36.771499) (xy 67.945994 -36.717551) (xy 67.945508 -36.6903) (xy 60.266834 -36.6903)
			(xy 59.771534 -37.1856) (xy 65.276982 -37.1856) (xy 65.281053 -37.129978) (xy 65.293179 -37.075541)
			(xy 65.313102 -37.02345) (xy 65.340398 -36.974815) (xy 65.374484 -36.930672) (xy 65.414633 -36.891963)
			(xy 65.459991 -36.859512) (xy 65.509591 -36.834011) (xy 65.562375 -36.816004) (xy 65.617218 -36.805874)
			(xy 65.672952 -36.803837) (xy 65.728389 -36.809937) (xy 65.782346 -36.824043) (xy 65.833675 -36.845855)
			(xy 65.881281 -36.874909) (xy 65.924149 -36.910584) (xy 65.961366 -36.952121) (xy 65.992139 -36.998634)
			(xy 66.015811 -37.049131) (xy 66.031879 -37.102538) (xy 66.039999 -37.157714) (xy 66.040508 -37.1856)
			(xy 66.039999 -37.213486) (xy 66.031879 -37.268662) (xy 66.015811 -37.322069) (xy 65.992139 -37.372566)
			(xy 65.961366 -37.419079) (xy 65.924149 -37.460616) (xy 65.881281 -37.496291) (xy 65.833675 -37.525345)
			(xy 65.782346 -37.547157) (xy 65.728389 -37.561263) (xy 65.672952 -37.567363) (xy 65.617218 -37.565326)
			(xy 65.562375 -37.555196) (xy 65.509591 -37.537189) (xy 65.459991 -37.511688) (xy 65.414633 -37.479237)
			(xy 65.374484 -37.440528) (xy 65.340398 -37.396385) (xy 65.313102 -37.34775) (xy 65.293179 -37.295659)
			(xy 65.281053 -37.241222) (xy 65.276982 -37.1856) (xy 59.771534 -37.1856) (xy 59.347862 -37.609272)
			(xy 59.36488 -37.642038) (xy 59.378155 -37.669146) (xy 59.396936 -37.726506) (xy 59.40647 -37.786104)
			(xy 59.407044 -37.816282) (xy 59.407044 -37.816536) (xy 59.406556 -37.843787) (xy 59.398795 -37.897732)
			(xy 59.383437 -37.950025) (xy 59.360795 -37.9996) (xy 59.331328 -38.045448) (xy 59.295637 -38.086637)
			(xy 59.254448 -38.122328) (xy 59.2086 -38.151795) (xy 59.159025 -38.174437) (xy 59.106732 -38.189795)
			(xy 59.052787 -38.197556) (xy 59.025536 -38.198044) (xy 59.025028 -38.198044) (xy 59.007656 -38.197835)
			(xy 58.973059 -38.194654) (xy 58.95594 -38.191694) (xy 58.9412 -38.189456) (xy 58.911571 -38.192643)
			(xy 58.884119 -38.204239) (xy 58.861179 -38.223261) (xy 58.8447 -38.24809) (xy 58.836082 -38.276616)
			(xy 58.835544 -38.291516) (xy 58.835544 -38.946074) (xy 58.835113 -38.976933) (xy 58.832286 -39.002033)
			(xy 59.360056 -39.002033) (xy 59.360056 -38.950059) (xy 59.368186 -38.898724) (xy 59.384247 -38.849294)
			(xy 59.407843 -38.802984) (xy 59.438393 -38.760936) (xy 59.475144 -38.724185) (xy 59.517192 -38.693635)
			(xy 59.563502 -38.670039) (xy 59.612932 -38.653978) (xy 59.664267 -38.645848) (xy 59.716241 -38.645848)
			(xy 59.767576 -38.653978) (xy 59.817006 -38.670039) (xy 59.863316 -38.693635) (xy 59.905364 -38.724185)
			(xy 59.942115 -38.760936) (xy 59.972665 -38.802984) (xy 59.996261 -38.849294) (xy 60.012322 -38.898724)
			(xy 60.020452 -38.950059) (xy 60.020962 -38.976046) (xy 60.020452 -39.002033) (xy 60.012322 -39.053368)
			(xy 59.996261 -39.102798) (xy 59.972665 -39.149108) (xy 59.942115 -39.191156) (xy 59.905364 -39.227907)
			(xy 59.863316 -39.258457) (xy 59.817006 -39.282053) (xy 59.767576 -39.298114) (xy 59.716241 -39.306244)
			(xy 59.664267 -39.306244) (xy 59.612932 -39.298114) (xy 59.563502 -39.282053) (xy 59.517192 -39.258457)
			(xy 59.475144 -39.227907) (xy 59.438393 -39.191156) (xy 59.407843 -39.149108) (xy 59.384247 -39.102798)
			(xy 59.368186 -39.053368) (xy 59.360056 -39.002033) (xy 58.832286 -39.002033) (xy 58.828206 -39.038263)
			(xy 58.814476 -39.098433) (xy 58.794096 -39.156689) (xy 58.767321 -39.212296) (xy 58.734489 -39.264556)
			(xy 58.696012 -39.312811) (xy 58.674508 -39.334948) (xy 58.267092 -39.74211) (xy 58.267092 -39.802133)
			(xy 58.559956 -39.802133) (xy 58.559956 -39.750159) (xy 58.568086 -39.698824) (xy 58.584147 -39.649394)
			(xy 58.607743 -39.603084) (xy 58.638293 -39.561036) (xy 58.675044 -39.524285) (xy 58.717092 -39.493735)
			(xy 58.763402 -39.470139) (xy 58.812832 -39.454078) (xy 58.864167 -39.445948) (xy 58.916141 -39.445948)
			(xy 58.967476 -39.454078) (xy 59.016906 -39.470139) (xy 59.063216 -39.493735) (xy 59.105264 -39.524285)
			(xy 59.142015 -39.561036) (xy 59.172565 -39.603084) (xy 59.196161 -39.649394) (xy 59.212222 -39.698824)
			(xy 59.220352 -39.750159) (xy 59.220862 -39.776146) (xy 59.220352 -39.802133) (xy 59.360056 -39.802133)
			(xy 59.360056 -39.750159) (xy 59.368186 -39.698824) (xy 59.384247 -39.649394) (xy 59.407843 -39.603084)
			(xy 59.438393 -39.561036) (xy 59.475144 -39.524285) (xy 59.517192 -39.493735) (xy 59.563502 -39.470139)
			(xy 59.612932 -39.454078) (xy 59.664267 -39.445948) (xy 59.716241 -39.445948) (xy 59.767576 -39.454078)
			(xy 59.817006 -39.470139) (xy 59.863316 -39.493735) (xy 59.905364 -39.524285) (xy 59.942115 -39.561036)
			(xy 59.972665 -39.603084) (xy 59.996261 -39.649394) (xy 60.012322 -39.698824) (xy 60.020452 -39.750159)
			(xy 60.020962 -39.776146) (xy 60.020452 -39.802133) (xy 60.159902 -39.802133) (xy 60.159902 -39.750159)
			(xy 60.168032 -39.698824) (xy 60.184093 -39.649394) (xy 60.207689 -39.603084) (xy 60.238239 -39.561036)
			(xy 60.27499 -39.524285) (xy 60.317038 -39.493735) (xy 60.363348 -39.470139) (xy 60.412778 -39.454078)
			(xy 60.464113 -39.445948) (xy 60.516087 -39.445948) (xy 60.567422 -39.454078) (xy 60.616852 -39.470139)
			(xy 60.663162 -39.493735) (xy 60.70521 -39.524285) (xy 60.741961 -39.561036) (xy 60.772511 -39.603084)
			(xy 60.796107 -39.649394) (xy 60.812168 -39.698824) (xy 60.820298 -39.750159) (xy 60.820808 -39.776146)
			(xy 60.820298 -39.802133) (xy 60.812168 -39.853468) (xy 60.796107 -39.902898) (xy 60.772511 -39.949208)
			(xy 60.741961 -39.991256) (xy 60.70521 -40.028007) (xy 60.663162 -40.058557) (xy 60.616852 -40.082153)
			(xy 60.567422 -40.098214) (xy 60.516087 -40.106344) (xy 60.464113 -40.106344) (xy 60.412778 -40.098214)
			(xy 60.363348 -40.082153) (xy 60.317038 -40.058557) (xy 60.27499 -40.028007) (xy 60.238239 -39.991256)
			(xy 60.207689 -39.949208) (xy 60.184093 -39.902898) (xy 60.168032 -39.853468) (xy 60.159902 -39.802133)
			(xy 60.020452 -39.802133) (xy 60.012322 -39.853468) (xy 59.996261 -39.902898) (xy 59.972665 -39.949208)
			(xy 59.942115 -39.991256) (xy 59.905364 -40.028007) (xy 59.863316 -40.058557) (xy 59.817006 -40.082153)
			(xy 59.767576 -40.098214) (xy 59.716241 -40.106344) (xy 59.664267 -40.106344) (xy 59.612932 -40.098214)
			(xy 59.563502 -40.082153) (xy 59.517192 -40.058557) (xy 59.475144 -40.028007) (xy 59.438393 -39.991256)
			(xy 59.407843 -39.949208) (xy 59.384247 -39.902898) (xy 59.368186 -39.853468) (xy 59.360056 -39.802133)
			(xy 59.220352 -39.802133) (xy 59.212222 -39.853468) (xy 59.196161 -39.902898) (xy 59.172565 -39.949208)
			(xy 59.142015 -39.991256) (xy 59.105264 -40.028007) (xy 59.063216 -40.058557) (xy 59.016906 -40.082153)
			(xy 58.967476 -40.098214) (xy 58.916141 -40.106344) (xy 58.864167 -40.106344) (xy 58.812832 -40.098214)
			(xy 58.763402 -40.082153) (xy 58.717092 -40.058557) (xy 58.675044 -40.028007) (xy 58.638293 -39.991256)
			(xy 58.607743 -39.949208) (xy 58.584147 -39.902898) (xy 58.568086 -39.853468) (xy 58.559956 -39.802133)
			(xy 58.267092 -39.802133) (xy 58.267092 -40.296592) (xy 58.288498 -40.310684) (xy 58.327082 -40.344413)
			(xy 58.359997 -40.383694) (xy 58.386453 -40.427584) (xy 58.405817 -40.475033) (xy 58.417625 -40.524902)
			(xy 58.421593 -40.575996) (xy 58.419576 -40.601979) (xy 58.559956 -40.601979) (xy 58.559956 -40.550005)
			(xy 58.568086 -40.49867) (xy 58.584147 -40.44924) (xy 58.607743 -40.40293) (xy 58.638293 -40.360882)
			(xy 58.675044 -40.324131) (xy 58.717092 -40.293581) (xy 58.763402 -40.269985) (xy 58.812832 -40.253924)
			(xy 58.864167 -40.245794) (xy 58.916141 -40.245794) (xy 58.967476 -40.253924) (xy 59.016906 -40.269985)
			(xy 59.063216 -40.293581) (xy 59.105264 -40.324131) (xy 59.142015 -40.360882) (xy 59.172565 -40.40293)
			(xy 59.196161 -40.44924) (xy 59.212222 -40.49867) (xy 59.220352 -40.550005) (xy 59.220862 -40.575992)
			(xy 59.220352 -40.601979) (xy 59.360056 -40.601979) (xy 59.360056 -40.550005) (xy 59.368186 -40.49867)
			(xy 59.384247 -40.44924) (xy 59.407843 -40.40293) (xy 59.438393 -40.360882) (xy 59.475144 -40.324131)
			(xy 59.517192 -40.293581) (xy 59.563502 -40.269985) (xy 59.612932 -40.253924) (xy 59.664267 -40.245794)
			(xy 59.716241 -40.245794) (xy 59.767576 -40.253924) (xy 59.817006 -40.269985) (xy 59.863316 -40.293581)
			(xy 59.905364 -40.324131) (xy 59.942115 -40.360882) (xy 59.972665 -40.40293) (xy 59.996261 -40.44924)
			(xy 60.012322 -40.49867) (xy 60.020452 -40.550005) (xy 60.020962 -40.575992) (xy 60.020452 -40.601979)
			(xy 60.159902 -40.601979) (xy 60.159902 -40.550005) (xy 60.168032 -40.49867) (xy 60.184093 -40.44924)
			(xy 60.207689 -40.40293) (xy 60.238239 -40.360882) (xy 60.27499 -40.324131) (xy 60.317038 -40.293581)
			(xy 60.363348 -40.269985) (xy 60.412778 -40.253924) (xy 60.464113 -40.245794) (xy 60.516087 -40.245794)
			(xy 60.567422 -40.253924) (xy 60.616852 -40.269985) (xy 60.663162 -40.293581) (xy 60.70521 -40.324131)
			(xy 60.741961 -40.360882) (xy 60.772511 -40.40293) (xy 60.796107 -40.44924) (xy 60.812168 -40.49867)
			(xy 60.820298 -40.550005) (xy 60.820808 -40.575992) (xy 60.820298 -40.601979) (xy 60.812168 -40.653314)
			(xy 60.796107 -40.702744) (xy 60.772511 -40.749054) (xy 60.741961 -40.791102) (xy 60.70521 -40.827853)
			(xy 60.663162 -40.858403) (xy 60.616852 -40.881999) (xy 60.567422 -40.89806) (xy 60.516087 -40.90619)
			(xy 60.464113 -40.90619) (xy 60.412778 -40.89806) (xy 60.363348 -40.881999) (xy 60.317038 -40.858403)
			(xy 60.27499 -40.827853) (xy 60.238239 -40.791102) (xy 60.207689 -40.749054) (xy 60.184093 -40.702744)
			(xy 60.168032 -40.653314) (xy 60.159902 -40.601979) (xy 60.020452 -40.601979) (xy 60.012322 -40.653314)
			(xy 59.996261 -40.702744) (xy 59.972665 -40.749054) (xy 59.942115 -40.791102) (xy 59.905364 -40.827853)
			(xy 59.863316 -40.858403) (xy 59.817006 -40.881999) (xy 59.767576 -40.89806) (xy 59.716241 -40.90619)
			(xy 59.664267 -40.90619) (xy 59.612932 -40.89806) (xy 59.563502 -40.881999) (xy 59.517192 -40.858403)
			(xy 59.475144 -40.827853) (xy 59.438393 -40.791102) (xy 59.407843 -40.749054) (xy 59.384247 -40.702744)
			(xy 59.368186 -40.653314) (xy 59.360056 -40.601979) (xy 59.220352 -40.601979) (xy 59.212222 -40.653314)
			(xy 59.196161 -40.702744) (xy 59.172565 -40.749054) (xy 59.142015 -40.791102) (xy 59.105264 -40.827853)
			(xy 59.063216 -40.858403) (xy 59.016906 -40.881999) (xy 58.967476 -40.89806) (xy 58.916141 -40.90619)
			(xy 58.864167 -40.90619) (xy 58.812832 -40.89806) (xy 58.763402 -40.881999) (xy 58.717092 -40.858403)
			(xy 58.675044 -40.827853) (xy 58.638293 -40.791102) (xy 58.607743 -40.749054) (xy 58.584147 -40.702744)
			(xy 58.568086 -40.653314) (xy 58.559956 -40.601979) (xy 58.419576 -40.601979) (xy 58.417626 -40.62709)
			(xy 58.40582 -40.676959) (xy 58.386457 -40.724408) (xy 58.360002 -40.768299) (xy 58.327088 -40.807581)
			(xy 58.288505 -40.841311) (xy 58.267092 -40.855392) (xy 58.267092 -41.096692) (xy 58.29026 -41.111997)
			(xy 58.331587 -41.149074) (xy 58.366133 -41.192538) (xy 58.392928 -41.241166) (xy 58.411216 -41.293589)
			(xy 58.420482 -41.348331) (xy 58.421016 -41.376092) (xy 58.420512 -41.402079) (xy 58.559956 -41.402079)
			(xy 58.559956 -41.350105) (xy 58.568086 -41.29877) (xy 58.584147 -41.24934) (xy 58.607743 -41.20303)
			(xy 58.638293 -41.160982) (xy 58.675044 -41.124231) (xy 58.717092 -41.093681) (xy 58.763402 -41.070085)
			(xy 58.812832 -41.054024) (xy 58.864167 -41.045894) (xy 58.916141 -41.045894) (xy 58.967476 -41.054024)
			(xy 59.016906 -41.070085) (xy 59.063216 -41.093681) (xy 59.105264 -41.124231) (xy 59.142015 -41.160982)
			(xy 59.172565 -41.20303) (xy 59.196161 -41.24934) (xy 59.212222 -41.29877) (xy 59.220352 -41.350105)
			(xy 59.220862 -41.376092) (xy 59.220352 -41.402079) (xy 59.360056 -41.402079) (xy 59.360056 -41.350105)
			(xy 59.368186 -41.29877) (xy 59.384247 -41.24934) (xy 59.407843 -41.20303) (xy 59.438393 -41.160982)
			(xy 59.475144 -41.124231) (xy 59.517192 -41.093681) (xy 59.563502 -41.070085) (xy 59.612932 -41.054024)
			(xy 59.664267 -41.045894) (xy 59.716241 -41.045894) (xy 59.767576 -41.054024) (xy 59.817006 -41.070085)
			(xy 59.863316 -41.093681) (xy 59.905364 -41.124231) (xy 59.942115 -41.160982) (xy 59.972665 -41.20303)
			(xy 59.996261 -41.24934) (xy 60.012322 -41.29877) (xy 60.020452 -41.350105) (xy 60.020962 -41.376092)
			(xy 60.020452 -41.402079) (xy 60.159902 -41.402079) (xy 60.159902 -41.350105) (xy 60.168032 -41.29877)
			(xy 60.184093 -41.24934) (xy 60.207689 -41.20303) (xy 60.238239 -41.160982) (xy 60.27499 -41.124231)
			(xy 60.317038 -41.093681) (xy 60.363348 -41.070085) (xy 60.412778 -41.054024) (xy 60.464113 -41.045894)
			(xy 60.516087 -41.045894) (xy 60.567422 -41.054024) (xy 60.616852 -41.070085) (xy 60.663162 -41.093681)
			(xy 60.70521 -41.124231) (xy 60.741961 -41.160982) (xy 60.772511 -41.20303) (xy 60.796107 -41.24934)
			(xy 60.812168 -41.29877) (xy 60.820298 -41.350105) (xy 60.820808 -41.376092) (xy 60.820298 -41.402079)
			(xy 60.812168 -41.453414) (xy 60.796107 -41.502844) (xy 60.772511 -41.549154) (xy 60.741961 -41.591202)
			(xy 60.70521 -41.627953) (xy 60.663162 -41.658503) (xy 60.616852 -41.682099) (xy 60.567422 -41.69816)
			(xy 60.516087 -41.70629) (xy 60.464113 -41.70629) (xy 60.412778 -41.69816) (xy 60.363348 -41.682099)
			(xy 60.317038 -41.658503) (xy 60.27499 -41.627953) (xy 60.238239 -41.591202) (xy 60.207689 -41.549154)
			(xy 60.184093 -41.502844) (xy 60.168032 -41.453414) (xy 60.159902 -41.402079) (xy 60.020452 -41.402079)
			(xy 60.012322 -41.453414) (xy 59.996261 -41.502844) (xy 59.972665 -41.549154) (xy 59.942115 -41.591202)
			(xy 59.905364 -41.627953) (xy 59.863316 -41.658503) (xy 59.817006 -41.682099) (xy 59.767576 -41.69816)
			(xy 59.716241 -41.70629) (xy 59.664267 -41.70629) (xy 59.612932 -41.69816) (xy 59.563502 -41.682099)
			(xy 59.517192 -41.658503) (xy 59.475144 -41.627953) (xy 59.438393 -41.591202) (xy 59.407843 -41.549154)
			(xy 59.384247 -41.502844) (xy 59.368186 -41.453414) (xy 59.360056 -41.402079) (xy 59.220352 -41.402079)
			(xy 59.212222 -41.453414) (xy 59.196161 -41.502844) (xy 59.172565 -41.549154) (xy 59.142015 -41.591202)
			(xy 59.105264 -41.627953) (xy 59.063216 -41.658503) (xy 59.016906 -41.682099) (xy 58.967476 -41.69816)
			(xy 58.916141 -41.70629) (xy 58.864167 -41.70629) (xy 58.812832 -41.69816) (xy 58.763402 -41.682099)
			(xy 58.717092 -41.658503) (xy 58.675044 -41.627953) (xy 58.638293 -41.591202) (xy 58.607743 -41.549154)
			(xy 58.584147 -41.502844) (xy 58.568086 -41.453414) (xy 58.559956 -41.402079) (xy 58.420512 -41.402079)
			(xy 58.42048 -41.403744) (xy 58.411312 -41.458282) (xy 58.393182 -41.51053) (xy 58.366596 -41.559024)
			(xy 58.349896 -41.58107) (xy 58.344816 -41.58742) (xy 58.327544 -41.634918) (xy 58.479436 -41.78681)
			(xy 58.500941 -41.808944) (xy 58.539402 -41.857208) (xy 58.572223 -41.909472) (xy 58.598991 -41.96508)
			(xy 58.61937 -42.023333) (xy 58.633105 -42.083501) (xy 58.640022 -42.144827) (xy 58.640472 -42.175684)
			(xy 58.640472 -42.175938) (xy 58.640068 -42.201925) (xy 59.360056 -42.201925) (xy 59.360056 -42.149951)
			(xy 59.368186 -42.098616) (xy 59.384247 -42.049186) (xy 59.407843 -42.002876) (xy 59.438393 -41.960828)
			(xy 59.475144 -41.924077) (xy 59.517192 -41.893527) (xy 59.563502 -41.869931) (xy 59.612932 -41.85387)
			(xy 59.664267 -41.84574) (xy 59.716241 -41.84574) (xy 59.767576 -41.85387) (xy 59.817006 -41.869931)
			(xy 59.863316 -41.893527) (xy 59.905364 -41.924077) (xy 59.942115 -41.960828) (xy 59.972665 -42.002876)
			(xy 59.996261 -42.049186) (xy 60.012322 -42.098616) (xy 60.020452 -42.149951) (xy 60.020962 -42.175938)
			(xy 60.020452 -42.201925) (xy 60.012322 -42.25326) (xy 59.996261 -42.30269) (xy 59.972665 -42.349)
			(xy 59.942115 -42.391048) (xy 59.905364 -42.427799) (xy 59.863316 -42.458349) (xy 59.817006 -42.481945)
			(xy 59.767576 -42.498006) (xy 59.716241 -42.506136) (xy 59.664267 -42.506136) (xy 59.612932 -42.498006)
			(xy 59.563502 -42.481945) (xy 59.517192 -42.458349) (xy 59.475144 -42.427799) (xy 59.438393 -42.391048)
			(xy 59.407843 -42.349) (xy 59.384247 -42.30269) (xy 59.368186 -42.25326) (xy 59.360056 -42.201925)
			(xy 58.640068 -42.201925) (xy 58.639937 -42.210365) (xy 58.631344 -42.27868) (xy 58.614296 -42.34539)
			(xy 58.589061 -42.409453) (xy 58.556031 -42.469867) (xy 58.515724 -42.52569) (xy 58.468768 -42.576048)
			(xy 58.415898 -42.620157) (xy 58.387234 -42.639234) (xy 58.375902 -42.647024) (xy 58.357544 -42.667483)
			(xy 58.345311 -42.692099) (xy 58.340091 -42.719087) (xy 58.342262 -42.746489) (xy 58.351667 -42.772318)
			(xy 58.359294 -42.78376) (xy 58.373831 -42.804918) (xy 58.396884 -42.850782) (xy 58.41257 -42.899659)
			(xy 58.420513 -42.950372) (xy 58.421016 -42.976038) (xy 58.420581 -43.000798) (xy 58.413209 -43.049767)
			(xy 58.398621 -43.09709) (xy 58.377141 -43.141709) (xy 58.349251 -43.182629) (xy 58.315574 -43.218934)
			(xy 58.276861 -43.249814) (xy 58.233978 -43.274579) (xy 58.187882 -43.292675) (xy 58.139604 -43.303699)
			(xy 58.114946 -43.305984) (xy 58.095896 -43.307508) (xy 58.046874 -43.357546) (xy 58.046874 -44.433998)
			(xy 58.062368 -44.449492) (xy 58.083643 -44.47131) (xy 58.121743 -44.518872) (xy 58.154342 -44.570361)
			(xy 58.169747 -44.601971) (xy 59.360056 -44.601971) (xy 59.360056 -44.549997) (xy 59.368186 -44.498662)
			(xy 59.384247 -44.449232) (xy 59.407843 -44.402922) (xy 59.438393 -44.360874) (xy 59.475144 -44.324123)
			(xy 59.517192 -44.293573) (xy 59.563502 -44.269977) (xy 59.612932 -44.253916) (xy 59.664267 -44.245786)
			(xy 59.716241 -44.245786) (xy 59.767576 -44.253916) (xy 59.817006 -44.269977) (xy 59.863316 -44.293573)
			(xy 59.905364 -44.324123) (xy 59.942115 -44.360874) (xy 59.972665 -44.402922) (xy 59.996261 -44.449232)
			(xy 60.012322 -44.498662) (xy 60.020452 -44.549997) (xy 60.020962 -44.575984) (xy 60.020452 -44.601971)
			(xy 60.012322 -44.653306) (xy 59.996261 -44.702736) (xy 59.972665 -44.749046) (xy 59.942115 -44.791094)
			(xy 59.905364 -44.827845) (xy 59.863316 -44.858395) (xy 59.817006 -44.881991) (xy 59.767576 -44.898052)
			(xy 59.716241 -44.906182) (xy 59.664267 -44.906182) (xy 59.612932 -44.898052) (xy 59.563502 -44.881991)
			(xy 59.517192 -44.858395) (xy 59.475144 -44.827845) (xy 59.438393 -44.791094) (xy 59.407843 -44.749046)
			(xy 59.384247 -44.702736) (xy 59.368186 -44.653306) (xy 59.360056 -44.601971) (xy 58.169747 -44.601971)
			(xy 58.181039 -44.625143) (xy 58.191654 -44.653708) (xy 58.195464 -44.66463) (xy 58.572654 -45.041566)
			(xy 58.585495 -45.055391) (xy 58.604252 -45.088115) (xy 58.613967 -45.124561) (xy 58.614564 -45.14342)
			(xy 58.614564 -45.306996) (xy 58.639535 -45.323405) (xy 58.686123 -45.360824) (xy 58.707528 -45.381672)
			(xy 58.727927 -45.402071) (xy 59.360056 -45.402071) (xy 59.360056 -45.350097) (xy 59.368186 -45.298762)
			(xy 59.384247 -45.249332) (xy 59.407843 -45.203022) (xy 59.438393 -45.160974) (xy 59.475144 -45.124223)
			(xy 59.517192 -45.093673) (xy 59.563502 -45.070077) (xy 59.612932 -45.054016) (xy 59.664267 -45.045886)
			(xy 59.716241 -45.045886) (xy 59.767576 -45.054016) (xy 59.817006 -45.070077) (xy 59.863316 -45.093673)
			(xy 59.905364 -45.124223) (xy 59.942115 -45.160974) (xy 59.972665 -45.203022) (xy 59.996261 -45.249332)
			(xy 60.012322 -45.298762) (xy 60.020452 -45.350097) (xy 60.020962 -45.376084) (xy 60.020452 -45.402071)
			(xy 60.012322 -45.453406) (xy 59.996261 -45.502836) (xy 59.972665 -45.549146) (xy 59.942115 -45.591194)
			(xy 59.905364 -45.627945) (xy 59.863316 -45.658495) (xy 59.817006 -45.682091) (xy 59.767576 -45.698152)
			(xy 59.716241 -45.706282) (xy 59.664267 -45.706282) (xy 59.612932 -45.698152) (xy 59.563502 -45.682091)
			(xy 59.517192 -45.658495) (xy 59.475144 -45.627945) (xy 59.438393 -45.591194) (xy 59.407843 -45.549146)
			(xy 59.384247 -45.502836) (xy 59.368186 -45.453406) (xy 59.360056 -45.402071) (xy 58.727927 -45.402071)
			(xy 58.852816 -45.52696) (xy 58.874836 -45.549592) (xy 58.914089 -45.599057) (xy 58.947412 -45.652695)
			(xy 58.974367 -45.709801) (xy 58.994598 -45.769619) (xy 59.007837 -45.831363) (xy 59.011312 -45.862748)
			(xy 59.01309 -45.881036) (xy 59.170316 -46.038262) (xy 60.452 -46.038262)
		)
		(stroke
			(width 0)
			(type solid)
		)
		(fill yes)
		(layer "In9.Cu")
		(net "P1V0_STBY_PLAVDD")
	)
	(gr_poly
		(pts
			(xy 82.249772 -99.083876) (xy 82.250735 -99.055624) (xy 82.259967 -98.999855) (xy 82.277326 -98.946059)
			(xy 82.302433 -98.895412) (xy 82.334736 -98.849024) (xy 82.37353 -98.80791) (xy 82.417966 -98.772969)
			(xy 82.46707 -98.744966) (xy 82.519768 -98.724515) (xy 82.574907 -98.712062) (xy 82.63128 -98.70788)
			(xy 82.687653 -98.712062) (xy 82.742792 -98.724515) (xy 82.79549 -98.744966) (xy 82.844594 -98.772969)
			(xy 82.88903 -98.80791) (xy 82.927824 -98.849024) (xy 82.960127 -98.895412) (xy 82.985234 -98.946059)
			(xy 83.002593 -98.999855) (xy 83.011825 -99.055624) (xy 83.012788 -99.083876) (xy 83.014058 -99.126294)
			(xy 86.939628 -99.126294) (xy 87.17534 -98.890582) (xy 87.17534 -86.828376) (xy 85.873844 -85.52688)
			(xy 85.873844 -73.067418) (xy 85.873293 -73.052285) (xy 85.864426 -73.023346) (xy 85.847467 -72.998277)
			(xy 85.823904 -72.979281) (xy 85.795808 -72.968025) (xy 85.765647 -72.965499) (xy 85.73607 -72.971925)
			(xy 85.709676 -72.986739) (xy 85.698838 -72.997314) (xy 85.680774 -73.015557) (xy 85.640601 -73.047524)
			(xy 85.596508 -73.073821) (xy 85.549288 -73.093971) (xy 85.499794 -73.107612) (xy 85.448918 -73.114498)
			(xy 85.423248 -73.114916) (xy 85.395993 -73.114456) (xy 85.342036 -73.106705) (xy 85.289732 -73.091353)
			(xy 85.240145 -73.068713) (xy 85.194286 -73.039247) (xy 85.153087 -73.003553) (xy 85.117387 -72.962359)
			(xy 85.087914 -72.916504) (xy 85.065267 -72.86692) (xy 85.049907 -72.814619) (xy 85.042148 -72.760663)
			(xy 85.04174 -72.733408) (xy 85.042251 -72.705146) (xy 85.050586 -72.649239) (xy 85.067077 -72.595173)
			(xy 85.09136 -72.544131) (xy 85.122907 -72.497228) (xy 85.161026 -72.455492) (xy 85.204884 -72.419834)
			(xy 85.228938 -72.404986) (xy 85.240198 -72.396849) (xy 85.258219 -72.375721) (xy 85.269885 -72.350522)
			(xy 85.274334 -72.323111) (xy 85.271237 -72.295515) (xy 85.260824 -72.269773) (xy 85.243863 -72.247785)
			(xy 85.233002 -72.239124) (xy 85.209622 -72.220992) (xy 85.168226 -72.178723) (xy 85.133851 -72.13057)
			(xy 85.107321 -72.077688) (xy 85.089272 -72.021344) (xy 85.080138 -71.96289) (xy 85.079586 -71.933308)
			(xy 85.080049 -71.906055) (xy 85.087805 -71.852103) (xy 85.10316 -71.799803) (xy 85.125802 -71.750222)
			(xy 85.15527 -71.704367) (xy 85.190963 -71.663173) (xy 85.232156 -71.627478) (xy 85.27801 -71.598009)
			(xy 85.32759 -71.575365) (xy 85.379889 -71.560008) (xy 85.433841 -71.55225) (xy 85.461094 -71.5518)
			(xy 85.488121 -71.552269) (xy 85.541635 -71.559899) (xy 85.593536 -71.575005) (xy 85.642785 -71.597287)
			(xy 85.688396 -71.626297) (xy 85.709252 -71.643494) (xy 85.720725 -71.651949) (xy 85.747089 -71.662741)
			(xy 85.77541 -71.665827) (xy 85.80348 -71.660967) (xy 85.829114 -71.648539) (xy 85.850315 -71.629511)
			(xy 85.865432 -71.605365) (xy 85.873288 -71.577982) (xy 85.873844 -71.563738) (xy 85.873844 -70.896988)
			(xy 84.884768 -69.907912) (xy 80.475582 -69.907912) (xy 79.281782 -71.101712) (xy 79.271922 -71.112341)
			(xy 79.258069 -71.137795) (xy 79.251922 -71.166114) (xy 79.253976 -71.19502) (xy 79.264066 -71.222186)
			(xy 79.28138 -71.245425) (xy 79.304523 -71.262865) (xy 79.331633 -71.273104) (xy 79.346044 -71.274686)
			(xy 79.374456 -71.277375) (xy 79.430083 -71.290122) (xy 79.48319 -71.311014) (xy 79.532591 -71.339587)
			(xy 79.577183 -71.375201) (xy 79.615971 -71.417061) (xy 79.648088 -71.464234) (xy 79.672819 -71.515666)
			(xy 79.68961 -71.570208) (xy 79.698087 -71.626644) (xy 79.698596 -71.655178) (xy 79.698117 -71.682679)
			(xy 79.690224 -71.73711) (xy 79.674598 -71.789845) (xy 79.651562 -71.83979) (xy 79.621595 -71.88591)
			(xy 79.585317 -71.92725) (xy 79.543479 -71.962954) (xy 79.496949 -71.992281) (xy 79.472028 -72.00392)
			(xy 79.459731 -72.009831) (xy 79.438599 -72.02707) (xy 79.422796 -72.049298) (xy 79.413454 -72.074921)
			(xy 79.411242 -72.102103) (xy 79.41632 -72.128899) (xy 79.428323 -72.153389) (xy 79.436976 -72.16394)
			(xy 79.457241 -72.185454) (xy 79.491553 -72.233575) (xy 79.518034 -72.28641) (xy 79.536052 -72.342698)
			(xy 79.545174 -72.40109) (xy 79.545688 -72.43064) (xy 79.545153 -72.459904) (xy 79.53621 -72.517745)
			(xy 79.51854 -72.573542) (xy 79.492557 -72.625987) (xy 79.458871 -72.673849) (xy 79.418271 -72.716007)
			(xy 79.39532 -72.73417) (xy 79.383489 -72.743767) (xy 79.365709 -72.768489) (xy 79.356008 -72.797353)
			(xy 79.355246 -72.827795) (xy 79.363493 -72.857109) (xy 79.380014 -72.882689) (xy 79.403341 -72.902262)
			(xy 79.417164 -72.908668) (xy 79.443471 -72.919632) (xy 79.492768 -72.948228) (xy 79.537261 -72.983841)
			(xy 79.575961 -73.025678) (xy 79.608004 -73.072807) (xy 79.632678 -73.12418) (xy 79.649434 -73.178652)
			(xy 79.657898 -73.23501) (xy 79.658464 -73.263506) (xy 79.657978 -73.290757) (xy 79.650222 -73.344705)
			(xy 79.634867 -73.397) (xy 79.612225 -73.446577) (xy 79.582759 -73.492427) (xy 79.547068 -73.533618)
			(xy 79.505877 -73.569309) (xy 79.460027 -73.598775) (xy 79.41045 -73.621417) (xy 79.358155 -73.636772)
			(xy 79.304207 -73.644528) (xy 79.249705 -73.644528) (xy 79.195757 -73.636772) (xy 79.143462 -73.621417)
			(xy 79.093885 -73.598775) (xy 79.048035 -73.569309) (xy 79.006844 -73.533618) (xy 78.971153 -73.492427)
			(xy 78.941687 -73.446577) (xy 78.919045 -73.397) (xy 78.90369 -73.344705) (xy 78.895934 -73.290757)
			(xy 78.895448 -73.263506) (xy 78.89598 -73.234241) (xy 78.904917 -73.176397) (xy 78.922584 -73.120596)
			(xy 78.948564 -73.068148) (xy 78.98225 -73.020282) (xy 79.02285 -72.978122) (xy 79.045816 -72.959976)
			(xy 79.057609 -72.950335) (xy 79.075385 -72.92562) (xy 79.085088 -72.896764) (xy 79.085856 -72.86633)
			(xy 79.07762 -72.837021) (xy 79.061112 -72.811442) (xy 79.037799 -72.791863) (xy 79.023972 -72.785478)
			(xy 78.997661 -72.774517) (xy 78.948356 -72.745924) (xy 78.903854 -72.710314) (xy 78.865147 -72.668478)
			(xy 78.833094 -72.621349) (xy 78.808412 -72.569975) (xy 78.791648 -72.515501) (xy 78.783176 -72.459138)
			(xy 78.782672 -72.43064) (xy 78.78315 -72.403138) (xy 78.79104 -72.348704) (xy 78.806664 -72.295966)
			(xy 78.829697 -72.246018) (xy 78.859662 -72.199893) (xy 78.895939 -72.158548) (xy 78.937775 -72.12284)
			(xy 78.984304 -72.093507) (xy 79.00924 -72.081898) (xy 79.021542 -72.07599) (xy 79.042685 -72.058752)
			(xy 79.058498 -72.036522) (xy 79.067847 -72.010894) (xy 79.070062 -71.983704) (xy 79.064984 -71.956901)
			(xy 79.052978 -71.932406) (xy 79.044292 -71.921878) (xy 79.026522 -71.903092) (xy 78.995692 -71.861576)
			(xy 78.970752 -71.816277) (xy 78.952157 -71.768025) (xy 78.94025 -71.717704) (xy 78.937358 -71.692008)
			(xy 78.936596 -71.684134) (xy 78.935004 -71.669719) (xy 78.924798 -71.642588) (xy 78.907373 -71.619423)
			(xy 78.884135 -71.602095) (xy 78.856961 -71.592004) (xy 78.828045 -71.589965) (xy 78.799724 -71.596142)
			(xy 78.774284 -71.610037) (xy 78.763622 -71.619872) (xy 78.650084 -71.73341) (xy 78.650084 -72.94372)
			(xy 78.64965 -72.98021) (xy 78.642494 -73.052837) (xy 78.628255 -73.124413) (xy 78.607068 -73.194249)
			(xy 78.579138 -73.261672) (xy 78.544734 -73.326033) (xy 78.504187 -73.386711) (xy 78.457887 -73.443123)
			(xy 78.432406 -73.469246) (xy 77.539088 -74.362818) (xy 77.148944 -74.752962) (xy 77.148944 -74.903651)
			(xy 78.282784 -74.903651) (xy 78.282784 -74.849149) (xy 78.29054 -74.795202) (xy 78.305895 -74.742908)
			(xy 78.328536 -74.693332) (xy 78.358002 -74.647482) (xy 78.393693 -74.606293) (xy 78.434882 -74.570602)
			(xy 78.480732 -74.541136) (xy 78.530308 -74.518495) (xy 78.582602 -74.50314) (xy 78.636549 -74.495384)
			(xy 78.6638 -74.494898) (xy 78.688556 -74.495292) (xy 78.737656 -74.501666) (xy 78.785519 -74.514335)
			(xy 78.80858 -74.523346) (xy 78.821279 -74.528105) (xy 78.848187 -74.531418) (xy 78.875018 -74.527534)
			(xy 78.899881 -74.516726) (xy 78.921025 -74.499758) (xy 78.936959 -74.477824) (xy 78.94656 -74.452471)
			(xy 78.94828 -74.439018) (xy 78.95145 -74.411001) (xy 78.964901 -74.356248) (xy 78.986264 -74.304072)
			(xy 79.015076 -74.255609) (xy 79.050708 -74.211915) (xy 79.092383 -74.173942) (xy 79.139195 -74.142518)
			(xy 79.190122 -74.118327) (xy 79.244055 -74.101896) (xy 79.29982 -74.093583) (xy 79.32801 -74.09307)
			(xy 79.355259 -74.093601) (xy 79.409203 -74.101358) (xy 79.461493 -74.116713) (xy 79.511066 -74.139354)
			(xy 79.556913 -74.168818) (xy 79.598099 -74.204508) (xy 79.633788 -74.245695) (xy 79.663251 -74.291543)
			(xy 79.68589 -74.341116) (xy 79.701244 -74.393407) (xy 79.709 -74.447351) (xy 79.709 -74.501849)
			(xy 79.701244 -74.555793) (xy 79.68589 -74.608084) (xy 79.663251 -74.657657) (xy 79.633788 -74.703505)
			(xy 79.598099 -74.744692) (xy 79.556913 -74.780382) (xy 79.511066 -74.809846) (xy 79.461493 -74.832487)
			(xy 79.409203 -74.847842) (xy 79.355259 -74.855599) (xy 79.32801 -74.856086) (xy 79.303254 -74.85569)
			(xy 79.254154 -74.849317) (xy 79.206291 -74.836649) (xy 79.18323 -74.827638) (xy 79.170523 -74.822904)
			(xy 79.14362 -74.819591) (xy 79.116793 -74.823472) (xy 79.091932 -74.834276) (xy 79.070789 -74.851239)
			(xy 79.054855 -74.873168) (xy 79.045251 -74.898516) (xy 79.04353 -74.911966) (xy 79.04042 -74.93999)
			(xy 79.026958 -74.994743) (xy 79.005584 -75.046919) (xy 78.976764 -75.09538) (xy 78.941125 -75.139073)
			(xy 78.899443 -75.177043) (xy 78.852627 -75.208466) (xy 78.801696 -75.232656) (xy 78.747759 -75.249087)
			(xy 78.691992 -75.2574) (xy 78.6638 -75.257914) (xy 78.636549 -75.257416) (xy 78.582602 -75.24966)
			(xy 78.530308 -75.234305) (xy 78.480732 -75.211664) (xy 78.434882 -75.182198) (xy 78.393693 -75.146507)
			(xy 78.358002 -75.105318) (xy 78.328536 -75.059468) (xy 78.305895 -75.009892) (xy 78.29054 -74.957598)
			(xy 78.282784 -74.903651) (xy 77.148944 -74.903651) (xy 77.148944 -75.226926) (xy 77.174254 -75.239861)
			(xy 77.22107 -75.272093) (xy 77.262586 -75.310914) (xy 77.297883 -75.355464) (xy 77.326181 -75.404757)
			(xy 77.346853 -75.457703) (xy 77.359441 -75.51313) (xy 77.363667 -75.569811) (xy 77.359437 -75.626492)
			(xy 77.346846 -75.681918) (xy 77.326171 -75.734863) (xy 77.29787 -75.784155) (xy 77.26257 -75.828703)
			(xy 77.221052 -75.867521) (xy 77.174234 -75.89975) (xy 77.148944 -75.912726) (xy 77.148944 -76.05776)
			(xy 79.420212 -76.05776) (xy 79.42064 -76.030594) (xy 79.428333 -75.976811) (xy 79.443586 -75.924665)
			(xy 79.466089 -75.875213) (xy 79.495387 -75.829459) (xy 79.530885 -75.788328) (xy 79.571865 -75.752656)
			(xy 79.617495 -75.723165) (xy 79.666851 -75.700452) (xy 79.692754 -75.692254) (xy 79.70593 -75.687884)
			(xy 79.7294 -75.673074) (xy 79.748023 -75.652498) (xy 79.760428 -75.627673) (xy 79.765702 -75.600427)
			(xy 79.763454 -75.572766) (xy 79.753852 -75.546728) (xy 79.737603 -75.524231) (xy 79.727044 -75.515216)
			(xy 79.704942 -75.497036) (xy 79.66594 -75.455156) (xy 79.633633 -75.407919) (xy 79.608746 -75.356385)
			(xy 79.591837 -75.301712) (xy 79.583285 -75.245126) (xy 79.582772 -75.216512) (xy 79.583231 -75.187806)
			(xy 79.591853 -75.131044) (xy 79.608875 -75.076212) (xy 79.633913 -75.024546) (xy 79.666403 -74.97721)
			(xy 79.705612 -74.935271) (xy 79.750657 -74.899674) (xy 79.800524 -74.87122) (xy 79.82712 -74.860404)
			(xy 79.840401 -74.854821) (xy 79.86331 -74.837366) (xy 79.880432 -74.814208) (xy 79.890405 -74.787189)
			(xy 79.892435 -74.75846) (xy 79.886361 -74.730307) (xy 79.879952 -74.717402) (xy 79.86558 -74.6894)
			(xy 79.845204 -74.629852) (xy 79.834876 -74.567769) (xy 79.834232 -74.5363) (xy 79.834672 -74.50939)
			(xy 79.842222 -74.456103) (xy 79.857187 -74.404405) (xy 79.87927 -74.355325) (xy 79.908031 -74.309835)
			(xy 79.942901 -74.268839) (xy 79.983187 -74.233151) (xy 80.028088 -74.203479) (xy 80.076714 -74.180413)
			(xy 80.1281 -74.16441) (xy 80.181225 -74.155789) (xy 80.20812 -74.154792) (xy 80.22176 -74.154051)
			(xy 80.247926 -74.146247) (xy 80.271092 -74.131793) (xy 80.289604 -74.11172) (xy 80.302139 -74.087462)
			(xy 80.307803 -74.060751) (xy 80.307434 -74.047096) (xy 80.306672 -74.02322) (xy 80.307158 -73.995969)
			(xy 80.314914 -73.942021) (xy 80.330269 -73.889726) (xy 80.352911 -73.840149) (xy 80.382377 -73.794299)
			(xy 80.418068 -73.753108) (xy 80.459259 -73.717417) (xy 80.505109 -73.687951) (xy 80.554686 -73.665309)
			(xy 80.606981 -73.649954) (xy 80.660929 -73.642198) (xy 80.715431 -73.642198) (xy 80.769379 -73.649954)
			(xy 80.821674 -73.665309) (xy 80.871251 -73.687951) (xy 80.917101 -73.717417) (xy 80.958292 -73.753108)
			(xy 80.993983 -73.794299) (xy 81.023449 -73.840149) (xy 81.046091 -73.889726) (xy 81.061446 -73.942021)
			(xy 81.069202 -73.995969) (xy 81.069688 -74.02322) (xy 81.069154 -74.050127) (xy 81.061615 -74.10341)
			(xy 81.046661 -74.155105) (xy 81.024589 -74.204184) (xy 80.995838 -74.249673) (xy 80.960978 -74.290669)
			(xy 80.920701 -74.326358) (xy 80.875808 -74.356032) (xy 80.827189 -74.3791) (xy 80.775811 -74.395105)
			(xy 80.722692 -74.40373) (xy 80.6958 -74.404728) (xy 80.682159 -74.405465) (xy 80.65599 -74.413266)
			(xy 80.632822 -74.42772) (xy 80.614309 -74.447794) (xy 80.601775 -74.472054) (xy 80.596115 -74.498768)
			(xy 80.596486 -74.512424) (xy 80.597248 -74.5363) (xy 80.59706 -74.552962) (xy 80.594137 -74.586157)
			(xy 80.591406 -74.602594) (xy 80.589477 -74.616115) (xy 80.592121 -74.643291) (xy 80.601865 -74.668798)
			(xy 80.618016 -74.690813) (xy 80.63942 -74.707767) (xy 80.664548 -74.718447) (xy 80.67802 -74.720704)
			(xy 80.705142 -74.724834) (xy 80.757902 -74.739875) (xy 80.807964 -74.762313) (xy 80.854299 -74.791687)
			(xy 80.895952 -74.827392) (xy 80.932064 -74.868692) (xy 80.961892 -74.914736) (xy 80.984822 -74.964576)
			(xy 81.00038 -75.017185) (xy 81.008247 -75.071479) (xy 81.008728 -75.09891) (xy 81.008232 -75.126161)
			(xy 81.000474 -75.180107) (xy 80.985119 -75.2324) (xy 80.962478 -75.281976) (xy 80.933013 -75.327826)
			(xy 80.897322 -75.369015) (xy 80.856134 -75.404707) (xy 80.810285 -75.434173) (xy 80.76071 -75.456815)
			(xy 80.708417 -75.472172) (xy 80.654471 -75.479931) (xy 80.62722 -75.480418) (xy 80.598831 -75.479877)
			(xy 80.542678 -75.471471) (xy 80.488389 -75.454842) (xy 80.437161 -75.430356) (xy 80.413352 -75.414886)
			(xy 80.399996 -75.406625) (xy 80.369899 -75.397738) (xy 80.338523 -75.398386) (xy 80.308819 -75.408509)
			(xy 80.283576 -75.427154) (xy 80.273906 -75.439524) (xy 80.258944 -75.459645) (xy 80.224542 -75.496123)
			(xy 80.185653 -75.527774) (xy 80.142949 -75.554052) (xy 80.097167 -75.574502) (xy 80.073246 -75.582018)
			(xy 80.060087 -75.586433) (xy 80.036622 -75.601237) (xy 80.018001 -75.621805) (xy 80.005596 -75.646622)
			(xy 80.000321 -75.673861) (xy 80.002564 -75.701515) (xy 80.01216 -75.727548) (xy 80.028401 -75.750042)
			(xy 80.038956 -75.759056) (xy 80.061045 -75.777251) (xy 80.100047 -75.819128) (xy 80.132356 -75.866362)
			(xy 80.157246 -75.917893) (xy 80.174158 -75.972563) (xy 80.182713 -76.029147) (xy 80.183228 -76.05776)
			(xy 80.182761 -76.085377) (xy 80.17477 -76.140029) (xy 80.158978 -76.192958) (xy 80.135717 -76.243054)
			(xy 80.105471 -76.289271) (xy 80.068875 -76.330641) (xy 80.0481 -76.348844) (xy 80.037049 -76.358824)
			(xy 80.020827 -76.383781) (xy 80.012485 -76.412353) (xy 80.012731 -76.442117) (xy 80.021544 -76.470548)
			(xy 80.038176 -76.495233) (xy 80.04937 -76.505054) (xy 80.070718 -76.523289) (xy 80.108394 -76.564909)
			(xy 80.139562 -76.611603) (xy 80.163547 -76.662362) (xy 80.179832 -76.71609) (xy 80.188063 -76.771624)
			(xy 80.188562 -76.799694) (xy 80.188076 -76.826945) (xy 80.18032 -76.880893) (xy 80.164965 -76.933188)
			(xy 80.142323 -76.982765) (xy 80.112857 -77.028615) (xy 80.077166 -77.069806) (xy 80.035975 -77.105497)
			(xy 79.990125 -77.134963) (xy 79.940548 -77.157605) (xy 79.888253 -77.17296) (xy 79.834305 -77.180716)
			(xy 79.779803 -77.180716) (xy 79.725855 -77.17296) (xy 79.67356 -77.157605) (xy 79.623983 -77.134963)
			(xy 79.578133 -77.105497) (xy 79.536942 -77.069806) (xy 79.501251 -77.028615) (xy 79.471785 -76.982765)
			(xy 79.449143 -76.933188) (xy 79.433788 -76.880893) (xy 79.426032 -76.826945) (xy 79.425546 -76.799694)
			(xy 79.426059 -76.772079) (xy 79.434042 -76.717429) (xy 79.449825 -76.664502) (xy 79.473078 -76.614405)
			(xy 79.503315 -76.568187) (xy 79.539903 -76.526815) (xy 79.560674 -76.50861) (xy 79.571672 -76.498575)
			(xy 79.587901 -76.473636) (xy 79.596251 -76.445077) (xy 79.596016 -76.415323) (xy 79.587214 -76.386899)
			(xy 79.570592 -76.36222) (xy 79.559404 -76.3524) (xy 79.538029 -76.334196) (xy 79.500355 -76.292569)
			(xy 79.469192 -76.245868) (xy 79.445211 -76.195103) (xy 79.428933 -76.14137) (xy 79.420708 -76.085832)
			(xy 79.420212 -76.05776) (xy 77.148944 -76.05776) (xy 77.148944 -76.988162) (xy 77.14945 -77.003428)
			(xy 77.158451 -77.032604) (xy 77.175662 -77.057823) (xy 77.199549 -77.076839) (xy 77.227985 -77.087958)
			(xy 77.243178 -77.089508) (xy 77.270327 -77.091912) (xy 77.323585 -77.103493) (xy 77.374652 -77.122535)
			(xy 77.42249 -77.148652) (xy 77.466123 -77.181312) (xy 77.504664 -77.219849) (xy 77.537328 -77.263479)
			(xy 77.563449 -77.311314) (xy 77.582497 -77.36238) (xy 77.594083 -77.415636) (xy 77.597971 -77.47)
			(xy 77.594083 -77.524364) (xy 77.582497 -77.57762) (xy 77.563449 -77.628686) (xy 77.537328 -77.676521)
			(xy 77.504664 -77.720151) (xy 77.466123 -77.758688) (xy 77.42249 -77.791348) (xy 77.374652 -77.817465)
			(xy 77.323585 -77.836507) (xy 77.270327 -77.848088) (xy 77.243178 -77.850492) (xy 77.227991 -77.852104)
			(xy 77.199552 -77.863199) (xy 77.175657 -77.882198) (xy 77.15844 -77.907406) (xy 77.149435 -77.936574)
			(xy 77.148944 -77.951838) (xy 77.148944 -78.204314) (xy 77.169578 -78.216345) (xy 77.207972 -78.244761)
			(xy 77.242536 -78.277728) (xy 77.25791 -78.296008) (xy 77.267591 -78.307096) (xy 77.291914 -78.32365)
			(xy 77.319944 -78.332595) (xy 77.34936 -78.33319) (xy 77.377728 -78.325387) (xy 77.402702 -78.30983)
			(xy 77.422213 -78.287808) (xy 77.428852 -78.274672) (xy 77.440676 -78.250276) (xy 77.470198 -78.204808)
			(xy 77.505863 -78.16398) (xy 77.546952 -78.128616) (xy 77.592636 -78.099429) (xy 77.641993 -78.077008)
			(xy 77.694029 -78.061804) (xy 77.747694 -78.054125) (xy 77.7748 -78.053692) (xy 77.802051 -78.054178)
			(xy 77.855999 -78.061934) (xy 77.908294 -78.077289) (xy 77.957871 -78.099931) (xy 78.003721 -78.129397)
			(xy 78.044912 -78.165088) (xy 78.080603 -78.206279) (xy 78.110069 -78.252129) (xy 78.132711 -78.301706)
			(xy 78.148066 -78.354001) (xy 78.155822 -78.407949) (xy 78.155822 -78.462451) (xy 78.148066 -78.516399)
			(xy 78.132711 -78.568694) (xy 78.110069 -78.618271) (xy 78.080603 -78.664121) (xy 78.044912 -78.705312)
			(xy 78.003721 -78.741003) (xy 77.957871 -78.770469) (xy 77.92559 -78.785212) (xy 79.40802 -78.785212)
			(xy 79.408478 -78.758178) (xy 79.416123 -78.704652) (xy 79.431246 -78.652741) (xy 79.453545 -78.603485)
			(xy 79.482574 -78.55787) (xy 79.517751 -78.516809) (xy 79.558372 -78.481124) (xy 79.58074 -78.465934)
			(xy 79.592363 -78.457704) (xy 79.61094 -78.436137) (xy 79.622844 -78.41028) (xy 79.627153 -78.382143)
			(xy 79.62353 -78.35391) (xy 79.612259 -78.327771) (xy 79.594212 -78.305758) (xy 79.582772 -78.297278)
			(xy 79.561289 -78.281961) (xy 79.522377 -78.246327) (xy 79.488747 -78.205672) (xy 79.461039 -78.160771)
			(xy 79.439783 -78.11248) (xy 79.425384 -78.06172) (xy 79.418117 -78.009461) (xy 79.417672 -77.98308)
			(xy 79.418158 -77.955829) (xy 79.425914 -77.901881) (xy 79.441269 -77.849586) (xy 79.463911 -77.800009)
			(xy 79.493377 -77.754159) (xy 79.529068 -77.712968) (xy 79.570259 -77.677277) (xy 79.616109 -77.647811)
			(xy 79.665686 -77.625169) (xy 79.717981 -77.609814) (xy 79.771929 -77.602058) (xy 79.826431 -77.602058)
			(xy 79.880379 -77.609814) (xy 79.932674 -77.625169) (xy 79.982251 -77.647811) (xy 80.028101 -77.677277)
			(xy 80.069292 -77.712968) (xy 80.104983 -77.754159) (xy 80.134449 -77.800009) (xy 80.157091 -77.849586)
			(xy 80.172446 -77.901881) (xy 80.180202 -77.955829) (xy 80.180688 -77.98308) (xy 80.18022 -78.010114)
			(xy 80.172577 -78.063639) (xy 80.157455 -78.115549) (xy 80.135157 -78.164805) (xy 80.10613 -78.210421)
			(xy 80.070955 -78.251482) (xy 80.030335 -78.287167) (xy 80.007968 -78.302358) (xy 79.996352 -78.310597)
			(xy 79.977774 -78.332162) (xy 79.965868 -78.358017) (xy 79.961558 -78.386152) (xy 79.96518 -78.414385)
			(xy 79.97645 -78.440522) (xy 79.994496 -78.462535) (xy 80.005936 -78.471014) (xy 80.027417 -78.486334)
			(xy 80.066328 -78.521967) (xy 80.099959 -78.562622) (xy 80.127666 -78.607523) (xy 80.148923 -78.655813)
			(xy 80.163322 -78.706572) (xy 80.170591 -78.758831) (xy 80.171036 -78.785212) (xy 80.17055 -78.812463)
			(xy 80.162794 -78.866411) (xy 80.147439 -78.918706) (xy 80.124797 -78.968283) (xy 80.095331 -79.014133)
			(xy 80.05964 -79.055324) (xy 80.018449 -79.091015) (xy 79.972599 -79.120481) (xy 79.923022 -79.143123)
			(xy 79.870727 -79.158478) (xy 79.816779 -79.166234) (xy 79.762277 -79.166234) (xy 79.708329 -79.158478)
			(xy 79.656034 -79.143123) (xy 79.606457 -79.120481) (xy 79.560607 -79.091015) (xy 79.519416 -79.055324)
			(xy 79.483725 -79.014133) (xy 79.454259 -78.968283) (xy 79.431617 -78.918706) (xy 79.416262 -78.866411)
			(xy 79.408506 -78.812463) (xy 79.40802 -78.785212) (xy 77.92559 -78.785212) (xy 77.908294 -78.793111)
			(xy 77.855999 -78.808466) (xy 77.802051 -78.816222) (xy 77.7748 -78.816708) (xy 77.746563 -78.816198)
			(xy 77.690706 -78.807873) (xy 77.636686 -78.791404) (xy 77.585685 -78.767152) (xy 77.538816 -78.735647)
			(xy 77.497103 -78.697576) (xy 77.47889 -78.675992) (xy 77.469209 -78.664904) (xy 77.444886 -78.64835)
			(xy 77.416856 -78.639405) (xy 77.38744 -78.63881) (xy 77.359072 -78.646613) (xy 77.334098 -78.66217)
			(xy 77.314587 -78.684192) (xy 77.307948 -78.697328) (xy 77.29659 -78.720814) (xy 77.268401 -78.764713)
			(xy 77.234493 -78.80436) (xy 77.195497 -78.839016) (xy 77.152142 -78.868034) (xy 77.105236 -78.890872)
			(xy 77.055656 -78.907105) (xy 77.030072 -78.912212) (xy 77.008197 -78.945051) (xy 76.958559 -79.00639)
			(xy 76.931012 -79.03464) (xy 76.562204 -79.403448) (xy 76.562204 -80.01) (xy 78.230982 -80.01) (xy 78.235053 -79.954378)
			(xy 78.247179 -79.899941) (xy 78.267102 -79.84785) (xy 78.294398 -79.799215) (xy 78.328484 -79.755072)
			(xy 78.368633 -79.716363) (xy 78.413991 -79.683912) (xy 78.463591 -79.658411) (xy 78.516375 -79.640404)
			(xy 78.571218 -79.630274) (xy 78.626952 -79.628237) (xy 78.682389 -79.634337) (xy 78.736346 -79.648443)
			(xy 78.787675 -79.670255) (xy 78.835281 -79.699309) (xy 78.878149 -79.734984) (xy 78.915366 -79.776521)
			(xy 78.946139 -79.823034) (xy 78.969811 -79.873531) (xy 78.985879 -79.926938) (xy 78.986889 -79.9338)
			(xy 83.666582 -79.9338) (xy 83.670653 -79.878178) (xy 83.682779 -79.823741) (xy 83.702702 -79.77165)
			(xy 83.729998 -79.723015) (xy 83.764084 -79.678872) (xy 83.804233 -79.640163) (xy 83.849591 -79.607712)
			(xy 83.899191 -79.582211) (xy 83.951975 -79.564204) (xy 84.006818 -79.554074) (xy 84.062552 -79.552037)
			(xy 84.117989 -79.558137) (xy 84.171946 -79.572243) (xy 84.223275 -79.594055) (xy 84.270881 -79.623109)
			(xy 84.313749 -79.658784) (xy 84.350966 -79.700321) (xy 84.381739 -79.746834) (xy 84.405411 -79.797331)
			(xy 84.421479 -79.850738) (xy 84.429599 -79.905914) (xy 84.430108 -79.9338) (xy 84.429599 -79.961686)
			(xy 84.421479 -80.016862) (xy 84.405411 -80.070269) (xy 84.381739 -80.120766) (xy 84.350966 -80.167279)
			(xy 84.313749 -80.208816) (xy 84.270881 -80.244491) (xy 84.223275 -80.273545) (xy 84.171946 -80.295357)
			(xy 84.117989 -80.309463) (xy 84.062552 -80.315563) (xy 84.006818 -80.313526) (xy 83.951975 -80.303396)
			(xy 83.899191 -80.285389) (xy 83.849591 -80.259888) (xy 83.804233 -80.227437) (xy 83.764084 -80.188728)
			(xy 83.729998 -80.144585) (xy 83.702702 -80.09595) (xy 83.682779 -80.043859) (xy 83.670653 -79.989422)
			(xy 83.666582 -79.9338) (xy 78.986889 -79.9338) (xy 78.993999 -79.982114) (xy 78.994508 -80.01) (xy 78.993999 -80.037886)
			(xy 78.985879 -80.093062) (xy 78.969811 -80.146469) (xy 78.946139 -80.196966) (xy 78.915366 -80.243479)
			(xy 78.878149 -80.285016) (xy 78.835281 -80.320691) (xy 78.787675 -80.349745) (xy 78.736346 -80.371557)
			(xy 78.682389 -80.385663) (xy 78.626952 -80.391763) (xy 78.571218 -80.389726) (xy 78.516375 -80.379596)
			(xy 78.463591 -80.361589) (xy 78.413991 -80.336088) (xy 78.368633 -80.303637) (xy 78.328484 -80.264928)
			(xy 78.294398 -80.220785) (xy 78.267102 -80.17215) (xy 78.247179 -80.120059) (xy 78.235053 -80.065622)
			(xy 78.230982 -80.01) (xy 76.562204 -80.01) (xy 76.562204 -81.407) (xy 78.611982 -81.407) (xy 78.616053 -81.351378)
			(xy 78.628179 -81.296941) (xy 78.648102 -81.24485) (xy 78.675398 -81.196215) (xy 78.709484 -81.152072)
			(xy 78.749633 -81.113363) (xy 78.794991 -81.080912) (xy 78.844591 -81.055411) (xy 78.897375 -81.037404)
			(xy 78.952218 -81.027274) (xy 79.007952 -81.025237) (xy 79.063389 -81.031337) (xy 79.117346 -81.045443)
			(xy 79.168675 -81.067255) (xy 79.216281 -81.096309) (xy 79.259149 -81.131984) (xy 79.296366 -81.173521)
			(xy 79.327139 -81.220034) (xy 79.350811 -81.270531) (xy 79.366879 -81.323938) (xy 79.374999 -81.379114)
			(xy 79.375508 -81.407) (xy 79.374999 -81.434886) (xy 79.366879 -81.490062) (xy 79.350811 -81.543469)
			(xy 79.327139 -81.593966) (xy 79.296366 -81.640479) (xy 79.259149 -81.682016) (xy 79.216281 -81.717691)
			(xy 79.168675 -81.746745) (xy 79.117346 -81.768557) (xy 79.063389 -81.782663) (xy 79.007952 -81.788763)
			(xy 78.952218 -81.786726) (xy 78.897375 -81.776596) (xy 78.844591 -81.758589) (xy 78.794991 -81.733088)
			(xy 78.749633 -81.700637) (xy 78.709484 -81.661928) (xy 78.675398 -81.617785) (xy 78.648102 -81.56915)
			(xy 78.628179 -81.517059) (xy 78.616053 -81.462622) (xy 78.611982 -81.407) (xy 76.562204 -81.407)
			(xy 76.562204 -81.41208) (xy 76.561772 -81.44857) (xy 76.55462 -81.5212) (xy 76.540384 -81.592779)
			(xy 76.519201 -81.662617) (xy 76.491274 -81.730043) (xy 76.456872 -81.794407) (xy 76.416328 -81.855089)
			(xy 76.37003 -81.911505) (xy 76.344526 -81.937606) (xy 76.298298 -81.984088) (xy 76.277978 -82.004408)
			(xy 76.277978 -82.491834) (xy 76.27845 -82.506393) (xy 76.286664 -82.53433) (xy 76.302416 -82.558821)
			(xy 76.324431 -82.577881) (xy 76.350924 -82.589966) (xy 76.379748 -82.594096) (xy 76.408569 -82.589938)
			(xy 76.421996 -82.58429) (xy 76.447047 -82.573301) (xy 76.49951 -82.557812) (xy 76.553649 -82.549986)
			(xy 76.581 -82.549492) (xy 76.608251 -82.549978) (xy 76.662199 -82.557734) (xy 76.714494 -82.573089)
			(xy 76.764071 -82.595731) (xy 76.809921 -82.625197) (xy 76.851112 -82.660888) (xy 76.886803 -82.702079)
			(xy 76.916269 -82.747929) (xy 76.938911 -82.797506) (xy 76.954266 -82.849801) (xy 76.962022 -82.903749)
			(xy 76.962022 -82.958251) (xy 76.954266 -83.012199) (xy 76.938911 -83.064494) (xy 76.916269 -83.114071)
			(xy 76.886803 -83.159921) (xy 76.851112 -83.201112) (xy 76.809921 -83.236803) (xy 76.764071 -83.266269)
			(xy 76.714494 -83.288911) (xy 76.662199 -83.304266) (xy 76.608251 -83.312022) (xy 76.581 -83.312508)
			(xy 76.55365 -83.312019) (xy 76.499513 -83.304176) (xy 76.447049 -83.288693) (xy 76.421996 -83.27771)
			(xy 76.408566 -83.272058) (xy 76.379743 -83.267864) (xy 76.350908 -83.271977) (xy 76.324407 -83.284062)
			(xy 76.302394 -83.303135) (xy 76.28666 -83.327646) (xy 76.278484 -83.355602) (xy 76.277978 -83.370166)
			(xy 76.277978 -83.466432) (xy 82.17027 -83.466432) (xy 82.17076 -83.437692) (xy 82.179392 -83.380863)
			(xy 82.196451 -83.325973) (xy 82.221549 -83.274262) (xy 82.254121 -83.2269) (xy 82.273394 -83.205574)
			(xy 82.283432 -83.194014) (xy 82.296775 -83.166477) (xy 82.301364 -83.136224) (xy 82.296789 -83.105968)
			(xy 82.283459 -83.078425) (xy 82.273394 -83.06689) (xy 82.254148 -83.045541) (xy 82.221576 -82.998186)
			(xy 82.196478 -82.94648) (xy 82.179422 -82.891594) (xy 82.170794 -82.83477) (xy 82.17027 -82.806032)
			(xy 82.170738 -82.778662) (xy 82.178553 -82.724482) (xy 82.19404 -82.671978) (xy 82.216882 -82.622231)
			(xy 82.246608 -82.576265) (xy 82.26425 -82.555334) (xy 82.273452 -82.543982) (xy 82.285627 -82.517432)
			(xy 82.289804 -82.488524) (xy 82.285641 -82.459614) (xy 82.273478 -82.433059) (xy 82.26425 -82.42173)
			(xy 82.246619 -82.400791) (xy 82.216904 -82.354821) (xy 82.194066 -82.305075) (xy 82.178573 -82.252576)
			(xy 82.170744 -82.198401) (xy 82.17027 -82.171032) (xy 82.170785 -82.143781) (xy 82.178537 -82.089833)
			(xy 82.193888 -82.037537) (xy 82.216525 -81.987959) (xy 82.245988 -81.942107) (xy 82.281676 -81.900914)
			(xy 82.322863 -81.86522) (xy 82.368711 -81.835751) (xy 82.418287 -81.813107) (xy 82.47058 -81.797749)
			(xy 82.524527 -81.789989) (xy 82.551778 -81.789524) (xy 82.577177 -81.789941) (xy 82.627525 -81.796679)
			(xy 82.676534 -81.810041) (xy 82.723336 -81.829788) (xy 82.767103 -81.855572) (xy 82.807061 -81.886937)
			(xy 82.825082 -81.90484) (xy 82.834695 -81.91413) (xy 82.85771 -81.927718) (xy 82.883461 -81.934872)
			(xy 82.910186 -81.935104) (xy 82.936058 -81.928396) (xy 82.959304 -81.915208) (xy 82.9691 -81.90611)
			(xy 82.990647 -81.885673) (xy 83.038895 -81.851053) (xy 83.091926 -81.82433) (xy 83.148458 -81.806148)
			(xy 83.207124 -81.796947) (xy 83.236816 -81.796382) (xy 83.264067 -81.796863) (xy 83.318015 -81.804621)
			(xy 83.370309 -81.819978) (xy 83.419885 -81.84262) (xy 83.465735 -81.872087) (xy 83.506925 -81.907779)
			(xy 83.542616 -81.94897) (xy 83.572083 -81.99482) (xy 83.594724 -82.044397) (xy 83.61008 -82.096691)
			(xy 83.617838 -82.150639) (xy 83.618324 -82.17789) (xy 83.617871 -82.205261) (xy 83.610053 -82.259441)
			(xy 83.594562 -82.311945) (xy 83.571716 -82.361692) (xy 83.541988 -82.407658) (xy 83.524344 -82.428588)
			(xy 83.515121 -82.439924) (xy 83.50295 -82.46648) (xy 83.498778 -82.495392) (xy 83.502945 -82.524306)
			(xy 83.515113 -82.550863) (xy 83.524344 -82.562192) (xy 83.542 -82.58311) (xy 83.571708 -82.629088)
			(xy 83.59454 -82.678839) (xy 83.610027 -82.731342) (xy 83.617852 -82.78552) (xy 83.618324 -82.81289)
			(xy 83.617788 -82.841628) (xy 83.609167 -82.898455) (xy 83.59212 -82.953345) (xy 83.567031 -83.005057)
			(xy 83.534469 -83.05242) (xy 83.5152 -83.073748) (xy 83.505141 -83.085291) (xy 83.491801 -83.112834)
			(xy 83.487216 -83.143093) (xy 83.491797 -83.173352) (xy 83.505132 -83.200897) (xy 83.5152 -83.212432)
			(xy 83.534455 -83.233773) (xy 83.567026 -83.28113) (xy 83.592122 -83.332838) (xy 83.609176 -83.387726)
			(xy 83.617802 -83.444552) (xy 83.618324 -83.47329) (xy 83.617812 -83.50054) (xy 83.610058 -83.554486)
			(xy 83.594705 -83.606779) (xy 83.572066 -83.656355) (xy 83.542602 -83.702205) (xy 83.506913 -83.743395)
			(xy 83.465726 -83.779087) (xy 83.419878 -83.808553) (xy 83.370304 -83.831196) (xy 83.318012 -83.846552)
			(xy 83.264066 -83.854311) (xy 83.236816 -83.854798) (xy 83.211417 -83.854379) (xy 83.161069 -83.847639)
			(xy 83.112061 -83.834278) (xy 83.065259 -83.814531) (xy 83.021492 -83.788748) (xy 82.981533 -83.757385)
			(xy 82.963512 -83.739482) (xy 82.953905 -83.730185) (xy 82.930889 -83.716594) (xy 82.905136 -83.709439)
			(xy 82.878408 -83.709209) (xy 82.852536 -83.715919) (xy 82.829289 -83.729111) (xy 82.819494 -83.738212)
			(xy 82.797954 -83.758656) (xy 82.749703 -83.793273) (xy 82.696671 -83.819995) (xy 82.640138 -83.838176)
			(xy 82.58147 -83.847376) (xy 82.551778 -83.84794) (xy 82.524528 -83.847443) (xy 82.470582 -83.839684)
			(xy 82.418289 -83.824328) (xy 82.368714 -83.801686) (xy 82.322866 -83.772221) (xy 82.281676 -83.736531)
			(xy 82.245985 -83.695342) (xy 82.216518 -83.649495) (xy 82.193876 -83.59992) (xy 82.178518 -83.547628)
			(xy 82.170758 -83.493682) (xy 82.17027 -83.466432) (xy 76.277978 -83.466432) (xy 76.277978 -86.207092)
			(xy 76.278409 -86.220391) (xy 76.28528 -86.246087) (xy 76.298557 -86.269135) (xy 76.317339 -86.287969)
			(xy 76.340349 -86.301311) (xy 76.366026 -86.308254) (xy 76.379324 -86.308692) (xy 76.406504 -86.309281)
			(xy 76.460287 -86.317214) (xy 76.512399 -86.3327) (xy 76.561785 -86.355428) (xy 76.607444 -86.384936)
			(xy 76.648453 -86.420626) (xy 76.683979 -86.461777) (xy 76.713305 -86.507554) (xy 76.727078 -86.5378)
			(xy 78.942182 -86.5378) (xy 78.946253 -86.482178) (xy 78.958379 -86.427741) (xy 78.978302 -86.37565)
			(xy 79.005598 -86.327015) (xy 79.039684 -86.282872) (xy 79.079833 -86.244163) (xy 79.125191 -86.211712)
			(xy 79.174791 -86.186211) (xy 79.227575 -86.168204) (xy 79.282418 -86.158074) (xy 79.338152 -86.156037)
			(xy 79.393589 -86.162137) (xy 79.447546 -86.176243) (xy 79.498875 -86.198055) (xy 79.546481 -86.227109)
			(xy 79.589349 -86.262784) (xy 79.626566 -86.304321) (xy 79.657339 -86.350834) (xy 79.681011 -86.401331)
			(xy 79.697079 -86.454738) (xy 79.705199 -86.509914) (xy 79.705708 -86.5378) (xy 79.705199 -86.565686)
			(xy 79.697079 -86.620862) (xy 79.681011 -86.674269) (xy 79.657339 -86.724766) (xy 79.626566 -86.771279)
			(xy 79.589349 -86.812816) (xy 79.546481 -86.848491) (xy 79.498875 -86.877545) (xy 79.447546 -86.899357)
			(xy 79.393589 -86.913463) (xy 79.338152 -86.919563) (xy 79.282418 -86.917526) (xy 79.227575 -86.907396)
			(xy 79.174791 -86.889389) (xy 79.125191 -86.863888) (xy 79.079833 -86.831437) (xy 79.039684 -86.792728)
			(xy 79.005598 -86.748585) (xy 78.978302 -86.69995) (xy 78.958379 -86.647859) (xy 78.946253 -86.593422)
			(xy 78.942182 -86.5378) (xy 76.727078 -86.5378) (xy 76.735834 -86.55703) (xy 76.751113 -86.609204)
			(xy 76.75883 -86.663018) (xy 76.75883 -86.717382) (xy 76.751113 -86.771196) (xy 76.735834 -86.82337)
			(xy 76.713305 -86.872846) (xy 76.683979 -86.918623) (xy 76.648453 -86.959774) (xy 76.607444 -86.995464)
			(xy 76.561785 -87.024972) (xy 76.512399 -87.0477) (xy 76.460287 -87.063186) (xy 76.406504 -87.071119)
			(xy 76.379324 -87.071708) (xy 76.36603 -87.072176) (xy 76.340361 -87.079116) (xy 76.317357 -87.092454)
			(xy 76.29858 -87.111283) (xy 76.285307 -87.134324) (xy 76.278438 -87.160013) (xy 76.277978 -87.173308)
			(xy 76.277978 -90.65006) (xy 82.177634 -90.65006) (xy 82.181705 -90.594438) (xy 82.193831 -90.540001)
			(xy 82.213754 -90.48791) (xy 82.24105 -90.439275) (xy 82.275136 -90.395132) (xy 82.315285 -90.356423)
			(xy 82.360643 -90.323972) (xy 82.410243 -90.298471) (xy 82.463027 -90.280464) (xy 82.51787 -90.270334)
			(xy 82.573604 -90.268297) (xy 82.629041 -90.274397) (xy 82.682998 -90.288503) (xy 82.734327 -90.310315)
			(xy 82.781933 -90.339369) (xy 82.824801 -90.375044) (xy 82.862018 -90.416581) (xy 82.892791 -90.463094)
			(xy 82.916463 -90.513591) (xy 82.932531 -90.566998) (xy 82.940651 -90.622174) (xy 82.94116 -90.65006)
			(xy 82.940651 -90.677946) (xy 82.932531 -90.733122) (xy 82.916463 -90.786529) (xy 82.892791 -90.837026)
			(xy 82.862018 -90.883539) (xy 82.824801 -90.925076) (xy 82.781933 -90.960751) (xy 82.734327 -90.989805)
			(xy 82.682998 -91.011617) (xy 82.629041 -91.025723) (xy 82.573604 -91.031823) (xy 82.51787 -91.029786)
			(xy 82.463027 -91.019656) (xy 82.410243 -91.001649) (xy 82.360643 -90.976148) (xy 82.315285 -90.943697)
			(xy 82.275136 -90.904988) (xy 82.24105 -90.860845) (xy 82.213754 -90.81221) (xy 82.193831 -90.760119)
			(xy 82.181705 -90.705682) (xy 82.177634 -90.65006) (xy 76.277978 -90.65006) (xy 76.277978 -91.059)
			(xy 84.828632 -91.059) (xy 84.832703 -91.003378) (xy 84.844829 -90.948941) (xy 84.864752 -90.89685)
			(xy 84.892048 -90.848215) (xy 84.926134 -90.804072) (xy 84.966283 -90.765363) (xy 85.011641 -90.732912)
			(xy 85.061241 -90.707411) (xy 85.114025 -90.689404) (xy 85.168868 -90.679274) (xy 85.224602 -90.677237)
			(xy 85.280039 -90.683337) (xy 85.333996 -90.697443) (xy 85.385325 -90.719255) (xy 85.432931 -90.748309)
			(xy 85.475799 -90.783984) (xy 85.513016 -90.825521) (xy 85.543789 -90.872034) (xy 85.567461 -90.922531)
			(xy 85.583529 -90.975938) (xy 85.591649 -91.031114) (xy 85.592158 -91.059) (xy 85.591649 -91.086886)
			(xy 85.583529 -91.142062) (xy 85.567461 -91.195469) (xy 85.543789 -91.245966) (xy 85.513016 -91.292479)
			(xy 85.475799 -91.334016) (xy 85.432931 -91.369691) (xy 85.385325 -91.398745) (xy 85.333996 -91.420557)
			(xy 85.280039 -91.434663) (xy 85.224602 -91.440763) (xy 85.168868 -91.438726) (xy 85.114025 -91.428596)
			(xy 85.061241 -91.410589) (xy 85.011641 -91.385088) (xy 84.966283 -91.352637) (xy 84.926134 -91.313928)
			(xy 84.892048 -91.269785) (xy 84.864752 -91.22115) (xy 84.844829 -91.169059) (xy 84.832703 -91.114622)
			(xy 84.828632 -91.059) (xy 76.277978 -91.059) (xy 76.277978 -92.2528) (xy 84.834982 -92.2528) (xy 84.839053 -92.197178)
			(xy 84.851179 -92.142741) (xy 84.871102 -92.09065) (xy 84.898398 -92.042015) (xy 84.932484 -91.997872)
			(xy 84.972633 -91.959163) (xy 85.017991 -91.926712) (xy 85.067591 -91.901211) (xy 85.120375 -91.883204)
			(xy 85.175218 -91.873074) (xy 85.230952 -91.871037) (xy 85.286389 -91.877137) (xy 85.340346 -91.891243)
			(xy 85.391675 -91.913055) (xy 85.439281 -91.942109) (xy 85.482149 -91.977784) (xy 85.519366 -92.019321)
			(xy 85.550139 -92.065834) (xy 85.573811 -92.116331) (xy 85.589879 -92.169738) (xy 85.597999 -92.224914)
			(xy 85.598508 -92.2528) (xy 85.597999 -92.280686) (xy 85.589879 -92.335862) (xy 85.573811 -92.389269)
			(xy 85.550139 -92.439766) (xy 85.519366 -92.486279) (xy 85.482149 -92.527816) (xy 85.439281 -92.563491)
			(xy 85.391675 -92.592545) (xy 85.340346 -92.614357) (xy 85.286389 -92.628463) (xy 85.230952 -92.634563)
			(xy 85.175218 -92.632526) (xy 85.120375 -92.622396) (xy 85.067591 -92.604389) (xy 85.017991 -92.578888)
			(xy 84.972633 -92.546437) (xy 84.932484 -92.507728) (xy 84.898398 -92.463585) (xy 84.871102 -92.41495)
			(xy 84.851179 -92.362859) (xy 84.839053 -92.308422) (xy 84.834982 -92.2528) (xy 76.277978 -92.2528)
			(xy 76.277978 -93.111845) (xy 78.848028 -93.111845) (xy 78.848028 -93.057355) (xy 78.855782 -93.003418)
			(xy 78.871133 -92.951135) (xy 78.893767 -92.901567) (xy 78.923225 -92.855725) (xy 78.958906 -92.814542)
			(xy 79.000085 -92.778855) (xy 79.045923 -92.749391) (xy 79.095488 -92.72675) (xy 79.14777 -92.711393)
			(xy 79.201705 -92.703632) (xy 79.22895 -92.703142) (xy 79.25576 -92.703633) (xy 79.308852 -92.711139)
			(xy 79.360369 -92.726012) (xy 79.409293 -92.747956) (xy 79.45466 -92.77654) (xy 79.495573 -92.811199)
			(xy 79.531226 -92.851249) (xy 79.54645 -92.873322) (xy 79.554733 -92.884866) (xy 79.576365 -92.903266)
			(xy 79.602226 -92.915) (xy 79.630319 -92.919162) (xy 79.658471 -92.91543) (xy 79.684509 -92.904093)
			(xy 79.70642 -92.886026) (xy 79.714852 -92.874592) (xy 79.730219 -92.853146) (xy 79.765844 -92.814233)
			(xy 79.80649 -92.780599) (xy 79.851383 -92.752887) (xy 79.899666 -92.731624) (xy 79.950418 -92.717218)
			(xy 80.002671 -92.709941) (xy 80.02905 -92.709492) (xy 80.056305 -92.709952) (xy 80.110262 -92.717703)
			(xy 80.162565 -92.733055) (xy 80.212152 -92.755694) (xy 80.258011 -92.785161) (xy 80.29921 -92.820855)
			(xy 80.334909 -92.862049) (xy 80.342155 -92.873322) (xy 82.396582 -92.873322) (xy 82.400653 -92.8177)
			(xy 82.412779 -92.763263) (xy 82.432702 -92.711172) (xy 82.459998 -92.662537) (xy 82.494084 -92.618394)
			(xy 82.534233 -92.579685) (xy 82.579591 -92.547234) (xy 82.629191 -92.521733) (xy 82.681975 -92.503726)
			(xy 82.736818 -92.493596) (xy 82.792552 -92.491559) (xy 82.847989 -92.497659) (xy 82.901946 -92.511765)
			(xy 82.953275 -92.533577) (xy 83.000881 -92.562631) (xy 83.043749 -92.598306) (xy 83.080966 -92.639843)
			(xy 83.111739 -92.686356) (xy 83.135411 -92.736853) (xy 83.151479 -92.79026) (xy 83.159599 -92.845436)
			(xy 83.160108 -92.873322) (xy 83.159599 -92.901208) (xy 83.151479 -92.956384) (xy 83.135411 -93.009791)
			(xy 83.111739 -93.060288) (xy 83.080966 -93.106801) (xy 83.043749 -93.148338) (xy 83.000881 -93.184013)
			(xy 82.953275 -93.213067) (xy 82.901946 -93.234879) (xy 82.847989 -93.248985) (xy 82.792552 -93.255085)
			(xy 82.736818 -93.253048) (xy 82.681975 -93.242918) (xy 82.629191 -93.224911) (xy 82.579591 -93.19941)
			(xy 82.534233 -93.166959) (xy 82.494084 -93.12825) (xy 82.459998 -93.084107) (xy 82.432702 -93.035472)
			(xy 82.412779 -92.983381) (xy 82.400653 -92.928944) (xy 82.396582 -92.873322) (xy 80.342155 -92.873322)
			(xy 80.364382 -92.907904) (xy 80.387028 -92.957488) (xy 80.402386 -93.00979) (xy 80.410145 -93.063745)
			(xy 80.410145 -93.118255) (xy 80.402386 -93.17221) (xy 80.387028 -93.224512) (xy 80.364382 -93.274096)
			(xy 80.334909 -93.319951) (xy 80.313201 -93.345) (xy 84.828632 -93.345) (xy 84.832703 -93.289378)
			(xy 84.844829 -93.234941) (xy 84.864752 -93.18285) (xy 84.892048 -93.134215) (xy 84.926134 -93.090072)
			(xy 84.966283 -93.051363) (xy 85.011641 -93.018912) (xy 85.061241 -92.993411) (xy 85.114025 -92.975404)
			(xy 85.168868 -92.965274) (xy 85.224602 -92.963237) (xy 85.280039 -92.969337) (xy 85.333996 -92.983443)
			(xy 85.385325 -93.005255) (xy 85.432931 -93.034309) (xy 85.475799 -93.069984) (xy 85.513016 -93.111521)
			(xy 85.543789 -93.158034) (xy 85.567461 -93.208531) (xy 85.583529 -93.261938) (xy 85.591649 -93.317114)
			(xy 85.592158 -93.345) (xy 85.591649 -93.372886) (xy 85.583529 -93.428062) (xy 85.567461 -93.481469)
			(xy 85.543789 -93.531966) (xy 85.513016 -93.578479) (xy 85.475799 -93.620016) (xy 85.432931 -93.655691)
			(xy 85.385325 -93.684745) (xy 85.333996 -93.706557) (xy 85.280039 -93.720663) (xy 85.224602 -93.726763)
			(xy 85.168868 -93.724726) (xy 85.114025 -93.714596) (xy 85.061241 -93.696589) (xy 85.011641 -93.671088)
			(xy 84.966283 -93.638637) (xy 84.926134 -93.599928) (xy 84.892048 -93.555785) (xy 84.864752 -93.50715)
			(xy 84.844829 -93.455059) (xy 84.832703 -93.400622) (xy 84.828632 -93.345) (xy 80.313201 -93.345)
			(xy 80.29921 -93.361145) (xy 80.258011 -93.396839) (xy 80.212152 -93.426306) (xy 80.162565 -93.448945)
			(xy 80.110262 -93.464297) (xy 80.056305 -93.472048) (xy 80.02905 -93.472508) (xy 80.002239 -93.47204)
			(xy 79.949145 -93.464532) (xy 79.897627 -93.449657) (xy 79.848702 -93.427709) (xy 79.803335 -93.399122)
			(xy 79.762423 -93.364458) (xy 79.726772 -93.324404) (xy 79.71155 -93.302328) (xy 79.70327 -93.29078)
			(xy 79.68164 -93.272371) (xy 79.655777 -93.26063) (xy 79.627681 -93.256466) (xy 79.599525 -93.2602)
			(xy 79.573486 -93.271543) (xy 79.551577 -93.289619) (xy 79.543148 -93.301058) (xy 79.527796 -93.322515)
			(xy 79.492167 -93.361426) (xy 79.451518 -93.395057) (xy 79.406622 -93.422767) (xy 79.358337 -93.444028)
			(xy 79.307584 -93.458433) (xy 79.255329 -93.465709) (xy 79.22895 -93.466158) (xy 79.201705 -93.465568)
			(xy 79.14777 -93.457807) (xy 79.095488 -93.44245) (xy 79.045923 -93.419809) (xy 79.000085 -93.390345)
			(xy 78.958906 -93.354658) (xy 78.923225 -93.313475) (xy 78.893767 -93.267633) (xy 78.871133 -93.218065)
			(xy 78.855782 -93.165782) (xy 78.848028 -93.111845) (xy 76.277978 -93.111845) (xy 76.277978 -94.152974)
			(xy 82.472782 -94.152974) (xy 82.476853 -94.097352) (xy 82.488979 -94.042915) (xy 82.508902 -93.990824)
			(xy 82.536198 -93.942189) (xy 82.570284 -93.898046) (xy 82.610433 -93.859337) (xy 82.655791 -93.826886)
			(xy 82.705391 -93.801385) (xy 82.758175 -93.783378) (xy 82.813018 -93.773248) (xy 82.868752 -93.771211)
			(xy 82.924189 -93.777311) (xy 82.978146 -93.791417) (xy 83.029475 -93.813229) (xy 83.077081 -93.842283)
			(xy 83.119949 -93.877958) (xy 83.157166 -93.919495) (xy 83.187939 -93.966008) (xy 83.211611 -94.016505)
			(xy 83.227679 -94.069912) (xy 83.235799 -94.125088) (xy 83.236308 -94.152974) (xy 83.235799 -94.18086)
			(xy 83.227679 -94.236036) (xy 83.211611 -94.289443) (xy 83.187939 -94.33994) (xy 83.157166 -94.386453)
			(xy 83.119949 -94.42799) (xy 83.077081 -94.463665) (xy 83.033878 -94.490032) (xy 84.887814 -94.490032)
			(xy 84.891885 -94.43441) (xy 84.904011 -94.379973) (xy 84.923934 -94.327882) (xy 84.95123 -94.279247)
			(xy 84.985316 -94.235104) (xy 85.025465 -94.196395) (xy 85.070823 -94.163944) (xy 85.120423 -94.138443)
			(xy 85.173207 -94.120436) (xy 85.22805 -94.110306) (xy 85.283784 -94.108269) (xy 85.339221 -94.114369)
			(xy 85.393178 -94.128475) (xy 85.444507 -94.150287) (xy 85.492113 -94.179341) (xy 85.534981 -94.215016)
			(xy 85.572198 -94.256553) (xy 85.602971 -94.303066) (xy 85.626643 -94.353563) (xy 85.642711 -94.40697)
			(xy 85.650831 -94.462146) (xy 85.65134 -94.490032) (xy 85.650831 -94.517918) (xy 85.642711 -94.573094)
			(xy 85.626643 -94.626501) (xy 85.602971 -94.676998) (xy 85.572198 -94.723511) (xy 85.534981 -94.765048)
			(xy 85.492113 -94.800723) (xy 85.444507 -94.829777) (xy 85.393178 -94.851589) (xy 85.339221 -94.865695)
			(xy 85.283784 -94.871795) (xy 85.22805 -94.869758) (xy 85.173207 -94.859628) (xy 85.120423 -94.841621)
			(xy 85.070823 -94.81612) (xy 85.025465 -94.783669) (xy 84.985316 -94.74496) (xy 84.95123 -94.700817)
			(xy 84.923934 -94.652182) (xy 84.904011 -94.600091) (xy 84.891885 -94.545654) (xy 84.887814 -94.490032)
			(xy 83.033878 -94.490032) (xy 83.029475 -94.492719) (xy 82.978146 -94.514531) (xy 82.924189 -94.528637)
			(xy 82.868752 -94.534737) (xy 82.813018 -94.5327) (xy 82.758175 -94.52257) (xy 82.705391 -94.504563)
			(xy 82.655791 -94.479062) (xy 82.610433 -94.446611) (xy 82.570284 -94.407902) (xy 82.536198 -94.363759)
			(xy 82.508902 -94.315124) (xy 82.488979 -94.263033) (xy 82.476853 -94.208596) (xy 82.472782 -94.152974)
			(xy 76.277978 -94.152974) (xy 76.277978 -94.817184) (xy 79.460342 -94.817184) (xy 79.464413 -94.761562)
			(xy 79.476539 -94.707125) (xy 79.496462 -94.655034) (xy 79.523758 -94.606399) (xy 79.557844 -94.562256)
			(xy 79.597993 -94.523547) (xy 79.643351 -94.491096) (xy 79.692951 -94.465595) (xy 79.745735 -94.447588)
			(xy 79.800578 -94.437458) (xy 79.856312 -94.435421) (xy 79.911749 -94.441521) (xy 79.965706 -94.455627)
			(xy 80.017035 -94.477439) (xy 80.064641 -94.506493) (xy 80.107509 -94.542168) (xy 80.144726 -94.583705)
			(xy 80.175499 -94.630218) (xy 80.199171 -94.680715) (xy 80.215239 -94.734122) (xy 80.223359 -94.789298)
			(xy 80.223868 -94.817184) (xy 80.223359 -94.84507) (xy 80.215239 -94.900246) (xy 80.199171 -94.953653)
			(xy 80.175499 -95.00415) (xy 80.144726 -95.050663) (xy 80.107509 -95.0922) (xy 80.064641 -95.127875)
			(xy 80.017035 -95.156929) (xy 79.965706 -95.178741) (xy 79.911749 -95.192847) (xy 79.856312 -95.198947)
			(xy 79.800578 -95.19691) (xy 79.745735 -95.18678) (xy 79.692951 -95.168773) (xy 79.643351 -95.143272)
			(xy 79.597993 -95.110821) (xy 79.557844 -95.072112) (xy 79.523758 -95.027969) (xy 79.496462 -94.979334)
			(xy 79.476539 -94.927243) (xy 79.464413 -94.872806) (xy 79.460342 -94.817184) (xy 76.277978 -94.817184)
			(xy 76.277978 -95.432118) (xy 82.447382 -95.432118) (xy 82.451453 -95.376496) (xy 82.463579 -95.322059)
			(xy 82.483502 -95.269968) (xy 82.510798 -95.221333) (xy 82.544884 -95.17719) (xy 82.585033 -95.138481)
			(xy 82.630391 -95.10603) (xy 82.679991 -95.080529) (xy 82.732775 -95.062522) (xy 82.787618 -95.052392)
			(xy 82.843352 -95.050355) (xy 82.898789 -95.056455) (xy 82.952746 -95.070561) (xy 83.004075 -95.092373)
			(xy 83.051681 -95.121427) (xy 83.094549 -95.157102) (xy 83.131766 -95.198639) (xy 83.162539 -95.245152)
			(xy 83.186211 -95.295649) (xy 83.202279 -95.349056) (xy 83.210399 -95.404232) (xy 83.210908 -95.432118)
			(xy 83.210399 -95.460004) (xy 83.202279 -95.51518) (xy 83.186211 -95.568587) (xy 83.16886 -95.6056)
			(xy 84.885782 -95.6056) (xy 84.889853 -95.549978) (xy 84.901979 -95.495541) (xy 84.921902 -95.44345)
			(xy 84.949198 -95.394815) (xy 84.983284 -95.350672) (xy 85.023433 -95.311963) (xy 85.068791 -95.279512)
			(xy 85.118391 -95.254011) (xy 85.171175 -95.236004) (xy 85.226018 -95.225874) (xy 85.281752 -95.223837)
			(xy 85.337189 -95.229937) (xy 85.391146 -95.244043) (xy 85.442475 -95.265855) (xy 85.490081 -95.294909)
			(xy 85.532949 -95.330584) (xy 85.570166 -95.372121) (xy 85.600939 -95.418634) (xy 85.624611 -95.469131)
			(xy 85.640679 -95.522538) (xy 85.648799 -95.577714) (xy 85.649308 -95.6056) (xy 85.648799 -95.633486)
			(xy 85.640679 -95.688662) (xy 85.624611 -95.742069) (xy 85.600939 -95.792566) (xy 85.570166 -95.839079)
			(xy 85.532949 -95.880616) (xy 85.490081 -95.916291) (xy 85.442475 -95.945345) (xy 85.391146 -95.967157)
			(xy 85.337189 -95.981263) (xy 85.281752 -95.987363) (xy 85.226018 -95.985326) (xy 85.171175 -95.975196)
			(xy 85.118391 -95.957189) (xy 85.068791 -95.931688) (xy 85.023433 -95.899237) (xy 84.983284 -95.860528)
			(xy 84.949198 -95.816385) (xy 84.921902 -95.76775) (xy 84.901979 -95.715659) (xy 84.889853 -95.661222)
			(xy 84.885782 -95.6056) (xy 83.16886 -95.6056) (xy 83.162539 -95.619084) (xy 83.131766 -95.665597)
			(xy 83.094549 -95.707134) (xy 83.051681 -95.742809) (xy 83.004075 -95.771863) (xy 82.952746 -95.793675)
			(xy 82.898789 -95.807781) (xy 82.843352 -95.813881) (xy 82.787618 -95.811844) (xy 82.732775 -95.801714)
			(xy 82.679991 -95.783707) (xy 82.630391 -95.758206) (xy 82.585033 -95.725755) (xy 82.544884 -95.687046)
			(xy 82.510798 -95.642903) (xy 82.483502 -95.594268) (xy 82.463579 -95.542177) (xy 82.451453 -95.48774)
			(xy 82.447382 -95.432118) (xy 76.277978 -95.432118) (xy 76.277978 -97.0534) (xy 77.976982 -97.0534)
			(xy 77.981053 -96.997778) (xy 77.993179 -96.943341) (xy 78.013102 -96.89125) (xy 78.040398 -96.842615)
			(xy 78.074484 -96.798472) (xy 78.114633 -96.759763) (xy 78.159991 -96.727312) (xy 78.209591 -96.701811)
			(xy 78.262375 -96.683804) (xy 78.317218 -96.673674) (xy 78.372952 -96.671637) (xy 78.428389 -96.677737)
			(xy 78.482346 -96.691843) (xy 78.533675 -96.713655) (xy 78.581281 -96.742709) (xy 78.624149 -96.778384)
			(xy 78.661366 -96.819921) (xy 78.692139 -96.866434) (xy 78.715811 -96.916931) (xy 78.731879 -96.970338)
			(xy 78.739999 -97.025514) (xy 78.740508 -97.0534) (xy 78.739999 -97.081286) (xy 78.731879 -97.136462)
			(xy 78.715811 -97.189869) (xy 78.700484 -97.222564) (xy 78.923386 -97.222564) (xy 78.927457 -97.166942)
			(xy 78.939583 -97.112505) (xy 78.959506 -97.060414) (xy 78.986802 -97.011779) (xy 79.020888 -96.967636)
			(xy 79.061037 -96.928927) (xy 79.106395 -96.896476) (xy 79.155995 -96.870975) (xy 79.208779 -96.852968)
			(xy 79.263622 -96.842838) (xy 79.319356 -96.840801) (xy 79.374793 -96.846901) (xy 79.42875 -96.861007)
			(xy 79.480079 -96.882819) (xy 79.527685 -96.911873) (xy 79.570553 -96.947548) (xy 79.60777 -96.989085)
			(xy 79.638543 -97.035598) (xy 79.662215 -97.086095) (xy 79.678283 -97.139502) (xy 79.686403 -97.194678)
			(xy 79.686912 -97.222564) (xy 79.686403 -97.25045) (xy 79.678283 -97.305626) (xy 79.662215 -97.359033)
			(xy 79.638543 -97.40953) (xy 79.60777 -97.456043) (xy 79.570553 -97.49758) (xy 79.554908 -97.5106)
			(xy 82.219292 -97.5106) (xy 82.219796 -97.482897) (xy 82.227837 -97.428076) (xy 82.243722 -97.374995)
			(xy 82.267117 -97.324769) (xy 82.297529 -97.278454) (xy 82.334319 -97.237024) (xy 82.376714 -97.20135)
			(xy 82.423822 -97.172182) (xy 82.474654 -97.150133) (xy 82.528139 -97.135667) (xy 82.555588 -97.131886)
			(xy 82.569401 -97.129723) (xy 82.595224 -97.119046) (xy 82.61718 -97.101763) (xy 82.633624 -97.079171)
			(xy 82.643321 -97.052965) (xy 82.645544 -97.025111) (xy 82.640125 -96.997699) (xy 82.627472 -96.972785)
			(xy 82.618326 -96.962214) (xy 82.599508 -96.940957) (xy 82.567704 -96.893933) (xy 82.543227 -96.842713)
			(xy 82.526617 -96.788428) (xy 82.518242 -96.732281) (xy 82.517742 -96.703896) (xy 82.518228 -96.676645)
			(xy 82.525984 -96.622697) (xy 82.541339 -96.570402) (xy 82.563981 -96.520825) (xy 82.593447 -96.474975)
			(xy 82.629138 -96.433784) (xy 82.670329 -96.398093) (xy 82.716179 -96.368627) (xy 82.765756 -96.345985)
			(xy 82.818051 -96.33063) (xy 82.871999 -96.322874) (xy 82.926501 -96.322874) (xy 82.980449 -96.33063)
			(xy 83.032744 -96.345985) (xy 83.082321 -96.368627) (xy 83.128171 -96.398093) (xy 83.169362 -96.433784)
			(xy 83.205053 -96.474975) (xy 83.233989 -96.52) (xy 84.834982 -96.52) (xy 84.839053 -96.464378) (xy 84.851179 -96.409941)
			(xy 84.871102 -96.35785) (xy 84.898398 -96.309215) (xy 84.932484 -96.265072) (xy 84.972633 -96.226363)
			(xy 85.017991 -96.193912) (xy 85.067591 -96.168411) (xy 85.120375 -96.150404) (xy 85.175218 -96.140274)
			(xy 85.230952 -96.138237) (xy 85.286389 -96.144337) (xy 85.340346 -96.158443) (xy 85.391675 -96.180255)
			(xy 85.439281 -96.209309) (xy 85.482149 -96.244984) (xy 85.519366 -96.286521) (xy 85.550139 -96.333034)
			(xy 85.573811 -96.383531) (xy 85.589879 -96.436938) (xy 85.597999 -96.492114) (xy 85.598508 -96.52)
			(xy 85.597999 -96.547886) (xy 85.589879 -96.603062) (xy 85.573811 -96.656469) (xy 85.550139 -96.706966)
			(xy 85.519366 -96.753479) (xy 85.482149 -96.795016) (xy 85.439281 -96.830691) (xy 85.391675 -96.859745)
			(xy 85.340346 -96.881557) (xy 85.286389 -96.895663) (xy 85.230952 -96.901763) (xy 85.175218 -96.899726)
			(xy 85.120375 -96.889596) (xy 85.067591 -96.871589) (xy 85.017991 -96.846088) (xy 84.972633 -96.813637)
			(xy 84.932484 -96.774928) (xy 84.898398 -96.730785) (xy 84.871102 -96.68215) (xy 84.851179 -96.630059)
			(xy 84.839053 -96.575622) (xy 84.834982 -96.52) (xy 83.233989 -96.52) (xy 83.234519 -96.520825) (xy 83.257161 -96.570402)
			(xy 83.272516 -96.622697) (xy 83.280272 -96.676645) (xy 83.280758 -96.703896) (xy 83.280206 -96.731597)
			(xy 83.272167 -96.786414) (xy 83.256285 -96.839491) (xy 83.232895 -96.889715) (xy 83.202488 -96.936028)
			(xy 83.165703 -96.977457) (xy 83.123315 -97.013132) (xy 83.076213 -97.042302) (xy 83.025388 -97.064355)
			(xy 82.971908 -97.078826) (xy 82.944462 -97.08261) (xy 82.930648 -97.084755) (xy 82.904831 -97.095441)
			(xy 82.88288 -97.112729) (xy 82.866441 -97.135323) (xy 82.856746 -97.161528) (xy 82.854522 -97.189381)
			(xy 82.859936 -97.216793) (xy 82.872582 -97.241709) (xy 82.881724 -97.252282) (xy 82.900548 -97.273533)
			(xy 82.932349 -97.320559) (xy 82.950335 -97.3582) (xy 84.606382 -97.3582) (xy 84.610453 -97.302578)
			(xy 84.622579 -97.248141) (xy 84.642502 -97.19605) (xy 84.669798 -97.147415) (xy 84.703884 -97.103272)
			(xy 84.744033 -97.064563) (xy 84.789391 -97.032112) (xy 84.838991 -97.006611) (xy 84.891775 -96.988604)
			(xy 84.946618 -96.978474) (xy 85.002352 -96.976437) (xy 85.057789 -96.982537) (xy 85.111746 -96.996643)
			(xy 85.163075 -97.018455) (xy 85.210681 -97.047509) (xy 85.253549 -97.083184) (xy 85.290766 -97.124721)
			(xy 85.321539 -97.171234) (xy 85.345211 -97.221731) (xy 85.361279 -97.275138) (xy 85.369399 -97.330314)
			(xy 85.369908 -97.3582) (xy 85.369399 -97.386086) (xy 85.361279 -97.441262) (xy 85.345211 -97.494669)
			(xy 85.321539 -97.545166) (xy 85.290766 -97.591679) (xy 85.253549 -97.633216) (xy 85.210681 -97.668891)
			(xy 85.163075 -97.697945) (xy 85.111746 -97.719757) (xy 85.057789 -97.733863) (xy 85.002352 -97.739963)
			(xy 84.946618 -97.737926) (xy 84.891775 -97.727796) (xy 84.838991 -97.709789) (xy 84.789391 -97.684288)
			(xy 84.744033 -97.651837) (xy 84.703884 -97.613128) (xy 84.669798 -97.568985) (xy 84.642502 -97.52035)
			(xy 84.622579 -97.468259) (xy 84.610453 -97.413822) (xy 84.606382 -97.3582) (xy 82.950335 -97.3582)
			(xy 82.956825 -97.371781) (xy 82.973433 -97.426067) (xy 82.981808 -97.482215) (xy 82.982308 -97.5106)
			(xy 82.981822 -97.537851) (xy 82.974066 -97.591799) (xy 82.958711 -97.644094) (xy 82.936069 -97.693671)
			(xy 82.906603 -97.739521) (xy 82.870912 -97.780712) (xy 82.829721 -97.816403) (xy 82.783871 -97.845869)
			(xy 82.734294 -97.868511) (xy 82.681999 -97.883866) (xy 82.628051 -97.891622) (xy 82.573549 -97.891622)
			(xy 82.519601 -97.883866) (xy 82.467306 -97.868511) (xy 82.417729 -97.845869) (xy 82.371879 -97.816403)
			(xy 82.330688 -97.780712) (xy 82.294997 -97.739521) (xy 82.265531 -97.693671) (xy 82.242889 -97.644094)
			(xy 82.227534 -97.591799) (xy 82.219778 -97.537851) (xy 82.219292 -97.5106) (xy 79.554908 -97.5106)
			(xy 79.527685 -97.533255) (xy 79.480079 -97.562309) (xy 79.42875 -97.584121) (xy 79.374793 -97.598227)
			(xy 79.319356 -97.604327) (xy 79.263622 -97.60229) (xy 79.208779 -97.59216) (xy 79.155995 -97.574153)
			(xy 79.106395 -97.548652) (xy 79.061037 -97.516201) (xy 79.020888 -97.477492) (xy 78.986802 -97.433349)
			(xy 78.959506 -97.384714) (xy 78.939583 -97.332623) (xy 78.927457 -97.278186) (xy 78.923386 -97.222564)
			(xy 78.700484 -97.222564) (xy 78.692139 -97.240366) (xy 78.661366 -97.286879) (xy 78.624149 -97.328416)
			(xy 78.581281 -97.364091) (xy 78.533675 -97.393145) (xy 78.482346 -97.414957) (xy 78.428389 -97.429063)
			(xy 78.372952 -97.435163) (xy 78.317218 -97.433126) (xy 78.262375 -97.422996) (xy 78.209591 -97.404989)
			(xy 78.159991 -97.379488) (xy 78.114633 -97.347037) (xy 78.074484 -97.308328) (xy 78.040398 -97.264185)
			(xy 78.013102 -97.21555) (xy 77.993179 -97.163459) (xy 77.981053 -97.109022) (xy 77.976982 -97.0534)
			(xy 76.277978 -97.0534) (xy 76.277978 -98.251772) (xy 77.1525 -99.126294) (xy 82.248502 -99.126294)
		)
		(stroke
			(width 0)
			(type solid)
		)
		(fill yes)
		(layer "In9.Cu")
		(net "P3V3_AUX")
	)
	(gr_poly
		(pts
			(xy -3.999992 -119.892064) (xy -3.944185 -119.891542) (xy -3.832883 -119.883201) (xy -3.722516 -119.866566)
			(xy -3.6137 -119.841729) (xy -3.507045 -119.80883) (xy -3.403146 -119.768053) (xy -3.302586 -119.719626)
			(xy -3.205925 -119.663818) (xy -3.113705 -119.600944) (xy -3.026442 -119.531354) (xy -2.944623 -119.455437)
			(xy -2.868706 -119.373618) (xy -2.799116 -119.286355) (xy -2.736242 -119.194135) (xy -2.680434 -119.097474)
			(xy -2.632007 -118.996914) (xy -2.59123 -118.893015) (xy -2.558331 -118.78636) (xy -2.533494 -118.677544)
			(xy -2.516859 -118.567177) (xy -2.508518 -118.455875) (xy -2.507996 -118.400068) (xy -2.507996 -6.59003)
			(xy -2.508518 -6.534223) (xy -2.516859 -6.422921) (xy -2.533494 -6.312554) (xy -2.558331 -6.203738)
			(xy -2.59123 -6.097083) (xy -2.632007 -5.993184) (xy -2.680434 -5.892624) (xy -2.736242 -5.795963)
			(xy -2.799116 -5.703743) (xy -2.868706 -5.61648) (xy -2.944623 -5.534661) (xy -3.026442 -5.458744)
			(xy -3.113705 -5.389154) (xy -3.205925 -5.32628) (xy -3.302586 -5.270472) (xy -3.403146 -5.222045)
			(xy -3.507045 -5.181268) (xy -3.6137 -5.148369) (xy -3.722516 -5.123532) (xy -3.832883 -5.106897)
			(xy -3.944185 -5.098556) (xy -3.999992 -5.098034) (xy -17.78 -5.098034) (xy -17.835807 -5.098556)
			(xy -17.947109 -5.106897) (xy -18.057476 -5.123532) (xy -18.166292 -5.148369) (xy -18.272947 -5.181268)
			(xy -18.376846 -5.222045) (xy -18.477406 -5.270472) (xy -18.574067 -5.32628) (xy -18.666287 -5.389154)
			(xy -18.75355 -5.458744) (xy -18.835369 -5.534661) (xy -18.911286 -5.61648) (xy -18.980876 -5.703743)
			(xy -19.04375 -5.795963) (xy -19.099558 -5.892624) (xy -19.147985 -5.993184) (xy -19.188762 -6.097083)
			(xy -19.221661 -6.203738) (xy -19.246498 -6.312554) (xy -19.263133 -6.422921) (xy -19.271474 -6.534223)
			(xy -19.271996 -6.59003) (xy -19.271996 -115.464644) (xy -16.875771 -115.464644) (xy -16.875771 -115.335504)
			(xy -16.867821 -115.206609) (xy -16.851951 -115.078449) (xy -16.828222 -114.951508) (xy -16.796723 -114.826269)
			(xy -16.757574 -114.703206) (xy -16.710923 -114.582787) (xy -16.656948 -114.465468) (xy -16.595853 -114.351694)
			(xy -16.52787 -114.241897) (xy -16.453256 -114.136494) (xy -16.372295 -114.035884) (xy -16.285295 -113.940449)
			(xy -16.192584 -113.85055) (xy -16.094514 -113.766529) (xy -15.991459 -113.688705) (xy -15.883808 -113.617373)
			(xy -15.771969 -113.552803) (xy -15.656368 -113.495241) (xy -15.537443 -113.444904) (xy -15.415644 -113.401984)
			(xy -15.291434 -113.366643) (xy -15.165285 -113.339016) (xy -15.037673 -113.319207) (xy -14.909084 -113.307291)
			(xy -14.780006 -113.303315) (xy -14.650928 -113.307291) (xy -14.522339 -113.319207) (xy -14.394727 -113.339016)
			(xy -14.268578 -113.366643) (xy -14.144368 -113.401984) (xy -14.022569 -113.444904) (xy -13.903644 -113.495241)
			(xy -13.788043 -113.552803) (xy -13.676204 -113.617373) (xy -13.568553 -113.688705) (xy -13.465498 -113.766529)
			(xy -13.367428 -113.85055) (xy -13.274717 -113.940449) (xy -13.187717 -114.035884) (xy -13.106756 -114.136494)
			(xy -13.032142 -114.241897) (xy -12.964159 -114.351694) (xy -12.903064 -114.465468) (xy -12.849089 -114.582787)
			(xy -12.802438 -114.703206) (xy -12.763289 -114.826269) (xy -12.73179 -114.951508) (xy -12.708061 -115.078449)
			(xy -12.692191 -115.206609) (xy -12.684241 -115.335504) (xy -12.683744 -115.400074) (xy -12.684241 -115.464644)
			(xy -12.692191 -115.593539) (xy -12.708061 -115.721699) (xy -12.73179 -115.84864) (xy -12.763289 -115.973879)
			(xy -12.802438 -116.096942) (xy -12.849089 -116.217361) (xy -12.903064 -116.33468) (xy -12.964159 -116.448454)
			(xy -13.032142 -116.558251) (xy -13.106756 -116.663654) (xy -13.187717 -116.764264) (xy -13.274717 -116.859699)
			(xy -13.367428 -116.949598) (xy -13.465498 -117.033619) (xy -13.568553 -117.111443) (xy -13.676204 -117.182775)
			(xy -13.788043 -117.247345) (xy -13.903644 -117.304907) (xy -14.022569 -117.355244) (xy -14.144368 -117.398164)
			(xy -14.268578 -117.433505) (xy -14.394727 -117.461132) (xy -14.522339 -117.480941) (xy -14.650928 -117.492857)
			(xy -14.780006 -117.496834) (xy -14.909084 -117.492857) (xy -15.037673 -117.480941) (xy -15.165285 -117.461132)
			(xy -15.291434 -117.433505) (xy -15.415644 -117.398164) (xy -15.537443 -117.355244) (xy -15.656368 -117.304907)
			(xy -15.771969 -117.247345) (xy -15.883808 -117.182775) (xy -15.991459 -117.111443) (xy -16.094514 -117.033619)
			(xy -16.192584 -116.949598) (xy -16.285295 -116.859699) (xy -16.372295 -116.764264) (xy -16.453256 -116.663654)
			(xy -16.52787 -116.558251) (xy -16.595853 -116.448454) (xy -16.656948 -116.33468) (xy -16.710923 -116.217361)
			(xy -16.757574 -116.096942) (xy -16.796723 -115.973879) (xy -16.828222 -115.84864) (xy -16.851951 -115.721699)
			(xy -16.867821 -115.593539) (xy -16.875771 -115.464644) (xy -19.271996 -115.464644) (xy -19.271996 -118.400068)
			(xy -19.271474 -118.455875) (xy -19.263133 -118.567177) (xy -19.246498 -118.677544) (xy -19.221661 -118.78636)
			(xy -19.188762 -118.893015) (xy -19.147985 -118.996914) (xy -19.099558 -119.097474) (xy -19.04375 -119.194135)
			(xy -18.980876 -119.286355) (xy -18.911286 -119.373618) (xy -18.835369 -119.455437) (xy -18.75355 -119.531354)
			(xy -18.666287 -119.600944) (xy -18.574067 -119.663818) (xy -18.477406 -119.719626) (xy -18.376846 -119.768053)
			(xy -18.272947 -119.80883) (xy -18.166292 -119.841729) (xy -18.057476 -119.866566) (xy -17.947109 -119.883201)
			(xy -17.835807 -119.891542) (xy -17.78 -119.892064)
		)
		(stroke
			(width 0)
			(type solid)
		)
		(fill yes)
		(layer "In10.Cu")
		(net "T_GND")
	)
	(gr_poly
		(pts
			(xy 10.256012 -118.78437) (xy 10.256012 -114.799872) (xy 10.256503 -114.755847) (xy 10.264197 -114.668134)
			(xy 10.279504 -114.581425) (xy 10.302308 -114.49638) (xy 10.332434 -114.413645) (xy 10.369655 -114.333849)
			(xy 10.413686 -114.257599) (xy 10.464194 -114.185476) (xy 10.520793 -114.118028) (xy 10.583054 -114.055768)
			(xy 10.650503 -113.999169) (xy 10.722626 -113.948662) (xy 10.798876 -113.904631) (xy 10.878672 -113.867411)
			(xy 10.961408 -113.837285) (xy 11.046453 -113.814482) (xy 11.133162 -113.799176) (xy 11.220875 -113.791483)
			(xy 11.2649 -113.790984) (xy 12.765024 -113.790984) (xy 12.809049 -113.791474) (xy 12.896764 -113.799165)
			(xy 12.983474 -113.81447) (xy 13.068521 -113.837272) (xy 13.078373 -113.840859) (xy 20.444184 -113.840859)
			(xy 20.444184 -113.786321) (xy 20.451946 -113.732337) (xy 20.467311 -113.680007) (xy 20.489968 -113.630397)
			(xy 20.519454 -113.584516) (xy 20.555169 -113.543299) (xy 20.596386 -113.507584) (xy 20.642267 -113.478098)
			(xy 20.691877 -113.455441) (xy 20.744207 -113.440076) (xy 20.798191 -113.432314) (xy 20.82546 -113.431828)
			(xy 21.71446 -113.431828) (xy 21.741732 -113.432309) (xy 21.795722 -113.440066) (xy 21.848058 -113.455428)
			(xy 21.897675 -113.478083) (xy 21.943562 -113.507569) (xy 21.984786 -113.543285) (xy 22.020507 -113.584506)
			(xy 22.049998 -113.63039) (xy 22.072658 -113.680004) (xy 22.088025 -113.732339) (xy 22.095788 -113.786328)
			(xy 22.095788 -113.840872) (xy 22.088025 -113.894861) (xy 22.072658 -113.947196) (xy 22.049998 -113.99681)
			(xy 22.020507 -114.042694) (xy 21.984786 -114.083915) (xy 21.943562 -114.119631) (xy 21.897675 -114.149117)
			(xy 21.848058 -114.171772) (xy 21.795722 -114.187134) (xy 21.741732 -114.194891) (xy 21.71446 -114.195352)
			(xy 20.82546 -114.195352) (xy 20.798191 -114.194866) (xy 20.744207 -114.187104) (xy 20.691877 -114.171739)
			(xy 20.642267 -114.149082) (xy 20.596386 -114.119596) (xy 20.555169 -114.083881) (xy 20.519454 -114.042664)
			(xy 20.489968 -113.996783) (xy 20.467311 -113.947173) (xy 20.451946 -113.894843) (xy 20.444184 -113.840859)
			(xy 13.078373 -113.840859) (xy 13.151258 -113.867397) (xy 13.231056 -113.904617) (xy 13.307307 -113.948648)
			(xy 13.379432 -113.999155) (xy 13.446881 -114.055754) (xy 13.509143 -114.118016) (xy 13.565743 -114.185465)
			(xy 13.61625 -114.25759) (xy 13.660282 -114.33384) (xy 13.697502 -114.413638) (xy 13.727627 -114.496375)
			(xy 13.750429 -114.581422) (xy 13.765734 -114.668132) (xy 13.773426 -114.755847) (xy 13.773912 -114.799872)
			(xy 13.773912 -116.038376) (xy 13.96492 -116.038376) (xy 13.96492 -115.149376) (xy 13.965406 -115.122125)
			(xy 13.973162 -115.068177) (xy 13.988517 -115.015882) (xy 14.011159 -114.966305) (xy 14.040625 -114.920455)
			(xy 14.076316 -114.879264) (xy 14.117507 -114.843573) (xy 14.163357 -114.814107) (xy 14.212934 -114.791465)
			(xy 14.265229 -114.77611) (xy 14.319177 -114.768354) (xy 14.373679 -114.768354) (xy 14.427627 -114.77611)
			(xy 14.479922 -114.791465) (xy 14.529499 -114.814107) (xy 14.575349 -114.843573) (xy 14.61654 -114.879264)
			(xy 14.652231 -114.920455) (xy 14.681697 -114.966305) (xy 14.704339 -115.015882) (xy 14.719694 -115.068177)
			(xy 14.72745 -115.122125) (xy 14.727936 -115.149376) (xy 14.727936 -116.038376) (xy 15.764764 -116.038376)
			(xy 15.764764 -115.149376) (xy 15.76525 -115.122107) (xy 15.773012 -115.068123) (xy 15.788377 -115.015793)
			(xy 15.811034 -114.966183) (xy 15.84052 -114.920302) (xy 15.876235 -114.879085) (xy 15.917452 -114.84337)
			(xy 15.963333 -114.813884) (xy 16.012943 -114.791227) (xy 16.065273 -114.775862) (xy 16.119257 -114.7681)
			(xy 16.173795 -114.7681) (xy 16.227779 -114.775862) (xy 16.280109 -114.791227) (xy 16.329719 -114.813884)
			(xy 16.3756 -114.84337) (xy 16.416817 -114.879085) (xy 16.452532 -114.920302) (xy 16.482018 -114.966183)
			(xy 16.504675 -115.015793) (xy 16.510811 -115.036691) (xy 23.190153 -115.036691) (xy 23.190153 -114.982149)
			(xy 23.197916 -114.928162) (xy 23.213282 -114.875829) (xy 23.23594 -114.826216) (xy 23.265428 -114.780333)
			(xy 23.301145 -114.739113) (xy 23.342366 -114.703395) (xy 23.38825 -114.673908) (xy 23.437863 -114.651251)
			(xy 23.490196 -114.635885) (xy 23.544183 -114.628123) (xy 23.571454 -114.62766) (xy 24.460454 -114.62766)
			(xy 24.487723 -114.628143) (xy 24.541707 -114.635905) (xy 24.594036 -114.651271) (xy 24.643646 -114.673927)
			(xy 24.689527 -114.703413) (xy 24.730744 -114.739129) (xy 24.766459 -114.780347) (xy 24.795945 -114.826227)
			(xy 24.818601 -114.875838) (xy 24.833966 -114.928167) (xy 24.841728 -114.982151) (xy 24.841728 -115.036689)
			(xy 24.833966 -115.090673) (xy 24.818601 -115.143002) (xy 24.795945 -115.192613) (xy 24.766459 -115.238493)
			(xy 24.730744 -115.279711) (xy 24.689527 -115.315427) (xy 24.643646 -115.344913) (xy 24.594036 -115.367569)
			(xy 24.541707 -115.382935) (xy 24.487723 -115.390697) (xy 24.460454 -115.391184) (xy 23.571454 -115.391184)
			(xy 23.544183 -115.390717) (xy 23.490196 -115.382955) (xy 23.437863 -115.367589) (xy 23.38825 -115.344932)
			(xy 23.342366 -115.315445) (xy 23.301145 -115.279727) (xy 23.265428 -115.238507) (xy 23.23594 -115.192624)
			(xy 23.213282 -115.143011) (xy 23.197916 -115.090678) (xy 23.190153 -115.036691) (xy 16.510811 -115.036691)
			(xy 16.52004 -115.068123) (xy 16.527802 -115.122107) (xy 16.528288 -115.149376) (xy 16.528288 -116.038376)
			(xy 16.527802 -116.065645) (xy 16.52004 -116.119629) (xy 16.504675 -116.171959) (xy 16.482018 -116.221569)
			(xy 16.452532 -116.26745) (xy 16.416817 -116.308667) (xy 16.3756 -116.344382) (xy 16.329719 -116.373868)
			(xy 16.280109 -116.396525) (xy 16.227779 -116.41189) (xy 16.173795 -116.419652) (xy 16.119257 -116.419652)
			(xy 16.065273 -116.41189) (xy 16.012943 -116.396525) (xy 15.963333 -116.373868) (xy 15.917452 -116.344382)
			(xy 15.876235 -116.308667) (xy 15.84052 -116.26745) (xy 15.811034 -116.221569) (xy 15.788377 -116.171959)
			(xy 15.773012 -116.119629) (xy 15.76525 -116.065645) (xy 15.764764 -116.038376) (xy 14.727936 -116.038376)
			(xy 14.72745 -116.065627) (xy 14.719694 -116.119575) (xy 14.704339 -116.17187) (xy 14.681697 -116.221447)
			(xy 14.652231 -116.267297) (xy 14.61654 -116.308488) (xy 14.575349 -116.344179) (xy 14.529499 -116.373645)
			(xy 14.479922 -116.396287) (xy 14.427627 -116.411642) (xy 14.373679 -116.419398) (xy 14.319177 -116.419398)
			(xy 14.265229 -116.411642) (xy 14.212934 -116.396287) (xy 14.163357 -116.373645) (xy 14.117507 -116.344179)
			(xy 14.076316 -116.308488) (xy 14.040625 -116.267297) (xy 14.011159 -116.221447) (xy 13.988517 -116.17187)
			(xy 13.973162 -116.119575) (xy 13.965406 -116.065627) (xy 13.96492 -116.038376) (xy 13.773912 -116.038376)
			(xy 13.773912 -117.3734) (xy 31.116016 -117.3734) (xy 31.116016 -114.77498) (xy 31.116505 -114.713316)
			(xy 31.124564 -114.590252) (xy 31.140653 -114.467979) (xy 31.164706 -114.34702) (xy 31.196619 -114.227893)
			(xy 31.236255 -114.111108) (xy 31.283445 -113.997166) (xy 31.337986 -113.886554) (xy 31.399645 -113.779747)
			(xy 31.468158 -113.677201) (xy 31.543231 -113.579356) (xy 31.624543 -113.48663) (xy 31.711746 -113.399422)
			(xy 31.804466 -113.318103) (xy 31.902306 -113.243024) (xy 32.004847 -113.174504) (xy 32.11165 -113.112838)
			(xy 32.222258 -113.058289) (xy 32.336197 -113.011092) (xy 32.452979 -112.971448) (xy 32.572104 -112.939527)
			(xy 32.693062 -112.915466) (xy 32.815334 -112.899368) (xy 32.938397 -112.891302) (xy 33.061725 -112.891302)
			(xy 33.184788 -112.899368) (xy 33.30706 -112.915466) (xy 33.428018 -112.939527) (xy 33.547143 -112.971448)
			(xy 33.663925 -113.011092) (xy 33.777864 -113.058289) (xy 33.888472 -113.112838) (xy 33.995275 -113.174504)
			(xy 34.097816 -113.243024) (xy 34.195656 -113.318103) (xy 34.288376 -113.399422) (xy 34.375579 -113.48663)
			(xy 34.456891 -113.579356) (xy 34.531964 -113.677201) (xy 34.600477 -113.779747) (xy 34.662136 -113.886554)
			(xy 34.716677 -113.997166) (xy 34.763867 -114.111108) (xy 34.803503 -114.227893) (xy 34.835416 -114.34702)
			(xy 34.859469 -114.467979) (xy 34.875558 -114.590252) (xy 34.883617 -114.713316) (xy 34.884106 -114.77498)
			(xy 34.884106 -117.3734) (xy 43.825922 -117.3734) (xy 43.825922 -114.324892) (xy 43.826423 -114.271251)
			(xy 43.83444 -114.164269) (xy 43.85043 -114.058186) (xy 43.874302 -113.953594) (xy 43.905924 -113.851078)
			(xy 43.945119 -113.751213) (xy 43.991666 -113.654555) (xy 44.045307 -113.561646) (xy 44.105741 -113.473006)
			(xy 44.17263 -113.38913) (xy 44.245601 -113.310487) (xy 44.324244 -113.237516) (xy 44.40812 -113.170627)
			(xy 44.49676 -113.110193) (xy 44.589669 -113.056552) (xy 44.686327 -113.010005) (xy 44.786192 -112.97081)
			(xy 44.888708 -112.939188) (xy 44.9933 -112.915316) (xy 45.099383 -112.899326) (xy 45.206365 -112.891309)
			(xy 45.313647 -112.891309) (xy 45.420629 -112.899326) (xy 45.526712 -112.915316) (xy 45.631304 -112.939188)
			(xy 45.73382 -112.97081) (xy 45.833685 -113.010005) (xy 45.930343 -113.056552) (xy 46.023252 -113.110193)
			(xy 46.111892 -113.170627) (xy 46.195768 -113.237516) (xy 46.274411 -113.310487) (xy 46.347382 -113.38913)
			(xy 46.414271 -113.473006) (xy 46.474705 -113.561646) (xy 46.528346 -113.654555) (xy 46.574893 -113.751213)
			(xy 46.614088 -113.851078) (xy 46.64571 -113.953594) (xy 46.669582 -114.058186) (xy 46.685572 -114.164269)
			(xy 46.693589 -114.271251) (xy 46.69409 -114.324892) (xy 46.69409 -117.3734) (xy 64.026034 -117.3734)
			(xy 64.026034 -114.525044) (xy 64.026532 -114.468001) (xy 64.03449 -114.354194) (xy 64.050367 -114.24122)
			(xy 64.074087 -114.129628) (xy 64.105533 -114.019962) (xy 64.144553 -113.912757) (xy 64.190955 -113.808535)
			(xy 64.244515 -113.707804) (xy 64.304971 -113.611054) (xy 64.372028 -113.518758) (xy 64.445361 -113.431363)
			(xy 64.524611 -113.349297) (xy 64.609393 -113.27296) (xy 64.699293 -113.202722) (xy 64.793874 -113.138926)
			(xy 64.892674 -113.081884) (xy 64.995213 -113.031872) (xy 65.100991 -112.989135) (xy 65.209492 -112.953881)
			(xy 65.320188 -112.926281) (xy 65.43254 -112.906471) (xy 65.546 -112.894546) (xy 65.660016 -112.890564)
			(xy 65.774032 -112.894546) (xy 65.887492 -112.906471) (xy 65.999844 -112.926281) (xy 66.11054 -112.953881)
			(xy 66.219041 -112.989135) (xy 66.324819 -113.031872) (xy 66.427358 -113.081884) (xy 66.526158 -113.138926)
			(xy 66.620739 -113.202722) (xy 66.710639 -113.27296) (xy 66.795421 -113.349297) (xy 66.874671 -113.431363)
			(xy 66.948004 -113.518758) (xy 67.015061 -113.611054) (xy 67.075517 -113.707804) (xy 67.129077 -113.808535)
			(xy 67.175479 -113.912757) (xy 67.214499 -114.019962) (xy 67.245945 -114.129628) (xy 67.269665 -114.24122)
			(xy 67.285542 -114.354194) (xy 67.2935 -114.468001) (xy 67.293998 -114.525044) (xy 67.293998 -117.3734)
			(xy 76.230988 -117.3734) (xy 76.230988 -114.799872) (xy 76.231478 -114.755847) (xy 76.23917 -114.668133)
			(xy 76.254475 -114.581423) (xy 76.277277 -114.496376) (xy 76.307402 -114.413639) (xy 76.344622 -114.333842)
			(xy 76.388653 -114.257592) (xy 76.439161 -114.185468) (xy 76.49576 -114.118018) (xy 76.558021 -114.055757)
			(xy 76.625471 -113.999158) (xy 76.697595 -113.948651) (xy 76.773846 -113.90462) (xy 76.853643 -113.867401)
			(xy 76.93638 -113.837275) (xy 77.021427 -113.814474) (xy 77.108137 -113.799169) (xy 77.195851 -113.791478)
			(xy 77.239876 -113.790984) (xy 78.74 -113.790984) (xy 78.784039 -113.79145) (xy 78.871783 -113.799127)
			(xy 78.958523 -113.814422) (xy 79.043601 -113.837219) (xy 79.126367 -113.867344) (xy 79.206193 -113.904568)
			(xy 79.282471 -113.948608) (xy 79.354621 -113.999129) (xy 79.422092 -114.055745) (xy 79.484372 -114.118027)
			(xy 79.540987 -114.1855) (xy 79.591506 -114.257651) (xy 79.635544 -114.33393) (xy 79.672766 -114.413757)
			(xy 79.702889 -114.496524) (xy 79.725684 -114.581602) (xy 79.740976 -114.668343) (xy 79.748651 -114.756087)
			(xy 79.749142 -114.800126) (xy 79.749142 -118.7196) (xy 79.85379 -118.824248) (xy 80.16875 -118.824248)
			(xy 80.272636 -118.720616) (xy 83.93684 -118.720616) (xy 84.094574 -118.878096) (xy 84.394548 -118.878096)
			(xy 84.491068 -118.781576) (xy 84.491068 -114.799872) (xy 84.491558 -114.755847) (xy 84.49925 -114.668132)
			(xy 84.514555 -114.581421) (xy 84.537356 -114.496374) (xy 84.567482 -114.413636) (xy 84.604701 -114.333838)
			(xy 84.648732 -114.257587) (xy 84.69924 -114.185462) (xy 84.755839 -114.118012) (xy 84.8181 -114.05575)
			(xy 84.885549 -113.999149) (xy 84.957674 -113.948641) (xy 85.033924 -113.904609) (xy 85.113722 -113.867388)
			(xy 85.196458 -113.837261) (xy 85.281506 -113.814458) (xy 85.368216 -113.799152) (xy 85.455931 -113.791459)
			(xy 85.499956 -113.790984) (xy 88.000078 -113.790984) (xy 88.055848 -113.790476) (xy 88.167076 -113.782142)
			(xy 88.277371 -113.76552) (xy 88.386115 -113.740701) (xy 88.4927 -113.707825) (xy 88.596531 -113.667076)
			(xy 88.697025 -113.618682) (xy 88.793622 -113.562913) (xy 88.885782 -113.500081) (xy 88.972988 -113.430538)
			(xy 89.054754 -113.354672) (xy 89.130621 -113.272908) (xy 89.200166 -113.185703) (xy 89.262999 -113.093545)
			(xy 89.31877 -112.996948) (xy 89.367166 -112.896454) (xy 89.407917 -112.792625) (xy 89.440794 -112.68604)
			(xy 89.465615 -112.577297) (xy 89.48224 -112.467002) (xy 89.490575 -112.355774) (xy 89.491058 -112.300004)
			(xy 89.491058 -85.5091) (xy 87.749888 -85.5091) (xy 87.705865 -85.508603) (xy 87.618157 -85.500897)
			(xy 87.531453 -85.485581) (xy 87.446413 -85.46277) (xy 87.363683 -85.432637) (xy 87.283893 -85.395413)
			(xy 87.207648 -85.351379) (xy 87.13553 -85.300871) (xy 87.068085 -85.244273) (xy 87.005827 -85.182015)
			(xy 86.949229 -85.11457) (xy 86.898721 -85.042452) (xy 86.854687 -84.966207) (xy 86.817463 -84.886417)
			(xy 86.78733 -84.803687) (xy 86.764519 -84.718647) (xy 86.749203 -84.631943) (xy 86.741497 -84.544235)
			(xy 86.741 -84.500212) (xy 86.741 -81.999836) (xy 86.741491 -81.955812) (xy 86.749186 -81.868101)
			(xy 86.764493 -81.781393) (xy 86.787298 -81.69635) (xy 86.817425 -81.613616) (xy 86.854646 -81.533822)
			(xy 86.898678 -81.457575) (xy 86.949186 -81.385454) (xy 87.005786 -81.318008) (xy 87.068047 -81.255751)
			(xy 87.135495 -81.199154) (xy 87.207619 -81.14865) (xy 87.283869 -81.104622) (xy 87.363664 -81.067405)
			(xy 87.446399 -81.037282) (xy 87.531444 -81.014482) (xy 87.618152 -80.999179) (xy 87.705864 -80.991489)
			(xy 87.749888 -80.990948) (xy 89.491058 -80.990948) (xy 89.491058 -69.07022) (xy 89.492074 -69.069204)
			(xy 89.492074 -67.757802) (xy 89.491058 -67.756786) (xy 89.491058 -1.999996) (xy 89.490549 -1.944227)
			(xy 89.482214 -1.833001) (xy 89.465589 -1.722708) (xy 89.440769 -1.613967) (xy 89.407892 -1.507384)
			(xy 89.367142 -1.403556) (xy 89.318747 -1.303064) (xy 89.262977 -1.206469) (xy 89.200145 -1.114313)
			(xy 89.130601 -1.027109) (xy 89.054735 -0.945346) (xy 88.972971 -0.869482) (xy 88.885767 -0.79994)
			(xy 88.793609 -0.737109) (xy 88.697013 -0.681341) (xy 88.59652 -0.632947) (xy 88.492692 -0.592199)
			(xy 88.386108 -0.559324) (xy 88.277366 -0.534506) (xy 88.167074 -0.517883) (xy 88.055847 -0.50955)
			(xy 88.000078 -0.509016) (xy 1.999996 -0.509016) (xy 1.944227 -0.509538) (xy 1.833001 -0.517873)
			(xy 1.722709 -0.534497) (xy 1.613967 -0.559317) (xy 1.507385 -0.592194) (xy 1.403557 -0.632943) (xy 1.303065 -0.681338)
			(xy 1.20647 -0.737107) (xy 1.114313 -0.799938) (xy 1.027109 -0.869481) (xy 0.945346 -0.945346) (xy 0.869481 -1.027109)
			(xy 0.799938 -1.114313) (xy 0.737107 -1.20647) (xy 0.681338 -1.303065) (xy 0.632943 -1.403557) (xy 0.592194 -1.507385)
			(xy 0.559317 -1.613967) (xy 0.534497 -1.722709) (xy 0.517873 -1.833001) (xy 0.509538 -1.944227) (xy 0.509016 -1.999996)
			(xy 0.509016 -4.69011) (xy 3.634743 -4.69011) (xy 3.638781 -4.606614) (xy 3.65086 -4.523897) (xy 3.670865 -4.442732)
			(xy 3.69861 -4.363877) (xy 3.733837 -4.288068) (xy 3.776216 -4.216013) (xy 3.825351 -4.148384) (xy 3.880784 -4.085813)
			(xy 3.941997 -4.028884) (xy 4.008419 -3.978129) (xy 4.079429 -3.934021) (xy 4.154365 -3.896973) (xy 4.232527 -3.867331)
			(xy 4.313184 -3.84537) (xy 4.395585 -3.831296) (xy 4.478959 -3.825241) (xy 4.562529 -3.827261) (xy 4.645513 -3.837337)
			(xy 4.727138 -3.855375) (xy 4.80664 -3.881207) (xy 4.883279 -3.914592) (xy 4.956337 -3.955217) (xy 5.025133 -4.002704)
			(xy 5.089025 -4.056609) (xy 5.147417 -4.116428) (xy 5.199762 -4.181604) (xy 5.245572 -4.251528) (xy 5.284421 -4.325547)
			(xy 5.315943 -4.402969) (xy 5.339847 -4.483073) (xy 5.355907 -4.565109) (xy 5.363975 -4.648313) (xy 5.36448 -4.69011)
			(xy 10.635237 -4.69011) (xy 10.639274 -4.606638) (xy 10.651349 -4.523946) (xy 10.671348 -4.442805)
			(xy 10.699086 -4.363973) (xy 10.734302 -4.288186) (xy 10.776668 -4.216152) (xy 10.825789 -4.148543)
			(xy 10.881206 -4.08599) (xy 10.942401 -4.029078) (xy 11.008803 -3.978338) (xy 11.079793 -3.934243)
			(xy 11.154707 -3.897206) (xy 11.232845 -3.867572) (xy 11.313479 -3.845618) (xy 11.395856 -3.831548)
			(xy 11.479206 -3.825495) (xy 11.562751 -3.827514) (xy 11.645711 -3.837588) (xy 11.727311 -3.85562)
			(xy 11.80679 -3.881445) (xy 11.883406 -3.914819) (xy 11.956443 -3.955433) (xy 12.025219 -4.002906)
			(xy 12.089092 -4.056795) (xy 12.147467 -4.116597) (xy 12.199797 -4.181754) (xy 12.245594 -4.251657)
			(xy 12.28443 -4.325654) (xy 12.315944 -4.403054) (xy 12.33984 -4.483134) (xy 12.355896 -4.565146)
			(xy 12.363962 -4.648325) (xy 12.364466 -4.69011) (xy 12.363962 -4.731895) (xy 12.355896 -4.815074)
			(xy 12.33984 -4.897086) (xy 12.315944 -4.977166) (xy 12.28443 -5.054566) (xy 12.265749 -5.09016)
			(xy 66.234821 -5.09016) (xy 66.238859 -5.006664) (xy 66.250938 -4.923947) (xy 66.270943 -4.842782)
			(xy 66.298688 -4.763927) (xy 66.333915 -4.688118) (xy 66.376294 -4.616063) (xy 66.425429 -4.548434)
			(xy 66.480862 -4.485863) (xy 66.542075 -4.428934) (xy 66.608497 -4.378179) (xy 66.679507 -4.334071)
			(xy 66.754443 -4.297023) (xy 66.832605 -4.267381) (xy 66.913262 -4.24542) (xy 66.995663 -4.231346)
			(xy 67.079037 -4.225291) (xy 67.162607 -4.227311) (xy 67.245591 -4.237387) (xy 67.327216 -4.255425)
			(xy 67.406718 -4.281257) (xy 67.483357 -4.314642) (xy 67.556415 -4.355267) (xy 67.625211 -4.402754)
			(xy 67.689103 -4.456659) (xy 67.747495 -4.516478) (xy 67.79984 -4.581654) (xy 67.84565 -4.651578)
			(xy 67.884499 -4.725597) (xy 67.916021 -4.803019) (xy 67.939925 -4.883123) (xy 67.955985 -4.965159)
			(xy 67.964053 -5.048363) (xy 67.964558 -5.09016) (xy 73.235315 -5.09016) (xy 73.239352 -5.006688)
			(xy 73.251427 -4.923996) (xy 73.271426 -4.842855) (xy 73.299164 -4.764023) (xy 73.33438 -4.688236)
			(xy 73.376746 -4.616202) (xy 73.425867 -4.548593) (xy 73.481284 -4.48604) (xy 73.542479 -4.429128)
			(xy 73.608881 -4.378388) (xy 73.679871 -4.334293) (xy 73.754785 -4.297256) (xy 73.832923 -4.267622)
			(xy 73.913557 -4.245668) (xy 73.995934 -4.231598) (xy 74.079284 -4.225545) (xy 74.162829 -4.227564)
			(xy 74.245789 -4.237638) (xy 74.327389 -4.25567) (xy 74.406868 -4.281495) (xy 74.483484 -4.314869)
			(xy 74.556521 -4.355483) (xy 74.625297 -4.402956) (xy 74.68917 -4.456845) (xy 74.747545 -4.516647)
			(xy 74.799875 -4.581804) (xy 74.845672 -4.651707) (xy 74.865827 -4.69011) (xy 77.634595 -4.69011)
			(xy 77.638634 -4.606589) (xy 77.650716 -4.523848) (xy 77.670728 -4.44266) (xy 77.698481 -4.363781)
			(xy 77.733718 -4.28795) (xy 77.776109 -4.215873) (xy 77.825259 -4.148225) (xy 77.880708 -4.085635)
			(xy 77.941939 -4.02869) (xy 78.008381 -3.97792) (xy 78.079412 -3.933799) (xy 78.15437 -3.89674) (xy 78.232554 -3.867089)
			(xy 78.313236 -3.845122) (xy 78.395661 -3.831044) (xy 78.479059 -3.824987) (xy 78.562653 -3.827008)
			(xy 78.645662 -3.837087) (xy 78.727311 -3.85513) (xy 78.806836 -3.88097) (xy 78.883497 -3.914364)
			(xy 78.956577 -3.955001) (xy 79.025394 -4.002502) (xy 79.089304 -4.056423) (xy 79.147713 -4.11626)
			(xy 79.200073 -4.181455) (xy 79.245897 -4.251399) (xy 79.284757 -4.32544) (xy 79.316289 -4.402885)
			(xy 79.340199 -4.483012) (xy 79.356265 -4.565073) (xy 79.364335 -4.648301) (xy 79.36484 -4.69011)
			(xy 84.635089 -4.69011) (xy 84.639127 -4.606614) (xy 84.651206 -4.523897) (xy 84.671211 -4.442732)
			(xy 84.698956 -4.363877) (xy 84.734183 -4.288068) (xy 84.776562 -4.216013) (xy 84.825697 -4.148384)
			(xy 84.88113 -4.085813) (xy 84.942343 -4.028884) (xy 85.008765 -3.978129) (xy 85.079775 -3.934021)
			(xy 85.154711 -3.896973) (xy 85.232873 -3.867331) (xy 85.31353 -3.84537) (xy 85.395931 -3.831296)
			(xy 85.479305 -3.825241) (xy 85.562875 -3.827261) (xy 85.645859 -3.837337) (xy 85.727484 -3.855375)
			(xy 85.806986 -3.881207) (xy 85.883625 -3.914592) (xy 85.956683 -3.955217) (xy 86.025479 -4.002704)
			(xy 86.089371 -4.056609) (xy 86.147763 -4.116428) (xy 86.200108 -4.181604) (xy 86.245918 -4.251528)
			(xy 86.284767 -4.325547) (xy 86.316289 -4.402969) (xy 86.340193 -4.483073) (xy 86.356253 -4.565109)
			(xy 86.364321 -4.648313) (xy 86.364826 -4.69011) (xy 86.364321 -4.731907) (xy 86.356253 -4.815111)
			(xy 86.340193 -4.897147) (xy 86.316289 -4.977251) (xy 86.284767 -5.054673) (xy 86.245918 -5.128692)
			(xy 86.200108 -5.198616) (xy 86.147763 -5.263792) (xy 86.089371 -5.323611) (xy 86.025479 -5.377516)
			(xy 85.956683 -5.425003) (xy 85.883625 -5.465628) (xy 85.806986 -5.499013) (xy 85.727484 -5.524845)
			(xy 85.645859 -5.542883) (xy 85.562875 -5.552959) (xy 85.479305 -5.554979) (xy 85.395931 -5.548924)
			(xy 85.31353 -5.53485) (xy 85.232873 -5.512889) (xy 85.154711 -5.483247) (xy 85.079775 -5.446199)
			(xy 85.008765 -5.402091) (xy 84.942343 -5.351336) (xy 84.88113 -5.294407) (xy 84.825697 -5.231836)
			(xy 84.776562 -5.164207) (xy 84.734183 -5.092152) (xy 84.698956 -5.016343) (xy 84.671211 -4.937488)
			(xy 84.651206 -4.856323) (xy 84.639127 -4.773606) (xy 84.635089 -4.69011) (xy 79.36484 -4.69011)
			(xy 79.364335 -4.731919) (xy 79.356265 -4.815147) (xy 79.340199 -4.897208) (xy 79.316289 -4.977335)
			(xy 79.284757 -5.05478) (xy 79.245897 -5.128821) (xy 79.200073 -5.198765) (xy 79.147713 -5.26396)
			(xy 79.089304 -5.323797) (xy 79.025394 -5.377718) (xy 78.956577 -5.425219) (xy 78.883497 -5.465856)
			(xy 78.806836 -5.49925) (xy 78.727311 -5.52509) (xy 78.645662 -5.543133) (xy 78.562653 -5.553212)
			(xy 78.479059 -5.555233) (xy 78.395661 -5.549176) (xy 78.313236 -5.535098) (xy 78.232554 -5.513131)
			(xy 78.15437 -5.48348) (xy 78.079412 -5.446421) (xy 78.008381 -5.4023) (xy 77.941939 -5.35153) (xy 77.880708 -5.294585)
			(xy 77.825259 -5.231995) (xy 77.776109 -5.164347) (xy 77.733718 -5.09227) (xy 77.698481 -5.016439)
			(xy 77.670728 -4.93756) (xy 77.650716 -4.856372) (xy 77.638634 -4.773631) (xy 77.634595 -4.69011)
			(xy 74.865827 -4.69011) (xy 74.884508 -4.725704) (xy 74.916022 -4.803104) (xy 74.939918 -4.883184)
			(xy 74.955974 -4.965196) (xy 74.96404 -5.048375) (xy 74.964544 -5.09016) (xy 74.96404 -5.131945)
			(xy 74.955974 -5.215124) (xy 74.939918 -5.297136) (xy 74.916022 -5.377216) (xy 74.884508 -5.454616)
			(xy 74.845672 -5.528613) (xy 74.799875 -5.598516) (xy 74.747545 -5.663673) (xy 74.68917 -5.723475)
			(xy 74.625297 -5.777364) (xy 74.556521 -5.824837) (xy 74.483484 -5.865451) (xy 74.406868 -5.898825)
			(xy 74.327389 -5.92465) (xy 74.245789 -5.942682) (xy 74.162829 -5.952756) (xy 74.079284 -5.954775)
			(xy 73.995934 -5.948722) (xy 73.913557 -5.934652) (xy 73.832923 -5.912698) (xy 73.754785 -5.883064)
			(xy 73.679871 -5.846027) (xy 73.608881 -5.801932) (xy 73.542479 -5.751192) (xy 73.481284 -5.69428)
			(xy 73.425867 -5.631727) (xy 73.376746 -5.564118) (xy 73.33438 -5.492084) (xy 73.299164 -5.416297)
			(xy 73.271426 -5.337465) (xy 73.251427 -5.256324) (xy 73.239352 -5.173632) (xy 73.235315 -5.09016)
			(xy 67.964558 -5.09016) (xy 67.964053 -5.131957) (xy 67.955985 -5.215161) (xy 67.939925 -5.297197)
			(xy 67.916021 -5.377301) (xy 67.884499 -5.454723) (xy 67.84565 -5.528742) (xy 67.79984 -5.598666)
			(xy 67.747495 -5.663842) (xy 67.689103 -5.723661) (xy 67.625211 -5.777566) (xy 67.556415 -5.825053)
			(xy 67.483357 -5.865678) (xy 67.406718 -5.899063) (xy 67.327216 -5.924895) (xy 67.245591 -5.942933)
			(xy 67.162607 -5.953009) (xy 67.079037 -5.955029) (xy 66.995663 -5.948974) (xy 66.913262 -5.9349)
			(xy 66.832605 -5.912939) (xy 66.754443 -5.883297) (xy 66.679507 -5.846249) (xy 66.608497 -5.802141)
			(xy 66.542075 -5.751386) (xy 66.480862 -5.694457) (xy 66.425429 -5.631886) (xy 66.376294 -5.564257)
			(xy 66.333915 -5.492202) (xy 66.298688 -5.416393) (xy 66.270943 -5.337538) (xy 66.250938 -5.256373)
			(xy 66.238859 -5.173656) (xy 66.234821 -5.09016) (xy 12.265749 -5.09016) (xy 12.245594 -5.128563)
			(xy 12.199797 -5.198466) (xy 12.147467 -5.263623) (xy 12.089092 -5.323425) (xy 12.025219 -5.377314)
			(xy 11.956443 -5.424787) (xy 11.883406 -5.465401) (xy 11.80679 -5.498775) (xy 11.727311 -5.5246)
			(xy 11.645711 -5.542632) (xy 11.562751 -5.552706) (xy 11.479206 -5.554725) (xy 11.395856 -5.548672)
			(xy 11.313479 -5.534602) (xy 11.232845 -5.512648) (xy 11.154707 -5.483014) (xy 11.079793 -5.445977)
			(xy 11.008803 -5.401882) (xy 10.942401 -5.351142) (xy 10.881206 -5.29423) (xy 10.825789 -5.231677)
			(xy 10.776668 -5.164068) (xy 10.734302 -5.092034) (xy 10.699086 -5.016247) (xy 10.671348 -4.937415)
			(xy 10.651349 -4.856274) (xy 10.639274 -4.773582) (xy 10.635237 -4.69011) (xy 5.36448 -4.69011) (xy 5.363975 -4.731907)
			(xy 5.355907 -4.815111) (xy 5.339847 -4.897147) (xy 5.315943 -4.977251) (xy 5.284421 -5.054673) (xy 5.245572 -5.128692)
			(xy 5.199762 -5.198616) (xy 5.147417 -5.263792) (xy 5.089025 -5.323611) (xy 5.025133 -5.377516) (xy 4.956337 -5.425003)
			(xy 4.883279 -5.465628) (xy 4.80664 -5.499013) (xy 4.727138 -5.524845) (xy 4.645513 -5.542883) (xy 4.562529 -5.552959)
			(xy 4.478959 -5.554979) (xy 4.395585 -5.548924) (xy 4.313184 -5.53485) (xy 4.232527 -5.512889) (xy 4.154365 -5.483247)
			(xy 4.079429 -5.446199) (xy 4.008419 -5.402091) (xy 3.941997 -5.351336) (xy 3.880784 -5.294407) (xy 3.825351 -5.231836)
			(xy 3.776216 -5.164207) (xy 3.733837 -5.092152) (xy 3.69861 -5.016343) (xy 3.670865 -4.937488) (xy 3.65086 -4.856323)
			(xy 3.638781 -4.773606) (xy 3.634743 -4.69011) (xy 0.509016 -4.69011) (xy 0.509016 -13.417248) (xy 41.210697 -13.417248)
			(xy 41.210697 -13.342672) (xy 41.218492 -13.268505) (xy 41.233997 -13.195559) (xy 41.257043 -13.124633)
			(xy 41.287375 -13.056505) (xy 41.324663 -12.991921) (xy 41.368498 -12.931588) (xy 41.418399 -12.876167)
			(xy 41.473819 -12.826266) (xy 41.534152 -12.782432) (xy 41.598737 -12.745144) (xy 41.666865 -12.714812)
			(xy 41.737791 -12.691767) (xy 41.810737 -12.676262) (xy 41.884904 -12.668467) (xy 41.922192 -12.667996)
			(xy 43.922188 -12.667996) (xy 43.959474 -12.668551) (xy 44.033637 -12.676344) (xy 44.106579 -12.691848)
			(xy 44.177502 -12.714891) (xy 44.245627 -12.745221) (xy 44.310208 -12.782506) (xy 44.370538 -12.826338)
			(xy 44.425956 -12.876235) (xy 44.475855 -12.931652) (xy 44.519687 -12.991982) (xy 44.556974 -13.056563)
			(xy 44.587305 -13.124687) (xy 44.610349 -13.195609) (xy 44.625854 -13.268551) (xy 44.633649 -13.342714)
			(xy 44.633649 -13.417286) (xy 44.625854 -13.491449) (xy 44.610349 -13.564391) (xy 44.587305 -13.635313)
			(xy 44.556974 -13.703437) (xy 44.519687 -13.768018) (xy 44.475855 -13.828348) (xy 44.425956 -13.883765)
			(xy 44.370538 -13.933662) (xy 44.310208 -13.977494) (xy 44.245627 -14.014779) (xy 44.177502 -14.045109)
			(xy 44.106579 -14.068152) (xy 44.033637 -14.083656) (xy 43.959474 -14.091449) (xy 43.922188 -14.09192)
			(xy 41.922192 -14.09192) (xy 41.884904 -14.091453) (xy 41.810737 -14.083658) (xy 41.737791 -14.068153)
			(xy 41.666865 -14.045108) (xy 41.598737 -14.014776) (xy 41.534152 -13.977488) (xy 41.473819 -13.933654)
			(xy 41.418399 -13.883753) (xy 41.368498 -13.828332) (xy 41.324663 -13.767999) (xy 41.287375 -13.703415)
			(xy 41.257043 -13.635287) (xy 41.233997 -13.564361) (xy 41.218492 -13.491415) (xy 41.210697 -13.417248)
			(xy 0.509016 -13.417248) (xy 0.509016 -14.917388) (xy 38.210708 -14.917388) (xy 38.210708 -14.842812)
			(xy 38.218503 -14.768646) (xy 38.234008 -14.6957) (xy 38.257053 -14.624775) (xy 38.287386 -14.556647)
			(xy 38.324673 -14.492062) (xy 38.368507 -14.43173) (xy 38.418408 -14.376309) (xy 38.473828 -14.326409)
			(xy 38.534161 -14.282574) (xy 38.598745 -14.245287) (xy 38.666873 -14.214954) (xy 38.737798 -14.191909)
			(xy 38.810744 -14.176403) (xy 38.88491 -14.168608) (xy 38.922198 -14.16812) (xy 40.922194 -14.16812)
			(xy 40.959481 -14.168627) (xy 41.033646 -14.176422) (xy 41.106591 -14.191926) (xy 41.177515 -14.21497)
			(xy 41.245641 -14.245301) (xy 41.310224 -14.282588) (xy 41.370556 -14.326421) (xy 41.425975 -14.37632)
			(xy 41.475875 -14.431739) (xy 41.519709 -14.492071) (xy 41.556996 -14.556653) (xy 41.587328 -14.62478)
			(xy 41.610373 -14.695704) (xy 41.625877 -14.768648) (xy 41.633673 -14.842813) (xy 41.633673 -14.917387)
			(xy 44.210708 -14.917387) (xy 44.210708 -14.842813) (xy 44.218503 -14.768647) (xy 44.234008 -14.695702)
			(xy 44.257052 -14.624777) (xy 44.287384 -14.55665) (xy 44.324671 -14.492066) (xy 44.368504 -14.431734)
			(xy 44.418404 -14.376314) (xy 44.473823 -14.326413) (xy 44.534154 -14.282578) (xy 44.598737 -14.24529)
			(xy 44.666864 -14.214957) (xy 44.737788 -14.191911) (xy 44.810733 -14.176405) (xy 44.884899 -14.168609)
			(xy 44.922186 -14.16812) (xy 46.922182 -14.16812) (xy 46.959469 -14.168626) (xy 47.033636 -14.17642)
			(xy 47.106581 -14.191923) (xy 47.177506 -14.214967) (xy 47.245634 -14.245298) (xy 47.310218 -14.282584)
			(xy 47.370551 -14.326417) (xy 47.425971 -14.376316) (xy 47.475872 -14.431735) (xy 47.519706 -14.492067)
			(xy 47.556994 -14.55665) (xy 47.587327 -14.624777) (xy 47.610372 -14.695702) (xy 47.625877 -14.768647)
			(xy 47.633673 -14.842813) (xy 47.633673 -14.917387) (xy 47.625877 -14.991553) (xy 47.610372 -15.064498)
			(xy 47.587327 -15.135423) (xy 47.556994 -15.20355) (xy 47.519706 -15.268133) (xy 47.475872 -15.328465)
			(xy 47.425971 -15.383884) (xy 47.370551 -15.433783) (xy 47.310218 -15.477616) (xy 47.245634 -15.514902)
			(xy 47.177506 -15.545233) (xy 47.106581 -15.568277) (xy 47.033636 -15.58378) (xy 46.959469 -15.591574)
			(xy 46.922182 -15.592044) (xy 44.922186 -15.592044) (xy 44.884899 -15.591591) (xy 44.810733 -15.583795)
			(xy 44.737788 -15.568289) (xy 44.666864 -15.545243) (xy 44.598737 -15.51491) (xy 44.534154 -15.477622)
			(xy 44.473823 -15.433787) (xy 44.418404 -15.383886) (xy 44.368504 -15.328466) (xy 44.324671 -15.268134)
			(xy 44.287384 -15.20355) (xy 44.257052 -15.135423) (xy 44.234008 -15.064498) (xy 44.218503 -14.991553)
			(xy 44.210708 -14.917387) (xy 41.633673 -14.917387) (xy 41.625877 -14.991552) (xy 41.610373 -15.064496)
			(xy 41.587328 -15.13542) (xy 41.556996 -15.203547) (xy 41.519709 -15.268129) (xy 41.475875 -15.328461)
			(xy 41.425975 -15.38388) (xy 41.370556 -15.433779) (xy 41.310224 -15.477612) (xy 41.245641 -15.514899)
			(xy 41.177515 -15.54523) (xy 41.106591 -15.568274) (xy 41.033646 -15.583778) (xy 40.959481 -15.591573)
			(xy 40.922194 -15.592044) (xy 38.922198 -15.592044) (xy 38.88491 -15.591592) (xy 38.810744 -15.583797)
			(xy 38.737798 -15.568291) (xy 38.666873 -15.545246) (xy 38.598745 -15.514913) (xy 38.534161 -15.477626)
			(xy 38.473828 -15.433791) (xy 38.418408 -15.383891) (xy 38.368507 -15.32847) (xy 38.324673 -15.268138)
			(xy 38.287386 -15.203553) (xy 38.257053 -15.135425) (xy 38.234008 -15.0645) (xy 38.218503 -14.991554)
			(xy 38.210708 -14.917388) (xy 0.509016 -14.917388) (xy 0.509016 -17.38737) (xy 4.838435 -17.38737)
			(xy 4.838435 -17.25823) (xy 4.846385 -17.129335) (xy 4.862255 -17.001175) (xy 4.885984 -16.874234)
			(xy 4.917483 -16.748995) (xy 4.956632 -16.625932) (xy 5.003283 -16.505513) (xy 5.057258 -16.388194)
			(xy 5.118353 -16.27442) (xy 5.186336 -16.164623) (xy 5.26095 -16.05922) (xy 5.341911 -15.95861) (xy 5.428911 -15.863175)
			(xy 5.521622 -15.773276) (xy 5.619692 -15.689255) (xy 5.722747 -15.611431) (xy 5.830398 -15.540099)
			(xy 5.942237 -15.475529) (xy 6.057838 -15.417967) (xy 6.176763 -15.36763) (xy 6.298562 -15.32471)
			(xy 6.422772 -15.289369) (xy 6.548921 -15.261742) (xy 6.676533 -15.241933) (xy 6.805122 -15.230017)
			(xy 6.9342 -15.226041) (xy 7.063278 -15.230017) (xy 7.191867 -15.241933) (xy 7.319479 -15.261742)
			(xy 7.445628 -15.289369) (xy 7.569838 -15.32471) (xy 7.691637 -15.36763) (xy 7.810562 -15.417967)
			(xy 7.926163 -15.475529) (xy 8.038002 -15.540099) (xy 8.145653 -15.611431) (xy 8.248708 -15.689255)
			(xy 8.346778 -15.773276) (xy 8.439489 -15.863175) (xy 8.526489 -15.95861) (xy 8.60745 -16.05922)
			(xy 8.682064 -16.164623) (xy 8.750047 -16.27442) (xy 8.811142 -16.388194) (xy 8.865117 -16.505513)
			(xy 8.911768 -16.625932) (xy 8.950917 -16.748995) (xy 8.982416 -16.874234) (xy 8.996233 -16.94815)
			(xy 25.574752 -16.94815) (xy 25.574752 -16.05915) (xy 25.575238 -16.031899) (xy 25.582994 -15.977951)
			(xy 25.598349 -15.925656) (xy 25.620991 -15.876079) (xy 25.650457 -15.830229) (xy 25.686148 -15.789038)
			(xy 25.727339 -15.753347) (xy 25.773189 -15.723881) (xy 25.822766 -15.701239) (xy 25.875061 -15.685884)
			(xy 25.929009 -15.678128) (xy 25.983511 -15.678128) (xy 26.037459 -15.685884) (xy 26.089754 -15.701239)
			(xy 26.139331 -15.723881) (xy 26.185181 -15.753347) (xy 26.226372 -15.789038) (xy 26.262063 -15.830229)
			(xy 26.291529 -15.876079) (xy 26.314171 -15.925656) (xy 26.329526 -15.977951) (xy 26.337282 -16.031899)
			(xy 26.337768 -16.05915) (xy 26.337768 -16.94815) (xy 26.337282 -16.975401) (xy 26.329526 -17.029349)
			(xy 26.314171 -17.081644) (xy 26.291529 -17.131221) (xy 26.262063 -17.177071) (xy 26.226372 -17.218262)
			(xy 26.185181 -17.253953) (xy 26.139331 -17.283419) (xy 26.089754 -17.306061) (xy 26.037459 -17.321416)
			(xy 25.983511 -17.329172) (xy 25.929009 -17.329172) (xy 25.875061 -17.321416) (xy 25.822766 -17.306061)
			(xy 25.773189 -17.283419) (xy 25.727339 -17.253953) (xy 25.686148 -17.218262) (xy 25.650457 -17.177071)
			(xy 25.620991 -17.131221) (xy 25.598349 -17.081644) (xy 25.582994 -17.029349) (xy 25.575238 -16.975401)
			(xy 25.574752 -16.94815) (xy 8.996233 -16.94815) (xy 9.006145 -17.001175) (xy 9.022015 -17.129335)
			(xy 9.029965 -17.25823) (xy 9.030462 -17.3228) (xy 9.029965 -17.38737) (xy 9.022015 -17.516265) (xy 9.006145 -17.644425)
			(xy 8.982416 -17.771366) (xy 8.950917 -17.896605) (xy 8.911768 -18.019668) (xy 8.865117 -18.140087)
			(xy 8.811142 -18.257406) (xy 8.750047 -18.37118) (xy 8.682064 -18.480977) (xy 8.60745 -18.58638)
			(xy 8.526489 -18.68699) (xy 8.439489 -18.782425) (xy 8.346778 -18.872324) (xy 8.248708 -18.956345)
			(xy 8.145653 -19.034169) (xy 8.038002 -19.105501) (xy 7.926163 -19.170071) (xy 7.810562 -19.227633)
			(xy 7.691637 -19.27797) (xy 7.569838 -19.32089) (xy 7.445628 -19.356231) (xy 7.319479 -19.383858)
			(xy 7.191867 -19.403667) (xy 7.063278 -19.415583) (xy 6.9342 -19.41956) (xy 6.805122 -19.415583)
			(xy 6.676533 -19.403667) (xy 6.548921 -19.383858) (xy 6.422772 -19.356231) (xy 6.298562 -19.32089)
			(xy 6.176763 -19.27797) (xy 6.057838 -19.227633) (xy 5.942237 -19.170071) (xy 5.830398 -19.105501)
			(xy 5.722747 -19.034169) (xy 5.619692 -18.956345) (xy 5.521622 -18.872324) (xy 5.428911 -18.782425)
			(xy 5.341911 -18.68699) (xy 5.26095 -18.58638) (xy 5.186336 -18.480977) (xy 5.118353 -18.37118) (xy 5.057258 -18.257406)
			(xy 5.003283 -18.140087) (xy 4.956632 -18.019668) (xy 4.917483 -17.896605) (xy 4.885984 -17.771366)
			(xy 4.862255 -17.644425) (xy 4.846385 -17.516265) (xy 4.838435 -17.38737) (xy 0.509016 -17.38737)
			(xy 0.509016 -24.482675) (xy 40.239076 -24.482675) (xy 40.239076 -24.428125) (xy 40.246839 -24.374131)
			(xy 40.262209 -24.321791) (xy 40.284871 -24.272172) (xy 40.314365 -24.226283) (xy 40.350089 -24.185059)
			(xy 40.391317 -24.149339) (xy 40.437209 -24.119851) (xy 40.486831 -24.097194) (xy 40.539172 -24.08183)
			(xy 40.593167 -24.074073) (xy 40.620442 -24.073612) (xy 41.509442 -24.073612) (xy 41.536708 -24.074153)
			(xy 41.590683 -24.081919) (xy 41.643004 -24.097287) (xy 41.692605 -24.119944) (xy 41.738478 -24.149429)
			(xy 41.779688 -24.185142) (xy 41.815396 -24.226356) (xy 41.844876 -24.272232) (xy 41.867528 -24.321836)
			(xy 41.88289 -24.374158) (xy 41.89065 -24.428134) (xy 41.89065 -24.482666) (xy 41.890649 -24.482675)
			(xy 42.632776 -24.482675) (xy 42.632776 -24.428125) (xy 42.640539 -24.374132) (xy 42.655909 -24.321792)
			(xy 42.67857 -24.272173) (xy 42.708064 -24.226285) (xy 42.743788 -24.185061) (xy 42.785015 -24.149341)
			(xy 42.830907 -24.119852) (xy 42.880528 -24.097195) (xy 42.932869 -24.081831) (xy 42.986863 -24.074073)
			(xy 43.014138 -24.073612) (xy 43.903138 -24.073612) (xy 43.930404 -24.074153) (xy 43.98438 -24.081918)
			(xy 44.036701 -24.097286) (xy 44.086303 -24.119943) (xy 44.132176 -24.149428) (xy 44.173386 -24.185141)
			(xy 44.209095 -24.226354) (xy 44.238575 -24.27223) (xy 44.261227 -24.321835) (xy 44.27659 -24.374158)
			(xy 44.28435 -24.428134) (xy 44.28435 -24.482666) (xy 44.27659 -24.536642) (xy 44.261227 -24.588965)
			(xy 44.238575 -24.63857) (xy 44.209095 -24.684446) (xy 44.173386 -24.725659) (xy 44.132176 -24.761372)
			(xy 44.086303 -24.790857) (xy 44.036701 -24.813514) (xy 43.98438 -24.828882) (xy 43.930404 -24.836647)
			(xy 43.903138 -24.837136) (xy 43.014138 -24.837136) (xy 42.986863 -24.836727) (xy 42.932869 -24.828969)
			(xy 42.880528 -24.813605) (xy 42.830907 -24.790948) (xy 42.785015 -24.761459) (xy 42.743788 -24.725739)
			(xy 42.708064 -24.684515) (xy 42.67857 -24.638627) (xy 42.655909 -24.589008) (xy 42.640539 -24.536668)
			(xy 42.632776 -24.482675) (xy 41.890649 -24.482675) (xy 41.88289 -24.536642) (xy 41.867528 -24.588964)
			(xy 41.844876 -24.638568) (xy 41.815396 -24.684444) (xy 41.779688 -24.725658) (xy 41.738478 -24.761371)
			(xy 41.692605 -24.790856) (xy 41.643004 -24.813513) (xy 41.590683 -24.828881) (xy 41.536708 -24.836647)
			(xy 41.509442 -24.837136) (xy 40.620442 -24.837136) (xy 40.593167 -24.836727) (xy 40.539172 -24.82897)
			(xy 40.486831 -24.813606) (xy 40.437209 -24.790949) (xy 40.391317 -24.761461) (xy 40.350089 -24.725741)
			(xy 40.314365 -24.684517) (xy 40.284871 -24.638628) (xy 40.262209 -24.589009) (xy 40.246839 -24.536669)
			(xy 40.239076 -24.482675) (xy 0.509016 -24.482675) (xy 0.509016 -26.898451) (xy 62.226946 -26.898451)
			(xy 62.226946 -26.843949) (xy 62.234702 -26.790001) (xy 62.250056 -26.737705) (xy 62.272695 -26.688127)
			(xy 62.302159 -26.642275) (xy 62.337849 -26.601083) (xy 62.379037 -26.565388) (xy 62.424885 -26.535918)
			(xy 62.47446 -26.513272) (xy 62.526754 -26.497912) (xy 62.580701 -26.490149) (xy 62.607952 -26.48966)
			(xy 63.496952 -26.48966) (xy 63.524205 -26.490184) (xy 63.578156 -26.497935) (xy 63.630456 -26.513285)
			(xy 63.680038 -26.535923) (xy 63.725893 -26.565387) (xy 63.767088 -26.601078) (xy 63.802784 -26.642269)
			(xy 63.832254 -26.68812) (xy 63.854898 -26.737699) (xy 63.870255 -26.789997) (xy 63.878013 -26.843947)
			(xy 63.878013 -26.898453) (xy 63.870255 -26.952403) (xy 63.863218 -26.976368) (xy 64.442847 -26.976368)
			(xy 64.442847 -26.921832) (xy 64.450609 -26.867852) (xy 64.465973 -26.815525) (xy 64.488628 -26.765918)
			(xy 64.518112 -26.72004) (xy 64.553826 -26.678824) (xy 64.595041 -26.643111) (xy 64.64092 -26.613627)
			(xy 64.690527 -26.590972) (xy 64.742854 -26.575608) (xy 64.796834 -26.567847) (xy 64.824102 -26.567384)
			(xy 65.713102 -26.567384) (xy 65.740375 -26.567779) (xy 65.794364 -26.575542) (xy 65.8467 -26.590909)
			(xy 65.896316 -26.613568) (xy 65.942202 -26.643057) (xy 65.983424 -26.678777) (xy 66.019144 -26.72)
			(xy 66.048633 -26.765886) (xy 66.071292 -26.815502) (xy 66.086659 -26.867838) (xy 66.094421 -26.921827)
			(xy 66.094421 -26.976373) (xy 66.086659 -27.030362) (xy 66.071292 -27.082698) (xy 66.048633 -27.132314)
			(xy 66.019144 -27.1782) (xy 65.983424 -27.219423) (xy 65.942202 -27.255143) (xy 65.896316 -27.284632)
			(xy 65.8467 -27.307291) (xy 65.794364 -27.322658) (xy 65.740375 -27.330421) (xy 65.713102 -27.330908)
			(xy 64.824102 -27.330908) (xy 64.796834 -27.330353) (xy 64.742854 -27.322592) (xy 64.690527 -27.307228)
			(xy 64.64092 -27.284573) (xy 64.595041 -27.255089) (xy 64.553826 -27.219376) (xy 64.518112 -27.17816)
			(xy 64.488628 -27.132282) (xy 64.465973 -27.082675) (xy 64.450609 -27.030348) (xy 64.442847 -26.976368)
			(xy 63.863218 -26.976368) (xy 63.854898 -27.004701) (xy 63.832254 -27.05428) (xy 63.802784 -27.100131)
			(xy 63.767088 -27.141322) (xy 63.725893 -27.177013) (xy 63.680038 -27.206477) (xy 63.630456 -27.229115)
			(xy 63.578156 -27.244465) (xy 63.524205 -27.252216) (xy 63.496952 -27.252676) (xy 62.607952 -27.252676)
			(xy 62.580701 -27.252251) (xy 62.526754 -27.244488) (xy 62.47446 -27.229128) (xy 62.424885 -27.206482)
			(xy 62.379037 -27.177012) (xy 62.337849 -27.141317) (xy 62.302159 -27.100125) (xy 62.272695 -27.054273)
			(xy 62.250056 -27.004695) (xy 62.234702 -26.952399) (xy 62.226946 -26.898451) (xy 0.509016 -26.898451)
			(xy 0.509016 -48.189134) (xy 23.749 -48.189134) (xy 23.749 -46.588934) (xy 23.749498 -46.511651)
			(xy 23.757454 -46.357291) (xy 23.773347 -46.203545) (xy 23.797133 -46.050821) (xy 23.82875 -45.899525)
			(xy 23.868113 -45.750056) (xy 23.915118 -45.602812) (xy 23.969642 -45.458182) (xy 24.031538 -45.316552)
			(xy 24.100643 -45.178295) (xy 24.176774 -45.04378) (xy 24.259728 -44.913361) (xy 24.349287 -44.787386)
			(xy 24.445211 -44.666189) (xy 24.547248 -44.55009) (xy 24.655125 -44.439398) (xy 24.768558 -44.334406)
			(xy 24.887246 -44.235393) (xy 25.010873 -44.14262) (xy 25.139112 -44.056335) (xy 25.271623 -43.976766)
			(xy 25.408055 -43.904124) (xy 25.548045 -43.838602) (xy 25.691222 -43.780373) (xy 25.837207 -43.729592)
			(xy 25.985613 -43.686393) (xy 26.136045 -43.650891) (xy 26.288106 -43.623181) (xy 26.441392 -43.603335)
			(xy 26.595496 -43.591406) (xy 26.75001 -43.587427) (xy 26.904524 -43.591406) (xy 27.058628 -43.603335)
			(xy 27.211914 -43.623181) (xy 27.363975 -43.650891) (xy 27.514407 -43.686393) (xy 27.662813 -43.729592)
			(xy 27.808798 -43.780373) (xy 27.951975 -43.838602) (xy 28.091965 -43.904124) (xy 28.228397 -43.976766)
			(xy 28.360908 -44.056335) (xy 28.489147 -44.14262) (xy 28.612774 -44.235393) (xy 28.731462 -44.334406)
			(xy 28.844895 -44.439398) (xy 28.952772 -44.55009) (xy 29.054809 -44.666189) (xy 29.150733 -44.787386)
			(xy 29.240292 -44.913361) (xy 29.252254 -44.932168) (xy 66.731138 -44.932168) (xy 66.731138 -44.877632)
			(xy 66.738899 -44.823652) (xy 66.754264 -44.771325) (xy 66.776918 -44.721717) (xy 66.806402 -44.675839)
			(xy 66.842114 -44.634623) (xy 66.883329 -44.598909) (xy 66.929207 -44.569424) (xy 66.978814 -44.546768)
			(xy 67.03114 -44.531402) (xy 67.08512 -44.523639) (xy 67.112388 -44.523152) (xy 68.001388 -44.523152)
			(xy 68.028661 -44.523587) (xy 68.082651 -44.531348) (xy 68.134987 -44.546714) (xy 68.184603 -44.569371)
			(xy 68.23049 -44.59886) (xy 68.271713 -44.634578) (xy 68.307433 -44.6758) (xy 68.336923 -44.721686)
			(xy 68.359582 -44.771302) (xy 68.37495 -44.823638) (xy 68.382712 -44.877627) (xy 68.382712 -44.932173)
			(xy 68.37495 -44.986162) (xy 68.359582 -45.038498) (xy 68.336923 -45.088114) (xy 68.307433 -45.134)
			(xy 68.271713 -45.175222) (xy 68.23049 -45.21094) (xy 68.184603 -45.240429) (xy 68.134987 -45.263086)
			(xy 68.082651 -45.278452) (xy 68.028661 -45.286213) (xy 68.001388 -45.286676) (xy 67.112388 -45.286676)
			(xy 67.08512 -45.286161) (xy 67.03114 -45.278398) (xy 66.978814 -45.263032) (xy 66.929207 -45.240376)
			(xy 66.883329 -45.210891) (xy 66.842114 -45.175177) (xy 66.806402 -45.133961) (xy 66.776918 -45.088083)
			(xy 66.754264 -45.038475) (xy 66.738899 -44.986148) (xy 66.731138 -44.932168) (xy 29.252254 -44.932168)
			(xy 29.323246 -45.04378) (xy 29.399377 -45.178295) (xy 29.468482 -45.316552) (xy 29.530378 -45.458182)
			(xy 29.584902 -45.602812) (xy 29.631907 -45.750056) (xy 29.67127 -45.899525) (xy 29.702887 -46.050821)
			(xy 29.726673 -46.203545) (xy 29.742566 -46.357291) (xy 29.750522 -46.511651) (xy 29.75102 -46.588934)
			(xy 29.75102 -48.189134) (xy 29.750522 -48.266417) (xy 29.742566 -48.420777) (xy 29.726673 -48.574523)
			(xy 29.702887 -48.727247) (xy 29.67127 -48.878543) (xy 29.631907 -49.028012) (xy 29.584902 -49.175256)
			(xy 29.530378 -49.319886) (xy 29.468482 -49.461516) (xy 29.399377 -49.599773) (xy 29.323246 -49.734288)
			(xy 29.240292 -49.864707) (xy 29.150733 -49.990682) (xy 29.054809 -50.111879) (xy 28.952772 -50.227978)
			(xy 28.844895 -50.33867) (xy 28.731462 -50.443662) (xy 28.612774 -50.542675) (xy 28.489147 -50.635448)
			(xy 28.360908 -50.721733) (xy 28.228397 -50.801302) (xy 28.091965 -50.873944) (xy 27.951975 -50.939466)
			(xy 27.808798 -50.997695) (xy 27.662813 -51.048476) (xy 27.514407 -51.091675) (xy 27.363975 -51.127177)
			(xy 27.211914 -51.154887) (xy 27.058628 -51.174733) (xy 26.904524 -51.186662) (xy 26.75001 -51.190642)
			(xy 26.595496 -51.186662) (xy 26.441392 -51.174733) (xy 26.288106 -51.154887) (xy 26.136045 -51.127177)
			(xy 25.985613 -51.091675) (xy 25.837207 -51.048476) (xy 25.691222 -50.997695) (xy 25.548045 -50.939466)
			(xy 25.408055 -50.873944) (xy 25.271623 -50.801302) (xy 25.139112 -50.721733) (xy 25.010873 -50.635448)
			(xy 24.887246 -50.542675) (xy 24.768558 -50.443662) (xy 24.655125 -50.33867) (xy 24.547248 -50.227978)
			(xy 24.445211 -50.111879) (xy 24.349287 -49.990682) (xy 24.259728 -49.864707) (xy 24.176774 -49.734288)
			(xy 24.100643 -49.599773) (xy 24.031538 -49.461516) (xy 23.969642 -49.319886) (xy 23.915118 -49.175256)
			(xy 23.868113 -49.028012) (xy 23.82875 -48.878543) (xy 23.797133 -48.727247) (xy 23.773347 -48.574523)
			(xy 23.757454 -48.420777) (xy 23.749498 -48.266417) (xy 23.749 -48.189134) (xy 0.509016 -48.189134)
			(xy 0.509016 -52.67175) (xy 66.314303 -52.67175) (xy 66.314303 -52.61725) (xy 66.32206 -52.563304)
			(xy 66.337415 -52.511011) (xy 66.360056 -52.461436) (xy 66.389522 -52.415587) (xy 66.425214 -52.374399)
			(xy 66.466403 -52.33871) (xy 66.512253 -52.309246) (xy 66.56183 -52.286608) (xy 66.614123 -52.271256)
			(xy 66.66807 -52.263502) (xy 66.69532 -52.26304) (xy 67.58432 -52.26304) (xy 67.611574 -52.263431)
			(xy 67.665526 -52.271191) (xy 67.717825 -52.28655) (xy 67.767406 -52.309195) (xy 67.81326 -52.338666)
			(xy 67.854453 -52.374362) (xy 67.890146 -52.415556) (xy 67.919615 -52.461412) (xy 67.942257 -52.510994)
			(xy 67.957613 -52.563293) (xy 67.96537 -52.617246) (xy 67.96537 -52.671754) (xy 67.957613 -52.725707)
			(xy 67.942257 -52.778006) (xy 67.919615 -52.827588) (xy 67.890146 -52.873444) (xy 67.854453 -52.914638)
			(xy 67.81326 -52.950334) (xy 67.767406 -52.979805) (xy 67.717825 -53.00245) (xy 67.665526 -53.017809)
			(xy 67.611574 -53.025569) (xy 67.58432 -53.026056) (xy 66.69532 -53.026056) (xy 66.66807 -53.025498)
			(xy 66.614123 -53.017744) (xy 66.56183 -53.002392) (xy 66.512253 -52.979754) (xy 66.466403 -52.95029)
			(xy 66.425214 -52.914601) (xy 66.389522 -52.873413) (xy 66.360056 -52.827564) (xy 66.337415 -52.777989)
			(xy 66.32206 -52.725696) (xy 66.314303 -52.67175) (xy 0.509016 -52.67175) (xy 0.509016 -54.53387)
			(xy 66.568023 -54.53387) (xy 66.568023 -54.47933) (xy 66.575786 -54.425344) (xy 66.591152 -54.373013)
			(xy 66.61381 -54.323401) (xy 66.643298 -54.277519) (xy 66.679015 -54.236301) (xy 66.720235 -54.200586)
			(xy 66.766119 -54.1711) (xy 66.815732 -54.148445) (xy 66.868064 -54.133081) (xy 66.92205 -54.125322)
			(xy 66.94932 -54.12486) (xy 67.83832 -54.12486) (xy 67.86559 -54.125304) (xy 67.919575 -54.133068)
			(xy 67.971905 -54.148436) (xy 68.021515 -54.171095) (xy 68.067396 -54.200583) (xy 68.108614 -54.2363)
			(xy 68.144329 -54.27752) (xy 68.173815 -54.323402) (xy 68.196471 -54.373014) (xy 68.211836 -54.425345)
			(xy 68.219598 -54.47933) (xy 68.219598 -54.53387) (xy 68.211836 -54.587855) (xy 68.196471 -54.640186)
			(xy 68.173815 -54.689798) (xy 68.144329 -54.73568) (xy 68.108614 -54.7769) (xy 68.067396 -54.812617)
			(xy 68.021515 -54.842105) (xy 67.971905 -54.864764) (xy 67.919575 -54.880132) (xy 67.86559 -54.887896)
			(xy 67.83832 -54.888384) (xy 66.94932 -54.888384) (xy 66.92205 -54.887878) (xy 66.868064 -54.880119)
			(xy 66.815732 -54.864755) (xy 66.766119 -54.8421) (xy 66.720235 -54.812614) (xy 66.679015 -54.776899)
			(xy 66.643298 -54.735681) (xy 66.61381 -54.689799) (xy 66.591152 -54.640187) (xy 66.575786 -54.587856)
			(xy 66.568023 -54.53387) (xy 0.509016 -54.53387) (xy 0.509016 -58.166508) (xy 60.959492 -58.166508)
			(xy 60.959492 -57.366662) (xy 60.959966 -57.340674) (xy 60.968103 -57.289338) (xy 60.984169 -57.239907)
			(xy 61.007769 -57.193597) (xy 61.038323 -57.15155) (xy 61.075078 -57.114799) (xy 61.11713 -57.08425)
			(xy 61.163442 -57.060654) (xy 61.212875 -57.044594) (xy 61.264212 -57.036464) (xy 61.2902 -57.035954)
			(xy 61.317668 -57.036479) (xy 61.371851 -57.04555) (xy 61.423791 -57.063444) (xy 61.472065 -57.089668)
			(xy 61.515345 -57.123503) (xy 61.534294 -57.143396) (xy 61.55212 -57.162087) (xy 61.582322 -57.203984)
			(xy 61.605643 -57.250068) (xy 61.621515 -57.299217) (xy 61.629551 -57.350236) (xy 61.630052 -57.37606)
			(xy 61.629773 -57.39555) (xy 61.625189 -57.43426) (xy 61.620908 -57.453276) (xy 61.620908 -58.166508)
			(xy 61.620398 -58.192491) (xy 63.359983 -58.192491) (xy 63.359983 -58.140509) (xy 63.368116 -58.089167)
			(xy 63.38418 -58.03973) (xy 63.407782 -57.993415) (xy 63.438338 -57.951362) (xy 63.475097 -57.914608)
			(xy 63.517154 -57.884058) (xy 63.563473 -57.860463) (xy 63.612912 -57.844405) (xy 63.664255 -57.83628)
			(xy 63.690246 -57.8358) (xy 64.490092 -57.8358) (xy 64.516082 -57.836267) (xy 64.567423 -57.844397)
			(xy 64.61686 -57.860459) (xy 64.663175 -57.884057) (xy 64.705229 -57.91461) (xy 64.741985 -57.951365)
			(xy 64.772539 -57.993418) (xy 64.796138 -58.039733) (xy 64.812201 -58.089169) (xy 64.820333 -58.14051)
			(xy 64.820333 -58.19249) (xy 64.812201 -58.243831) (xy 64.796138 -58.293267) (xy 64.772539 -58.339582)
			(xy 64.741985 -58.381635) (xy 64.705229 -58.41839) (xy 64.663175 -58.448943) (xy 64.61686 -58.472541)
			(xy 64.567423 -58.488603) (xy 64.516082 -58.496733) (xy 64.490092 -58.497216) (xy 63.690246 -58.497216)
			(xy 63.664255 -58.49672) (xy 63.612912 -58.488595) (xy 63.563473 -58.472537) (xy 63.517154 -58.448942)
			(xy 63.475097 -58.418392) (xy 63.438338 -58.381638) (xy 63.407782 -58.339585) (xy 63.38418 -58.29327)
			(xy 63.368116 -58.243833) (xy 63.359983 -58.192491) (xy 61.620398 -58.192491) (xy 61.620398 -58.192495)
			(xy 61.612268 -58.24383) (xy 61.596207 -58.29326) (xy 61.572611 -58.33957) (xy 61.542061 -58.381618)
			(xy 61.50531 -58.418369) (xy 61.463262 -58.448919) (xy 61.416952 -58.472515) (xy 61.367522 -58.488576)
			(xy 61.316187 -58.496706) (xy 61.264213 -58.496706) (xy 61.212878 -58.488576) (xy 61.163448 -58.472515)
			(xy 61.117138 -58.448919) (xy 61.07509 -58.418369) (xy 61.038339 -58.381618) (xy 61.007789 -58.33957)
			(xy 60.984193 -58.29326) (xy 60.968132 -58.24383) (xy 60.960002 -58.192495) (xy 60.959492 -58.166508)
			(xy 0.509016 -58.166508) (xy 0.509016 -58.992411) (xy 61.759802 -58.992411) (xy 61.759802 -58.940389)
			(xy 61.76794 -58.889008) (xy 61.784015 -58.839533) (xy 61.807633 -58.793181) (xy 61.83821 -58.751095)
			(xy 61.874995 -58.71431) (xy 61.917081 -58.683733) (xy 61.963433 -58.660115) (xy 62.012908 -58.64404)
			(xy 62.064289 -58.635902) (xy 62.0903 -58.635392) (xy 62.890146 -58.635392) (xy 62.916147 -58.635998)
			(xy 62.967508 -58.644139) (xy 63.016964 -58.660214) (xy 63.063296 -58.683827) (xy 63.105364 -58.714397)
			(xy 63.142133 -58.751171) (xy 63.172697 -58.793243) (xy 63.196303 -58.839579) (xy 63.212372 -58.889036)
			(xy 63.220506 -58.940399) (xy 63.220506 -58.992401) (xy 63.220505 -58.99241) (xy 64.159602 -58.99241)
			(xy 64.159602 -58.94039) (xy 64.16774 -58.889009) (xy 64.183815 -58.839535) (xy 64.207431 -58.793184)
			(xy 64.238008 -58.751098) (xy 64.274792 -58.714313) (xy 64.316877 -58.683735) (xy 64.363227 -58.660118)
			(xy 64.412702 -58.644042) (xy 64.464082 -58.635903) (xy 64.490092 -58.635392) (xy 65.289938 -58.635392)
			(xy 65.31594 -58.635997) (xy 65.367302 -58.644137) (xy 65.416758 -58.660212) (xy 65.463091 -58.683825)
			(xy 65.505161 -58.714394) (xy 65.541931 -58.751168) (xy 65.572495 -58.793241) (xy 65.596103 -58.839577)
			(xy 65.612171 -58.889035) (xy 65.620306 -58.940398) (xy 65.620306 -58.992402) (xy 65.612171 -59.043765)
			(xy 65.596103 -59.093223) (xy 65.572495 -59.139559) (xy 65.541931 -59.181632) (xy 65.505161 -59.218406)
			(xy 65.463091 -59.248975) (xy 65.416758 -59.272588) (xy 65.367302 -59.288663) (xy 65.31594 -59.296803)
			(xy 65.289938 -59.297316) (xy 64.490092 -59.297316) (xy 64.464082 -59.296897) (xy 64.412702 -59.288758)
			(xy 64.363227 -59.272682) (xy 64.316877 -59.249065) (xy 64.274792 -59.218487) (xy 64.238008 -59.181702)
			(xy 64.207431 -59.139616) (xy 64.183815 -59.093265) (xy 64.16774 -59.043791) (xy 64.159602 -58.99241)
			(xy 63.220505 -58.99241) (xy 63.212372 -59.043763) (xy 63.196303 -59.093221) (xy 63.172697 -59.139557)
			(xy 63.142133 -59.181629) (xy 63.105364 -59.218403) (xy 63.063296 -59.248973) (xy 63.016964 -59.272586)
			(xy 62.967508 -59.288661) (xy 62.916147 -59.296802) (xy 62.890146 -59.297316) (xy 62.0903 -59.297316)
			(xy 62.064289 -59.296898) (xy 62.012908 -59.28876) (xy 61.963433 -59.272685) (xy 61.917081 -59.249067)
			(xy 61.874995 -59.21849) (xy 61.83821 -59.181705) (xy 61.807633 -59.139619) (xy 61.784015 -59.093267)
			(xy 61.76794 -59.043792) (xy 61.759802 -58.992411) (xy 0.509016 -58.992411) (xy 0.509016 -59.792515)
			(xy 63.359676 -59.792515) (xy 63.359676 -59.740485) (xy 63.367816 -59.689095) (xy 63.383895 -59.639612)
			(xy 63.407519 -59.593254) (xy 63.438104 -59.551162) (xy 63.474897 -59.514374) (xy 63.516993 -59.483794)
			(xy 63.563355 -59.460178) (xy 63.61284 -59.444105) (xy 63.664231 -59.435972) (xy 63.690246 -59.435492)
			(xy 64.490092 -59.435492) (xy 64.516098 -59.436067) (xy 64.56747 -59.444202) (xy 64.616937 -59.460274)
			(xy 64.66328 -59.483886) (xy 64.705359 -59.514457) (xy 64.742138 -59.551235) (xy 64.77271 -59.593313)
			(xy 64.796323 -59.639656) (xy 64.812396 -59.689122) (xy 64.820533 -59.740494) (xy 64.820533 -59.792506)
			(xy 64.812396 -59.843878) (xy 64.796323 -59.893344) (xy 64.77271 -59.939687) (xy 64.742138 -59.981765)
			(xy 64.705359 -60.018543) (xy 64.66328 -60.049114) (xy 64.616937 -60.072726) (xy 64.56747 -60.088798)
			(xy 64.516098 -60.096933) (xy 64.490092 -60.097416) (xy 63.690246 -60.097416) (xy 63.664231 -60.097028)
			(xy 63.61284 -60.088895) (xy 63.563355 -60.072822) (xy 63.516993 -60.049206) (xy 63.474897 -60.018626)
			(xy 63.438104 -59.981838) (xy 63.407519 -59.939746) (xy 63.383895 -59.893388) (xy 63.367816 -59.843905)
			(xy 63.359676 -59.792515) (xy 0.509016 -59.792515) (xy 0.509016 -60.3494) (xy 60.569868 -60.3494)
			(xy 60.573857 -60.296174) (xy 60.585733 -60.244137) (xy 60.605233 -60.194451) (xy 60.631919 -60.148227)
			(xy 60.665197 -60.106496) (xy 60.704323 -60.07019) (xy 60.748422 -60.040121) (xy 60.796511 -60.016961)
			(xy 60.847514 -60.001226) (xy 60.900292 -59.993268) (xy 60.92698 -59.992768) (xy 60.949767 -59.993141)
			(xy 60.994967 -59.998968) (xy 61.03906 -60.010491) (xy 61.06033 -60.018676) (xy 61.555376 -60.018676)
			(xy 61.564012 -60.015374) (xy 61.594178 -60.00485) (xy 61.657039 -59.993478) (xy 61.68898 -59.992768)
			(xy 61.717333 -59.993267) (xy 61.773326 -60.002234) (xy 61.827196 -60.019945) (xy 61.877586 -60.045954)
			(xy 61.923227 -60.079606) (xy 61.943488 -60.099448) (xy 61.962622 -60.116719) (xy 61.995857 -60.156112)
			(xy 62.022581 -60.200183) (xy 62.042146 -60.247865) (xy 62.054078 -60.298005) (xy 62.058089 -60.34939)
			(xy 62.054081 -60.400774) (xy 62.042152 -60.450915) (xy 62.022591 -60.498599) (xy 61.99587 -60.542671)
			(xy 61.962636 -60.582066) (xy 61.943488 -60.59932) (xy 61.923242 -60.619175) (xy 61.877589 -60.652806)
			(xy 61.827194 -60.678797) (xy 61.773323 -60.696496) (xy 61.717332 -60.705456) (xy 61.68898 -60.706)
			(xy 61.657039 -60.705289) (xy 61.594177 -60.693921) (xy 61.564012 -60.683394) (xy 61.555376 -60.680092)
			(xy 61.06033 -60.680092) (xy 61.039069 -60.688303) (xy 60.994975 -60.699837) (xy 60.949769 -60.705644)
			(xy 60.92698 -60.706) (xy 60.900292 -60.705532) (xy 60.847514 -60.697574) (xy 60.796511 -60.681839)
			(xy 60.748422 -60.658679) (xy 60.704323 -60.62861) (xy 60.665197 -60.592304) (xy 60.631919 -60.550573)
			(xy 60.605233 -60.504349) (xy 60.585733 -60.454663) (xy 60.573857 -60.402626) (xy 60.569868 -60.3494)
			(xy 0.509016 -60.3494) (xy 0.509016 -61.539628) (xy 0.508 -61.540644) (xy 0.508 -61.596524) (xy 61.326776 -61.596524)
			(xy 61.326776 -61.455808) (xy 61.327185 -61.442722) (xy 61.333989 -61.417449) (xy 61.347132 -61.394815)
			(xy 61.365708 -61.376377) (xy 61.38844 -61.363405) (xy 61.413763 -61.35679) (xy 61.426852 -61.356494)
			(xy 61.427106 -61.356748) (xy 61.727334 -61.356748) (xy 61.727588 -61.356494) (xy 61.74068 -61.35674)
			(xy 61.766009 -61.363365) (xy 61.788744 -61.376347) (xy 61.807322 -61.394794) (xy 61.820466 -61.417437)
			(xy 61.82727 -61.442718) (xy 61.827664 -61.455808) (xy 61.827664 -61.596524) (xy 62.342776 -61.596524)
			(xy 62.342776 -61.455808) (xy 62.343185 -61.442722) (xy 62.349989 -61.417449) (xy 62.363132 -61.394815)
			(xy 62.381708 -61.376377) (xy 62.40444 -61.363405) (xy 62.429763 -61.35679) (xy 62.442852 -61.356494)
			(xy 62.443106 -61.356748) (xy 62.743334 -61.356748) (xy 62.743588 -61.356494) (xy 62.75668 -61.35674)
			(xy 62.782009 -61.363365) (xy 62.804744 -61.376347) (xy 62.823322 -61.394794) (xy 62.836466 -61.417437)
			(xy 62.84327 -61.442718) (xy 62.843664 -61.455808) (xy 62.843664 -61.596524) (xy 62.78372 -61.596524)
			(xy 62.78372 -61.8617) (xy 62.40272 -61.8617) (xy 62.40272 -61.596524) (xy 62.342776 -61.596524)
			(xy 61.827664 -61.596524) (xy 61.76772 -61.596524) (xy 61.76772 -61.8617) (xy 61.38672 -61.8617)
			(xy 61.38672 -61.596524) (xy 61.326776 -61.596524) (xy 0.508 -61.596524) (xy 0.508 -62.516004) (xy 61.326776 -62.516004)
			(xy 61.326776 -62.375288) (xy 61.38672 -62.375288) (xy 61.38672 -62.110112) (xy 61.76772 -62.110112)
			(xy 61.76772 -62.375288) (xy 61.827664 -62.375288) (xy 61.827664 -62.516004) (xy 62.342776 -62.516004)
			(xy 62.342776 -62.375288) (xy 62.40272 -62.375288) (xy 62.40272 -62.110112) (xy 62.78372 -62.110112)
			(xy 62.78372 -62.375288) (xy 62.843664 -62.375288) (xy 62.843664 -62.516004) (xy 62.843325 -62.529096)
			(xy 62.836513 -62.554378) (xy 62.823359 -62.577018) (xy 62.804768 -62.595457) (xy 62.78202 -62.608425)
			(xy 62.756683 -62.615029) (xy 62.743588 -62.615318) (xy 62.743334 -62.615064) (xy 62.443106 -62.615064)
			(xy 62.442852 -62.615318) (xy 62.429762 -62.615025) (xy 62.404437 -62.608411) (xy 62.381703 -62.595438)
			(xy 62.363124 -62.577) (xy 62.349979 -62.554366) (xy 62.343171 -62.529091) (xy 62.342776 -62.516004)
			(xy 61.827664 -62.516004) (xy 61.827325 -62.529096) (xy 61.820513 -62.554378) (xy 61.807359 -62.577018)
			(xy 61.788768 -62.595457) (xy 61.76602 -62.608425) (xy 61.740683 -62.615029) (xy 61.727588 -62.615318)
			(xy 61.727334 -62.615064) (xy 61.427106 -62.615064) (xy 61.426852 -62.615318) (xy 61.413762 -62.615025)
			(xy 61.388437 -62.608411) (xy 61.365703 -62.595438) (xy 61.347124 -62.577) (xy 61.333979 -62.554366)
			(xy 61.327171 -62.529091) (xy 61.326776 -62.516004) (xy 0.508 -62.516004) (xy 0.508 -62.988444) (xy 0.509016 -62.98946)
			(xy 0.509016 -75.635104) (xy 15.732516 -75.635104) (xy 15.736498 -75.545176) (xy 15.748412 -75.455952)
			(xy 15.768165 -75.36813) (xy 15.795602 -75.282397) (xy 15.830509 -75.199425) (xy 15.872613 -75.119862)
			(xy 15.921583 -75.044332) (xy 15.977038 -74.973426) (xy 16.038542 -74.907698) (xy 16.105614 -74.847663)
			(xy 16.17773 -74.793791) (xy 16.254325 -74.746503) (xy 16.334799 -74.70617) (xy 16.418523 -74.673107)
			(xy 16.504842 -74.647573) (xy 16.59308 -74.629768) (xy 16.682545 -74.61983) (xy 16.77254 -74.617839)
			(xy 16.862357 -74.623809) (xy 16.951296 -74.637694) (xy 17.03866 -74.659385) (xy 17.123765 -74.688712)
			(xy 17.205944 -74.725446) (xy 17.284556 -74.7693) (xy 17.358984 -74.819929) (xy 17.428646 -74.876939)
			(xy 17.492997 -74.939882) (xy 17.551534 -75.008266) (xy 17.603797 -75.081556) (xy 17.649379 -75.159178)
			(xy 17.687922 -75.240525) (xy 17.719125 -75.32496) (xy 17.742743 -75.411822) (xy 17.758592 -75.500432)
			(xy 17.766548 -75.590096) (xy 17.767046 -75.635104) (xy 35.491176 -75.635104) (xy 35.495155 -75.535091)
			(xy 35.507068 -75.43571) (xy 35.526839 -75.33759) (xy 35.554343 -75.241351) (xy 35.589406 -75.147602)
			(xy 35.631807 -75.056934) (xy 35.681278 -74.969922) (xy 35.737505 -74.887115) (xy 35.800133 -74.809038)
			(xy 35.868767 -74.736183) (xy 35.942972 -74.669011) (xy 36.02228 -74.607948) (xy 36.106188 -74.553378)
			(xy 36.194166 -74.505647) (xy 36.285659 -74.465057) (xy 36.380087 -74.431865) (xy 36.476854 -74.40628)
			(xy 36.575348 -74.388463) (xy 36.674946 -74.378529) (xy 36.775018 -74.376539) (xy 36.874932 -74.382506)
			(xy 36.974056 -74.396392) (xy 37.071764 -74.41811) (xy 37.167437 -74.447522) (xy 37.260471 -74.484443)
			(xy 37.350277 -74.528638) (xy 37.436289 -74.579828) (xy 37.517961 -74.637691) (xy 37.594778 -74.701859)
			(xy 37.666254 -74.771928) (xy 37.731937 -74.847454) (xy 37.791412 -74.92796) (xy 37.844303 -75.012936)
			(xy 37.890275 -75.101846) (xy 37.929037 -75.194128) (xy 37.960346 -75.289197) (xy 37.984002 -75.386454)
			(xy 37.999856 -75.485282) (xy 38.007809 -75.585058) (xy 38.008306 -75.635104) (xy 38.007809 -75.68515)
			(xy 37.999856 -75.784926) (xy 37.984002 -75.883754) (xy 37.960346 -75.981011) (xy 37.929037 -76.07608)
			(xy 37.890275 -76.168362) (xy 37.844303 -76.257272) (xy 37.791412 -76.342248) (xy 37.731937 -76.422754)
			(xy 37.666254 -76.49828) (xy 37.594778 -76.568349) (xy 37.517961 -76.632517) (xy 37.436289 -76.69038)
			(xy 37.350277 -76.74157) (xy 37.260471 -76.785765) (xy 37.167437 -76.822686) (xy 37.071764 -76.852098)
			(xy 36.974056 -76.873816) (xy 36.874932 -76.887702) (xy 36.775018 -76.893669) (xy 36.674946 -76.891679)
			(xy 36.575348 -76.881745) (xy 36.476854 -76.863928) (xy 36.380087 -76.838343) (xy 36.285659 -76.805151)
			(xy 36.194166 -76.764561) (xy 36.106188 -76.71683) (xy 36.02228 -76.66226) (xy 35.942972 -76.601197)
			(xy 35.868767 -76.534025) (xy 35.800133 -76.46117) (xy 35.737505 -76.383093) (xy 35.681278 -76.300286)
			(xy 35.631807 -76.213274) (xy 35.589406 -76.122606) (xy 35.554343 -76.028857) (xy 35.526839 -75.932618)
			(xy 35.507068 -75.834498) (xy 35.495155 -75.735117) (xy 35.491176 -75.635104) (xy 17.767046 -75.635104)
			(xy 17.766548 -75.680112) (xy 17.758592 -75.769776) (xy 17.742743 -75.858386) (xy 17.719125 -75.945248)
			(xy 17.687922 -76.029683) (xy 17.649379 -76.11103) (xy 17.603797 -76.188652) (xy 17.551534 -76.261942)
			(xy 17.492997 -76.330326) (xy 17.428646 -76.393269) (xy 17.358984 -76.450279) (xy 17.284556 -76.500908)
			(xy 17.205944 -76.544762) (xy 17.123765 -76.581496) (xy 17.03866 -76.610823) (xy 16.951296 -76.632514)
			(xy 16.862357 -76.646399) (xy 16.77254 -76.652369) (xy 16.682545 -76.650378) (xy 16.59308 -76.64044)
			(xy 16.504842 -76.622635) (xy 16.418523 -76.597101) (xy 16.334799 -76.564038) (xy 16.254325 -76.523705)
			(xy 16.17773 -76.476417) (xy 16.105614 -76.422545) (xy 16.038542 -76.36251) (xy 15.977038 -76.296782)
			(xy 15.921583 -76.225876) (xy 15.872613 -76.150346) (xy 15.830509 -76.070783) (xy 15.795602 -75.987811)
			(xy 15.768165 -75.902078) (xy 15.748412 -75.814256) (xy 15.736498 -75.725032) (xy 15.732516 -75.635104)
			(xy 0.509016 -75.635104) (xy 0.509016 -80.990948) (xy 2.249932 -80.990948) (xy 2.293971 -80.991429)
			(xy 2.381714 -80.999105) (xy 2.468454 -81.0144) (xy 2.553531 -81.037196) (xy 2.636297 -81.067321)
			(xy 2.716123 -81.104545) (xy 2.792401 -81.148584) (xy 2.86455 -81.199103) (xy 2.932022 -81.255719)
			(xy 2.994302 -81.318) (xy 3.050918 -81.385471) (xy 3.101437 -81.457621) (xy 3.145476 -81.533899)
			(xy 3.1827 -81.613725) (xy 3.212824 -81.696491) (xy 3.23562 -81.781568) (xy 3.250915 -81.868308)
			(xy 3.258592 -81.956051) (xy 3.259074 -82.00009) (xy 3.259074 -84.499958) (xy 3.258594 -84.543997)
			(xy 3.250917 -84.63174) (xy 3.235623 -84.718481) (xy 3.212827 -84.803558) (xy 3.182702 -84.886325)
			(xy 3.145479 -84.966151) (xy 3.10144 -85.042429) (xy 3.05092 -85.114579) (xy 2.994305 -85.182051)
			(xy 2.932024 -85.244332) (xy 2.864552 -85.300948) (xy 2.792403 -85.351468) (xy 2.716124 -85.395507)
			(xy 2.636298 -85.432731) (xy 2.553532 -85.462855) (xy 2.468455 -85.485652) (xy 2.381714 -85.500947)
			(xy 2.293971 -85.508623) (xy 2.249932 -85.5091) (xy 0.509016 -85.5091) (xy 0.509016 -91.068144) (xy 40.040052 -91.068144)
			(xy 40.31996 -91.068144) (xy 40.539924 -91.068144) (xy 40.819832 -91.068144) (xy 42.040048 -91.068144)
			(xy 42.319956 -91.068144) (xy 42.53992 -91.068144) (xy 42.819828 -91.068144) (xy 42.819828 -91.72956)
			(xy 42.53992 -91.72956) (xy 42.53992 -91.068144) (xy 42.319956 -91.068144) (xy 42.319956 -91.72956)
			(xy 42.040048 -91.72956) (xy 42.040048 -91.068144) (xy 40.819832 -91.068144) (xy 40.819832 -91.72956)
			(xy 40.539924 -91.72956) (xy 40.539924 -91.068144) (xy 40.31996 -91.068144) (xy 40.31996 -91.72956)
			(xy 40.040052 -91.72956) (xy 40.040052 -91.068144) (xy 0.509016 -91.068144) (xy 0.509016 -93.268292)
			(xy 41.539668 -93.268292) (xy 41.820084 -93.268292) (xy 42.040048 -93.268292) (xy 42.319956 -93.268292)
			(xy 42.53992 -93.268292) (xy 42.819828 -93.268292) (xy 43.039792 -93.268292) (xy 43.320208 -93.268292)
			(xy 43.320208 -93.929708) (xy 43.039792 -93.929708) (xy 43.039792 -93.268292) (xy 42.819828 -93.268292)
			(xy 42.819828 -93.929708) (xy 42.53992 -93.929708) (xy 42.53992 -93.268292) (xy 42.319956 -93.268292)
			(xy 42.319956 -93.929708) (xy 42.040048 -93.929708) (xy 42.040048 -93.268292) (xy 41.820084 -93.268292)
			(xy 41.820084 -93.929708) (xy 41.539668 -93.929708) (xy 41.539668 -93.268292) (xy 0.509016 -93.268292)
			(xy 0.509016 -96.435672) (xy 45.088556 -96.435672) (xy 45.088556 -96.294702) (xy 45.08898 -96.281617)
			(xy 45.095784 -96.256347) (xy 45.108924 -96.233715) (xy 45.127497 -96.215278) (xy 45.150225 -96.202304)
			(xy 45.175544 -96.195686) (xy 45.188632 -96.195388) (xy 45.489368 -96.195388) (xy 45.502459 -96.195657)
			(xy 45.527786 -96.202277) (xy 45.550521 -96.215255) (xy 45.569099 -96.233697) (xy 45.582243 -96.256336)
			(xy 45.589049 -96.281613) (xy 45.589444 -96.294702) (xy 45.589444 -96.435672) (xy 46.104556 -96.435672)
			(xy 46.104556 -96.294702) (xy 46.10498 -96.281617) (xy 46.111784 -96.256347) (xy 46.124924 -96.233715)
			(xy 46.143497 -96.215278) (xy 46.166225 -96.202304) (xy 46.191544 -96.195686) (xy 46.204632 -96.195388)
			(xy 46.505368 -96.195388) (xy 46.518459 -96.195657) (xy 46.543786 -96.202277) (xy 46.566521 -96.215255)
			(xy 46.585099 -96.233697) (xy 46.598243 -96.256336) (xy 46.605049 -96.281613) (xy 46.605444 -96.294702)
			(xy 46.605444 -96.435672) (xy 46.5455 -96.435672) (xy 46.5455 -96.70034) (xy 46.1645 -96.70034) (xy 46.1645 -96.435672)
			(xy 46.104556 -96.435672) (xy 45.589444 -96.435672) (xy 45.5295 -96.435672) (xy 45.5295 -96.70034)
			(xy 45.1485 -96.70034) (xy 45.1485 -96.435672) (xy 45.088556 -96.435672) (xy 0.509016 -96.435672)
			(xy 0.509016 -97.354898) (xy 45.088556 -97.354898) (xy 45.088556 -97.213928) (xy 45.1485 -97.213928)
			(xy 45.1485 -96.94926) (xy 45.5295 -96.94926) (xy 45.5295 -97.213928) (xy 45.589444 -97.213928) (xy 45.589444 -97.354898)
			(xy 46.104556 -97.354898) (xy 46.104556 -97.213928) (xy 46.1645 -97.213928) (xy 46.1645 -96.94926)
			(xy 46.5455 -96.94926) (xy 46.5455 -97.213928) (xy 46.605444 -97.213928) (xy 46.605444 -97.354898)
			(xy 46.60502 -97.367983) (xy 46.598216 -97.393253) (xy 46.585076 -97.415885) (xy 46.566503 -97.434322)
			(xy 46.543775 -97.447296) (xy 46.518456 -97.453914) (xy 46.505368 -97.454212) (xy 46.204632 -97.454212)
			(xy 46.191541 -97.453943) (xy 46.166214 -97.447323) (xy 46.143479 -97.434345) (xy 46.124901 -97.415903)
			(xy 46.111757 -97.393264) (xy 46.104951 -97.367987) (xy 46.104556 -97.354898) (xy 45.589444 -97.354898)
			(xy 45.58902 -97.367983) (xy 45.582216 -97.393253) (xy 45.569076 -97.415885) (xy 45.550503 -97.434322)
			(xy 45.527775 -97.447296) (xy 45.502456 -97.453914) (xy 45.489368 -97.454212) (xy 45.188632 -97.454212)
			(xy 45.175541 -97.453943) (xy 45.150214 -97.447323) (xy 45.127479 -97.434345) (xy 45.108901 -97.415903)
			(xy 45.095757 -97.393264) (xy 45.088951 -97.367987) (xy 45.088556 -97.354898) (xy 0.509016 -97.354898)
			(xy 0.509016 -97.978249) (xy 45.046914 -97.978249) (xy 45.046914 -97.923751) (xy 45.05467 -97.869809)
			(xy 45.070024 -97.817519) (xy 45.092663 -97.767947) (xy 45.122126 -97.722101) (xy 45.157814 -97.680914)
			(xy 45.199001 -97.645226) (xy 45.244847 -97.615763) (xy 45.294419 -97.593124) (xy 45.346709 -97.57777)
			(xy 45.400651 -97.570014) (xy 45.4279 -97.569528) (xy 46.3169 -97.569528) (xy 46.344154 -97.569942)
			(xy 46.398107 -97.577699) (xy 46.450406 -97.593056) (xy 46.499988 -97.615699) (xy 46.545843 -97.645168)
			(xy 46.587037 -97.680863) (xy 46.622732 -97.722057) (xy 46.652201 -97.767912) (xy 46.674844 -97.817494)
			(xy 46.690201 -97.869793) (xy 46.697958 -97.923746) (xy 46.697958 -97.978254) (xy 46.690201 -98.032207)
			(xy 46.674844 -98.084506) (xy 46.652201 -98.134088) (xy 46.622732 -98.179943) (xy 46.587037 -98.221137)
			(xy 46.545843 -98.256832) (xy 46.499988 -98.286301) (xy 46.450406 -98.308944) (xy 46.398107 -98.324301)
			(xy 46.344154 -98.332058) (xy 46.3169 -98.332544) (xy 45.4279 -98.332544) (xy 45.400651 -98.331986)
			(xy 45.346709 -98.32423) (xy 45.294419 -98.308876) (xy 45.244847 -98.286237) (xy 45.199001 -98.256774)
			(xy 45.157814 -98.221086) (xy 45.122126 -98.179899) (xy 45.092663 -98.134053) (xy 45.070024 -98.084481)
			(xy 45.05467 -98.032191) (xy 45.046914 -97.978249) (xy 0.509016 -97.978249) (xy 0.509016 -98.410049)
			(xy 40.017714 -98.410049) (xy 40.017714 -98.355551) (xy 40.02547 -98.301609) (xy 40.040824 -98.249319)
			(xy 40.063463 -98.199747) (xy 40.092926 -98.153901) (xy 40.128614 -98.112714) (xy 40.169801 -98.077026)
			(xy 40.215647 -98.047563) (xy 40.265219 -98.024924) (xy 40.317509 -98.00957) (xy 40.371451 -98.001814)
			(xy 40.3987 -98.001328) (xy 41.2877 -98.001328) (xy 41.314954 -98.001742) (xy 41.368907 -98.009499)
			(xy 41.421206 -98.024856) (xy 41.470788 -98.047499) (xy 41.516643 -98.076968) (xy 41.557837 -98.112663)
			(xy 41.593532 -98.153857) (xy 41.623001 -98.199712) (xy 41.645644 -98.249294) (xy 41.661001 -98.301593)
			(xy 41.668758 -98.355546) (xy 41.668758 -98.410054) (xy 41.661001 -98.464007) (xy 41.645644 -98.516306)
			(xy 41.623001 -98.565888) (xy 41.593532 -98.611743) (xy 41.557837 -98.652937) (xy 41.516643 -98.688632)
			(xy 41.470788 -98.718101) (xy 41.421206 -98.740744) (xy 41.368907 -98.756101) (xy 41.314954 -98.763858)
			(xy 41.2877 -98.764344) (xy 40.3987 -98.764344) (xy 40.371451 -98.763786) (xy 40.317509 -98.75603)
			(xy 40.265219 -98.740676) (xy 40.215647 -98.718037) (xy 40.169801 -98.688574) (xy 40.128614 -98.652886)
			(xy 40.092926 -98.611699) (xy 40.063463 -98.565853) (xy 40.040824 -98.516281) (xy 40.02547 -98.463991)
			(xy 40.017714 -98.410049) (xy 0.509016 -98.410049) (xy 0.509016 -104.205349) (xy 54.921178 -104.205349)
			(xy 54.921178 -104.150851) (xy 54.928933 -104.096908) (xy 54.944285 -104.044617) (xy 54.966923 -103.995043)
			(xy 54.996385 -103.949195) (xy 55.032071 -103.908006) (xy 55.073255 -103.872315) (xy 55.119099 -103.842847)
			(xy 55.16867 -103.820203) (xy 55.220959 -103.804843) (xy 55.274901 -103.797081) (xy 55.30215 -103.796592)
			(xy 56.19115 -103.796592) (xy 56.218405 -103.797052) (xy 56.272362 -103.804803) (xy 56.324665 -103.820155)
			(xy 56.374252 -103.842794) (xy 56.420111 -103.872261) (xy 56.46131 -103.907955) (xy 56.497009 -103.949149)
			(xy 56.526482 -103.995004) (xy 56.549128 -104.044588) (xy 56.564486 -104.09689) (xy 56.572245 -104.150845)
			(xy 56.572245 -104.205355) (xy 56.564486 -104.25931) (xy 56.549128 -104.311612) (xy 56.526482 -104.361196)
			(xy 56.497009 -104.407051) (xy 56.46131 -104.448245) (xy 56.420111 -104.483939) (xy 56.374252 -104.513406)
			(xy 56.324665 -104.536045) (xy 56.272362 -104.551397) (xy 56.218405 -104.559148) (xy 56.19115 -104.559608)
			(xy 55.30215 -104.559608) (xy 55.274901 -104.559119) (xy 55.220959 -104.551357) (xy 55.16867 -104.535997)
			(xy 55.119099 -104.513353) (xy 55.073255 -104.483885) (xy 55.032071 -104.448194) (xy 54.996385 -104.407005)
			(xy 54.966923 -104.361157) (xy 54.944285 -104.311583) (xy 54.928933 -104.259292) (xy 54.921178 -104.205349)
			(xy 0.509016 -104.205349) (xy 0.509016 -107.774051) (xy 13.017478 -107.774051) (xy 13.017478 -107.719549)
			(xy 13.025234 -107.665601) (xy 13.040589 -107.613306) (xy 13.063231 -107.563729) (xy 13.092697 -107.517879)
			(xy 13.128388 -107.476688) (xy 13.169579 -107.440997) (xy 13.215429 -107.411531) (xy 13.265006 -107.388889)
			(xy 13.317301 -107.373534) (xy 13.371249 -107.365778) (xy 13.3985 -107.365292) (xy 14.2875 -107.365292)
			(xy 14.314751 -107.365778) (xy 14.368699 -107.373534) (xy 14.420994 -107.388889) (xy 14.470571 -107.411531)
			(xy 14.516421 -107.440997) (xy 14.557612 -107.476688) (xy 14.593303 -107.517879) (xy 14.622769 -107.563729)
			(xy 14.645411 -107.613306) (xy 14.660766 -107.665601) (xy 14.668522 -107.719549) (xy 14.668522 -107.77382)
			(xy 17.94482 -107.77382) (xy 17.94482 -107.71928) (xy 17.952582 -107.665296) (xy 17.967948 -107.612966)
			(xy 17.990604 -107.563355) (xy 18.02009 -107.517474) (xy 18.055806 -107.476256) (xy 18.097024 -107.44054)
			(xy 18.142905 -107.411054) (xy 18.192516 -107.388398) (xy 18.244846 -107.373032) (xy 18.29883 -107.36527)
			(xy 18.3261 -107.364784) (xy 19.2151 -107.364784) (xy 19.242369 -107.365278) (xy 19.296352 -107.37304)
			(xy 19.348681 -107.388405) (xy 19.398291 -107.411061) (xy 19.444171 -107.440547) (xy 19.485388 -107.476262)
			(xy 19.521103 -107.517479) (xy 19.550589 -107.563359) (xy 19.573245 -107.612969) (xy 19.58861 -107.665298)
			(xy 19.596372 -107.719281) (xy 19.596372 -107.773819) (xy 19.58861 -107.827802) (xy 19.573245 -107.880131)
			(xy 19.550589 -107.929741) (xy 19.521103 -107.975621) (xy 19.485388 -108.016838) (xy 19.444171 -108.052553)
			(xy 19.398291 -108.082039) (xy 19.348681 -108.104695) (xy 19.296352 -108.12006) (xy 19.242369 -108.127822)
			(xy 19.2151 -108.128308) (xy 18.3261 -108.128308) (xy 18.29883 -108.12783) (xy 18.244846 -108.120068)
			(xy 18.192516 -108.104702) (xy 18.142905 -108.082046) (xy 18.097024 -108.05256) (xy 18.055806 -108.016844)
			(xy 18.02009 -107.975626) (xy 17.990604 -107.929745) (xy 17.967948 -107.880134) (xy 17.952582 -107.827804)
			(xy 17.94482 -107.77382) (xy 14.668522 -107.77382) (xy 14.668522 -107.774051) (xy 14.660766 -107.827999)
			(xy 14.645411 -107.880294) (xy 14.622769 -107.929871) (xy 14.593303 -107.975721) (xy 14.557612 -108.016912)
			(xy 14.516421 -108.052603) (xy 14.470571 -108.082069) (xy 14.420994 -108.104711) (xy 14.368699 -108.120066)
			(xy 14.314751 -108.127822) (xy 14.2875 -108.128308) (xy 13.3985 -108.128308) (xy 13.371249 -108.127822)
			(xy 13.317301 -108.120066) (xy 13.265006 -108.104711) (xy 13.215429 -108.082069) (xy 13.169579 -108.052603)
			(xy 13.128388 -108.016912) (xy 13.092697 -107.975721) (xy 13.063231 -107.929871) (xy 13.040589 -107.880294)
			(xy 13.025234 -107.827999) (xy 13.017478 -107.774051) (xy 0.509016 -107.774051) (xy 0.509016 -109.570609)
			(xy 15.016716 -109.570609) (xy 15.016716 -109.516071) (xy 15.024478 -109.462088) (xy 15.039843 -109.409759)
			(xy 15.062499 -109.360149) (xy 15.091985 -109.314268) (xy 15.127699 -109.273051) (xy 15.168917 -109.237336)
			(xy 15.214797 -109.20785) (xy 15.264407 -109.185194) (xy 15.316736 -109.169828) (xy 15.370719 -109.162067)
			(xy 15.397988 -109.16158) (xy 16.286988 -109.16158) (xy 16.314259 -109.162039) (xy 16.368247 -109.169801)
			(xy 16.42058 -109.185167) (xy 16.470193 -109.207825) (xy 16.516078 -109.237313) (xy 16.557298 -109.27303)
			(xy 16.593016 -109.314251) (xy 16.622504 -109.360135) (xy 16.645162 -109.409748) (xy 16.660528 -109.462081)
			(xy 16.668291 -109.516069) (xy 16.668291 -109.570611) (xy 16.660528 -109.624599) (xy 16.645162 -109.676932)
			(xy 16.622504 -109.726545) (xy 16.593016 -109.772429) (xy 16.557298 -109.81365) (xy 16.516078 -109.849367)
			(xy 16.470193 -109.878855) (xy 16.42058 -109.901513) (xy 16.368247 -109.916879) (xy 16.314259 -109.924641)
			(xy 16.286988 -109.925104) (xy 15.397988 -109.925104) (xy 15.370719 -109.924613) (xy 15.316736 -109.916852)
			(xy 15.264407 -109.901486) (xy 15.214797 -109.87883) (xy 15.168917 -109.849344) (xy 15.127699 -109.813629)
			(xy 15.091985 -109.772412) (xy 15.062499 -109.726531) (xy 15.039843 -109.676921) (xy 15.024478 -109.624592)
			(xy 15.016716 -109.570609) (xy 0.509016 -109.570609) (xy 0.509016 -109.998056) (xy 84.426541 -109.998056)
			(xy 84.426541 -109.868916) (xy 84.434491 -109.740021) (xy 84.450361 -109.611861) (xy 84.47409 -109.48492)
			(xy 84.505589 -109.359681) (xy 84.544738 -109.236618) (xy 84.591389 -109.116199) (xy 84.645364 -108.99888)
			(xy 84.706459 -108.885106) (xy 84.774442 -108.775309) (xy 84.849056 -108.669906) (xy 84.930017 -108.569296)
			(xy 85.017017 -108.473861) (xy 85.109728 -108.383962) (xy 85.207798 -108.299941) (xy 85.310853 -108.222117)
			(xy 85.418504 -108.150785) (xy 85.530343 -108.086215) (xy 85.645944 -108.028653) (xy 85.764869 -107.978316)
			(xy 85.886668 -107.935396) (xy 86.010878 -107.900055) (xy 86.137027 -107.872428) (xy 86.264639 -107.852619)
			(xy 86.393228 -107.840703) (xy 86.522306 -107.836727) (xy 86.651384 -107.840703) (xy 86.779973 -107.852619)
			(xy 86.907585 -107.872428) (xy 87.033734 -107.900055) (xy 87.157944 -107.935396) (xy 87.279743 -107.978316)
			(xy 87.398668 -108.028653) (xy 87.514269 -108.086215) (xy 87.626108 -108.150785) (xy 87.733759 -108.222117)
			(xy 87.836814 -108.299941) (xy 87.934884 -108.383962) (xy 88.027595 -108.473861) (xy 88.114595 -108.569296)
			(xy 88.195556 -108.669906) (xy 88.27017 -108.775309) (xy 88.338153 -108.885106) (xy 88.399248 -108.99888)
			(xy 88.453223 -109.116199) (xy 88.499874 -109.236618) (xy 88.539023 -109.359681) (xy 88.570522 -109.48492)
			(xy 88.594251 -109.611861) (xy 88.610121 -109.740021) (xy 88.618071 -109.868916) (xy 88.618568 -109.933486)
			(xy 88.618071 -109.998056) (xy 88.610121 -110.126951) (xy 88.594251 -110.255111) (xy 88.570522 -110.382052)
			(xy 88.539023 -110.507291) (xy 88.499874 -110.630354) (xy 88.453223 -110.750773) (xy 88.399248 -110.868092)
			(xy 88.338153 -110.981866) (xy 88.27017 -111.091663) (xy 88.195556 -111.197066) (xy 88.114595 -111.297676)
			(xy 88.027595 -111.393111) (xy 87.934884 -111.48301) (xy 87.836814 -111.567031) (xy 87.733759 -111.644855)
			(xy 87.626108 -111.716187) (xy 87.514269 -111.780757) (xy 87.398668 -111.838319) (xy 87.279743 -111.888656)
			(xy 87.157944 -111.931576) (xy 87.033734 -111.966917) (xy 86.907585 -111.994544) (xy 86.779973 -112.014353)
			(xy 86.651384 -112.026269) (xy 86.522306 -112.030246) (xy 86.393228 -112.026269) (xy 86.264639 -112.014353)
			(xy 86.137027 -111.994544) (xy 86.010878 -111.966917) (xy 85.886668 -111.931576) (xy 85.764869 -111.888656)
			(xy 85.645944 -111.838319) (xy 85.530343 -111.780757) (xy 85.418504 -111.716187) (xy 85.310853 -111.644855)
			(xy 85.207798 -111.567031) (xy 85.109728 -111.48301) (xy 85.017017 -111.393111) (xy 84.930017 -111.297676)
			(xy 84.849056 -111.197066) (xy 84.774442 -111.091663) (xy 84.706459 -110.981866) (xy 84.645364 -110.868092)
			(xy 84.591389 -110.750773) (xy 84.544738 -110.630354) (xy 84.505589 -110.507291) (xy 84.47409 -110.382052)
			(xy 84.450361 -110.255111) (xy 84.434491 -110.126951) (xy 84.426541 -109.998056) (xy 0.509016 -109.998056)
			(xy 0.509016 -112.300004) (xy 0.509494 -112.35115) (xy 53.778158 -112.35115) (xy 53.778158 -112.29665)
			(xy 53.785913 -112.242703) (xy 53.801267 -112.19041) (xy 53.823905 -112.140833) (xy 53.853369 -112.094983)
			(xy 53.889057 -112.053792) (xy 53.930243 -112.018099) (xy 53.976089 -111.988629) (xy 54.025663 -111.965984)
			(xy 54.077955 -111.950624) (xy 54.1319 -111.942861) (xy 54.15915 -111.942372) (xy 55.04815 -111.942372)
			(xy 55.075404 -111.942872) (xy 55.129357 -111.950623) (xy 55.181658 -111.965974) (xy 55.231242 -111.988612)
			(xy 55.277099 -112.018077) (xy 55.318296 -112.053769) (xy 55.353993 -112.094961) (xy 55.383464 -112.140814)
			(xy 55.406109 -112.190395) (xy 55.421467 -112.242694) (xy 55.429225 -112.296646) (xy 55.429225 -112.351154)
			(xy 55.421467 -112.405106) (xy 55.406109 -112.457405) (xy 55.383464 -112.506986) (xy 55.353993 -112.552839)
			(xy 55.318296 -112.594031) (xy 55.277099 -112.629723) (xy 55.231242 -112.659188) (xy 55.181658 -112.681826)
			(xy 55.129357 -112.697177) (xy 55.075404 -112.704928) (xy 55.04815 -112.705388) (xy 54.15915 -112.705388)
			(xy 54.1319 -112.704939) (xy 54.077955 -112.697176) (xy 54.025663 -112.681816) (xy 53.976089 -112.659171)
			(xy 53.930243 -112.629701) (xy 53.889057 -112.594008) (xy 53.853369 -112.552817) (xy 53.823905 -112.506967)
			(xy 53.801267 -112.45739) (xy 53.785913 -112.405097) (xy 53.778158 -112.35115) (xy 0.509494 -112.35115)
			(xy 0.509537 -112.355773) (xy 0.517873 -112.466999) (xy 0.534497 -112.577291) (xy 0.559316 -112.686033)
			(xy 0.592193 -112.792616) (xy 0.632942 -112.896444) (xy 0.681337 -112.996936) (xy 0.737106 -113.093531)
			(xy 0.796039 -113.17997) (xy 23.969706 -113.17997) (xy 23.969706 -113.12543) (xy 23.977468 -113.071446)
			(xy 23.992833 -113.019115) (xy 24.015489 -112.969504) (xy 24.044974 -112.923622) (xy 24.080689 -112.882403)
			(xy 24.121906 -112.846686) (xy 24.167787 -112.817198) (xy 24.217397 -112.79454) (xy 24.269726 -112.779172)
			(xy 24.32371 -112.771408) (xy 24.35098 -112.77092) (xy 25.23998 -112.77092) (xy 25.267251 -112.771418)
			(xy 25.321237 -112.779178) (xy 25.37357 -112.794541) (xy 25.423183 -112.817197) (xy 25.469067 -112.846682)
			(xy 25.510288 -112.882398) (xy 25.546006 -112.923617) (xy 25.575494 -112.969499) (xy 25.598152 -113.019111)
			(xy 25.613518 -113.071443) (xy 25.62128 -113.125429) (xy 25.62128 -113.179971) (xy 25.613518 -113.233957)
			(xy 25.598152 -113.286289) (xy 25.575494 -113.335901) (xy 25.546006 -113.381783) (xy 25.510288 -113.423002)
			(xy 25.469067 -113.458718) (xy 25.423183 -113.488203) (xy 25.37357 -113.510859) (xy 25.321237 -113.526222)
			(xy 25.267251 -113.533982) (xy 25.23998 -113.534444) (xy 24.35098 -113.534444) (xy 24.32371 -113.533992)
			(xy 24.269726 -113.526228) (xy 24.217397 -113.51086) (xy 24.167787 -113.488202) (xy 24.121906 -113.458714)
			(xy 24.080689 -113.422997) (xy 24.044974 -113.381778) (xy 24.015489 -113.335896) (xy 23.992833 -113.286285)
			(xy 23.977468 -113.233954) (xy 23.969706 -113.17997) (xy 0.796039 -113.17997) (xy 0.799937 -113.185688)
			(xy 0.86948 -113.272892) (xy 0.945345 -113.354655) (xy 1.027108 -113.43052) (xy 1.114312 -113.500063)
			(xy 1.206469 -113.562894) (xy 1.303064 -113.618663) (xy 1.403556 -113.667058) (xy 1.507384 -113.707807)
			(xy 1.613967 -113.740684) (xy 1.722709 -113.765503) (xy 1.833001 -113.782127) (xy 1.944227 -113.790463)
			(xy 1.999996 -113.790984) (xy 4.500118 -113.790984) (xy 4.544143 -113.791475) (xy 4.631856 -113.799169)
			(xy 4.718565 -113.814476) (xy 4.803611 -113.83728) (xy 4.886347 -113.867406) (xy 4.966143 -113.904627)
			(xy 5.042392 -113.948658) (xy 5.114516 -113.999166) (xy 5.181964 -114.055765) (xy 5.244225 -114.118026)
			(xy 5.300824 -114.185474) (xy 5.351332 -114.257598) (xy 5.395363 -114.333847) (xy 5.432584 -114.413643)
			(xy 5.46271 -114.496379) (xy 5.485514 -114.581425) (xy 5.500821 -114.668134) (xy 5.508515 -114.755847)
			(xy 5.509006 -114.799872) (xy 5.509006 -118.711726) (xy 5.621528 -118.824248) (xy 5.936488 -118.824248)
			(xy 6.040374 -118.720616) (xy 9.704578 -118.720616) (xy 9.862312 -118.878096) (xy 10.162286 -118.878096)
		)
		(stroke
			(width 0)
			(type solid)
		)
		(fill yes)
		(layer "In10.Cu")
		(net "GND")
	)
	(gr_poly
		(pts
			(xy 121.000012 -119.892064) (xy 121.055819 -119.891554) (xy 121.16712 -119.883212) (xy 121.277487 -119.866576)
			(xy 121.386302 -119.841739) (xy 121.492956 -119.808839) (xy 121.596854 -119.768061) (xy 121.697414 -119.719632)
			(xy 121.794073 -119.663824) (xy 121.886292 -119.600949) (xy 121.973554 -119.531358) (xy 122.055371 -119.45544)
			(xy 122.131287 -119.373621) (xy 122.200875 -119.286356) (xy 122.263748 -119.194136) (xy 122.319553 -119.097475)
			(xy 122.367978 -118.996914) (xy 122.408754 -118.893015) (xy 122.44165 -118.786359) (xy 122.466484 -118.677544)
			(xy 122.483117 -118.567176) (xy 122.491456 -118.455875) (xy 122.492008 -118.400068) (xy 122.492008 129.499868)
			(xy 122.4915 129.555676) (xy 122.483161 129.666981) (xy 122.466528 129.777352) (xy 122.441693 129.886171)
			(xy 122.408795 129.992829) (xy 122.368019 130.096731) (xy 122.319592 130.197295) (xy 122.263785 130.293959)
			(xy 122.200911 130.386183) (xy 122.13132 130.473449) (xy 122.055402 130.555271) (xy 121.973583 130.631191)
			(xy 121.886318 130.700784) (xy 121.794097 130.763662) (xy 121.697434 130.819471) (xy 121.596872 130.867901)
			(xy 121.492971 130.908681) (xy 121.386313 130.941581) (xy 121.277495 130.96642) (xy 121.167125 130.983056)
			(xy 121.05582 130.991398) (xy 121.000012 130.991864) (xy 94.000066 130.991864) (xy 93.94426 130.991341)
			(xy 93.832961 130.982998) (xy 93.722596 130.96636) (xy 93.613784 130.941522) (xy 93.507131 130.908622)
			(xy 93.403236 130.867843) (xy 93.302679 130.819414) (xy 93.206021 130.763606) (xy 93.113805 130.700731)
			(xy 93.026545 130.631141) (xy 92.94473 130.555224) (xy 92.868816 130.473405) (xy 92.79923 130.386142)
			(xy 92.736359 130.293923) (xy 92.680555 130.197263) (xy 92.632131 130.096703) (xy 92.591357 129.992806)
			(xy 92.558461 129.886153) (xy 92.533627 129.777339) (xy 92.516995 129.666973) (xy 92.508656 129.555674)
			(xy 92.50807 129.499868) (xy 92.50807 126.435304) (xy 115.904253 126.435304) (xy 115.904253 126.564444)
			(xy 115.912203 126.693339) (xy 115.928073 126.821499) (xy 115.951802 126.94844) (xy 115.983301 127.073679)
			(xy 116.02245 127.196742) (xy 116.069101 127.317161) (xy 116.123076 127.43448) (xy 116.184171 127.548254)
			(xy 116.252154 127.658051) (xy 116.326768 127.763454) (xy 116.407729 127.864064) (xy 116.494729 127.959499)
			(xy 116.58744 128.049398) (xy 116.68551 128.133419) (xy 116.788565 128.211243) (xy 116.896216 128.282575)
			(xy 117.008055 128.347145) (xy 117.123656 128.404707) (xy 117.242581 128.455044) (xy 117.36438 128.497964)
			(xy 117.48859 128.533305) (xy 117.614739 128.560932) (xy 117.742351 128.580741) (xy 117.87094 128.592657)
			(xy 118.000018 128.596634) (xy 118.129096 128.592657) (xy 118.257685 128.580741) (xy 118.385297 128.560932)
			(xy 118.511446 128.533305) (xy 118.635656 128.497964) (xy 118.757455 128.455044) (xy 118.87638 128.404707)
			(xy 118.991981 128.347145) (xy 119.10382 128.282575) (xy 119.211471 128.211243) (xy 119.314526 128.133419)
			(xy 119.412596 128.049398) (xy 119.505307 127.959499) (xy 119.592307 127.864064) (xy 119.673268 127.763454)
			(xy 119.747882 127.658051) (xy 119.815865 127.548254) (xy 119.87696 127.43448) (xy 119.930935 127.317161)
			(xy 119.977586 127.196742) (xy 120.016735 127.073679) (xy 120.048234 126.94844) (xy 120.071963 126.821499)
			(xy 120.087833 126.693339) (xy 120.095783 126.564444) (xy 120.09628 126.499874) (xy 120.095783 126.435304)
			(xy 120.087833 126.306409) (xy 120.071963 126.178249) (xy 120.048234 126.051308) (xy 120.016735 125.926069)
			(xy 119.977586 125.803006) (xy 119.930935 125.682587) (xy 119.87696 125.565268) (xy 119.815865 125.451494)
			(xy 119.747882 125.341697) (xy 119.673268 125.236294) (xy 119.592307 125.135684) (xy 119.505307 125.040249)
			(xy 119.412596 124.95035) (xy 119.314526 124.866329) (xy 119.211471 124.788505) (xy 119.10382 124.717173)
			(xy 118.991981 124.652603) (xy 118.87638 124.595041) (xy 118.757455 124.544704) (xy 118.635656 124.501784)
			(xy 118.511446 124.466443) (xy 118.385297 124.438816) (xy 118.257685 124.419007) (xy 118.129096 124.407091)
			(xy 118.000018 124.403115) (xy 117.87094 124.407091) (xy 117.742351 124.419007) (xy 117.614739 124.438816)
			(xy 117.48859 124.466443) (xy 117.36438 124.501784) (xy 117.242581 124.544704) (xy 117.123656 124.595041)
			(xy 117.008055 124.652603) (xy 116.896216 124.717173) (xy 116.788565 124.788505) (xy 116.68551 124.866329)
			(xy 116.58744 124.95035) (xy 116.494729 125.040249) (xy 116.407729 125.135684) (xy 116.326768 125.236294)
			(xy 116.252154 125.341697) (xy 116.184171 125.451494) (xy 116.123076 125.565268) (xy 116.069101 125.682587)
			(xy 116.02245 125.803006) (xy 115.983301 125.926069) (xy 115.951802 126.051308) (xy 115.928073 126.178249)
			(xy 115.912203 126.306409) (xy 115.904253 126.435304) (xy 92.50807 126.435304) (xy 92.50807 122.226375)
			(xy 99.070401 122.226375) (xy 99.070401 122.312125) (xy 99.078313 122.397508) (xy 99.094069 122.481798)
			(xy 99.117536 122.564274) (xy 99.148512 122.644233) (xy 99.186734 122.720993) (xy 99.231875 122.793899)
			(xy 99.283551 122.862328) (xy 99.34132 122.925698) (xy 99.40469 122.983467) (xy 99.473119 123.035143)
			(xy 99.546025 123.080284) (xy 99.622785 123.118506) (xy 99.702744 123.149482) (xy 99.78522 123.172949)
			(xy 99.86951 123.188705) (xy 99.954893 123.196617) (xy 100.040643 123.196617) (xy 100.126026 123.188705)
			(xy 100.210316 123.172949) (xy 100.292792 123.149482) (xy 100.372751 123.118506) (xy 100.449511 123.080284)
			(xy 100.522417 123.035143) (xy 100.590846 122.983467) (xy 100.654216 122.925698) (xy 100.711985 122.862328)
			(xy 100.763661 122.793899) (xy 100.808802 122.720993) (xy 100.847024 122.644233) (xy 100.878 122.564274)
			(xy 100.901467 122.481798) (xy 100.917223 122.397508) (xy 100.925135 122.312125) (xy 100.92563 122.26925)
			(xy 100.925135 122.226375) (xy 101.610401 122.226375) (xy 101.610401 122.312125) (xy 101.618313 122.397508)
			(xy 101.634069 122.481798) (xy 101.657536 122.564274) (xy 101.688512 122.644233) (xy 101.726734 122.720993)
			(xy 101.771875 122.793899) (xy 101.823551 122.862328) (xy 101.88132 122.925698) (xy 101.94469 122.983467)
			(xy 102.013119 123.035143) (xy 102.086025 123.080284) (xy 102.162785 123.118506) (xy 102.242744 123.149482)
			(xy 102.32522 123.172949) (xy 102.40951 123.188705) (xy 102.494893 123.196617) (xy 102.580643 123.196617)
			(xy 102.666026 123.188705) (xy 102.750316 123.172949) (xy 102.832792 123.149482) (xy 102.912751 123.118506)
			(xy 102.989511 123.080284) (xy 103.062417 123.035143) (xy 103.130846 122.983467) (xy 103.194216 122.925698)
			(xy 103.251985 122.862328) (xy 103.303661 122.793899) (xy 103.348802 122.720993) (xy 103.387024 122.644233)
			(xy 103.418 122.564274) (xy 103.441467 122.481798) (xy 103.457223 122.397508) (xy 103.465135 122.312125)
			(xy 103.46563 122.26925) (xy 103.465135 122.226375) (xy 103.457223 122.140992) (xy 103.441467 122.056702)
			(xy 103.418 121.974226) (xy 103.387024 121.894267) (xy 103.348802 121.817507) (xy 103.303661 121.744601)
			(xy 103.251985 121.676172) (xy 103.194216 121.612802) (xy 103.130846 121.555033) (xy 103.062417 121.503357)
			(xy 102.989511 121.458216) (xy 102.912751 121.419994) (xy 102.832792 121.389018) (xy 102.750316 121.365551)
			(xy 102.666026 121.349795) (xy 102.580643 121.341883) (xy 102.494893 121.341883) (xy 102.40951 121.349795)
			(xy 102.32522 121.365551) (xy 102.242744 121.389018) (xy 102.162785 121.419994) (xy 102.086025 121.458216)
			(xy 102.013119 121.503357) (xy 101.94469 121.555033) (xy 101.88132 121.612802) (xy 101.823551 121.676172)
			(xy 101.771875 121.744601) (xy 101.726734 121.817507) (xy 101.688512 121.894267) (xy 101.657536 121.974226)
			(xy 101.634069 122.056702) (xy 101.618313 122.140992) (xy 101.610401 122.226375) (xy 100.925135 122.226375)
			(xy 100.917223 122.140992) (xy 100.901467 122.056702) (xy 100.878 121.974226) (xy 100.847024 121.894267)
			(xy 100.808802 121.817507) (xy 100.763661 121.744601) (xy 100.711985 121.676172) (xy 100.654216 121.612802)
			(xy 100.590846 121.555033) (xy 100.522417 121.503357) (xy 100.449511 121.458216) (xy 100.372751 121.419994)
			(xy 100.292792 121.389018) (xy 100.210316 121.365551) (xy 100.126026 121.349795) (xy 100.040643 121.341883)
			(xy 99.954893 121.341883) (xy 99.86951 121.349795) (xy 99.78522 121.365551) (xy 99.702744 121.389018)
			(xy 99.622785 121.419994) (xy 99.546025 121.458216) (xy 99.473119 121.503357) (xy 99.40469 121.555033)
			(xy 99.34132 121.612802) (xy 99.283551 121.676172) (xy 99.231875 121.744601) (xy 99.186734 121.817507)
			(xy 99.148512 121.894267) (xy 99.117536 121.974226) (xy 99.094069 122.056702) (xy 99.078313 122.140992)
			(xy 99.070401 122.226375) (xy 92.50807 122.226375) (xy 92.50807 117.908578) (xy 100.45446 117.908578)
			(xy 100.454977 117.937121) (xy 100.463462 117.993573) (xy 100.480261 118.048131) (xy 100.504999 118.099579)
			(xy 100.537125 118.146768) (xy 100.575921 118.188645) (xy 100.620521 118.224276) (xy 100.64496 118.239032)
			(xy 100.64496 119.037608) (xy 101.895656 119.037608) (xy 101.895656 118.235984) (xy 101.919524 118.221112)
			(xy 101.962986 118.185424) (xy 102.000743 118.143747) (xy 102.031977 118.096983) (xy 102.056013 118.046142)
			(xy 102.072331 117.992325) (xy 102.080578 117.936696) (xy 102.081076 117.908578) (xy 102.080597 117.88132)
			(xy 102.072839 117.827359) (xy 102.057485 117.775051) (xy 102.034845 117.725458) (xy 102.005382 117.679591)
			(xy 101.969694 117.63838) (xy 101.928507 117.602665) (xy 101.882658 117.573173) (xy 101.83308 117.550501)
			(xy 101.780781 117.535113) (xy 101.726825 117.527321) (xy 101.699568 117.526816) (xy 100.835968 117.526816)
			(xy 100.808702 117.527226) (xy 100.754725 117.534994) (xy 100.702405 117.550369) (xy 100.652806 117.573035)
			(xy 100.606939 117.602532) (xy 100.56574 117.638259) (xy 100.530046 117.679488) (xy 100.500586 117.725378)
			(xy 100.47796 117.774995) (xy 100.462628 117.827329) (xy 100.454904 117.881311) (xy 100.45446 117.908578)
			(xy 92.50807 117.908578) (xy 92.50807 115.606627) (xy 93.714049 115.606627) (xy 93.714049 115.692377)
			(xy 93.721961 115.77776) (xy 93.737717 115.86205) (xy 93.761184 115.944526) (xy 93.79216 116.024485)
			(xy 93.830382 116.101245) (xy 93.875523 116.174151) (xy 93.927199 116.24258) (xy 93.984968 116.30595)
			(xy 94.048338 116.363719) (xy 94.116767 116.415395) (xy 94.189673 116.460536) (xy 94.266433 116.498758)
			(xy 94.346392 116.529734) (xy 94.428868 116.553201) (xy 94.513158 116.568957) (xy 94.598541 116.576869)
			(xy 94.684291 116.576869) (xy 94.769674 116.568957) (xy 94.853964 116.553201) (xy 94.93644 116.529734)
			(xy 95.016399 116.498758) (xy 95.093159 116.460536) (xy 95.166065 116.415395) (xy 95.234494 116.363719)
			(xy 95.297864 116.30595) (xy 95.355633 116.24258) (xy 95.407309 116.174151) (xy 95.45245 116.101245)
			(xy 95.490672 116.024485) (xy 95.521648 115.944526) (xy 95.545115 115.86205) (xy 95.560871 115.77776)
			(xy 95.568783 115.692377) (xy 95.569278 115.649502) (xy 95.568783 115.606627) (xy 96.254049 115.606627)
			(xy 96.254049 115.692377) (xy 96.261961 115.77776) (xy 96.277717 115.86205) (xy 96.301184 115.944526)
			(xy 96.33216 116.024485) (xy 96.370382 116.101245) (xy 96.415523 116.174151) (xy 96.467199 116.24258)
			(xy 96.524968 116.30595) (xy 96.588338 116.363719) (xy 96.656767 116.415395) (xy 96.729673 116.460536)
			(xy 96.806433 116.498758) (xy 96.886392 116.529734) (xy 96.968868 116.553201) (xy 97.053158 116.568957)
			(xy 97.138541 116.576869) (xy 97.224291 116.576869) (xy 97.309674 116.568957) (xy 97.393964 116.553201)
			(xy 97.47644 116.529734) (xy 97.556399 116.498758) (xy 97.633159 116.460536) (xy 97.706065 116.415395)
			(xy 97.774494 116.363719) (xy 97.837864 116.30595) (xy 97.895633 116.24258) (xy 97.947309 116.174151)
			(xy 97.99245 116.101245) (xy 98.030672 116.024485) (xy 98.061648 115.944526) (xy 98.081039 115.876375)
			(xy 99.070401 115.876375) (xy 99.070401 115.962125) (xy 99.078313 116.047508) (xy 99.094069 116.131798)
			(xy 99.117536 116.214274) (xy 99.148512 116.294233) (xy 99.186734 116.370993) (xy 99.231875 116.443899)
			(xy 99.283551 116.512328) (xy 99.34132 116.575698) (xy 99.40469 116.633467) (xy 99.473119 116.685143)
			(xy 99.546025 116.730284) (xy 99.622785 116.768506) (xy 99.702744 116.799482) (xy 99.78522 116.822949)
			(xy 99.86951 116.838705) (xy 99.954893 116.846617) (xy 100.040643 116.846617) (xy 100.126026 116.838705)
			(xy 100.210316 116.822949) (xy 100.292792 116.799482) (xy 100.372751 116.768506) (xy 100.449511 116.730284)
			(xy 100.522417 116.685143) (xy 100.590846 116.633467) (xy 100.654216 116.575698) (xy 100.711985 116.512328)
			(xy 100.763661 116.443899) (xy 100.808802 116.370993) (xy 100.847024 116.294233) (xy 100.878 116.214274)
			(xy 100.901467 116.131798) (xy 100.917223 116.047508) (xy 100.925135 115.962125) (xy 100.92563 115.91925)
			(xy 100.925135 115.876375) (xy 101.610401 115.876375) (xy 101.610401 115.962125) (xy 101.618313 116.047508)
			(xy 101.634069 116.131798) (xy 101.657536 116.214274) (xy 101.688512 116.294233) (xy 101.726734 116.370993)
			(xy 101.771875 116.443899) (xy 101.823551 116.512328) (xy 101.88132 116.575698) (xy 101.94469 116.633467)
			(xy 102.013119 116.685143) (xy 102.086025 116.730284) (xy 102.162785 116.768506) (xy 102.242744 116.799482)
			(xy 102.32522 116.822949) (xy 102.40951 116.838705) (xy 102.494893 116.846617) (xy 102.580643 116.846617)
			(xy 102.666026 116.838705) (xy 102.750316 116.822949) (xy 102.832792 116.799482) (xy 102.912751 116.768506)
			(xy 102.989511 116.730284) (xy 103.062417 116.685143) (xy 103.130846 116.633467) (xy 103.194216 116.575698)
			(xy 103.251985 116.512328) (xy 103.303661 116.443899) (xy 103.348802 116.370993) (xy 103.387024 116.294233)
			(xy 103.418 116.214274) (xy 103.441467 116.131798) (xy 103.457223 116.047508) (xy 103.465135 115.962125)
			(xy 103.46563 115.91925) (xy 103.465135 115.876375) (xy 103.457223 115.790992) (xy 103.441467 115.706702)
			(xy 103.418 115.624226) (xy 103.387024 115.544267) (xy 103.348802 115.467507) (xy 103.303661 115.394601)
			(xy 103.251985 115.326172) (xy 103.194216 115.262802) (xy 103.130846 115.205033) (xy 103.062417 115.153357)
			(xy 102.989511 115.108216) (xy 102.912751 115.069994) (xy 102.832792 115.039018) (xy 102.750316 115.015551)
			(xy 102.666026 114.999795) (xy 102.580643 114.991883) (xy 102.494893 114.991883) (xy 102.40951 114.999795)
			(xy 102.32522 115.015551) (xy 102.242744 115.039018) (xy 102.162785 115.069994) (xy 102.086025 115.108216)
			(xy 102.013119 115.153357) (xy 101.94469 115.205033) (xy 101.88132 115.262802) (xy 101.823551 115.326172)
			(xy 101.771875 115.394601) (xy 101.726734 115.467507) (xy 101.688512 115.544267) (xy 101.657536 115.624226)
			(xy 101.634069 115.706702) (xy 101.618313 115.790992) (xy 101.610401 115.876375) (xy 100.925135 115.876375)
			(xy 100.917223 115.790992) (xy 100.901467 115.706702) (xy 100.878 115.624226) (xy 100.847024 115.544267)
			(xy 100.808802 115.467507) (xy 100.763661 115.394601) (xy 100.711985 115.326172) (xy 100.654216 115.262802)
			(xy 100.590846 115.205033) (xy 100.522417 115.153357) (xy 100.449511 115.108216) (xy 100.372751 115.069994)
			(xy 100.292792 115.039018) (xy 100.210316 115.015551) (xy 100.126026 114.999795) (xy 100.040643 114.991883)
			(xy 99.954893 114.991883) (xy 99.86951 114.999795) (xy 99.78522 115.015551) (xy 99.702744 115.039018)
			(xy 99.622785 115.069994) (xy 99.546025 115.108216) (xy 99.473119 115.153357) (xy 99.40469 115.205033)
			(xy 99.34132 115.262802) (xy 99.283551 115.326172) (xy 99.231875 115.394601) (xy 99.186734 115.467507)
			(xy 99.148512 115.544267) (xy 99.117536 115.624226) (xy 99.094069 115.706702) (xy 99.078313 115.790992)
			(xy 99.070401 115.876375) (xy 98.081039 115.876375) (xy 98.085115 115.86205) (xy 98.100871 115.77776)
			(xy 98.108783 115.692377) (xy 98.109278 115.649502) (xy 98.108783 115.606627) (xy 98.100871 115.521244)
			(xy 98.085115 115.436954) (xy 98.061648 115.354478) (xy 98.030672 115.274519) (xy 97.99245 115.197759)
			(xy 97.947309 115.124853) (xy 97.895633 115.056424) (xy 97.837864 114.993054) (xy 97.774494 114.935285)
			(xy 97.706065 114.883609) (xy 97.633159 114.838468) (xy 97.556399 114.800246) (xy 97.47644 114.76927)
			(xy 97.393964 114.745803) (xy 97.309674 114.730047) (xy 97.224291 114.722135) (xy 97.138541 114.722135)
			(xy 97.053158 114.730047) (xy 96.968868 114.745803) (xy 96.886392 114.76927) (xy 96.806433 114.800246)
			(xy 96.729673 114.838468) (xy 96.656767 114.883609) (xy 96.588338 114.935285) (xy 96.524968 114.993054)
			(xy 96.467199 115.056424) (xy 96.415523 115.124853) (xy 96.370382 115.197759) (xy 96.33216 115.274519)
			(xy 96.301184 115.354478) (xy 96.277717 115.436954) (xy 96.261961 115.521244) (xy 96.254049 115.606627)
			(xy 95.568783 115.606627) (xy 95.560871 115.521244) (xy 95.545115 115.436954) (xy 95.521648 115.354478)
			(xy 95.490672 115.274519) (xy 95.45245 115.197759) (xy 95.407309 115.124853) (xy 95.355633 115.056424)
			(xy 95.297864 114.993054) (xy 95.234494 114.935285) (xy 95.166065 114.883609) (xy 95.093159 114.838468)
			(xy 95.016399 114.800246) (xy 94.93644 114.76927) (xy 94.853964 114.745803) (xy 94.769674 114.730047)
			(xy 94.684291 114.722135) (xy 94.598541 114.722135) (xy 94.513158 114.730047) (xy 94.428868 114.745803)
			(xy 94.346392 114.76927) (xy 94.266433 114.800246) (xy 94.189673 114.838468) (xy 94.116767 114.883609)
			(xy 94.048338 114.935285) (xy 93.984968 114.993054) (xy 93.927199 115.056424) (xy 93.875523 115.124853)
			(xy 93.830382 115.197759) (xy 93.79216 115.274519) (xy 93.761184 115.354478) (xy 93.737717 115.436954)
			(xy 93.721961 115.521244) (xy 93.714049 115.606627) (xy 92.50807 115.606627) (xy 92.50807 111.28883)
			(xy 95.098108 111.28883) (xy 95.098639 111.317373) (xy 95.107119 111.373825) (xy 95.123913 111.428385)
			(xy 95.148649 111.479833) (xy 95.180772 111.527022) (xy 95.219568 111.568899) (xy 95.264169 111.604529)
			(xy 95.288608 111.619284) (xy 95.288608 112.41786) (xy 96.539304 112.41786) (xy 96.539304 111.616236)
			(xy 96.563136 111.601309) (xy 96.606601 111.565633) (xy 96.644362 111.523966) (xy 96.675601 111.47721)
			(xy 96.699643 111.426378) (xy 96.715968 111.372568) (xy 96.724221 111.316946) (xy 96.724724 111.28883)
			(xy 96.724248 111.261571) (xy 96.716496 111.207608) (xy 96.701146 111.155296) (xy 96.678509 111.1057)
			(xy 96.649046 111.059829) (xy 96.613357 111.018617) (xy 96.572168 110.982901) (xy 96.526316 110.953409)
			(xy 96.476735 110.93074) (xy 96.424433 110.915356) (xy 96.370475 110.907569) (xy 96.343216 110.907068)
			(xy 95.479616 110.907068) (xy 95.452353 110.907571) (xy 95.398382 110.915332) (xy 95.346067 110.930697)
			(xy 95.296471 110.953355) (xy 95.250607 110.982842) (xy 95.209408 111.01856) (xy 95.173714 111.059778)
			(xy 95.144252 111.105659) (xy 95.121622 111.155267) (xy 95.106286 111.207592) (xy 95.098556 111.261567)
			(xy 95.098108 111.28883) (xy 92.50807 111.28883) (xy 92.50807 109.256627) (xy 93.714049 109.256627)
			(xy 93.714049 109.342377) (xy 93.721961 109.42776) (xy 93.737717 109.51205) (xy 93.761184 109.594526)
			(xy 93.79216 109.674485) (xy 93.830382 109.751245) (xy 93.875523 109.824151) (xy 93.927199 109.89258)
			(xy 93.984968 109.95595) (xy 94.048338 110.013719) (xy 94.116767 110.065395) (xy 94.189673 110.110536)
			(xy 94.266433 110.148758) (xy 94.346392 110.179734) (xy 94.428868 110.203201) (xy 94.513158 110.218957)
			(xy 94.598541 110.226869) (xy 94.684291 110.226869) (xy 94.769674 110.218957) (xy 94.853964 110.203201)
			(xy 94.93644 110.179734) (xy 95.016399 110.148758) (xy 95.093159 110.110536) (xy 95.166065 110.065395)
			(xy 95.234494 110.013719) (xy 95.297864 109.95595) (xy 95.355633 109.89258) (xy 95.407309 109.824151)
			(xy 95.45245 109.751245) (xy 95.490672 109.674485) (xy 95.521648 109.594526) (xy 95.545115 109.51205)
			(xy 95.560871 109.42776) (xy 95.568783 109.342377) (xy 95.569278 109.299502) (xy 95.568783 109.256627)
			(xy 96.254049 109.256627) (xy 96.254049 109.342377) (xy 96.261961 109.42776) (xy 96.277717 109.51205)
			(xy 96.301184 109.594526) (xy 96.33216 109.674485) (xy 96.370382 109.751245) (xy 96.415523 109.824151)
			(xy 96.467199 109.89258) (xy 96.524968 109.95595) (xy 96.588338 110.013719) (xy 96.656767 110.065395)
			(xy 96.729673 110.110536) (xy 96.806433 110.148758) (xy 96.886392 110.179734) (xy 96.968868 110.203201)
			(xy 97.053158 110.218957) (xy 97.138541 110.226869) (xy 97.224291 110.226869) (xy 97.309674 110.218957)
			(xy 97.393964 110.203201) (xy 97.47644 110.179734) (xy 97.556399 110.148758) (xy 97.633159 110.110536)
			(xy 97.706065 110.065395) (xy 97.774494 110.013719) (xy 97.837864 109.95595) (xy 97.895633 109.89258)
			(xy 97.947309 109.824151) (xy 97.99245 109.751245) (xy 98.030672 109.674485) (xy 98.061648 109.594526)
			(xy 98.085115 109.51205) (xy 98.100871 109.42776) (xy 98.108783 109.342377) (xy 98.109278 109.299502)
			(xy 98.108783 109.256627) (xy 98.100871 109.171244) (xy 98.085115 109.086954) (xy 98.061648 109.004478)
			(xy 98.030672 108.924519) (xy 97.99245 108.847759) (xy 97.947309 108.774853) (xy 97.895633 108.706424)
			(xy 97.837864 108.643054) (xy 97.774494 108.585285) (xy 97.706065 108.533609) (xy 97.633159 108.488468)
			(xy 97.556399 108.450246) (xy 97.47644 108.41927) (xy 97.393964 108.395803) (xy 97.309674 108.380047)
			(xy 97.224291 108.372135) (xy 97.138541 108.372135) (xy 97.053158 108.380047) (xy 96.968868 108.395803)
			(xy 96.886392 108.41927) (xy 96.806433 108.450246) (xy 96.729673 108.488468) (xy 96.656767 108.533609)
			(xy 96.588338 108.585285) (xy 96.524968 108.643054) (xy 96.467199 108.706424) (xy 96.415523 108.774853)
			(xy 96.370382 108.847759) (xy 96.33216 108.924519) (xy 96.301184 109.004478) (xy 96.277717 109.086954)
			(xy 96.261961 109.171244) (xy 96.254049 109.256627) (xy 95.568783 109.256627) (xy 95.560871 109.171244)
			(xy 95.545115 109.086954) (xy 95.521648 109.004478) (xy 95.490672 108.924519) (xy 95.45245 108.847759)
			(xy 95.407309 108.774853) (xy 95.355633 108.706424) (xy 95.297864 108.643054) (xy 95.234494 108.585285)
			(xy 95.166065 108.533609) (xy 95.093159 108.488468) (xy 95.016399 108.450246) (xy 94.93644 108.41927)
			(xy 94.853964 108.395803) (xy 94.769674 108.380047) (xy 94.684291 108.372135) (xy 94.598541 108.372135)
			(xy 94.513158 108.380047) (xy 94.428868 108.395803) (xy 94.346392 108.41927) (xy 94.266433 108.450246)
			(xy 94.189673 108.488468) (xy 94.116767 108.533609) (xy 94.048338 108.585285) (xy 93.984968 108.643054)
			(xy 93.927199 108.706424) (xy 93.875523 108.774853) (xy 93.830382 108.847759) (xy 93.79216 108.924519)
			(xy 93.761184 109.004478) (xy 93.737717 109.086954) (xy 93.721961 109.171244) (xy 93.714049 109.256627)
			(xy 92.50807 109.256627) (xy 92.50807 56.800039) (xy 93.729289 56.800039) (xy 93.729289 56.885789)
			(xy 93.737201 56.971172) (xy 93.752957 57.055462) (xy 93.776424 57.137938) (xy 93.8074 57.217897)
			(xy 93.845622 57.294657) (xy 93.890763 57.367563) (xy 93.942439 57.435992) (xy 94.000208 57.499362)
			(xy 94.063578 57.557131) (xy 94.132007 57.608807) (xy 94.204913 57.653948) (xy 94.281673 57.69217)
			(xy 94.361632 57.723146) (xy 94.444108 57.746613) (xy 94.528398 57.762369) (xy 94.613781 57.770281)
			(xy 94.699531 57.770281) (xy 94.784914 57.762369) (xy 94.869204 57.746613) (xy 94.95168 57.723146)
			(xy 95.031639 57.69217) (xy 95.108399 57.653948) (xy 95.181305 57.608807) (xy 95.249734 57.557131)
			(xy 95.313104 57.499362) (xy 95.370873 57.435992) (xy 95.422549 57.367563) (xy 95.46769 57.294657)
			(xy 95.505912 57.217897) (xy 95.536888 57.137938) (xy 95.560355 57.055462) (xy 95.576111 56.971172)
			(xy 95.584023 56.885789) (xy 95.584518 56.842914) (xy 95.584023 56.800039) (xy 96.269289 56.800039)
			(xy 96.269289 56.885789) (xy 96.277201 56.971172) (xy 96.292957 57.055462) (xy 96.316424 57.137938)
			(xy 96.3474 57.217897) (xy 96.385622 57.294657) (xy 96.430763 57.367563) (xy 96.482439 57.435992)
			(xy 96.540208 57.499362) (xy 96.603578 57.557131) (xy 96.672007 57.608807) (xy 96.744913 57.653948)
			(xy 96.821673 57.69217) (xy 96.901632 57.723146) (xy 96.984108 57.746613) (xy 97.068398 57.762369)
			(xy 97.153781 57.770281) (xy 97.239531 57.770281) (xy 97.324914 57.762369) (xy 97.409204 57.746613)
			(xy 97.49168 57.723146) (xy 97.571639 57.69217) (xy 97.648399 57.653948) (xy 97.721305 57.608807)
			(xy 97.789734 57.557131) (xy 97.853104 57.499362) (xy 97.910873 57.435992) (xy 97.962549 57.367563)
			(xy 98.00769 57.294657) (xy 98.045912 57.217897) (xy 98.076888 57.137938) (xy 98.100355 57.055462)
			(xy 98.116111 56.971172) (xy 98.124023 56.885789) (xy 98.124518 56.842914) (xy 98.124023 56.800039)
			(xy 98.116111 56.714656) (xy 98.100355 56.630366) (xy 98.076888 56.54789) (xy 98.045912 56.467931)
			(xy 98.00769 56.391171) (xy 97.962549 56.318265) (xy 97.910873 56.249836) (xy 97.853104 56.186466)
			(xy 97.789734 56.128697) (xy 97.721305 56.077021) (xy 97.648399 56.03188) (xy 97.571639 55.993658)
			(xy 97.49168 55.962682) (xy 97.409204 55.939215) (xy 97.324914 55.923459) (xy 97.239531 55.915547)
			(xy 97.153781 55.915547) (xy 97.068398 55.923459) (xy 96.984108 55.939215) (xy 96.901632 55.962682)
			(xy 96.821673 55.993658) (xy 96.744913 56.03188) (xy 96.672007 56.077021) (xy 96.603578 56.128697)
			(xy 96.540208 56.186466) (xy 96.482439 56.249836) (xy 96.430763 56.318265) (xy 96.385622 56.391171)
			(xy 96.3474 56.467931) (xy 96.316424 56.54789) (xy 96.292957 56.630366) (xy 96.277201 56.714656)
			(xy 96.269289 56.800039) (xy 95.584023 56.800039) (xy 95.576111 56.714656) (xy 95.560355 56.630366)
			(xy 95.536888 56.54789) (xy 95.505912 56.467931) (xy 95.46769 56.391171) (xy 95.422549 56.318265)
			(xy 95.370873 56.249836) (xy 95.313104 56.186466) (xy 95.249734 56.128697) (xy 95.181305 56.077021)
			(xy 95.108399 56.03188) (xy 95.031639 55.993658) (xy 94.95168 55.962682) (xy 94.869204 55.939215)
			(xy 94.784914 55.923459) (xy 94.699531 55.915547) (xy 94.613781 55.915547) (xy 94.528398 55.923459)
			(xy 94.444108 55.939215) (xy 94.361632 55.962682) (xy 94.281673 55.993658) (xy 94.204913 56.03188)
			(xy 94.132007 56.077021) (xy 94.063578 56.128697) (xy 94.000208 56.186466) (xy 93.942439 56.249836)
			(xy 93.890763 56.318265) (xy 93.845622 56.391171) (xy 93.8074 56.467931) (xy 93.776424 56.54789)
			(xy 93.752957 56.630366) (xy 93.737201 56.714656) (xy 93.729289 56.800039) (xy 92.50807 56.800039)
			(xy 92.50807 54.853586) (xy 95.113348 54.853586) (xy 95.113837 54.880844) (xy 95.12159 54.934806)
			(xy 95.136941 54.987115) (xy 95.159578 55.036709) (xy 95.18904 55.082579) (xy 95.224727 55.12379)
			(xy 95.265915 55.159505) (xy 95.311764 55.188998) (xy 95.361343 55.211668) (xy 95.413642 55.227055)
			(xy 95.467598 55.234845) (xy 95.494856 55.235348) (xy 96.358456 55.235348) (xy 96.385717 55.234803)
			(xy 96.439686 55.227047) (xy 96.492 55.211685) (xy 96.541594 55.189032) (xy 96.587458 55.159549)
			(xy 96.628657 55.123836) (xy 96.664351 55.082622) (xy 96.693814 55.036745) (xy 96.716445 54.98714)
			(xy 96.731783 54.934819) (xy 96.739515 54.880848) (xy 96.739964 54.853586) (xy 96.739384 54.825045)
			(xy 96.730909 54.768597) (xy 96.71412 54.71404) (xy 96.689392 54.662593) (xy 96.657277 54.615404)
			(xy 96.61849 54.573525) (xy 96.573899 54.53789) (xy 96.549464 54.523132) (xy 96.549464 53.724556)
			(xy 95.298768 53.724556) (xy 95.298768 54.52618) (xy 95.274922 54.541086) (xy 95.231459 54.576767)
			(xy 95.1937 54.618438) (xy 95.162463 54.665197) (xy 95.138423 54.716032) (xy 95.122101 54.769845)
			(xy 95.113849 54.825469) (xy 95.113348 54.853586) (xy 92.50807 54.853586) (xy 92.50807 50.450039)
			(xy 93.729289 50.450039) (xy 93.729289 50.535789) (xy 93.737201 50.621172) (xy 93.752957 50.705462)
			(xy 93.776424 50.787938) (xy 93.8074 50.867897) (xy 93.845622 50.944657) (xy 93.890763 51.017563)
			(xy 93.942439 51.085992) (xy 94.000208 51.149362) (xy 94.063578 51.207131) (xy 94.132007 51.258807)
			(xy 94.204913 51.303948) (xy 94.281673 51.34217) (xy 94.361632 51.373146) (xy 94.444108 51.396613)
			(xy 94.528398 51.412369) (xy 94.613781 51.420281) (xy 94.699531 51.420281) (xy 94.784914 51.412369)
			(xy 94.869204 51.396613) (xy 94.95168 51.373146) (xy 95.031639 51.34217) (xy 95.108399 51.303948)
			(xy 95.181305 51.258807) (xy 95.249734 51.207131) (xy 95.313104 51.149362) (xy 95.370873 51.085992)
			(xy 95.422549 51.017563) (xy 95.46769 50.944657) (xy 95.505912 50.867897) (xy 95.536888 50.787938)
			(xy 95.560355 50.705462) (xy 95.576111 50.621172) (xy 95.584023 50.535789) (xy 95.584518 50.492914)
			(xy 95.584023 50.450039) (xy 96.269289 50.450039) (xy 96.269289 50.535789) (xy 96.277201 50.621172)
			(xy 96.292957 50.705462) (xy 96.316424 50.787938) (xy 96.3474 50.867897) (xy 96.385622 50.944657)
			(xy 96.430763 51.017563) (xy 96.482439 51.085992) (xy 96.540208 51.149362) (xy 96.603578 51.207131)
			(xy 96.672007 51.258807) (xy 96.744913 51.303948) (xy 96.821673 51.34217) (xy 96.901632 51.373146)
			(xy 96.984108 51.396613) (xy 97.068398 51.412369) (xy 97.153781 51.420281) (xy 97.239531 51.420281)
			(xy 97.324914 51.412369) (xy 97.409204 51.396613) (xy 97.49168 51.373146) (xy 97.571639 51.34217)
			(xy 97.648399 51.303948) (xy 97.721305 51.258807) (xy 97.789734 51.207131) (xy 97.853104 51.149362)
			(xy 97.910873 51.085992) (xy 97.962549 51.017563) (xy 98.00769 50.944657) (xy 98.045912 50.867897)
			(xy 98.076888 50.787938) (xy 98.100355 50.705462) (xy 98.116111 50.621172) (xy 98.124023 50.535789)
			(xy 98.124518 50.492914) (xy 98.124023 50.450039) (xy 98.116111 50.364656) (xy 98.100355 50.280366)
			(xy 98.076888 50.19789) (xy 98.045912 50.117931) (xy 98.00769 50.041171) (xy 97.962549 49.968265)
			(xy 97.910873 49.899836) (xy 97.853104 49.836466) (xy 97.789734 49.778697) (xy 97.721305 49.727021)
			(xy 97.648399 49.68188) (xy 97.571639 49.643658) (xy 97.49168 49.612682) (xy 97.409204 49.589215)
			(xy 97.324914 49.573459) (xy 97.239531 49.565547) (xy 97.153781 49.565547) (xy 97.068398 49.573459)
			(xy 96.984108 49.589215) (xy 96.901632 49.612682) (xy 96.821673 49.643658) (xy 96.744913 49.68188)
			(xy 96.672007 49.727021) (xy 96.603578 49.778697) (xy 96.540208 49.836466) (xy 96.482439 49.899836)
			(xy 96.430763 49.968265) (xy 96.385622 50.041171) (xy 96.3474 50.117931) (xy 96.316424 50.19789)
			(xy 96.292957 50.280366) (xy 96.277201 50.364656) (xy 96.269289 50.450039) (xy 95.584023 50.450039)
			(xy 95.576111 50.364656) (xy 95.560355 50.280366) (xy 95.536888 50.19789) (xy 95.505912 50.117931)
			(xy 95.46769 50.041171) (xy 95.422549 49.968265) (xy 95.370873 49.899836) (xy 95.313104 49.836466)
			(xy 95.249734 49.778697) (xy 95.181305 49.727021) (xy 95.108399 49.68188) (xy 95.031639 49.643658)
			(xy 94.95168 49.612682) (xy 94.869204 49.589215) (xy 94.784914 49.573459) (xy 94.699531 49.565547)
			(xy 94.613781 49.565547) (xy 94.528398 49.573459) (xy 94.444108 49.589215) (xy 94.361632 49.612682)
			(xy 94.281673 49.643658) (xy 94.204913 49.68188) (xy 94.132007 49.727021) (xy 94.063578 49.778697)
			(xy 94.000208 49.836466) (xy 93.942439 49.899836) (xy 93.890763 49.968265) (xy 93.845622 50.041171)
			(xy 93.8074 50.117931) (xy 93.776424 50.19789) (xy 93.752957 50.280366) (xy 93.737201 50.364656)
			(xy 93.729289 50.450039) (xy 92.50807 50.450039) (xy 92.50807 44.925539) (xy 93.706937 44.925539)
			(xy 93.706937 45.011289) (xy 93.714849 45.096672) (xy 93.730605 45.180962) (xy 93.754072 45.263438)
			(xy 93.785048 45.343397) (xy 93.82327 45.420157) (xy 93.868411 45.493063) (xy 93.920087 45.561492)
			(xy 93.977856 45.624862) (xy 94.041226 45.682631) (xy 94.109655 45.734307) (xy 94.182561 45.779448)
			(xy 94.259321 45.81767) (xy 94.33928 45.848646) (xy 94.421756 45.872113) (xy 94.506046 45.887869)
			(xy 94.591429 45.895781) (xy 94.677179 45.895781) (xy 94.762562 45.887869) (xy 94.846852 45.872113)
			(xy 94.929328 45.848646) (xy 95.009287 45.81767) (xy 95.086047 45.779448) (xy 95.158953 45.734307)
			(xy 95.227382 45.682631) (xy 95.290752 45.624862) (xy 95.348521 45.561492) (xy 95.400197 45.493063)
			(xy 95.445338 45.420157) (xy 95.48356 45.343397) (xy 95.514536 45.263438) (xy 95.538003 45.180962)
			(xy 95.553759 45.096672) (xy 95.561671 45.011289) (xy 95.562166 44.968414) (xy 95.561671 44.925539)
			(xy 96.246937 44.925539) (xy 96.246937 45.011289) (xy 96.254849 45.096672) (xy 96.270605 45.180962)
			(xy 96.294072 45.263438) (xy 96.325048 45.343397) (xy 96.36327 45.420157) (xy 96.408411 45.493063)
			(xy 96.460087 45.561492) (xy 96.517856 45.624862) (xy 96.581226 45.682631) (xy 96.649655 45.734307)
			(xy 96.722561 45.779448) (xy 96.799321 45.81767) (xy 96.87928 45.848646) (xy 96.961756 45.872113)
			(xy 97.046046 45.887869) (xy 97.131429 45.895781) (xy 97.217179 45.895781) (xy 97.302562 45.887869)
			(xy 97.386852 45.872113) (xy 97.469328 45.848646) (xy 97.549287 45.81767) (xy 97.626047 45.779448)
			(xy 97.698953 45.734307) (xy 97.767382 45.682631) (xy 97.830752 45.624862) (xy 97.888521 45.561492)
			(xy 97.940197 45.493063) (xy 97.985338 45.420157) (xy 98.02356 45.343397) (xy 98.054536 45.263438)
			(xy 98.078003 45.180962) (xy 98.093759 45.096672) (xy 98.101671 45.011289) (xy 98.102166 44.968414)
			(xy 98.101671 44.925539) (xy 98.093759 44.840156) (xy 98.078003 44.755866) (xy 98.054536 44.67339)
			(xy 98.02356 44.593431) (xy 97.985338 44.516671) (xy 97.940197 44.443765) (xy 97.888521 44.375336)
			(xy 97.830752 44.311966) (xy 97.767382 44.254197) (xy 97.698953 44.202521) (xy 97.626047 44.15738)
			(xy 97.549287 44.119158) (xy 97.469328 44.088182) (xy 97.386852 44.064715) (xy 97.302562 44.048959)
			(xy 97.217179 44.041047) (xy 97.131429 44.041047) (xy 97.046046 44.048959) (xy 96.961756 44.064715)
			(xy 96.87928 44.088182) (xy 96.799321 44.119158) (xy 96.722561 44.15738) (xy 96.649655 44.202521)
			(xy 96.581226 44.254197) (xy 96.517856 44.311966) (xy 96.460087 44.375336) (xy 96.408411 44.443765)
			(xy 96.36327 44.516671) (xy 96.325048 44.593431) (xy 96.294072 44.67339) (xy 96.270605 44.755866)
			(xy 96.254849 44.840156) (xy 96.246937 44.925539) (xy 95.561671 44.925539) (xy 95.553759 44.840156)
			(xy 95.538003 44.755866) (xy 95.514536 44.67339) (xy 95.48356 44.593431) (xy 95.445338 44.516671)
			(xy 95.400197 44.443765) (xy 95.348521 44.375336) (xy 95.290752 44.311966) (xy 95.227382 44.254197)
			(xy 95.158953 44.202521) (xy 95.086047 44.15738) (xy 95.009287 44.119158) (xy 94.929328 44.088182)
			(xy 94.846852 44.064715) (xy 94.762562 44.048959) (xy 94.677179 44.041047) (xy 94.591429 44.041047)
			(xy 94.506046 44.048959) (xy 94.421756 44.064715) (xy 94.33928 44.088182) (xy 94.259321 44.119158)
			(xy 94.182561 44.15738) (xy 94.109655 44.202521) (xy 94.041226 44.254197) (xy 93.977856 44.311966)
			(xy 93.920087 44.375336) (xy 93.868411 44.443765) (xy 93.82327 44.516671) (xy 93.785048 44.593431)
			(xy 93.754072 44.67339) (xy 93.730605 44.755866) (xy 93.714849 44.840156) (xy 93.706937 44.925539)
			(xy 92.50807 44.925539) (xy 92.50807 40.580426) (xy 95.09116 40.580426) (xy 95.09116 40.634974) (xy 95.098923 40.688967)
			(xy 95.114291 40.741306) (xy 95.136951 40.790925) (xy 95.166442 40.836814) (xy 95.202164 40.878039)
			(xy 95.243389 40.91376) (xy 95.289279 40.943251) (xy 95.338898 40.965911) (xy 95.391237 40.981278)
			(xy 95.44523 40.989041) (xy 95.472504 40.989504) (xy 96.336104 40.989504) (xy 96.36337 40.988933)
			(xy 96.417347 40.981172) (xy 96.469671 40.965808) (xy 96.519275 40.943154) (xy 96.56515 40.913671)
			(xy 96.606363 40.87796) (xy 96.642074 40.836747) (xy 96.671556 40.790871) (xy 96.69421 40.741267)
			(xy 96.709573 40.688944) (xy 96.717334 40.634966) (xy 96.717334 40.580434) (xy 96.709573 40.526456)
			(xy 96.69421 40.474133) (xy 96.671556 40.424529) (xy 96.642074 40.378653) (xy 96.606363 40.33744)
			(xy 96.56515 40.301729) (xy 96.519275 40.272246) (xy 96.469671 40.249592) (xy 96.417347 40.234228)
			(xy 96.36337 40.226467) (xy 96.336104 40.22598) (xy 95.472504 40.22598) (xy 95.44523 40.226359) (xy 95.391237 40.234122)
			(xy 95.338898 40.249489) (xy 95.289279 40.272149) (xy 95.243389 40.30164) (xy 95.202164 40.337361)
			(xy 95.166442 40.378586) (xy 95.136951 40.424475) (xy 95.114291 40.474094) (xy 95.098923 40.526433)
			(xy 95.09116 40.580426) (xy 92.50807 40.580426) (xy 92.50807 38.575539) (xy 93.706937 38.575539)
			(xy 93.706937 38.661289) (xy 93.714849 38.746672) (xy 93.730605 38.830962) (xy 93.754072 38.913438)
			(xy 93.785048 38.993397) (xy 93.82327 39.070157) (xy 93.868411 39.143063) (xy 93.920087 39.211492)
			(xy 93.977856 39.274862) (xy 94.041226 39.332631) (xy 94.109655 39.384307) (xy 94.182561 39.429448)
			(xy 94.259321 39.46767) (xy 94.33928 39.498646) (xy 94.421756 39.522113) (xy 94.506046 39.537869)
			(xy 94.591429 39.545781) (xy 94.677179 39.545781) (xy 94.762562 39.537869) (xy 94.846852 39.522113)
			(xy 94.929328 39.498646) (xy 95.009287 39.46767) (xy 95.086047 39.429448) (xy 95.158953 39.384307)
			(xy 95.227382 39.332631) (xy 95.290752 39.274862) (xy 95.348521 39.211492) (xy 95.400197 39.143063)
			(xy 95.445338 39.070157) (xy 95.48356 38.993397) (xy 95.514536 38.913438) (xy 95.538003 38.830962)
			(xy 95.553759 38.746672) (xy 95.561671 38.661289) (xy 95.562166 38.618414) (xy 95.561671 38.575539)
			(xy 96.246937 38.575539) (xy 96.246937 38.661289) (xy 96.254849 38.746672) (xy 96.270605 38.830962)
			(xy 96.294072 38.913438) (xy 96.325048 38.993397) (xy 96.36327 39.070157) (xy 96.408411 39.143063)
			(xy 96.460087 39.211492) (xy 96.517856 39.274862) (xy 96.581226 39.332631) (xy 96.649655 39.384307)
			(xy 96.722561 39.429448) (xy 96.799321 39.46767) (xy 96.87928 39.498646) (xy 96.961756 39.522113)
			(xy 97.046046 39.537869) (xy 97.131429 39.545781) (xy 97.217179 39.545781) (xy 97.302562 39.537869)
			(xy 97.386852 39.522113) (xy 97.469328 39.498646) (xy 97.549287 39.46767) (xy 97.626047 39.429448)
			(xy 97.698953 39.384307) (xy 97.767382 39.332631) (xy 97.830752 39.274862) (xy 97.888521 39.211492)
			(xy 97.940197 39.143063) (xy 97.985338 39.070157) (xy 98.02356 38.993397) (xy 98.054536 38.913438)
			(xy 98.078003 38.830962) (xy 98.093759 38.746672) (xy 98.101671 38.661289) (xy 98.102166 38.618414)
			(xy 98.101671 38.575539) (xy 98.093759 38.490156) (xy 98.078003 38.405866) (xy 98.054536 38.32339)
			(xy 98.02356 38.243431) (xy 97.985338 38.166671) (xy 97.940197 38.093765) (xy 97.888521 38.025336)
			(xy 97.830752 37.961966) (xy 97.767382 37.904197) (xy 97.698953 37.852521) (xy 97.626047 37.80738)
			(xy 97.549287 37.769158) (xy 97.469328 37.738182) (xy 97.386852 37.714715) (xy 97.302562 37.698959)
			(xy 97.217179 37.691047) (xy 97.131429 37.691047) (xy 97.046046 37.698959) (xy 96.961756 37.714715)
			(xy 96.87928 37.738182) (xy 96.799321 37.769158) (xy 96.722561 37.80738) (xy 96.649655 37.852521)
			(xy 96.581226 37.904197) (xy 96.517856 37.961966) (xy 96.460087 38.025336) (xy 96.408411 38.093765)
			(xy 96.36327 38.166671) (xy 96.325048 38.243431) (xy 96.294072 38.32339) (xy 96.270605 38.405866)
			(xy 96.254849 38.490156) (xy 96.246937 38.575539) (xy 95.561671 38.575539) (xy 95.553759 38.490156)
			(xy 95.538003 38.405866) (xy 95.514536 38.32339) (xy 95.48356 38.243431) (xy 95.445338 38.166671)
			(xy 95.400197 38.093765) (xy 95.348521 38.025336) (xy 95.290752 37.961966) (xy 95.227382 37.904197)
			(xy 95.158953 37.852521) (xy 95.086047 37.80738) (xy 95.009287 37.769158) (xy 94.929328 37.738182)
			(xy 94.846852 37.714715) (xy 94.762562 37.698959) (xy 94.677179 37.691047) (xy 94.591429 37.691047)
			(xy 94.506046 37.698959) (xy 94.421756 37.714715) (xy 94.33928 37.738182) (xy 94.259321 37.769158)
			(xy 94.182561 37.80738) (xy 94.109655 37.852521) (xy 94.041226 37.904197) (xy 93.977856 37.961966)
			(xy 93.920087 38.025336) (xy 93.868411 38.093765) (xy 93.82327 38.166671) (xy 93.785048 38.243431)
			(xy 93.754072 38.32339) (xy 93.730605 38.405866) (xy 93.714849 38.490156) (xy 93.706937 38.575539)
			(xy 92.50807 38.575539) (xy 92.50807 32.685787) (xy 99.092753 32.685787) (xy 99.092753 32.771537)
			(xy 99.100665 32.85692) (xy 99.116421 32.94121) (xy 99.139888 33.023686) (xy 99.170864 33.103645)
			(xy 99.209086 33.180405) (xy 99.254227 33.253311) (xy 99.305903 33.32174) (xy 99.363672 33.38511)
			(xy 99.427042 33.442879) (xy 99.495471 33.494555) (xy 99.568377 33.539696) (xy 99.645137 33.577918)
			(xy 99.725096 33.608894) (xy 99.807572 33.632361) (xy 99.891862 33.648117) (xy 99.977245 33.656029)
			(xy 100.062995 33.656029) (xy 100.148378 33.648117) (xy 100.232668 33.632361) (xy 100.315144 33.608894)
			(xy 100.395103 33.577918) (xy 100.471863 33.539696) (xy 100.544769 33.494555) (xy 100.613198 33.442879)
			(xy 100.676568 33.38511) (xy 100.734337 33.32174) (xy 100.786013 33.253311) (xy 100.831154 33.180405)
			(xy 100.869376 33.103645) (xy 100.900352 33.023686) (xy 100.923819 32.94121) (xy 100.939575 32.85692)
			(xy 100.947487 32.771537) (xy 100.947982 32.728662) (xy 100.947487 32.685787) (xy 101.632753 32.685787)
			(xy 101.632753 32.771537) (xy 101.640665 32.85692) (xy 101.656421 32.94121) (xy 101.679888 33.023686)
			(xy 101.710864 33.103645) (xy 101.749086 33.180405) (xy 101.794227 33.253311) (xy 101.845903 33.32174)
			(xy 101.903672 33.38511) (xy 101.967042 33.442879) (xy 102.035471 33.494555) (xy 102.108377 33.539696)
			(xy 102.185137 33.577918) (xy 102.265096 33.608894) (xy 102.347572 33.632361) (xy 102.431862 33.648117)
			(xy 102.517245 33.656029) (xy 102.602995 33.656029) (xy 102.688378 33.648117) (xy 102.772668 33.632361)
			(xy 102.855144 33.608894) (xy 102.935103 33.577918) (xy 103.011863 33.539696) (xy 103.084769 33.494555)
			(xy 103.153198 33.442879) (xy 103.216568 33.38511) (xy 103.274337 33.32174) (xy 103.326013 33.253311)
			(xy 103.371154 33.180405) (xy 103.409376 33.103645) (xy 103.440352 33.023686) (xy 103.463819 32.94121)
			(xy 103.479575 32.85692) (xy 103.487487 32.771537) (xy 103.487982 32.728662) (xy 103.487487 32.685787)
			(xy 103.479575 32.600404) (xy 103.463819 32.516114) (xy 103.440352 32.433638) (xy 103.409376 32.353679)
			(xy 103.371154 32.276919) (xy 103.326013 32.204013) (xy 103.274337 32.135584) (xy 103.216568 32.072214)
			(xy 103.153198 32.014445) (xy 103.084769 31.962769) (xy 103.011863 31.917628) (xy 102.935103 31.879406)
			(xy 102.855144 31.84843) (xy 102.772668 31.824963) (xy 102.688378 31.809207) (xy 102.602995 31.801295)
			(xy 102.517245 31.801295) (xy 102.431862 31.809207) (xy 102.347572 31.824963) (xy 102.265096 31.84843)
			(xy 102.185137 31.879406) (xy 102.108377 31.917628) (xy 102.035471 31.962769) (xy 101.967042 32.014445)
			(xy 101.903672 32.072214) (xy 101.845903 32.135584) (xy 101.794227 32.204013) (xy 101.749086 32.276919)
			(xy 101.710864 32.353679) (xy 101.679888 32.433638) (xy 101.656421 32.516114) (xy 101.640665 32.600404)
			(xy 101.632753 32.685787) (xy 100.947487 32.685787) (xy 100.939575 32.600404) (xy 100.923819 32.516114)
			(xy 100.900352 32.433638) (xy 100.869376 32.353679) (xy 100.831154 32.276919) (xy 100.786013 32.204013)
			(xy 100.734337 32.135584) (xy 100.676568 32.072214) (xy 100.613198 32.014445) (xy 100.544769 31.962769)
			(xy 100.471863 31.917628) (xy 100.395103 31.879406) (xy 100.315144 31.84843) (xy 100.232668 31.824963)
			(xy 100.148378 31.809207) (xy 100.062995 31.801295) (xy 99.977245 31.801295) (xy 99.891862 31.809207)
			(xy 99.807572 31.824963) (xy 99.725096 31.84843) (xy 99.645137 31.879406) (xy 99.568377 31.917628)
			(xy 99.495471 31.962769) (xy 99.427042 32.014445) (xy 99.363672 32.072214) (xy 99.305903 32.135584)
			(xy 99.254227 32.204013) (xy 99.209086 32.276919) (xy 99.170864 32.353679) (xy 99.139888 32.433638)
			(xy 99.116421 32.516114) (xy 99.100665 32.600404) (xy 99.092753 32.685787) (xy 92.50807 32.685787)
			(xy 92.50807 30.739334) (xy 100.476812 30.739334) (xy 100.477292 30.766592) (xy 100.485051 30.820552)
			(xy 100.500406 30.872859) (xy 100.523046 30.922451) (xy 100.55251 30.968318) (xy 100.588198 31.009528)
			(xy 100.629385 31.045243) (xy 100.675233 31.074736) (xy 100.72481 31.097407) (xy 100.777108 31.112797)
			(xy 100.831063 31.120591) (xy 100.85832 31.121096) (xy 101.72192 31.121096) (xy 101.749185 31.120663)
			(xy 101.803161 31.112896) (xy 101.85548 31.097524) (xy 101.905078 31.07486) (xy 101.950944 31.045365)
			(xy 101.992143 31.009641) (xy 102.027837 30.968415) (xy 102.057297 30.922527) (xy 102.079924 30.872912)
			(xy 102.095257 30.820581) (xy 102.102983 30.7666) (xy 102.103428 30.739334) (xy 102.102907 30.710791)
			(xy 102.094424 30.654339) (xy 102.077626 30.59978) (xy 102.052888 30.548333) (xy 102.020763 30.501144)
			(xy 101.981968 30.459267) (xy 101.937367 30.423636) (xy 101.912928 30.40888) (xy 101.912928 29.610304)
			(xy 100.662232 29.610304) (xy 100.662232 30.411928) (xy 100.638356 30.426788) (xy 100.594894 30.462478)
			(xy 100.557139 30.504157) (xy 100.525905 30.550924) (xy 100.501871 30.601767) (xy 100.485554 30.655585)
			(xy 100.477309 30.711215) (xy 100.476812 30.739334) (xy 92.50807 30.739334) (xy 92.50807 26.335787)
			(xy 99.092753 26.335787) (xy 99.092753 26.421537) (xy 99.100665 26.50692) (xy 99.116421 26.59121)
			(xy 99.139888 26.673686) (xy 99.170864 26.753645) (xy 99.209086 26.830405) (xy 99.254227 26.903311)
			(xy 99.305903 26.97174) (xy 99.363672 27.03511) (xy 99.427042 27.092879) (xy 99.495471 27.144555)
			(xy 99.568377 27.189696) (xy 99.645137 27.227918) (xy 99.725096 27.258894) (xy 99.807572 27.282361)
			(xy 99.891862 27.298117) (xy 99.977245 27.306029) (xy 100.062995 27.306029) (xy 100.148378 27.298117)
			(xy 100.232668 27.282361) (xy 100.315144 27.258894) (xy 100.395103 27.227918) (xy 100.471863 27.189696)
			(xy 100.544769 27.144555) (xy 100.613198 27.092879) (xy 100.676568 27.03511) (xy 100.734337 26.97174)
			(xy 100.786013 26.903311) (xy 100.831154 26.830405) (xy 100.869376 26.753645) (xy 100.900352 26.673686)
			(xy 100.923819 26.59121) (xy 100.939575 26.50692) (xy 100.947487 26.421537) (xy 100.947982 26.378662)
			(xy 100.947487 26.335787) (xy 101.632753 26.335787) (xy 101.632753 26.421537) (xy 101.640665 26.50692)
			(xy 101.656421 26.59121) (xy 101.679888 26.673686) (xy 101.710864 26.753645) (xy 101.749086 26.830405)
			(xy 101.794227 26.903311) (xy 101.845903 26.97174) (xy 101.903672 27.03511) (xy 101.967042 27.092879)
			(xy 102.035471 27.144555) (xy 102.108377 27.189696) (xy 102.185137 27.227918) (xy 102.265096 27.258894)
			(xy 102.347572 27.282361) (xy 102.431862 27.298117) (xy 102.517245 27.306029) (xy 102.602995 27.306029)
			(xy 102.688378 27.298117) (xy 102.772668 27.282361) (xy 102.855144 27.258894) (xy 102.935103 27.227918)
			(xy 103.011863 27.189696) (xy 103.084769 27.144555) (xy 103.153198 27.092879) (xy 103.216568 27.03511)
			(xy 103.274337 26.97174) (xy 103.326013 26.903311) (xy 103.371154 26.830405) (xy 103.409376 26.753645)
			(xy 103.440352 26.673686) (xy 103.463819 26.59121) (xy 103.479575 26.50692) (xy 103.487487 26.421537)
			(xy 103.487982 26.378662) (xy 103.487487 26.335787) (xy 103.479575 26.250404) (xy 103.463819 26.166114)
			(xy 103.440352 26.083638) (xy 103.409376 26.003679) (xy 103.371154 25.926919) (xy 103.326013 25.854013)
			(xy 103.274337 25.785584) (xy 103.216568 25.722214) (xy 103.153198 25.664445) (xy 103.084769 25.612769)
			(xy 103.011863 25.567628) (xy 102.935103 25.529406) (xy 102.855144 25.49843) (xy 102.772668 25.474963)
			(xy 102.688378 25.459207) (xy 102.602995 25.451295) (xy 102.517245 25.451295) (xy 102.431862 25.459207)
			(xy 102.347572 25.474963) (xy 102.265096 25.49843) (xy 102.185137 25.529406) (xy 102.108377 25.567628)
			(xy 102.035471 25.612769) (xy 101.967042 25.664445) (xy 101.903672 25.722214) (xy 101.845903 25.785584)
			(xy 101.794227 25.854013) (xy 101.749086 25.926919) (xy 101.710864 26.003679) (xy 101.679888 26.083638)
			(xy 101.656421 26.166114) (xy 101.640665 26.250404) (xy 101.632753 26.335787) (xy 100.947487 26.335787)
			(xy 100.939575 26.250404) (xy 100.923819 26.166114) (xy 100.900352 26.083638) (xy 100.869376 26.003679)
			(xy 100.831154 25.926919) (xy 100.786013 25.854013) (xy 100.734337 25.785584) (xy 100.676568 25.722214)
			(xy 100.613198 25.664445) (xy 100.544769 25.612769) (xy 100.471863 25.567628) (xy 100.395103 25.529406)
			(xy 100.315144 25.49843) (xy 100.232668 25.474963) (xy 100.148378 25.459207) (xy 100.062995 25.451295)
			(xy 99.977245 25.451295) (xy 99.891862 25.459207) (xy 99.807572 25.474963) (xy 99.725096 25.49843)
			(xy 99.645137 25.529406) (xy 99.568377 25.567628) (xy 99.495471 25.612769) (xy 99.427042 25.664445)
			(xy 99.363672 25.722214) (xy 99.305903 25.785584) (xy 99.254227 25.854013) (xy 99.209086 25.926919)
			(xy 99.170864 26.003679) (xy 99.139888 26.083638) (xy 99.116421 26.166114) (xy 99.100665 26.250404)
			(xy 99.092753 26.335787) (xy 92.50807 26.335787) (xy 92.50807 20.841513) (xy 99.085133 20.841513)
			(xy 99.085133 20.927263) (xy 99.093045 21.012646) (xy 99.108801 21.096936) (xy 99.132268 21.179412)
			(xy 99.163244 21.259371) (xy 99.201466 21.336131) (xy 99.246607 21.409037) (xy 99.298283 21.477466)
			(xy 99.356052 21.540836) (xy 99.419422 21.598605) (xy 99.487851 21.650281) (xy 99.560757 21.695422)
			(xy 99.637517 21.733644) (xy 99.717476 21.76462) (xy 99.799952 21.788087) (xy 99.884242 21.803843)
			(xy 99.969625 21.811755) (xy 100.055375 21.811755) (xy 100.140758 21.803843) (xy 100.225048 21.788087)
			(xy 100.307524 21.76462) (xy 100.387483 21.733644) (xy 100.464243 21.695422) (xy 100.537149 21.650281)
			(xy 100.605578 21.598605) (xy 100.668948 21.540836) (xy 100.726717 21.477466) (xy 100.778393 21.409037)
			(xy 100.823534 21.336131) (xy 100.861756 21.259371) (xy 100.892732 21.179412) (xy 100.916199 21.096936)
			(xy 100.931955 21.012646) (xy 100.939867 20.927263) (xy 100.940362 20.884388) (xy 100.939867 20.841513)
			(xy 101.625133 20.841513) (xy 101.625133 20.927263) (xy 101.633045 21.012646) (xy 101.648801 21.096936)
			(xy 101.672268 21.179412) (xy 101.703244 21.259371) (xy 101.741466 21.336131) (xy 101.786607 21.409037)
			(xy 101.838283 21.477466) (xy 101.896052 21.540836) (xy 101.959422 21.598605) (xy 102.027851 21.650281)
			(xy 102.100757 21.695422) (xy 102.177517 21.733644) (xy 102.257476 21.76462) (xy 102.339952 21.788087)
			(xy 102.424242 21.803843) (xy 102.509625 21.811755) (xy 102.595375 21.811755) (xy 102.680758 21.803843)
			(xy 102.765048 21.788087) (xy 102.847524 21.76462) (xy 102.927483 21.733644) (xy 103.004243 21.695422)
			(xy 103.077149 21.650281) (xy 103.145578 21.598605) (xy 103.208948 21.540836) (xy 103.266717 21.477466)
			(xy 103.318393 21.409037) (xy 103.363534 21.336131) (xy 103.401756 21.259371) (xy 103.432732 21.179412)
			(xy 103.456199 21.096936) (xy 103.471955 21.012646) (xy 103.479867 20.927263) (xy 103.480362 20.884388)
			(xy 103.479867 20.841513) (xy 104.165133 20.841513) (xy 104.165133 20.927263) (xy 104.173045 21.012646)
			(xy 104.188801 21.096936) (xy 104.212268 21.179412) (xy 104.243244 21.259371) (xy 104.281466 21.336131)
			(xy 104.326607 21.409037) (xy 104.378283 21.477466) (xy 104.436052 21.540836) (xy 104.499422 21.598605)
			(xy 104.567851 21.650281) (xy 104.640757 21.695422) (xy 104.717517 21.733644) (xy 104.797476 21.76462)
			(xy 104.879952 21.788087) (xy 104.964242 21.803843) (xy 105.049625 21.811755) (xy 105.135375 21.811755)
			(xy 105.220758 21.803843) (xy 105.305048 21.788087) (xy 105.387524 21.76462) (xy 105.467483 21.733644)
			(xy 105.544243 21.695422) (xy 105.617149 21.650281) (xy 105.685578 21.598605) (xy 105.748948 21.540836)
			(xy 105.806717 21.477466) (xy 105.858393 21.409037) (xy 105.903534 21.336131) (xy 105.941756 21.259371)
			(xy 105.972732 21.179412) (xy 105.996199 21.096936) (xy 106.011955 21.012646) (xy 106.019867 20.927263)
			(xy 106.020362 20.884388) (xy 106.019867 20.841513) (xy 106.011955 20.75613) (xy 105.996199 20.67184)
			(xy 105.972732 20.589364) (xy 105.941756 20.509405) (xy 105.903534 20.432645) (xy 105.858393 20.359739)
			(xy 105.806717 20.29131) (xy 105.748948 20.22794) (xy 105.685578 20.170171) (xy 105.617149 20.118495)
			(xy 105.544243 20.073354) (xy 105.467483 20.035132) (xy 105.387524 20.004156) (xy 105.305048 19.980689)
			(xy 105.220758 19.964933) (xy 105.135375 19.957021) (xy 105.049625 19.957021) (xy 104.964242 19.964933)
			(xy 104.879952 19.980689) (xy 104.797476 20.004156) (xy 104.717517 20.035132) (xy 104.640757 20.073354)
			(xy 104.567851 20.118495) (xy 104.499422 20.170171) (xy 104.436052 20.22794) (xy 104.378283 20.29131)
			(xy 104.326607 20.359739) (xy 104.281466 20.432645) (xy 104.243244 20.509405) (xy 104.212268 20.589364)
			(xy 104.188801 20.67184) (xy 104.173045 20.75613) (xy 104.165133 20.841513) (xy 103.479867 20.841513)
			(xy 103.471955 20.75613) (xy 103.456199 20.67184) (xy 103.432732 20.589364) (xy 103.401756 20.509405)
			(xy 103.363534 20.432645) (xy 103.318393 20.359739) (xy 103.266717 20.29131) (xy 103.208948 20.22794)
			(xy 103.145578 20.170171) (xy 103.077149 20.118495) (xy 103.004243 20.073354) (xy 102.927483 20.035132)
			(xy 102.847524 20.004156) (xy 102.765048 19.980689) (xy 102.680758 19.964933) (xy 102.595375 19.957021)
			(xy 102.509625 19.957021) (xy 102.424242 19.964933) (xy 102.339952 19.980689) (xy 102.257476 20.004156)
			(xy 102.177517 20.035132) (xy 102.100757 20.073354) (xy 102.027851 20.118495) (xy 101.959422 20.170171)
			(xy 101.896052 20.22794) (xy 101.838283 20.29131) (xy 101.786607 20.359739) (xy 101.741466 20.432645)
			(xy 101.703244 20.509405) (xy 101.672268 20.589364) (xy 101.648801 20.67184) (xy 101.633045 20.75613)
			(xy 101.625133 20.841513) (xy 100.939867 20.841513) (xy 100.931955 20.75613) (xy 100.916199 20.67184)
			(xy 100.892732 20.589364) (xy 100.861756 20.509405) (xy 100.823534 20.432645) (xy 100.778393 20.359739)
			(xy 100.726717 20.29131) (xy 100.668948 20.22794) (xy 100.605578 20.170171) (xy 100.537149 20.118495)
			(xy 100.464243 20.073354) (xy 100.387483 20.035132) (xy 100.307524 20.004156) (xy 100.225048 19.980689)
			(xy 100.140758 19.964933) (xy 100.055375 19.957021) (xy 99.969625 19.957021) (xy 99.884242 19.964933)
			(xy 99.799952 19.980689) (xy 99.717476 20.004156) (xy 99.637517 20.035132) (xy 99.560757 20.073354)
			(xy 99.487851 20.118495) (xy 99.419422 20.170171) (xy 99.356052 20.22794) (xy 99.298283 20.29131)
			(xy 99.246607 20.359739) (xy 99.201466 20.432645) (xy 99.163244 20.509405) (xy 99.132268 20.589364)
			(xy 99.108801 20.67184) (xy 99.093045 20.75613) (xy 99.085133 20.841513) (xy 92.50807 20.841513)
			(xy 92.50807 17.653) (xy 100.659692 17.653) (xy 101.910388 17.653) (xy 101.910388 16.887444) (xy 100.659692 16.887444)
			(xy 100.659692 17.653) (xy 92.50807 17.653) (xy 92.50807 14.491513) (xy 99.085133 14.491513) (xy 99.085133 14.577263)
			(xy 99.093045 14.662646) (xy 99.108801 14.746936) (xy 99.132268 14.829412) (xy 99.163244 14.909371)
			(xy 99.201466 14.986131) (xy 99.246607 15.059037) (xy 99.298283 15.127466) (xy 99.356052 15.190836)
			(xy 99.419422 15.248605) (xy 99.487851 15.300281) (xy 99.560757 15.345422) (xy 99.637517 15.383644)
			(xy 99.717476 15.41462) (xy 99.799952 15.438087) (xy 99.884242 15.453843) (xy 99.969625 15.461755)
			(xy 100.055375 15.461755) (xy 100.140758 15.453843) (xy 100.225048 15.438087) (xy 100.307524 15.41462)
			(xy 100.387483 15.383644) (xy 100.464243 15.345422) (xy 100.537149 15.300281) (xy 100.605578 15.248605)
			(xy 100.668948 15.190836) (xy 100.726717 15.127466) (xy 100.778393 15.059037) (xy 100.823534 14.986131)
			(xy 100.861756 14.909371) (xy 100.892732 14.829412) (xy 100.916199 14.746936) (xy 100.931955 14.662646)
			(xy 100.939867 14.577263) (xy 100.940362 14.534388) (xy 100.939867 14.491513) (xy 101.625133 14.491513)
			(xy 101.625133 14.577263) (xy 101.633045 14.662646) (xy 101.648801 14.746936) (xy 101.672268 14.829412)
			(xy 101.703244 14.909371) (xy 101.741466 14.986131) (xy 101.786607 15.059037) (xy 101.838283 15.127466)
			(xy 101.896052 15.190836) (xy 101.959422 15.248605) (xy 102.027851 15.300281) (xy 102.100757 15.345422)
			(xy 102.177517 15.383644) (xy 102.257476 15.41462) (xy 102.339952 15.438087) (xy 102.424242 15.453843)
			(xy 102.509625 15.461755) (xy 102.595375 15.461755) (xy 102.680758 15.453843) (xy 102.765048 15.438087)
			(xy 102.847524 15.41462) (xy 102.927483 15.383644) (xy 103.004243 15.345422) (xy 103.077149 15.300281)
			(xy 103.145578 15.248605) (xy 103.208948 15.190836) (xy 103.266717 15.127466) (xy 103.318393 15.059037)
			(xy 103.363534 14.986131) (xy 103.401756 14.909371) (xy 103.432732 14.829412) (xy 103.456199 14.746936)
			(xy 103.471955 14.662646) (xy 103.479867 14.577263) (xy 103.480362 14.534388) (xy 103.479867 14.491513)
			(xy 104.165133 14.491513) (xy 104.165133 14.577263) (xy 104.173045 14.662646) (xy 104.188801 14.746936)
			(xy 104.212268 14.829412) (xy 104.243244 14.909371) (xy 104.281466 14.986131) (xy 104.326607 15.059037)
			(xy 104.378283 15.127466) (xy 104.436052 15.190836) (xy 104.499422 15.248605) (xy 104.567851 15.300281)
			(xy 104.640757 15.345422) (xy 104.717517 15.383644) (xy 104.797476 15.41462) (xy 104.879952 15.438087)
			(xy 104.964242 15.453843) (xy 105.049625 15.461755) (xy 105.135375 15.461755) (xy 105.220758 15.453843)
			(xy 105.305048 15.438087) (xy 105.387524 15.41462) (xy 105.467483 15.383644) (xy 105.544243 15.345422)
			(xy 105.617149 15.300281) (xy 105.685578 15.248605) (xy 105.748948 15.190836) (xy 105.806717 15.127466)
			(xy 105.858393 15.059037) (xy 105.903534 14.986131) (xy 105.941756 14.909371) (xy 105.972732 14.829412)
			(xy 105.996199 14.746936) (xy 106.011955 14.662646) (xy 106.019867 14.577263) (xy 106.020362 14.534388)
			(xy 106.019867 14.491513) (xy 106.011955 14.40613) (xy 105.996199 14.32184) (xy 105.972732 14.239364)
			(xy 105.941756 14.159405) (xy 105.903534 14.082645) (xy 105.858393 14.009739) (xy 105.806717 13.94131)
			(xy 105.748948 13.87794) (xy 105.685578 13.820171) (xy 105.617149 13.768495) (xy 105.544243 13.723354)
			(xy 105.467483 13.685132) (xy 105.387524 13.654156) (xy 105.305048 13.630689) (xy 105.220758 13.614933)
			(xy 105.135375 13.607021) (xy 105.049625 13.607021) (xy 104.964242 13.614933) (xy 104.879952 13.630689)
			(xy 104.797476 13.654156) (xy 104.717517 13.685132) (xy 104.640757 13.723354) (xy 104.567851 13.768495)
			(xy 104.499422 13.820171) (xy 104.436052 13.87794) (xy 104.378283 13.94131) (xy 104.326607 14.009739)
			(xy 104.281466 14.082645) (xy 104.243244 14.159405) (xy 104.212268 14.239364) (xy 104.188801 14.32184)
			(xy 104.173045 14.40613) (xy 104.165133 14.491513) (xy 103.479867 14.491513) (xy 103.471955 14.40613)
			(xy 103.456199 14.32184) (xy 103.432732 14.239364) (xy 103.401756 14.159405) (xy 103.363534 14.082645)
			(xy 103.318393 14.009739) (xy 103.266717 13.94131) (xy 103.208948 13.87794) (xy 103.145578 13.820171)
			(xy 103.077149 13.768495) (xy 103.004243 13.723354) (xy 102.927483 13.685132) (xy 102.847524 13.654156)
			(xy 102.765048 13.630689) (xy 102.680758 13.614933) (xy 102.595375 13.607021) (xy 102.509625 13.607021)
			(xy 102.424242 13.614933) (xy 102.339952 13.630689) (xy 102.257476 13.654156) (xy 102.177517 13.685132)
			(xy 102.100757 13.723354) (xy 102.027851 13.768495) (xy 101.959422 13.820171) (xy 101.896052 13.87794)
			(xy 101.838283 13.94131) (xy 101.786607 14.009739) (xy 101.741466 14.082645) (xy 101.703244 14.159405)
			(xy 101.672268 14.239364) (xy 101.648801 14.32184) (xy 101.633045 14.40613) (xy 101.625133 14.491513)
			(xy 100.939867 14.491513) (xy 100.931955 14.40613) (xy 100.916199 14.32184) (xy 100.892732 14.239364)
			(xy 100.861756 14.159405) (xy 100.823534 14.082645) (xy 100.778393 14.009739) (xy 100.726717 13.94131)
			(xy 100.668948 13.87794) (xy 100.605578 13.820171) (xy 100.537149 13.768495) (xy 100.464243 13.723354)
			(xy 100.387483 13.685132) (xy 100.307524 13.654156) (xy 100.225048 13.630689) (xy 100.140758 13.614933)
			(xy 100.055375 13.607021) (xy 99.969625 13.607021) (xy 99.884242 13.614933) (xy 99.799952 13.630689)
			(xy 99.717476 13.654156) (xy 99.637517 13.685132) (xy 99.560757 13.723354) (xy 99.487851 13.768495)
			(xy 99.419422 13.820171) (xy 99.356052 13.87794) (xy 99.298283 13.94131) (xy 99.246607 14.009739)
			(xy 99.201466 14.082645) (xy 99.163244 14.159405) (xy 99.132268 14.239364) (xy 99.108801 14.32184)
			(xy 99.093045 14.40613) (xy 99.085133 14.491513) (xy 92.50807 14.491513) (xy 92.50807 -1.181049)
			(xy 93.729289 -1.181049) (xy 93.729289 -1.095299) (xy 93.737201 -1.009916) (xy 93.752957 -0.925626)
			(xy 93.776424 -0.84315) (xy 93.8074 -0.763191) (xy 93.845622 -0.686431) (xy 93.890763 -0.613525)
			(xy 93.942439 -0.545096) (xy 94.000208 -0.481726) (xy 94.063578 -0.423957) (xy 94.132007 -0.372281)
			(xy 94.204913 -0.32714) (xy 94.281673 -0.288918) (xy 94.361632 -0.257942) (xy 94.444108 -0.234475)
			(xy 94.528398 -0.218719) (xy 94.613781 -0.210807) (xy 94.699531 -0.210807) (xy 94.784914 -0.218719)
			(xy 94.869204 -0.234475) (xy 94.95168 -0.257942) (xy 95.031639 -0.288918) (xy 95.108399 -0.32714)
			(xy 95.181305 -0.372281) (xy 95.249734 -0.423957) (xy 95.313104 -0.481726) (xy 95.370873 -0.545096)
			(xy 95.422549 -0.613525) (xy 95.46769 -0.686431) (xy 95.505912 -0.763191) (xy 95.536888 -0.84315)
			(xy 95.560355 -0.925626) (xy 95.576111 -1.009916) (xy 95.584023 -1.095299) (xy 95.584518 -1.138174)
			(xy 95.584023 -1.181049) (xy 96.269289 -1.181049) (xy 96.269289 -1.095299) (xy 96.277201 -1.009916)
			(xy 96.292957 -0.925626) (xy 96.316424 -0.84315) (xy 96.3474 -0.763191) (xy 96.385622 -0.686431)
			(xy 96.430763 -0.613525) (xy 96.482439 -0.545096) (xy 96.540208 -0.481726) (xy 96.603578 -0.423957)
			(xy 96.672007 -0.372281) (xy 96.744913 -0.32714) (xy 96.821673 -0.288918) (xy 96.901632 -0.257942)
			(xy 96.984108 -0.234475) (xy 97.068398 -0.218719) (xy 97.153781 -0.210807) (xy 97.239531 -0.210807)
			(xy 97.324914 -0.218719) (xy 97.409204 -0.234475) (xy 97.49168 -0.257942) (xy 97.571639 -0.288918)
			(xy 97.648399 -0.32714) (xy 97.721305 -0.372281) (xy 97.789734 -0.423957) (xy 97.853104 -0.481726)
			(xy 97.910873 -0.545096) (xy 97.962549 -0.613525) (xy 98.00769 -0.686431) (xy 98.045912 -0.763191)
			(xy 98.076888 -0.84315) (xy 98.100355 -0.925626) (xy 98.116111 -1.009916) (xy 98.124023 -1.095299)
			(xy 98.124518 -1.138174) (xy 98.124023 -1.181049) (xy 98.116111 -1.266432) (xy 98.100355 -1.350722)
			(xy 98.076888 -1.433198) (xy 98.045912 -1.513157) (xy 98.00769 -1.589917) (xy 97.962549 -1.662823)
			(xy 97.910873 -1.731252) (xy 97.853104 -1.794622) (xy 97.789734 -1.852391) (xy 97.721305 -1.904067)
			(xy 97.648399 -1.949208) (xy 97.571639 -1.98743) (xy 97.49168 -2.018406) (xy 97.409204 -2.041873)
			(xy 97.324914 -2.057629) (xy 97.239531 -2.065541) (xy 97.153781 -2.065541) (xy 97.068398 -2.057629)
			(xy 96.984108 -2.041873) (xy 96.901632 -2.018406) (xy 96.821673 -1.98743) (xy 96.744913 -1.949208)
			(xy 96.672007 -1.904067) (xy 96.603578 -1.852391) (xy 96.540208 -1.794622) (xy 96.482439 -1.731252)
			(xy 96.430763 -1.662823) (xy 96.385622 -1.589917) (xy 96.3474 -1.513157) (xy 96.316424 -1.433198)
			(xy 96.292957 -1.350722) (xy 96.277201 -1.266432) (xy 96.269289 -1.181049) (xy 95.584023 -1.181049)
			(xy 95.576111 -1.266432) (xy 95.560355 -1.350722) (xy 95.536888 -1.433198) (xy 95.505912 -1.513157)
			(xy 95.46769 -1.589917) (xy 95.422549 -1.662823) (xy 95.370873 -1.731252) (xy 95.313104 -1.794622)
			(xy 95.249734 -1.852391) (xy 95.181305 -1.904067) (xy 95.108399 -1.949208) (xy 95.031639 -1.98743)
			(xy 94.95168 -2.018406) (xy 94.869204 -2.041873) (xy 94.784914 -2.057629) (xy 94.699531 -2.065541)
			(xy 94.613781 -2.065541) (xy 94.528398 -2.057629) (xy 94.444108 -2.041873) (xy 94.361632 -2.018406)
			(xy 94.281673 -1.98743) (xy 94.204913 -1.949208) (xy 94.132007 -1.904067) (xy 94.063578 -1.852391)
			(xy 94.000208 -1.794622) (xy 93.942439 -1.731252) (xy 93.890763 -1.662823) (xy 93.845622 -1.589917)
			(xy 93.8074 -1.513157) (xy 93.776424 -1.433198) (xy 93.752957 -1.350722) (xy 93.737201 -1.266432)
			(xy 93.729289 -1.181049) (xy 92.50807 -1.181049) (xy 92.50807 -3.154767) (xy 95.113626 -3.154767)
			(xy 95.113626 -3.100233) (xy 95.121387 -3.046253) (xy 95.13675 -2.993928) (xy 95.159403 -2.944321)
			(xy 95.188884 -2.898442) (xy 95.224595 -2.857226) (xy 95.265807 -2.821511) (xy 95.311682 -2.792024)
			(xy 95.361286 -2.769365) (xy 95.41361 -2.753996) (xy 95.467589 -2.746229) (xy 95.494856 -2.74574)
			(xy 96.358456 -2.74574) (xy 96.385729 -2.746196) (xy 96.439721 -2.753954) (xy 96.492059 -2.769316)
			(xy 96.541678 -2.791971) (xy 96.587568 -2.821458) (xy 96.628793 -2.857176) (xy 96.664516 -2.898397)
			(xy 96.694008 -2.944283) (xy 96.716668 -2.993899) (xy 96.732037 -3.046236) (xy 96.7398 -3.100227)
			(xy 96.7398 -3.154773) (xy 96.732037 -3.208764) (xy 96.716668 -3.261101) (xy 96.694008 -3.310717)
			(xy 96.664516 -3.356603) (xy 96.628793 -3.397824) (xy 96.587568 -3.433542) (xy 96.541678 -3.463029)
			(xy 96.492059 -3.485684) (xy 96.439721 -3.501046) (xy 96.385729 -3.508804) (xy 96.358456 -3.509264)
			(xy 95.494856 -3.509264) (xy 95.467589 -3.508771) (xy 95.41361 -3.501004) (xy 95.361286 -3.485635)
			(xy 95.311682 -3.462976) (xy 95.265807 -3.433489) (xy 95.224595 -3.397774) (xy 95.188884 -3.356558)
			(xy 95.159403 -3.310679) (xy 95.13675 -3.261072) (xy 95.121387 -3.208747) (xy 95.113626 -3.154767)
			(xy 92.50807 -3.154767) (xy 92.50807 -7.531049) (xy 93.729289 -7.531049) (xy 93.729289 -7.445299)
			(xy 93.737201 -7.359916) (xy 93.752957 -7.275626) (xy 93.776424 -7.19315) (xy 93.8074 -7.113191)
			(xy 93.845622 -7.036431) (xy 93.890763 -6.963525) (xy 93.942439 -6.895096) (xy 94.000208 -6.831726)
			(xy 94.063578 -6.773957) (xy 94.132007 -6.722281) (xy 94.204913 -6.67714) (xy 94.281673 -6.638918)
			(xy 94.361632 -6.607942) (xy 94.444108 -6.584475) (xy 94.528398 -6.568719) (xy 94.613781 -6.560807)
			(xy 94.699531 -6.560807) (xy 94.784914 -6.568719) (xy 94.869204 -6.584475) (xy 94.95168 -6.607942)
			(xy 95.031639 -6.638918) (xy 95.108399 -6.67714) (xy 95.181305 -6.722281) (xy 95.249734 -6.773957)
			(xy 95.313104 -6.831726) (xy 95.370873 -6.895096) (xy 95.422549 -6.963525) (xy 95.46769 -7.036431)
			(xy 95.505912 -7.113191) (xy 95.536888 -7.19315) (xy 95.560355 -7.275626) (xy 95.576111 -7.359916)
			(xy 95.584023 -7.445299) (xy 95.584518 -7.488174) (xy 95.584023 -7.531049) (xy 96.269289 -7.531049)
			(xy 96.269289 -7.445299) (xy 96.277201 -7.359916) (xy 96.292957 -7.275626) (xy 96.316424 -7.19315)
			(xy 96.3474 -7.113191) (xy 96.385622 -7.036431) (xy 96.430763 -6.963525) (xy 96.482439 -6.895096)
			(xy 96.540208 -6.831726) (xy 96.603578 -6.773957) (xy 96.672007 -6.722281) (xy 96.744913 -6.67714)
			(xy 96.821673 -6.638918) (xy 96.901632 -6.607942) (xy 96.984108 -6.584475) (xy 97.068398 -6.568719)
			(xy 97.153781 -6.560807) (xy 97.239531 -6.560807) (xy 97.324914 -6.568719) (xy 97.409204 -6.584475)
			(xy 97.49168 -6.607942) (xy 97.571639 -6.638918) (xy 97.648399 -6.67714) (xy 97.721305 -6.722281)
			(xy 97.789734 -6.773957) (xy 97.853104 -6.831726) (xy 97.910873 -6.895096) (xy 97.962549 -6.963525)
			(xy 98.00769 -7.036431) (xy 98.045912 -7.113191) (xy 98.076888 -7.19315) (xy 98.100355 -7.275626)
			(xy 98.116111 -7.359916) (xy 98.124023 -7.445299) (xy 98.124518 -7.488174) (xy 98.124023 -7.531049)
			(xy 98.116111 -7.616432) (xy 98.100355 -7.700722) (xy 98.076888 -7.783198) (xy 98.045912 -7.863157)
			(xy 98.00769 -7.939917) (xy 97.962549 -8.012823) (xy 97.910873 -8.081252) (xy 97.853104 -8.144622)
			(xy 97.789734 -8.202391) (xy 97.721305 -8.254067) (xy 97.648399 -8.299208) (xy 97.571639 -8.33743)
			(xy 97.49168 -8.368406) (xy 97.409204 -8.391873) (xy 97.324914 -8.407629) (xy 97.239531 -8.415541)
			(xy 97.153781 -8.415541) (xy 97.068398 -8.407629) (xy 96.984108 -8.391873) (xy 96.901632 -8.368406)
			(xy 96.821673 -8.33743) (xy 96.744913 -8.299208) (xy 96.672007 -8.254067) (xy 96.603578 -8.202391)
			(xy 96.540208 -8.144622) (xy 96.482439 -8.081252) (xy 96.430763 -8.012823) (xy 96.385622 -7.939917)
			(xy 96.3474 -7.863157) (xy 96.316424 -7.783198) (xy 96.292957 -7.700722) (xy 96.277201 -7.616432)
			(xy 96.269289 -7.531049) (xy 95.584023 -7.531049) (xy 95.576111 -7.616432) (xy 95.560355 -7.700722)
			(xy 95.536888 -7.783198) (xy 95.505912 -7.863157) (xy 95.46769 -7.939917) (xy 95.422549 -8.012823)
			(xy 95.370873 -8.081252) (xy 95.313104 -8.144622) (xy 95.249734 -8.202391) (xy 95.181305 -8.254067)
			(xy 95.108399 -8.299208) (xy 95.031639 -8.33743) (xy 94.95168 -8.368406) (xy 94.869204 -8.391873)
			(xy 94.784914 -8.407629) (xy 94.699531 -8.415541) (xy 94.613781 -8.415541) (xy 94.528398 -8.407629)
			(xy 94.444108 -8.391873) (xy 94.361632 -8.368406) (xy 94.281673 -8.33743) (xy 94.204913 -8.299208)
			(xy 94.132007 -8.254067) (xy 94.063578 -8.202391) (xy 94.000208 -8.144622) (xy 93.942439 -8.081252)
			(xy 93.890763 -8.012823) (xy 93.845622 -7.939917) (xy 93.8074 -7.863157) (xy 93.776424 -7.783198)
			(xy 93.752957 -7.700722) (xy 93.737201 -7.616432) (xy 93.729289 -7.531049) (xy 92.50807 -7.531049)
			(xy 92.50807 -13.055549) (xy 93.714049 -13.055549) (xy 93.714049 -12.969799) (xy 93.721961 -12.884416)
			(xy 93.737717 -12.800126) (xy 93.761184 -12.71765) (xy 93.79216 -12.637691) (xy 93.830382 -12.560931)
			(xy 93.875523 -12.488025) (xy 93.927199 -12.419596) (xy 93.984968 -12.356226) (xy 94.048338 -12.298457)
			(xy 94.116767 -12.246781) (xy 94.189673 -12.20164) (xy 94.266433 -12.163418) (xy 94.346392 -12.132442)
			(xy 94.428868 -12.108975) (xy 94.513158 -12.093219) (xy 94.598541 -12.085307) (xy 94.684291 -12.085307)
			(xy 94.769674 -12.093219) (xy 94.853964 -12.108975) (xy 94.93644 -12.132442) (xy 95.016399 -12.163418)
			(xy 95.093159 -12.20164) (xy 95.166065 -12.246781) (xy 95.234494 -12.298457) (xy 95.297864 -12.356226)
			(xy 95.355633 -12.419596) (xy 95.407309 -12.488025) (xy 95.45245 -12.560931) (xy 95.490672 -12.637691)
			(xy 95.521648 -12.71765) (xy 95.545115 -12.800126) (xy 95.560871 -12.884416) (xy 95.568783 -12.969799)
			(xy 95.569278 -13.012674) (xy 95.568783 -13.055549) (xy 96.254049 -13.055549) (xy 96.254049 -12.969799)
			(xy 96.261961 -12.884416) (xy 96.277717 -12.800126) (xy 96.301184 -12.71765) (xy 96.33216 -12.637691)
			(xy 96.370382 -12.560931) (xy 96.415523 -12.488025) (xy 96.467199 -12.419596) (xy 96.524968 -12.356226)
			(xy 96.588338 -12.298457) (xy 96.656767 -12.246781) (xy 96.729673 -12.20164) (xy 96.806433 -12.163418)
			(xy 96.886392 -12.132442) (xy 96.968868 -12.108975) (xy 97.053158 -12.093219) (xy 97.138541 -12.085307)
			(xy 97.224291 -12.085307) (xy 97.309674 -12.093219) (xy 97.393964 -12.108975) (xy 97.47644 -12.132442)
			(xy 97.556399 -12.163418) (xy 97.633159 -12.20164) (xy 97.706065 -12.246781) (xy 97.774494 -12.298457)
			(xy 97.837864 -12.356226) (xy 97.895633 -12.419596) (xy 97.947309 -12.488025) (xy 97.99245 -12.560931)
			(xy 98.030672 -12.637691) (xy 98.061648 -12.71765) (xy 98.085115 -12.800126) (xy 98.100871 -12.884416)
			(xy 98.108783 -12.969799) (xy 98.109278 -13.012674) (xy 98.108783 -13.055549) (xy 98.100871 -13.140932)
			(xy 98.085115 -13.225222) (xy 98.061648 -13.307698) (xy 98.030672 -13.387657) (xy 97.99245 -13.464417)
			(xy 97.947309 -13.537323) (xy 97.895633 -13.605752) (xy 97.837864 -13.669122) (xy 97.774494 -13.726891)
			(xy 97.706065 -13.778567) (xy 97.633159 -13.823708) (xy 97.556399 -13.86193) (xy 97.47644 -13.892906)
			(xy 97.393964 -13.916373) (xy 97.309674 -13.932129) (xy 97.224291 -13.940041) (xy 97.138541 -13.940041)
			(xy 97.053158 -13.932129) (xy 96.968868 -13.916373) (xy 96.886392 -13.892906) (xy 96.806433 -13.86193)
			(xy 96.729673 -13.823708) (xy 96.656767 -13.778567) (xy 96.588338 -13.726891) (xy 96.524968 -13.669122)
			(xy 96.467199 -13.605752) (xy 96.415523 -13.537323) (xy 96.370382 -13.464417) (xy 96.33216 -13.387657)
			(xy 96.301184 -13.307698) (xy 96.277717 -13.225222) (xy 96.261961 -13.140932) (xy 96.254049 -13.055549)
			(xy 95.568783 -13.055549) (xy 95.560871 -13.140932) (xy 95.545115 -13.225222) (xy 95.521648 -13.307698)
			(xy 95.490672 -13.387657) (xy 95.45245 -13.464417) (xy 95.407309 -13.537323) (xy 95.355633 -13.605752)
			(xy 95.297864 -13.669122) (xy 95.234494 -13.726891) (xy 95.166065 -13.778567) (xy 95.093159 -13.823708)
			(xy 95.016399 -13.86193) (xy 94.93644 -13.892906) (xy 94.853964 -13.916373) (xy 94.769674 -13.932129)
			(xy 94.684291 -13.940041) (xy 94.598541 -13.940041) (xy 94.513158 -13.932129) (xy 94.428868 -13.916373)
			(xy 94.346392 -13.892906) (xy 94.266433 -13.86193) (xy 94.189673 -13.823708) (xy 94.116767 -13.778567)
			(xy 94.048338 -13.726891) (xy 93.984968 -13.669122) (xy 93.927199 -13.605752) (xy 93.875523 -13.537323)
			(xy 93.830382 -13.464417) (xy 93.79216 -13.387657) (xy 93.761184 -13.307698) (xy 93.737717 -13.225222)
			(xy 93.721961 -13.140932) (xy 93.714049 -13.055549) (xy 92.50807 -13.055549) (xy 92.50807 -17.400568)
			(xy 95.098347 -17.400568) (xy 95.098347 -17.346032) (xy 95.106109 -17.29205) (xy 95.121474 -17.239722)
			(xy 95.14413 -17.190114) (xy 95.173616 -17.144235) (xy 95.209331 -17.103019) (xy 95.250548 -17.067306)
			(xy 95.296428 -17.037823) (xy 95.346037 -17.015169) (xy 95.398365 -16.999806) (xy 95.452348 -16.992046)
			(xy 95.479616 -16.991584) (xy 96.343216 -16.991584) (xy 96.370488 -16.99198) (xy 96.424476 -16.999744)
			(xy 96.47681 -17.015113) (xy 96.526424 -17.037773) (xy 96.572309 -17.067262) (xy 96.613529 -17.102982)
			(xy 96.649247 -17.144204) (xy 96.678735 -17.19009) (xy 96.701393 -17.239705) (xy 96.716759 -17.292039)
			(xy 96.724522 -17.346028) (xy 96.724522 -17.400572) (xy 96.716759 -17.454561) (xy 96.701393 -17.506895)
			(xy 96.678735 -17.55651) (xy 96.649247 -17.602396) (xy 96.613529 -17.643618) (xy 96.572309 -17.679338)
			(xy 96.526424 -17.708827) (xy 96.47681 -17.731487) (xy 96.424476 -17.746856) (xy 96.370488 -17.75462)
			(xy 96.343216 -17.755108) (xy 95.479616 -17.755108) (xy 95.452348 -17.754554) (xy 95.398365 -17.746794)
			(xy 95.346037 -17.731431) (xy 95.296428 -17.708777) (xy 95.250548 -17.679294) (xy 95.209331 -17.643581)
			(xy 95.173616 -17.602365) (xy 95.14413 -17.556486) (xy 95.121474 -17.506878) (xy 95.106109 -17.45455)
			(xy 95.098347 -17.400568) (xy 92.50807 -17.400568) (xy 92.50807 -19.405549) (xy 93.714049 -19.405549)
			(xy 93.714049 -19.319799) (xy 93.721961 -19.234416) (xy 93.737717 -19.150126) (xy 93.761184 -19.06765)
			(xy 93.79216 -18.987691) (xy 93.830382 -18.910931) (xy 93.875523 -18.838025) (xy 93.927199 -18.769596)
			(xy 93.984968 -18.706226) (xy 94.048338 -18.648457) (xy 94.116767 -18.596781) (xy 94.189673 -18.55164)
			(xy 94.266433 -18.513418) (xy 94.346392 -18.482442) (xy 94.428868 -18.458975) (xy 94.513158 -18.443219)
			(xy 94.598541 -18.435307) (xy 94.684291 -18.435307) (xy 94.769674 -18.443219) (xy 94.853964 -18.458975)
			(xy 94.93644 -18.482442) (xy 95.016399 -18.513418) (xy 95.093159 -18.55164) (xy 95.166065 -18.596781)
			(xy 95.234494 -18.648457) (xy 95.297864 -18.706226) (xy 95.355633 -18.769596) (xy 95.407309 -18.838025)
			(xy 95.45245 -18.910931) (xy 95.490672 -18.987691) (xy 95.521648 -19.06765) (xy 95.545115 -19.150126)
			(xy 95.560871 -19.234416) (xy 95.568783 -19.319799) (xy 95.569278 -19.362674) (xy 95.568783 -19.405549)
			(xy 96.254049 -19.405549) (xy 96.254049 -19.319799) (xy 96.261961 -19.234416) (xy 96.277717 -19.150126)
			(xy 96.301184 -19.06765) (xy 96.33216 -18.987691) (xy 96.370382 -18.910931) (xy 96.415523 -18.838025)
			(xy 96.467199 -18.769596) (xy 96.524968 -18.706226) (xy 96.588338 -18.648457) (xy 96.656767 -18.596781)
			(xy 96.729673 -18.55164) (xy 96.806433 -18.513418) (xy 96.886392 -18.482442) (xy 96.968868 -18.458975)
			(xy 97.053158 -18.443219) (xy 97.138541 -18.435307) (xy 97.224291 -18.435307) (xy 97.309674 -18.443219)
			(xy 97.393964 -18.458975) (xy 97.47644 -18.482442) (xy 97.556399 -18.513418) (xy 97.633159 -18.55164)
			(xy 97.706065 -18.596781) (xy 97.774494 -18.648457) (xy 97.837864 -18.706226) (xy 97.895633 -18.769596)
			(xy 97.947309 -18.838025) (xy 97.99245 -18.910931) (xy 98.030672 -18.987691) (xy 98.061648 -19.06765)
			(xy 98.085115 -19.150126) (xy 98.100871 -19.234416) (xy 98.108783 -19.319799) (xy 98.109278 -19.362674)
			(xy 98.108783 -19.405549) (xy 98.100871 -19.490932) (xy 98.085115 -19.575222) (xy 98.061648 -19.657698)
			(xy 98.030672 -19.737657) (xy 97.99245 -19.814417) (xy 97.947309 -19.887323) (xy 97.895633 -19.955752)
			(xy 97.837864 -20.019122) (xy 97.774494 -20.076891) (xy 97.706065 -20.128567) (xy 97.633159 -20.173708)
			(xy 97.556399 -20.21193) (xy 97.47644 -20.242906) (xy 97.393964 -20.266373) (xy 97.309674 -20.282129)
			(xy 97.224291 -20.290041) (xy 97.138541 -20.290041) (xy 97.053158 -20.282129) (xy 96.968868 -20.266373)
			(xy 96.886392 -20.242906) (xy 96.806433 -20.21193) (xy 96.729673 -20.173708) (xy 96.656767 -20.128567)
			(xy 96.588338 -20.076891) (xy 96.524968 -20.019122) (xy 96.467199 -19.955752) (xy 96.415523 -19.887323)
			(xy 96.370382 -19.814417) (xy 96.33216 -19.737657) (xy 96.301184 -19.657698) (xy 96.277717 -19.575222)
			(xy 96.261961 -19.490932) (xy 96.254049 -19.405549) (xy 95.568783 -19.405549) (xy 95.560871 -19.490932)
			(xy 95.545115 -19.575222) (xy 95.521648 -19.657698) (xy 95.490672 -19.737657) (xy 95.45245 -19.814417)
			(xy 95.407309 -19.887323) (xy 95.355633 -19.955752) (xy 95.297864 -20.019122) (xy 95.234494 -20.076891)
			(xy 95.166065 -20.128567) (xy 95.093159 -20.173708) (xy 95.016399 -20.21193) (xy 94.93644 -20.242906)
			(xy 94.853964 -20.266373) (xy 94.769674 -20.282129) (xy 94.684291 -20.290041) (xy 94.598541 -20.290041)
			(xy 94.513158 -20.282129) (xy 94.428868 -20.266373) (xy 94.346392 -20.242906) (xy 94.266433 -20.21193)
			(xy 94.189673 -20.173708) (xy 94.116767 -20.128567) (xy 94.048338 -20.076891) (xy 93.984968 -20.019122)
			(xy 93.927199 -19.955752) (xy 93.875523 -19.887323) (xy 93.830382 -19.814417) (xy 93.79216 -19.737657)
			(xy 93.761184 -19.657698) (xy 93.737717 -19.575222) (xy 93.721961 -19.490932) (xy 93.714049 -19.405549)
			(xy 92.50807 -19.405549) (xy 92.50807 -50.979527) (xy 99.085133 -50.979527) (xy 99.085133 -50.893777)
			(xy 99.093045 -50.808394) (xy 99.108801 -50.724104) (xy 99.132268 -50.641628) (xy 99.163244 -50.561669)
			(xy 99.201466 -50.484909) (xy 99.246607 -50.412003) (xy 99.298283 -50.343574) (xy 99.356052 -50.280204)
			(xy 99.419422 -50.222435) (xy 99.487851 -50.170759) (xy 99.560757 -50.125618) (xy 99.637517 -50.087396)
			(xy 99.717476 -50.05642) (xy 99.799952 -50.032953) (xy 99.884242 -50.017197) (xy 99.969625 -50.009285)
			(xy 100.055375 -50.009285) (xy 100.140758 -50.017197) (xy 100.225048 -50.032953) (xy 100.307524 -50.05642)
			(xy 100.387483 -50.087396) (xy 100.464243 -50.125618) (xy 100.537149 -50.170759) (xy 100.605578 -50.222435)
			(xy 100.668948 -50.280204) (xy 100.726717 -50.343574) (xy 100.778393 -50.412003) (xy 100.823534 -50.484909)
			(xy 100.861756 -50.561669) (xy 100.892732 -50.641628) (xy 100.916199 -50.724104) (xy 100.931955 -50.808394)
			(xy 100.939867 -50.893777) (xy 100.940362 -50.936652) (xy 100.939867 -50.979527) (xy 101.625133 -50.979527)
			(xy 101.625133 -50.893777) (xy 101.633045 -50.808394) (xy 101.648801 -50.724104) (xy 101.672268 -50.641628)
			(xy 101.703244 -50.561669) (xy 101.741466 -50.484909) (xy 101.786607 -50.412003) (xy 101.838283 -50.343574)
			(xy 101.896052 -50.280204) (xy 101.959422 -50.222435) (xy 102.027851 -50.170759) (xy 102.100757 -50.125618)
			(xy 102.177517 -50.087396) (xy 102.257476 -50.05642) (xy 102.339952 -50.032953) (xy 102.424242 -50.017197)
			(xy 102.509625 -50.009285) (xy 102.595375 -50.009285) (xy 102.680758 -50.017197) (xy 102.765048 -50.032953)
			(xy 102.847524 -50.05642) (xy 102.927483 -50.087396) (xy 103.004243 -50.125618) (xy 103.077149 -50.170759)
			(xy 103.145578 -50.222435) (xy 103.208948 -50.280204) (xy 103.266717 -50.343574) (xy 103.318393 -50.412003)
			(xy 103.363534 -50.484909) (xy 103.401756 -50.561669) (xy 103.432732 -50.641628) (xy 103.456199 -50.724104)
			(xy 103.471955 -50.808394) (xy 103.479867 -50.893777) (xy 103.480362 -50.936652) (xy 103.479867 -50.979527)
			(xy 104.165133 -50.979527) (xy 104.165133 -50.893777) (xy 104.173045 -50.808394) (xy 104.188801 -50.724104)
			(xy 104.212268 -50.641628) (xy 104.243244 -50.561669) (xy 104.281466 -50.484909) (xy 104.326607 -50.412003)
			(xy 104.378283 -50.343574) (xy 104.436052 -50.280204) (xy 104.499422 -50.222435) (xy 104.567851 -50.170759)
			(xy 104.640757 -50.125618) (xy 104.717517 -50.087396) (xy 104.797476 -50.05642) (xy 104.879952 -50.032953)
			(xy 104.964242 -50.017197) (xy 105.049625 -50.009285) (xy 105.135375 -50.009285) (xy 105.220758 -50.017197)
			(xy 105.305048 -50.032953) (xy 105.387524 -50.05642) (xy 105.467483 -50.087396) (xy 105.544243 -50.125618)
			(xy 105.617149 -50.170759) (xy 105.685578 -50.222435) (xy 105.748948 -50.280204) (xy 105.806717 -50.343574)
			(xy 105.858393 -50.412003) (xy 105.903534 -50.484909) (xy 105.941756 -50.561669) (xy 105.972732 -50.641628)
			(xy 105.996199 -50.724104) (xy 106.011955 -50.808394) (xy 106.019867 -50.893777) (xy 106.020362 -50.936652)
			(xy 106.019867 -50.979527) (xy 106.011955 -51.06491) (xy 105.996199 -51.1492) (xy 105.972732 -51.231676)
			(xy 105.941756 -51.311635) (xy 105.903534 -51.388395) (xy 105.858393 -51.461301) (xy 105.806717 -51.52973)
			(xy 105.748948 -51.5931) (xy 105.685578 -51.650869) (xy 105.617149 -51.702545) (xy 105.544243 -51.747686)
			(xy 105.467483 -51.785908) (xy 105.387524 -51.816884) (xy 105.305048 -51.840351) (xy 105.220758 -51.856107)
			(xy 105.135375 -51.864019) (xy 105.049625 -51.864019) (xy 104.964242 -51.856107) (xy 104.879952 -51.840351)
			(xy 104.797476 -51.816884) (xy 104.717517 -51.785908) (xy 104.640757 -51.747686) (xy 104.567851 -51.702545)
			(xy 104.499422 -51.650869) (xy 104.436052 -51.5931) (xy 104.378283 -51.52973) (xy 104.326607 -51.461301)
			(xy 104.281466 -51.388395) (xy 104.243244 -51.311635) (xy 104.212268 -51.231676) (xy 104.188801 -51.1492)
			(xy 104.173045 -51.06491) (xy 104.165133 -50.979527) (xy 103.479867 -50.979527) (xy 103.471955 -51.06491)
			(xy 103.456199 -51.1492) (xy 103.432732 -51.231676) (xy 103.401756 -51.311635) (xy 103.363534 -51.388395)
			(xy 103.318393 -51.461301) (xy 103.266717 -51.52973) (xy 103.208948 -51.5931) (xy 103.145578 -51.650869)
			(xy 103.077149 -51.702545) (xy 103.004243 -51.747686) (xy 102.927483 -51.785908) (xy 102.847524 -51.816884)
			(xy 102.765048 -51.840351) (xy 102.680758 -51.856107) (xy 102.595375 -51.864019) (xy 102.509625 -51.864019)
			(xy 102.424242 -51.856107) (xy 102.339952 -51.840351) (xy 102.257476 -51.816884) (xy 102.177517 -51.785908)
			(xy 102.100757 -51.747686) (xy 102.027851 -51.702545) (xy 101.959422 -51.650869) (xy 101.896052 -51.5931)
			(xy 101.838283 -51.52973) (xy 101.786607 -51.461301) (xy 101.741466 -51.388395) (xy 101.703244 -51.311635)
			(xy 101.672268 -51.231676) (xy 101.648801 -51.1492) (xy 101.633045 -51.06491) (xy 101.625133 -50.979527)
			(xy 100.939867 -50.979527) (xy 100.931955 -51.06491) (xy 100.916199 -51.1492) (xy 100.892732 -51.231676)
			(xy 100.861756 -51.311635) (xy 100.823534 -51.388395) (xy 100.778393 -51.461301) (xy 100.726717 -51.52973)
			(xy 100.668948 -51.5931) (xy 100.605578 -51.650869) (xy 100.537149 -51.702545) (xy 100.464243 -51.747686)
			(xy 100.387483 -51.785908) (xy 100.307524 -51.816884) (xy 100.225048 -51.840351) (xy 100.140758 -51.856107)
			(xy 100.055375 -51.864019) (xy 99.969625 -51.864019) (xy 99.884242 -51.856107) (xy 99.799952 -51.840351)
			(xy 99.717476 -51.816884) (xy 99.637517 -51.785908) (xy 99.560757 -51.747686) (xy 99.487851 -51.702545)
			(xy 99.419422 -51.650869) (xy 99.356052 -51.5931) (xy 99.298283 -51.52973) (xy 99.246607 -51.461301)
			(xy 99.201466 -51.388395) (xy 99.163244 -51.311635) (xy 99.132268 -51.231676) (xy 99.108801 -51.1492)
			(xy 99.093045 -51.06491) (xy 99.085133 -50.979527) (xy 92.50807 -50.979527) (xy 92.50807 -53.289708)
			(xy 100.654612 -53.289708) (xy 101.905308 -53.289708) (xy 101.905308 -54.055264) (xy 100.654612 -54.055264)
			(xy 100.654612 -53.289708) (xy 92.50807 -53.289708) (xy 92.50807 -57.329527) (xy 99.085133 -57.329527)
			(xy 99.085133 -57.243777) (xy 99.093045 -57.158394) (xy 99.108801 -57.074104) (xy 99.132268 -56.991628)
			(xy 99.163244 -56.911669) (xy 99.201466 -56.834909) (xy 99.246607 -56.762003) (xy 99.298283 -56.693574)
			(xy 99.356052 -56.630204) (xy 99.419422 -56.572435) (xy 99.487851 -56.520759) (xy 99.560757 -56.475618)
			(xy 99.637517 -56.437396) (xy 99.717476 -56.40642) (xy 99.799952 -56.382953) (xy 99.884242 -56.367197)
			(xy 99.969625 -56.359285) (xy 100.055375 -56.359285) (xy 100.140758 -56.367197) (xy 100.225048 -56.382953)
			(xy 100.307524 -56.40642) (xy 100.387483 -56.437396) (xy 100.464243 -56.475618) (xy 100.537149 -56.520759)
			(xy 100.605578 -56.572435) (xy 100.668948 -56.630204) (xy 100.726717 -56.693574) (xy 100.778393 -56.762003)
			(xy 100.823534 -56.834909) (xy 100.861756 -56.911669) (xy 100.892732 -56.991628) (xy 100.916199 -57.074104)
			(xy 100.931955 -57.158394) (xy 100.939867 -57.243777) (xy 100.940362 -57.286652) (xy 100.939867 -57.329527)
			(xy 101.625133 -57.329527) (xy 101.625133 -57.243777) (xy 101.633045 -57.158394) (xy 101.648801 -57.074104)
			(xy 101.672268 -56.991628) (xy 101.703244 -56.911669) (xy 101.741466 -56.834909) (xy 101.786607 -56.762003)
			(xy 101.838283 -56.693574) (xy 101.896052 -56.630204) (xy 101.959422 -56.572435) (xy 102.027851 -56.520759)
			(xy 102.100757 -56.475618) (xy 102.177517 -56.437396) (xy 102.257476 -56.40642) (xy 102.339952 -56.382953)
			(xy 102.424242 -56.367197) (xy 102.509625 -56.359285) (xy 102.595375 -56.359285) (xy 102.680758 -56.367197)
			(xy 102.765048 -56.382953) (xy 102.847524 -56.40642) (xy 102.927483 -56.437396) (xy 103.004243 -56.475618)
			(xy 103.077149 -56.520759) (xy 103.145578 -56.572435) (xy 103.208948 -56.630204) (xy 103.266717 -56.693574)
			(xy 103.318393 -56.762003) (xy 103.363534 -56.834909) (xy 103.401756 -56.911669) (xy 103.432732 -56.991628)
			(xy 103.456199 -57.074104) (xy 103.471955 -57.158394) (xy 103.479867 -57.243777) (xy 103.480362 -57.286652)
			(xy 103.479867 -57.329527) (xy 104.165133 -57.329527) (xy 104.165133 -57.243777) (xy 104.173045 -57.158394)
			(xy 104.188801 -57.074104) (xy 104.212268 -56.991628) (xy 104.243244 -56.911669) (xy 104.281466 -56.834909)
			(xy 104.326607 -56.762003) (xy 104.378283 -56.693574) (xy 104.436052 -56.630204) (xy 104.499422 -56.572435)
			(xy 104.567851 -56.520759) (xy 104.640757 -56.475618) (xy 104.717517 -56.437396) (xy 104.797476 -56.40642)
			(xy 104.879952 -56.382953) (xy 104.964242 -56.367197) (xy 105.049625 -56.359285) (xy 105.135375 -56.359285)
			(xy 105.220758 -56.367197) (xy 105.305048 -56.382953) (xy 105.387524 -56.40642) (xy 105.467483 -56.437396)
			(xy 105.544243 -56.475618) (xy 105.617149 -56.520759) (xy 105.685578 -56.572435) (xy 105.748948 -56.630204)
			(xy 105.806717 -56.693574) (xy 105.858393 -56.762003) (xy 105.903534 -56.834909) (xy 105.941756 -56.911669)
			(xy 105.972732 -56.991628) (xy 105.996199 -57.074104) (xy 106.011955 -57.158394) (xy 106.019867 -57.243777)
			(xy 106.020362 -57.286652) (xy 106.019867 -57.329527) (xy 106.011955 -57.41491) (xy 105.996199 -57.4992)
			(xy 105.972732 -57.581676) (xy 105.941756 -57.661635) (xy 105.903534 -57.738395) (xy 105.858393 -57.811301)
			(xy 105.806717 -57.87973) (xy 105.748948 -57.9431) (xy 105.685578 -58.000869) (xy 105.617149 -58.052545)
			(xy 105.544243 -58.097686) (xy 105.467483 -58.135908) (xy 105.387524 -58.166884) (xy 105.305048 -58.190351)
			(xy 105.220758 -58.206107) (xy 105.135375 -58.214019) (xy 105.049625 -58.214019) (xy 104.964242 -58.206107)
			(xy 104.879952 -58.190351) (xy 104.797476 -58.166884) (xy 104.717517 -58.135908) (xy 104.640757 -58.097686)
			(xy 104.567851 -58.052545) (xy 104.499422 -58.000869) (xy 104.436052 -57.9431) (xy 104.378283 -57.87973)
			(xy 104.326607 -57.811301) (xy 104.281466 -57.738395) (xy 104.243244 -57.661635) (xy 104.212268 -57.581676)
			(xy 104.188801 -57.4992) (xy 104.173045 -57.41491) (xy 104.165133 -57.329527) (xy 103.479867 -57.329527)
			(xy 103.471955 -57.41491) (xy 103.456199 -57.4992) (xy 103.432732 -57.581676) (xy 103.401756 -57.661635)
			(xy 103.363534 -57.738395) (xy 103.318393 -57.811301) (xy 103.266717 -57.87973) (xy 103.208948 -57.9431)
			(xy 103.145578 -58.000869) (xy 103.077149 -58.052545) (xy 103.004243 -58.097686) (xy 102.927483 -58.135908)
			(xy 102.847524 -58.166884) (xy 102.765048 -58.190351) (xy 102.680758 -58.206107) (xy 102.595375 -58.214019)
			(xy 102.509625 -58.214019) (xy 102.424242 -58.206107) (xy 102.339952 -58.190351) (xy 102.257476 -58.166884)
			(xy 102.177517 -58.135908) (xy 102.100757 -58.097686) (xy 102.027851 -58.052545) (xy 101.959422 -58.000869)
			(xy 101.896052 -57.9431) (xy 101.838283 -57.87973) (xy 101.786607 -57.811301) (xy 101.741466 -57.738395)
			(xy 101.703244 -57.661635) (xy 101.672268 -57.581676) (xy 101.648801 -57.4992) (xy 101.633045 -57.41491)
			(xy 101.625133 -57.329527) (xy 100.939867 -57.329527) (xy 100.931955 -57.41491) (xy 100.916199 -57.4992)
			(xy 100.892732 -57.581676) (xy 100.861756 -57.661635) (xy 100.823534 -57.738395) (xy 100.778393 -57.811301)
			(xy 100.726717 -57.87973) (xy 100.668948 -57.9431) (xy 100.605578 -58.000869) (xy 100.537149 -58.052545)
			(xy 100.464243 -58.097686) (xy 100.387483 -58.135908) (xy 100.307524 -58.166884) (xy 100.225048 -58.190351)
			(xy 100.140758 -58.206107) (xy 100.055375 -58.214019) (xy 99.969625 -58.214019) (xy 99.884242 -58.206107)
			(xy 99.799952 -58.190351) (xy 99.717476 -58.166884) (xy 99.637517 -58.135908) (xy 99.560757 -58.097686)
			(xy 99.487851 -58.052545) (xy 99.419422 -58.000869) (xy 99.356052 -57.9431) (xy 99.298283 -57.87973)
			(xy 99.246607 -57.811301) (xy 99.201466 -57.738395) (xy 99.163244 -57.661635) (xy 99.132268 -57.581676)
			(xy 99.108801 -57.4992) (xy 99.093045 -57.41491) (xy 99.085133 -57.329527) (xy 92.50807 -57.329527)
			(xy 92.50807 -62.793575) (xy 99.085133 -62.793575) (xy 99.085133 -62.707825) (xy 99.093045 -62.622442)
			(xy 99.108801 -62.538152) (xy 99.132268 -62.455676) (xy 99.163244 -62.375717) (xy 99.201466 -62.298957)
			(xy 99.246607 -62.226051) (xy 99.298283 -62.157622) (xy 99.356052 -62.094252) (xy 99.419422 -62.036483)
			(xy 99.487851 -61.984807) (xy 99.560757 -61.939666) (xy 99.637517 -61.901444) (xy 99.717476 -61.870468)
			(xy 99.799952 -61.847001) (xy 99.884242 -61.831245) (xy 99.969625 -61.823333) (xy 100.055375 -61.823333)
			(xy 100.140758 -61.831245) (xy 100.225048 -61.847001) (xy 100.307524 -61.870468) (xy 100.387483 -61.901444)
			(xy 100.464243 -61.939666) (xy 100.537149 -61.984807) (xy 100.605578 -62.036483) (xy 100.668948 -62.094252)
			(xy 100.726717 -62.157622) (xy 100.778393 -62.226051) (xy 100.823534 -62.298957) (xy 100.861756 -62.375717)
			(xy 100.892732 -62.455676) (xy 100.916199 -62.538152) (xy 100.931955 -62.622442) (xy 100.939867 -62.707825)
			(xy 100.940362 -62.7507) (xy 100.939867 -62.793575) (xy 101.625133 -62.793575) (xy 101.625133 -62.707825)
			(xy 101.633045 -62.622442) (xy 101.648801 -62.538152) (xy 101.672268 -62.455676) (xy 101.703244 -62.375717)
			(xy 101.741466 -62.298957) (xy 101.786607 -62.226051) (xy 101.838283 -62.157622) (xy 101.896052 -62.094252)
			(xy 101.959422 -62.036483) (xy 102.027851 -61.984807) (xy 102.100757 -61.939666) (xy 102.177517 -61.901444)
			(xy 102.257476 -61.870468) (xy 102.339952 -61.847001) (xy 102.424242 -61.831245) (xy 102.509625 -61.823333)
			(xy 102.595375 -61.823333) (xy 102.680758 -61.831245) (xy 102.765048 -61.847001) (xy 102.847524 -61.870468)
			(xy 102.927483 -61.901444) (xy 103.004243 -61.939666) (xy 103.077149 -61.984807) (xy 103.145578 -62.036483)
			(xy 103.208948 -62.094252) (xy 103.266717 -62.157622) (xy 103.318393 -62.226051) (xy 103.363534 -62.298957)
			(xy 103.401756 -62.375717) (xy 103.432732 -62.455676) (xy 103.456199 -62.538152) (xy 103.471955 -62.622442)
			(xy 103.479867 -62.707825) (xy 103.480362 -62.7507) (xy 103.479867 -62.793575) (xy 104.165133 -62.793575)
			(xy 104.165133 -62.707825) (xy 104.173045 -62.622442) (xy 104.188801 -62.538152) (xy 104.212268 -62.455676)
			(xy 104.243244 -62.375717) (xy 104.281466 -62.298957) (xy 104.326607 -62.226051) (xy 104.378283 -62.157622)
			(xy 104.436052 -62.094252) (xy 104.499422 -62.036483) (xy 104.567851 -61.984807) (xy 104.640757 -61.939666)
			(xy 104.717517 -61.901444) (xy 104.797476 -61.870468) (xy 104.879952 -61.847001) (xy 104.964242 -61.831245)
			(xy 105.049625 -61.823333) (xy 105.135375 -61.823333) (xy 105.220758 -61.831245) (xy 105.305048 -61.847001)
			(xy 105.387524 -61.870468) (xy 105.467483 -61.901444) (xy 105.544243 -61.939666) (xy 105.617149 -61.984807)
			(xy 105.685578 -62.036483) (xy 105.748948 -62.094252) (xy 105.806717 -62.157622) (xy 105.858393 -62.226051)
			(xy 105.903534 -62.298957) (xy 105.941756 -62.375717) (xy 105.972732 -62.455676) (xy 105.996199 -62.538152)
			(xy 106.011955 -62.622442) (xy 106.019867 -62.707825) (xy 106.020362 -62.7507) (xy 106.019867 -62.793575)
			(xy 106.011955 -62.878958) (xy 105.996199 -62.963248) (xy 105.972732 -63.045724) (xy 105.941756 -63.125683)
			(xy 105.903534 -63.202443) (xy 105.858393 -63.275349) (xy 105.806717 -63.343778) (xy 105.748948 -63.407148)
			(xy 105.685578 -63.464917) (xy 105.617149 -63.516593) (xy 105.544243 -63.561734) (xy 105.467483 -63.599956)
			(xy 105.387524 -63.630932) (xy 105.305048 -63.654399) (xy 105.220758 -63.670155) (xy 105.135375 -63.678067)
			(xy 105.049625 -63.678067) (xy 104.964242 -63.670155) (xy 104.879952 -63.654399) (xy 104.797476 -63.630932)
			(xy 104.717517 -63.599956) (xy 104.640757 -63.561734) (xy 104.567851 -63.516593) (xy 104.499422 -63.464917)
			(xy 104.436052 -63.407148) (xy 104.378283 -63.343778) (xy 104.326607 -63.275349) (xy 104.281466 -63.202443)
			(xy 104.243244 -63.125683) (xy 104.212268 -63.045724) (xy 104.188801 -62.963248) (xy 104.173045 -62.878958)
			(xy 104.165133 -62.793575) (xy 103.479867 -62.793575) (xy 103.471955 -62.878958) (xy 103.456199 -62.963248)
			(xy 103.432732 -63.045724) (xy 103.401756 -63.125683) (xy 103.363534 -63.202443) (xy 103.318393 -63.275349)
			(xy 103.266717 -63.343778) (xy 103.208948 -63.407148) (xy 103.145578 -63.464917) (xy 103.077149 -63.516593)
			(xy 103.004243 -63.561734) (xy 102.927483 -63.599956) (xy 102.847524 -63.630932) (xy 102.765048 -63.654399)
			(xy 102.680758 -63.670155) (xy 102.595375 -63.678067) (xy 102.509625 -63.678067) (xy 102.424242 -63.670155)
			(xy 102.339952 -63.654399) (xy 102.257476 -63.630932) (xy 102.177517 -63.599956) (xy 102.100757 -63.561734)
			(xy 102.027851 -63.516593) (xy 101.959422 -63.464917) (xy 101.896052 -63.407148) (xy 101.838283 -63.343778)
			(xy 101.786607 -63.275349) (xy 101.741466 -63.202443) (xy 101.703244 -63.125683) (xy 101.672268 -63.045724)
			(xy 101.648801 -62.963248) (xy 101.633045 -62.878958) (xy 101.625133 -62.793575) (xy 100.939867 -62.793575)
			(xy 100.931955 -62.878958) (xy 100.916199 -62.963248) (xy 100.892732 -63.045724) (xy 100.861756 -63.125683)
			(xy 100.823534 -63.202443) (xy 100.778393 -63.275349) (xy 100.726717 -63.343778) (xy 100.668948 -63.407148)
			(xy 100.605578 -63.464917) (xy 100.537149 -63.516593) (xy 100.464243 -63.561734) (xy 100.387483 -63.599956)
			(xy 100.307524 -63.630932) (xy 100.225048 -63.654399) (xy 100.140758 -63.670155) (xy 100.055375 -63.678067)
			(xy 99.969625 -63.678067) (xy 99.884242 -63.670155) (xy 99.799952 -63.654399) (xy 99.717476 -63.630932)
			(xy 99.637517 -63.599956) (xy 99.560757 -63.561734) (xy 99.487851 -63.516593) (xy 99.419422 -63.464917)
			(xy 99.356052 -63.407148) (xy 99.298283 -63.343778) (xy 99.246607 -63.275349) (xy 99.201466 -63.202443)
			(xy 99.163244 -63.125683) (xy 99.132268 -63.045724) (xy 99.108801 -62.963248) (xy 99.093045 -62.878958)
			(xy 99.085133 -62.793575) (xy 92.50807 -62.793575) (xy 92.50807 -65.982088) (xy 103.199692 -65.982088)
			(xy 104.450388 -65.982088) (xy 104.450388 -66.747644) (xy 103.199692 -66.747644) (xy 103.199692 -65.982088)
			(xy 92.50807 -65.982088) (xy 92.50807 -69.143575) (xy 99.085133 -69.143575) (xy 99.085133 -69.057825)
			(xy 99.093045 -68.972442) (xy 99.108801 -68.888152) (xy 99.132268 -68.805676) (xy 99.163244 -68.725717)
			(xy 99.201466 -68.648957) (xy 99.246607 -68.576051) (xy 99.298283 -68.507622) (xy 99.356052 -68.444252)
			(xy 99.419422 -68.386483) (xy 99.487851 -68.334807) (xy 99.560757 -68.289666) (xy 99.637517 -68.251444)
			(xy 99.717476 -68.220468) (xy 99.799952 -68.197001) (xy 99.884242 -68.181245) (xy 99.969625 -68.173333)
			(xy 100.055375 -68.173333) (xy 100.140758 -68.181245) (xy 100.225048 -68.197001) (xy 100.307524 -68.220468)
			(xy 100.387483 -68.251444) (xy 100.464243 -68.289666) (xy 100.537149 -68.334807) (xy 100.605578 -68.386483)
			(xy 100.668948 -68.444252) (xy 100.726717 -68.507622) (xy 100.778393 -68.576051) (xy 100.823534 -68.648957)
			(xy 100.861756 -68.725717) (xy 100.892732 -68.805676) (xy 100.916199 -68.888152) (xy 100.931955 -68.972442)
			(xy 100.939867 -69.057825) (xy 100.940362 -69.1007) (xy 100.939867 -69.143575) (xy 101.625133 -69.143575)
			(xy 101.625133 -69.057825) (xy 101.633045 -68.972442) (xy 101.648801 -68.888152) (xy 101.672268 -68.805676)
			(xy 101.703244 -68.725717) (xy 101.741466 -68.648957) (xy 101.786607 -68.576051) (xy 101.838283 -68.507622)
			(xy 101.896052 -68.444252) (xy 101.959422 -68.386483) (xy 102.027851 -68.334807) (xy 102.100757 -68.289666)
			(xy 102.177517 -68.251444) (xy 102.257476 -68.220468) (xy 102.339952 -68.197001) (xy 102.424242 -68.181245)
			(xy 102.509625 -68.173333) (xy 102.595375 -68.173333) (xy 102.680758 -68.181245) (xy 102.765048 -68.197001)
			(xy 102.847524 -68.220468) (xy 102.927483 -68.251444) (xy 103.004243 -68.289666) (xy 103.077149 -68.334807)
			(xy 103.145578 -68.386483) (xy 103.208948 -68.444252) (xy 103.266717 -68.507622) (xy 103.318393 -68.576051)
			(xy 103.363534 -68.648957) (xy 103.401756 -68.725717) (xy 103.432732 -68.805676) (xy 103.456199 -68.888152)
			(xy 103.471955 -68.972442) (xy 103.479867 -69.057825) (xy 103.480362 -69.1007) (xy 103.479867 -69.143575)
			(xy 104.165133 -69.143575) (xy 104.165133 -69.057825) (xy 104.173045 -68.972442) (xy 104.188801 -68.888152)
			(xy 104.212268 -68.805676) (xy 104.243244 -68.725717) (xy 104.281466 -68.648957) (xy 104.326607 -68.576051)
			(xy 104.378283 -68.507622) (xy 104.436052 -68.444252) (xy 104.499422 -68.386483) (xy 104.567851 -68.334807)
			(xy 104.640757 -68.289666) (xy 104.717517 -68.251444) (xy 104.797476 -68.220468) (xy 104.879952 -68.197001)
			(xy 104.964242 -68.181245) (xy 105.049625 -68.173333) (xy 105.135375 -68.173333) (xy 105.220758 -68.181245)
			(xy 105.305048 -68.197001) (xy 105.387524 -68.220468) (xy 105.467483 -68.251444) (xy 105.544243 -68.289666)
			(xy 105.617149 -68.334807) (xy 105.685578 -68.386483) (xy 105.748948 -68.444252) (xy 105.806717 -68.507622)
			(xy 105.858393 -68.576051) (xy 105.903534 -68.648957) (xy 105.941756 -68.725717) (xy 105.972732 -68.805676)
			(xy 105.996199 -68.888152) (xy 106.011955 -68.972442) (xy 106.019867 -69.057825) (xy 106.020362 -69.1007)
			(xy 106.019867 -69.143575) (xy 106.011955 -69.228958) (xy 105.996199 -69.313248) (xy 105.972732 -69.395724)
			(xy 105.941756 -69.475683) (xy 105.903534 -69.552443) (xy 105.858393 -69.625349) (xy 105.806717 -69.693778)
			(xy 105.748948 -69.757148) (xy 105.685578 -69.814917) (xy 105.617149 -69.866593) (xy 105.544243 -69.911734)
			(xy 105.467483 -69.949956) (xy 105.387524 -69.980932) (xy 105.305048 -70.004399) (xy 105.220758 -70.020155)
			(xy 105.135375 -70.028067) (xy 105.049625 -70.028067) (xy 104.964242 -70.020155) (xy 104.879952 -70.004399)
			(xy 104.797476 -69.980932) (xy 104.717517 -69.949956) (xy 104.640757 -69.911734) (xy 104.567851 -69.866593)
			(xy 104.499422 -69.814917) (xy 104.436052 -69.757148) (xy 104.378283 -69.693778) (xy 104.326607 -69.625349)
			(xy 104.281466 -69.552443) (xy 104.243244 -69.475683) (xy 104.212268 -69.395724) (xy 104.188801 -69.313248)
			(xy 104.173045 -69.228958) (xy 104.165133 -69.143575) (xy 103.479867 -69.143575) (xy 103.471955 -69.228958)
			(xy 103.456199 -69.313248) (xy 103.432732 -69.395724) (xy 103.401756 -69.475683) (xy 103.363534 -69.552443)
			(xy 103.318393 -69.625349) (xy 103.266717 -69.693778) (xy 103.208948 -69.757148) (xy 103.145578 -69.814917)
			(xy 103.077149 -69.866593) (xy 103.004243 -69.911734) (xy 102.927483 -69.949956) (xy 102.847524 -69.980932)
			(xy 102.765048 -70.004399) (xy 102.680758 -70.020155) (xy 102.595375 -70.028067) (xy 102.509625 -70.028067)
			(xy 102.424242 -70.020155) (xy 102.339952 -70.004399) (xy 102.257476 -69.980932) (xy 102.177517 -69.949956)
			(xy 102.100757 -69.911734) (xy 102.027851 -69.866593) (xy 101.959422 -69.814917) (xy 101.896052 -69.757148)
			(xy 101.838283 -69.693778) (xy 101.786607 -69.625349) (xy 101.741466 -69.552443) (xy 101.703244 -69.475683)
			(xy 101.672268 -69.395724) (xy 101.648801 -69.313248) (xy 101.633045 -69.228958) (xy 101.625133 -69.143575)
			(xy 100.939867 -69.143575) (xy 100.931955 -69.228958) (xy 100.916199 -69.313248) (xy 100.892732 -69.395724)
			(xy 100.861756 -69.475683) (xy 100.823534 -69.552443) (xy 100.778393 -69.625349) (xy 100.726717 -69.693778)
			(xy 100.668948 -69.757148) (xy 100.605578 -69.814917) (xy 100.537149 -69.866593) (xy 100.464243 -69.911734)
			(xy 100.387483 -69.949956) (xy 100.307524 -69.980932) (xy 100.225048 -70.004399) (xy 100.140758 -70.020155)
			(xy 100.055375 -70.028067) (xy 99.969625 -70.028067) (xy 99.884242 -70.020155) (xy 99.799952 -70.004399)
			(xy 99.717476 -69.980932) (xy 99.637517 -69.949956) (xy 99.560757 -69.911734) (xy 99.487851 -69.866593)
			(xy 99.419422 -69.814917) (xy 99.356052 -69.757148) (xy 99.298283 -69.693778) (xy 99.246607 -69.625349)
			(xy 99.201466 -69.552443) (xy 99.163244 -69.475683) (xy 99.132268 -69.395724) (xy 99.108801 -69.313248)
			(xy 99.093045 -69.228958) (xy 99.085133 -69.143575) (xy 92.50807 -69.143575) (xy 92.50807 -94.976137)
			(xy 93.729289 -94.976137) (xy 93.729289 -94.890387) (xy 93.737201 -94.805004) (xy 93.752957 -94.720714)
			(xy 93.776424 -94.638238) (xy 93.8074 -94.558279) (xy 93.845622 -94.481519) (xy 93.890763 -94.408613)
			(xy 93.942439 -94.340184) (xy 94.000208 -94.276814) (xy 94.063578 -94.219045) (xy 94.132007 -94.167369)
			(xy 94.204913 -94.122228) (xy 94.281673 -94.084006) (xy 94.361632 -94.05303) (xy 94.444108 -94.029563)
			(xy 94.528398 -94.013807) (xy 94.613781 -94.005895) (xy 94.699531 -94.005895) (xy 94.784914 -94.013807)
			(xy 94.869204 -94.029563) (xy 94.95168 -94.05303) (xy 95.031639 -94.084006) (xy 95.108399 -94.122228)
			(xy 95.181305 -94.167369) (xy 95.249734 -94.219045) (xy 95.313104 -94.276814) (xy 95.370873 -94.340184)
			(xy 95.422549 -94.408613) (xy 95.46769 -94.481519) (xy 95.505912 -94.558279) (xy 95.536888 -94.638238)
			(xy 95.560355 -94.720714) (xy 95.576111 -94.805004) (xy 95.584023 -94.890387) (xy 95.584518 -94.933262)
			(xy 95.584023 -94.976137) (xy 96.269289 -94.976137) (xy 96.269289 -94.890387) (xy 96.277201 -94.805004)
			(xy 96.292957 -94.720714) (xy 96.316424 -94.638238) (xy 96.3474 -94.558279) (xy 96.385622 -94.481519)
			(xy 96.430763 -94.408613) (xy 96.482439 -94.340184) (xy 96.540208 -94.276814) (xy 96.603578 -94.219045)
			(xy 96.672007 -94.167369) (xy 96.744913 -94.122228) (xy 96.821673 -94.084006) (xy 96.901632 -94.05303)
			(xy 96.984108 -94.029563) (xy 97.068398 -94.013807) (xy 97.153781 -94.005895) (xy 97.239531 -94.005895)
			(xy 97.324914 -94.013807) (xy 97.409204 -94.029563) (xy 97.49168 -94.05303) (xy 97.571639 -94.084006)
			(xy 97.648399 -94.122228) (xy 97.721305 -94.167369) (xy 97.789734 -94.219045) (xy 97.853104 -94.276814)
			(xy 97.910873 -94.340184) (xy 97.962549 -94.408613) (xy 98.00769 -94.481519) (xy 98.045912 -94.558279)
			(xy 98.076888 -94.638238) (xy 98.100355 -94.720714) (xy 98.116111 -94.805004) (xy 98.124023 -94.890387)
			(xy 98.124518 -94.933262) (xy 98.124023 -94.976137) (xy 98.116111 -95.06152) (xy 98.100355 -95.14581)
			(xy 98.076888 -95.228286) (xy 98.045912 -95.308245) (xy 98.00769 -95.385005) (xy 97.962549 -95.457911)
			(xy 97.910873 -95.52634) (xy 97.853104 -95.58971) (xy 97.789734 -95.647479) (xy 97.721305 -95.699155)
			(xy 97.648399 -95.744296) (xy 97.571639 -95.782518) (xy 97.49168 -95.813494) (xy 97.409204 -95.836961)
			(xy 97.324914 -95.852717) (xy 97.239531 -95.860629) (xy 97.153781 -95.860629) (xy 97.068398 -95.852717)
			(xy 96.984108 -95.836961) (xy 96.901632 -95.813494) (xy 96.821673 -95.782518) (xy 96.744913 -95.744296)
			(xy 96.672007 -95.699155) (xy 96.603578 -95.647479) (xy 96.540208 -95.58971) (xy 96.482439 -95.52634)
			(xy 96.430763 -95.457911) (xy 96.385622 -95.385005) (xy 96.3474 -95.308245) (xy 96.316424 -95.228286)
			(xy 96.292957 -95.14581) (xy 96.277201 -95.06152) (xy 96.269289 -94.976137) (xy 95.584023 -94.976137)
			(xy 95.576111 -95.06152) (xy 95.560355 -95.14581) (xy 95.536888 -95.228286) (xy 95.505912 -95.308245)
			(xy 95.46769 -95.385005) (xy 95.422549 -95.457911) (xy 95.370873 -95.52634) (xy 95.313104 -95.58971)
			(xy 95.249734 -95.647479) (xy 95.181305 -95.699155) (xy 95.108399 -95.744296) (xy 95.031639 -95.782518)
			(xy 94.95168 -95.813494) (xy 94.869204 -95.836961) (xy 94.784914 -95.852717) (xy 94.699531 -95.860629)
			(xy 94.613781 -95.860629) (xy 94.528398 -95.852717) (xy 94.444108 -95.836961) (xy 94.361632 -95.813494)
			(xy 94.281673 -95.782518) (xy 94.204913 -95.744296) (xy 94.132007 -95.699155) (xy 94.063578 -95.647479)
			(xy 94.000208 -95.58971) (xy 93.942439 -95.52634) (xy 93.890763 -95.457911) (xy 93.845622 -95.385005)
			(xy 93.8074 -95.308245) (xy 93.776424 -95.228286) (xy 93.752957 -95.14581) (xy 93.737201 -95.06152)
			(xy 93.729289 -94.976137) (xy 92.50807 -94.976137) (xy 92.50807 -96.949868) (xy 95.113614 -96.949868)
			(xy 95.113614 -96.895332) (xy 95.121375 -96.841351) (xy 95.136739 -96.789023) (xy 95.159392 -96.739415)
			(xy 95.188875 -96.693535) (xy 95.224586 -96.652317) (xy 95.2658 -96.616601) (xy 95.311676 -96.587113)
			(xy 95.361282 -96.564454) (xy 95.413608 -96.549084) (xy 95.467588 -96.541317) (xy 95.494856 -96.540828)
			(xy 96.358456 -96.540828) (xy 96.385728 -96.541308) (xy 96.439719 -96.549065) (xy 96.492055 -96.564427)
			(xy 96.541673 -96.587082) (xy 96.587561 -96.616568) (xy 96.628785 -96.652284) (xy 96.664506 -96.693504)
			(xy 96.693997 -96.739389) (xy 96.716657 -96.789004) (xy 96.732025 -96.841338) (xy 96.739788 -96.895328)
			(xy 96.739788 -96.949872) (xy 96.732025 -97.003862) (xy 96.716657 -97.056196) (xy 96.693997 -97.105811)
			(xy 96.664506 -97.151696) (xy 96.628785 -97.192916) (xy 96.587561 -97.228632) (xy 96.541673 -97.258118)
			(xy 96.492055 -97.280773) (xy 96.439719 -97.296135) (xy 96.385728 -97.303892) (xy 96.358456 -97.304352)
			(xy 95.494856 -97.304352) (xy 95.467588 -97.303883) (xy 95.413608 -97.296116) (xy 95.361282 -97.280746)
			(xy 95.311676 -97.258087) (xy 95.2658 -97.228599) (xy 95.224586 -97.192883) (xy 95.188875 -97.151665)
			(xy 95.159392 -97.105785) (xy 95.136739 -97.056177) (xy 95.121375 -97.003849) (xy 95.113614 -96.949868)
			(xy 92.50807 -96.949868) (xy 92.50807 -101.326137) (xy 93.729289 -101.326137) (xy 93.729289 -101.240387)
			(xy 93.737201 -101.155004) (xy 93.752957 -101.070714) (xy 93.776424 -100.988238) (xy 93.8074 -100.908279)
			(xy 93.845622 -100.831519) (xy 93.890763 -100.758613) (xy 93.942439 -100.690184) (xy 94.000208 -100.626814)
			(xy 94.063578 -100.569045) (xy 94.132007 -100.517369) (xy 94.204913 -100.472228) (xy 94.281673 -100.434006)
			(xy 94.361632 -100.40303) (xy 94.444108 -100.379563) (xy 94.528398 -100.363807) (xy 94.613781 -100.355895)
			(xy 94.699531 -100.355895) (xy 94.784914 -100.363807) (xy 94.869204 -100.379563) (xy 94.95168 -100.40303)
			(xy 95.031639 -100.434006) (xy 95.108399 -100.472228) (xy 95.181305 -100.517369) (xy 95.249734 -100.569045)
			(xy 95.313104 -100.626814) (xy 95.370873 -100.690184) (xy 95.422549 -100.758613) (xy 95.46769 -100.831519)
			(xy 95.505912 -100.908279) (xy 95.536888 -100.988238) (xy 95.560355 -101.070714) (xy 95.576111 -101.155004)
			(xy 95.584023 -101.240387) (xy 95.584518 -101.283262) (xy 95.584023 -101.326137) (xy 96.269289 -101.326137)
			(xy 96.269289 -101.240387) (xy 96.277201 -101.155004) (xy 96.292957 -101.070714) (xy 96.316424 -100.988238)
			(xy 96.3474 -100.908279) (xy 96.385622 -100.831519) (xy 96.430763 -100.758613) (xy 96.482439 -100.690184)
			(xy 96.540208 -100.626814) (xy 96.603578 -100.569045) (xy 96.672007 -100.517369) (xy 96.744913 -100.472228)
			(xy 96.821673 -100.434006) (xy 96.901632 -100.40303) (xy 96.984108 -100.379563) (xy 97.068398 -100.363807)
			(xy 97.153781 -100.355895) (xy 97.239531 -100.355895) (xy 97.324914 -100.363807) (xy 97.409204 -100.379563)
			(xy 97.49168 -100.40303) (xy 97.571639 -100.434006) (xy 97.648399 -100.472228) (xy 97.721305 -100.517369)
			(xy 97.789734 -100.569045) (xy 97.853104 -100.626814) (xy 97.910873 -100.690184) (xy 97.962549 -100.758613)
			(xy 98.00769 -100.831519) (xy 98.045912 -100.908279) (xy 98.076888 -100.988238) (xy 98.100355 -101.070714)
			(xy 98.116111 -101.155004) (xy 98.124023 -101.240387) (xy 98.124518 -101.283262) (xy 98.124023 -101.326137)
			(xy 98.122681 -101.340615) (xy 99.085133 -101.340615) (xy 99.085133 -101.254865) (xy 99.093045 -101.169482)
			(xy 99.108801 -101.085192) (xy 99.132268 -101.002716) (xy 99.163244 -100.922757) (xy 99.201466 -100.845997)
			(xy 99.246607 -100.773091) (xy 99.298283 -100.704662) (xy 99.356052 -100.641292) (xy 99.419422 -100.583523)
			(xy 99.487851 -100.531847) (xy 99.560757 -100.486706) (xy 99.637517 -100.448484) (xy 99.717476 -100.417508)
			(xy 99.799952 -100.394041) (xy 99.884242 -100.378285) (xy 99.969625 -100.370373) (xy 100.055375 -100.370373)
			(xy 100.140758 -100.378285) (xy 100.225048 -100.394041) (xy 100.307524 -100.417508) (xy 100.387483 -100.448484)
			(xy 100.464243 -100.486706) (xy 100.537149 -100.531847) (xy 100.605578 -100.583523) (xy 100.668948 -100.641292)
			(xy 100.726717 -100.704662) (xy 100.778393 -100.773091) (xy 100.823534 -100.845997) (xy 100.861756 -100.922757)
			(xy 100.892732 -101.002716) (xy 100.916199 -101.085192) (xy 100.931955 -101.169482) (xy 100.939867 -101.254865)
			(xy 100.940362 -101.29774) (xy 100.939867 -101.340615) (xy 101.625133 -101.340615) (xy 101.625133 -101.254865)
			(xy 101.633045 -101.169482) (xy 101.648801 -101.085192) (xy 101.672268 -101.002716) (xy 101.703244 -100.922757)
			(xy 101.741466 -100.845997) (xy 101.786607 -100.773091) (xy 101.838283 -100.704662) (xy 101.896052 -100.641292)
			(xy 101.959422 -100.583523) (xy 102.027851 -100.531847) (xy 102.100757 -100.486706) (xy 102.177517 -100.448484)
			(xy 102.257476 -100.417508) (xy 102.339952 -100.394041) (xy 102.424242 -100.378285) (xy 102.509625 -100.370373)
			(xy 102.595375 -100.370373) (xy 102.680758 -100.378285) (xy 102.765048 -100.394041) (xy 102.847524 -100.417508)
			(xy 102.927483 -100.448484) (xy 103.004243 -100.486706) (xy 103.077149 -100.531847) (xy 103.145578 -100.583523)
			(xy 103.208948 -100.641292) (xy 103.266717 -100.704662) (xy 103.318393 -100.773091) (xy 103.363534 -100.845997)
			(xy 103.401756 -100.922757) (xy 103.432732 -101.002716) (xy 103.456199 -101.085192) (xy 103.471955 -101.169482)
			(xy 103.479867 -101.254865) (xy 103.480362 -101.29774) (xy 103.479867 -101.340615) (xy 104.165133 -101.340615)
			(xy 104.165133 -101.254865) (xy 104.173045 -101.169482) (xy 104.188801 -101.085192) (xy 104.212268 -101.002716)
			(xy 104.243244 -100.922757) (xy 104.281466 -100.845997) (xy 104.326607 -100.773091) (xy 104.378283 -100.704662)
			(xy 104.436052 -100.641292) (xy 104.499422 -100.583523) (xy 104.567851 -100.531847) (xy 104.640757 -100.486706)
			(xy 104.717517 -100.448484) (xy 104.797476 -100.417508) (xy 104.879952 -100.394041) (xy 104.964242 -100.378285)
			(xy 105.049625 -100.370373) (xy 105.135375 -100.370373) (xy 105.220758 -100.378285) (xy 105.305048 -100.394041)
			(xy 105.387524 -100.417508) (xy 105.467483 -100.448484) (xy 105.544243 -100.486706) (xy 105.617149 -100.531847)
			(xy 105.685578 -100.583523) (xy 105.748948 -100.641292) (xy 105.806717 -100.704662) (xy 105.858393 -100.773091)
			(xy 105.903534 -100.845997) (xy 105.941756 -100.922757) (xy 105.972732 -101.002716) (xy 105.996199 -101.085192)
			(xy 106.011955 -101.169482) (xy 106.019867 -101.254865) (xy 106.020362 -101.29774) (xy 106.019867 -101.340615)
			(xy 106.011955 -101.425998) (xy 105.996199 -101.510288) (xy 105.972732 -101.592764) (xy 105.941756 -101.672723)
			(xy 105.903534 -101.749483) (xy 105.858393 -101.822389) (xy 105.806717 -101.890818) (xy 105.748948 -101.954188)
			(xy 105.685578 -102.011957) (xy 105.617149 -102.063633) (xy 105.544243 -102.108774) (xy 105.467483 -102.146996)
			(xy 105.387524 -102.177972) (xy 105.305048 -102.201439) (xy 105.220758 -102.217195) (xy 105.135375 -102.225107)
			(xy 105.049625 -102.225107) (xy 104.964242 -102.217195) (xy 104.879952 -102.201439) (xy 104.797476 -102.177972)
			(xy 104.717517 -102.146996) (xy 104.640757 -102.108774) (xy 104.567851 -102.063633) (xy 104.499422 -102.011957)
			(xy 104.436052 -101.954188) (xy 104.378283 -101.890818) (xy 104.326607 -101.822389) (xy 104.281466 -101.749483)
			(xy 104.243244 -101.672723) (xy 104.212268 -101.592764) (xy 104.188801 -101.510288) (xy 104.173045 -101.425998)
			(xy 104.165133 -101.340615) (xy 103.479867 -101.340615) (xy 103.471955 -101.425998) (xy 103.456199 -101.510288)
			(xy 103.432732 -101.592764) (xy 103.401756 -101.672723) (xy 103.363534 -101.749483) (xy 103.318393 -101.822389)
			(xy 103.266717 -101.890818) (xy 103.208948 -101.954188) (xy 103.145578 -102.011957) (xy 103.077149 -102.063633)
			(xy 103.004243 -102.108774) (xy 102.927483 -102.146996) (xy 102.847524 -102.177972) (xy 102.765048 -102.201439)
			(xy 102.680758 -102.217195) (xy 102.595375 -102.225107) (xy 102.509625 -102.225107) (xy 102.424242 -102.217195)
			(xy 102.339952 -102.201439) (xy 102.257476 -102.177972) (xy 102.177517 -102.146996) (xy 102.100757 -102.108774)
			(xy 102.027851 -102.063633) (xy 101.959422 -102.011957) (xy 101.896052 -101.954188) (xy 101.838283 -101.890818)
			(xy 101.786607 -101.822389) (xy 101.741466 -101.749483) (xy 101.703244 -101.672723) (xy 101.672268 -101.592764)
			(xy 101.648801 -101.510288) (xy 101.633045 -101.425998) (xy 101.625133 -101.340615) (xy 100.939867 -101.340615)
			(xy 100.931955 -101.425998) (xy 100.916199 -101.510288) (xy 100.892732 -101.592764) (xy 100.861756 -101.672723)
			(xy 100.823534 -101.749483) (xy 100.778393 -101.822389) (xy 100.726717 -101.890818) (xy 100.668948 -101.954188)
			(xy 100.605578 -102.011957) (xy 100.537149 -102.063633) (xy 100.464243 -102.108774) (xy 100.387483 -102.146996)
			(xy 100.307524 -102.177972) (xy 100.225048 -102.201439) (xy 100.140758 -102.217195) (xy 100.055375 -102.225107)
			(xy 99.969625 -102.225107) (xy 99.884242 -102.217195) (xy 99.799952 -102.201439) (xy 99.717476 -102.177972)
			(xy 99.637517 -102.146996) (xy 99.560757 -102.108774) (xy 99.487851 -102.063633) (xy 99.419422 -102.011957)
			(xy 99.356052 -101.954188) (xy 99.298283 -101.890818) (xy 99.246607 -101.822389) (xy 99.201466 -101.749483)
			(xy 99.163244 -101.672723) (xy 99.132268 -101.592764) (xy 99.108801 -101.510288) (xy 99.093045 -101.425998)
			(xy 99.085133 -101.340615) (xy 98.122681 -101.340615) (xy 98.116111 -101.41152) (xy 98.100355 -101.49581)
			(xy 98.076888 -101.578286) (xy 98.045912 -101.658245) (xy 98.00769 -101.735005) (xy 97.962549 -101.807911)
			(xy 97.910873 -101.87634) (xy 97.853104 -101.93971) (xy 97.789734 -101.997479) (xy 97.721305 -102.049155)
			(xy 97.648399 -102.094296) (xy 97.571639 -102.132518) (xy 97.49168 -102.163494) (xy 97.409204 -102.186961)
			(xy 97.324914 -102.202717) (xy 97.239531 -102.210629) (xy 97.153781 -102.210629) (xy 97.068398 -102.202717)
			(xy 96.984108 -102.186961) (xy 96.901632 -102.163494) (xy 96.821673 -102.132518) (xy 96.744913 -102.094296)
			(xy 96.672007 -102.049155) (xy 96.603578 -101.997479) (xy 96.540208 -101.93971) (xy 96.482439 -101.87634)
			(xy 96.430763 -101.807911) (xy 96.385622 -101.735005) (xy 96.3474 -101.658245) (xy 96.316424 -101.578286)
			(xy 96.292957 -101.49581) (xy 96.277201 -101.41152) (xy 96.269289 -101.326137) (xy 95.584023 -101.326137)
			(xy 95.576111 -101.41152) (xy 95.560355 -101.49581) (xy 95.536888 -101.578286) (xy 95.505912 -101.658245)
			(xy 95.46769 -101.735005) (xy 95.422549 -101.807911) (xy 95.370873 -101.87634) (xy 95.313104 -101.93971)
			(xy 95.249734 -101.997479) (xy 95.181305 -102.049155) (xy 95.108399 -102.094296) (xy 95.031639 -102.132518)
			(xy 94.95168 -102.163494) (xy 94.869204 -102.186961) (xy 94.784914 -102.202717) (xy 94.699531 -102.210629)
			(xy 94.613781 -102.210629) (xy 94.528398 -102.202717) (xy 94.444108 -102.186961) (xy 94.361632 -102.163494)
			(xy 94.281673 -102.132518) (xy 94.204913 -102.094296) (xy 94.132007 -102.049155) (xy 94.063578 -101.997479)
			(xy 94.000208 -101.93971) (xy 93.942439 -101.87634) (xy 93.890763 -101.807911) (xy 93.845622 -101.735005)
			(xy 93.8074 -101.658245) (xy 93.776424 -101.578286) (xy 93.752957 -101.49581) (xy 93.737201 -101.41152)
			(xy 93.729289 -101.326137) (xy 92.50807 -101.326137) (xy 92.50807 -103.650796) (xy 103.194612 -103.650796)
			(xy 104.445308 -103.650796) (xy 104.445308 -104.416352) (xy 103.194612 -104.416352) (xy 103.194612 -103.650796)
			(xy 92.50807 -103.650796) (xy 92.50807 -107.690615) (xy 99.085133 -107.690615) (xy 99.085133 -107.604865)
			(xy 99.093045 -107.519482) (xy 99.108801 -107.435192) (xy 99.132268 -107.352716) (xy 99.163244 -107.272757)
			(xy 99.201466 -107.195997) (xy 99.246607 -107.123091) (xy 99.298283 -107.054662) (xy 99.356052 -106.991292)
			(xy 99.419422 -106.933523) (xy 99.487851 -106.881847) (xy 99.560757 -106.836706) (xy 99.637517 -106.798484)
			(xy 99.717476 -106.767508) (xy 99.799952 -106.744041) (xy 99.884242 -106.728285) (xy 99.969625 -106.720373)
			(xy 100.055375 -106.720373) (xy 100.140758 -106.728285) (xy 100.225048 -106.744041) (xy 100.307524 -106.767508)
			(xy 100.387483 -106.798484) (xy 100.464243 -106.836706) (xy 100.537149 -106.881847) (xy 100.605578 -106.933523)
			(xy 100.668948 -106.991292) (xy 100.726717 -107.054662) (xy 100.778393 -107.123091) (xy 100.823534 -107.195997)
			(xy 100.861756 -107.272757) (xy 100.892732 -107.352716) (xy 100.916199 -107.435192) (xy 100.931955 -107.519482)
			(xy 100.939867 -107.604865) (xy 100.940362 -107.64774) (xy 100.939867 -107.690615) (xy 101.625133 -107.690615)
			(xy 101.625133 -107.604865) (xy 101.633045 -107.519482) (xy 101.648801 -107.435192) (xy 101.672268 -107.352716)
			(xy 101.703244 -107.272757) (xy 101.741466 -107.195997) (xy 101.786607 -107.123091) (xy 101.838283 -107.054662)
			(xy 101.896052 -106.991292) (xy 101.959422 -106.933523) (xy 102.027851 -106.881847) (xy 102.100757 -106.836706)
			(xy 102.177517 -106.798484) (xy 102.257476 -106.767508) (xy 102.339952 -106.744041) (xy 102.424242 -106.728285)
			(xy 102.509625 -106.720373) (xy 102.595375 -106.720373) (xy 102.680758 -106.728285) (xy 102.765048 -106.744041)
			(xy 102.847524 -106.767508) (xy 102.927483 -106.798484) (xy 103.004243 -106.836706) (xy 103.077149 -106.881847)
			(xy 103.145578 -106.933523) (xy 103.208948 -106.991292) (xy 103.266717 -107.054662) (xy 103.318393 -107.123091)
			(xy 103.363534 -107.195997) (xy 103.401756 -107.272757) (xy 103.432732 -107.352716) (xy 103.456199 -107.435192)
			(xy 103.471955 -107.519482) (xy 103.479867 -107.604865) (xy 103.480362 -107.64774) (xy 103.479867 -107.690615)
			(xy 104.165133 -107.690615) (xy 104.165133 -107.604865) (xy 104.173045 -107.519482) (xy 104.188801 -107.435192)
			(xy 104.212268 -107.352716) (xy 104.243244 -107.272757) (xy 104.281466 -107.195997) (xy 104.326607 -107.123091)
			(xy 104.378283 -107.054662) (xy 104.436052 -106.991292) (xy 104.499422 -106.933523) (xy 104.567851 -106.881847)
			(xy 104.640757 -106.836706) (xy 104.717517 -106.798484) (xy 104.797476 -106.767508) (xy 104.879952 -106.744041)
			(xy 104.964242 -106.728285) (xy 105.049625 -106.720373) (xy 105.135375 -106.720373) (xy 105.220758 -106.728285)
			(xy 105.305048 -106.744041) (xy 105.387524 -106.767508) (xy 105.467483 -106.798484) (xy 105.544243 -106.836706)
			(xy 105.617149 -106.881847) (xy 105.685578 -106.933523) (xy 105.748948 -106.991292) (xy 105.806717 -107.054662)
			(xy 105.858393 -107.123091) (xy 105.903534 -107.195997) (xy 105.941756 -107.272757) (xy 105.972732 -107.352716)
			(xy 105.996199 -107.435192) (xy 106.011955 -107.519482) (xy 106.019867 -107.604865) (xy 106.020362 -107.64774)
			(xy 106.019867 -107.690615) (xy 106.011955 -107.775998) (xy 105.996199 -107.860288) (xy 105.972732 -107.942764)
			(xy 105.941756 -108.022723) (xy 105.903534 -108.099483) (xy 105.858393 -108.172389) (xy 105.806717 -108.240818)
			(xy 105.748948 -108.304188) (xy 105.685578 -108.361957) (xy 105.617149 -108.413633) (xy 105.544243 -108.458774)
			(xy 105.467483 -108.496996) (xy 105.387524 -108.527972) (xy 105.305048 -108.551439) (xy 105.220758 -108.567195)
			(xy 105.135375 -108.575107) (xy 105.049625 -108.575107) (xy 104.964242 -108.567195) (xy 104.879952 -108.551439)
			(xy 104.797476 -108.527972) (xy 104.717517 -108.496996) (xy 104.640757 -108.458774) (xy 104.567851 -108.413633)
			(xy 104.499422 -108.361957) (xy 104.436052 -108.304188) (xy 104.378283 -108.240818) (xy 104.326607 -108.172389)
			(xy 104.281466 -108.099483) (xy 104.243244 -108.022723) (xy 104.212268 -107.942764) (xy 104.188801 -107.860288)
			(xy 104.173045 -107.775998) (xy 104.165133 -107.690615) (xy 103.479867 -107.690615) (xy 103.471955 -107.775998)
			(xy 103.456199 -107.860288) (xy 103.432732 -107.942764) (xy 103.401756 -108.022723) (xy 103.363534 -108.099483)
			(xy 103.318393 -108.172389) (xy 103.266717 -108.240818) (xy 103.208948 -108.304188) (xy 103.145578 -108.361957)
			(xy 103.077149 -108.413633) (xy 103.004243 -108.458774) (xy 102.927483 -108.496996) (xy 102.847524 -108.527972)
			(xy 102.765048 -108.551439) (xy 102.680758 -108.567195) (xy 102.595375 -108.575107) (xy 102.509625 -108.575107)
			(xy 102.424242 -108.567195) (xy 102.339952 -108.551439) (xy 102.257476 -108.527972) (xy 102.177517 -108.496996)
			(xy 102.100757 -108.458774) (xy 102.027851 -108.413633) (xy 101.959422 -108.361957) (xy 101.896052 -108.304188)
			(xy 101.838283 -108.240818) (xy 101.786607 -108.172389) (xy 101.741466 -108.099483) (xy 101.703244 -108.022723)
			(xy 101.672268 -107.942764) (xy 101.648801 -107.860288) (xy 101.633045 -107.775998) (xy 101.625133 -107.690615)
			(xy 100.939867 -107.690615) (xy 100.931955 -107.775998) (xy 100.916199 -107.860288) (xy 100.892732 -107.942764)
			(xy 100.861756 -108.022723) (xy 100.823534 -108.099483) (xy 100.778393 -108.172389) (xy 100.726717 -108.240818)
			(xy 100.668948 -108.304188) (xy 100.605578 -108.361957) (xy 100.537149 -108.413633) (xy 100.464243 -108.458774)
			(xy 100.387483 -108.496996) (xy 100.307524 -108.527972) (xy 100.225048 -108.551439) (xy 100.140758 -108.567195)
			(xy 100.055375 -108.575107) (xy 99.969625 -108.575107) (xy 99.884242 -108.567195) (xy 99.799952 -108.551439)
			(xy 99.717476 -108.527972) (xy 99.637517 -108.496996) (xy 99.560757 -108.458774) (xy 99.487851 -108.413633)
			(xy 99.419422 -108.361957) (xy 99.356052 -108.304188) (xy 99.298283 -108.240818) (xy 99.246607 -108.172389)
			(xy 99.201466 -108.099483) (xy 99.163244 -108.022723) (xy 99.132268 -107.942764) (xy 99.108801 -107.860288)
			(xy 99.093045 -107.775998) (xy 99.085133 -107.690615) (xy 92.50807 -107.690615) (xy 92.50807 -115.464644)
			(xy 115.904253 -115.464644) (xy 115.904253 -115.335504) (xy 115.912203 -115.206609) (xy 115.928073 -115.078449)
			(xy 115.951802 -114.951508) (xy 115.983301 -114.826269) (xy 116.02245 -114.703206) (xy 116.069101 -114.582787)
			(xy 116.123076 -114.465468) (xy 116.184171 -114.351694) (xy 116.252154 -114.241897) (xy 116.326768 -114.136494)
			(xy 116.407729 -114.035884) (xy 116.494729 -113.940449) (xy 116.58744 -113.85055) (xy 116.68551 -113.766529)
			(xy 116.788565 -113.688705) (xy 116.896216 -113.617373) (xy 117.008055 -113.552803) (xy 117.123656 -113.495241)
			(xy 117.242581 -113.444904) (xy 117.36438 -113.401984) (xy 117.48859 -113.366643) (xy 117.614739 -113.339016)
			(xy 117.742351 -113.319207) (xy 117.87094 -113.307291) (xy 118.000018 -113.303315) (xy 118.129096 -113.307291)
			(xy 118.257685 -113.319207) (xy 118.385297 -113.339016) (xy 118.511446 -113.366643) (xy 118.635656 -113.401984)
			(xy 118.757455 -113.444904) (xy 118.87638 -113.495241) (xy 118.991981 -113.552803) (xy 119.10382 -113.617373)
			(xy 119.211471 -113.688705) (xy 119.314526 -113.766529) (xy 119.412596 -113.85055) (xy 119.505307 -113.940449)
			(xy 119.592307 -114.035884) (xy 119.673268 -114.136494) (xy 119.747882 -114.241897) (xy 119.815865 -114.351694)
			(xy 119.87696 -114.465468) (xy 119.930935 -114.582787) (xy 119.977586 -114.703206) (xy 120.016735 -114.826269)
			(xy 120.048234 -114.951508) (xy 120.071963 -115.078449) (xy 120.087833 -115.206609) (xy 120.095783 -115.335504)
			(xy 120.09628 -115.400074) (xy 120.095783 -115.464644) (xy 120.087833 -115.593539) (xy 120.071963 -115.721699)
			(xy 120.048234 -115.84864) (xy 120.016735 -115.973879) (xy 119.977586 -116.096942) (xy 119.930935 -116.217361)
			(xy 119.87696 -116.33468) (xy 119.815865 -116.448454) (xy 119.747882 -116.558251) (xy 119.673268 -116.663654)
			(xy 119.592307 -116.764264) (xy 119.505307 -116.859699) (xy 119.412596 -116.949598) (xy 119.314526 -117.033619)
			(xy 119.211471 -117.111443) (xy 119.10382 -117.182775) (xy 118.991981 -117.247345) (xy 118.87638 -117.304907)
			(xy 118.757455 -117.355244) (xy 118.635656 -117.398164) (xy 118.511446 -117.433505) (xy 118.385297 -117.461132)
			(xy 118.257685 -117.480941) (xy 118.129096 -117.492857) (xy 118.000018 -117.496834) (xy 117.87094 -117.492857)
			(xy 117.742351 -117.480941) (xy 117.614739 -117.461132) (xy 117.48859 -117.433505) (xy 117.36438 -117.398164)
			(xy 117.242581 -117.355244) (xy 117.123656 -117.304907) (xy 117.008055 -117.247345) (xy 116.896216 -117.182775)
			(xy 116.788565 -117.111443) (xy 116.68551 -117.033619) (xy 116.58744 -116.949598) (xy 116.494729 -116.859699)
			(xy 116.407729 -116.764264) (xy 116.326768 -116.663654) (xy 116.252154 -116.558251) (xy 116.184171 -116.448454)
			(xy 116.123076 -116.33468) (xy 116.069101 -116.217361) (xy 116.02245 -116.096942) (xy 115.983301 -115.973879)
			(xy 115.951802 -115.84864) (xy 115.928073 -115.721699) (xy 115.912203 -115.593539) (xy 115.904253 -115.464644)
			(xy 92.50807 -115.464644) (xy 92.50807 -118.400068) (xy 92.508591 -118.455876) (xy 92.516929 -118.567181)
			(xy 92.533562 -118.677551) (xy 92.558397 -118.78637) (xy 92.591294 -118.893028) (xy 92.63207 -118.99693)
			(xy 92.680497 -119.097494) (xy 92.736303 -119.194158) (xy 92.799176 -119.286381) (xy 92.868766 -119.373648)
			(xy 92.944683 -119.45547) (xy 93.026502 -119.531391) (xy 93.113766 -119.600984) (xy 93.205986 -119.663862)
			(xy 93.302648 -119.719673) (xy 93.40321 -119.768103) (xy 93.50711 -119.808884) (xy 93.613767 -119.841786)
			(xy 93.722584 -119.866625) (xy 93.832954 -119.883263) (xy 93.944258 -119.891607) (xy 94.000066 -119.892064)
		)
		(stroke
			(width 0)
			(type solid)
		)
		(fill yes)
		(layer "In10.Cu")
		(net "GND_P1")
	)
	(gr_line
		(start 0 -112.300004)
		(end 0 -85.25002)
		(stroke
			(width 0.05)
			(type default)
		)
		(layer "Edge.Cuts")
	)
	(gr_arc
		(start 0 -112.300004)
		(mid 0.585785 -113.714215)
		(end 1.999996 -114.3)
		(stroke
			(width 0.05)
			(type default)
		)
		(layer "Edge.Cuts")
	)
	(gr_line
		(start 0 -81.250028)
		(end 0 -1.999996)
		(stroke
			(width 0.05)
			(type default)
		)
		(layer "Edge.Cuts")
	)
	(gr_arc
		(start 0 -81.250028)
		(mid 0.073204 -81.426762)
		(end 0.249936 -81.499964)
		(stroke
			(width 0.05)
			(type default)
		)
		(layer "Edge.Cuts")
	)
	(gr_arc
		(start 0.249936 -85.000084)
		(mid 0.073205 -85.073289)
		(end 0 -85.25002)
		(stroke
			(width 0.05)
			(type default)
		)
		(layer "Edge.Cuts")
	)
	(gr_line
		(start 0.249936 -85.000084)
		(end 2.249932 -85.000084)
		(stroke
			(width 0.05)
			(type default)
		)
		(layer "Edge.Cuts")
	)
	(gr_arc
		(start 1.999996 0)
		(mid 0.585785 -0.585785)
		(end 0 -1.999996)
		(stroke
			(width 0.05)
			(type default)
		)
		(layer "Edge.Cuts")
	)
	(gr_line
		(start 1.999996 0)
		(end 88.000078 0)
		(stroke
			(width 0.05)
			(type default)
		)
		(layer "Edge.Cuts")
	)
	(gr_arc
		(start 2.249932 -85.000084)
		(mid 2.603574 -84.8536)
		(end 2.750058 -84.499958)
		(stroke
			(width 0.05)
			(type default)
		)
		(layer "Edge.Cuts")
	)
	(gr_line
		(start 2.249932 -81.499964)
		(end 0.249936 -81.499964)
		(stroke
			(width 0.05)
			(type default)
		)
		(layer "Edge.Cuts")
	)
	(gr_line
		(start 2.750058 -84.499958)
		(end 2.750058 -82.00009)
		(stroke
			(width 0.05)
			(type default)
		)
		(layer "Edge.Cuts")
	)
	(gr_arc
		(start 2.750058 -82.00009)
		(mid 2.603574 -81.646448)
		(end 2.249932 -81.499964)
		(stroke
			(width 0.05)
			(type default)
		)
		(layer "Edge.Cuts")
	)
	(gr_line
		(start 4.500118 -114.3)
		(end 1.999996 -114.3)
		(stroke
			(width 0.05)
			(type default)
		)
		(layer "Edge.Cuts")
	)
	(gr_line
		(start 4.99999 -119.132096)
		(end 4.99999 -114.800126)
		(stroke
			(width 0.05)
			(type default)
		)
		(layer "Edge.Cuts")
	)
	(gr_arc
		(start 4.99999 -114.800126)
		(mid 4.853581 -114.446663)
		(end 4.500118 -114.3)
		(stroke
			(width 0.05)
			(type default)
		)
		(layer "Edge.Cuts")
	)
	(gr_line
		(start 5.732018 -120.400064)
		(end 4.99999 -119.132096)
		(stroke
			(width 0.05)
			(type default)
		)
		(layer "Edge.Cuts")
	)
	(gr_line
		(start 10.014966 -120.400064)
		(end 5.732018 -120.400064)
		(stroke
			(width 0.05)
			(type default)
		)
		(layer "Edge.Cuts")
	)
	(gr_line
		(start 10.765028 -119.650002)
		(end 10.014966 -120.400064)
		(stroke
			(width 0.05)
			(type default)
		)
		(layer "Edge.Cuts")
	)
	(gr_line
		(start 10.765028 -114.800126)
		(end 10.765028 -119.650002)
		(stroke
			(width 0.05)
			(type default)
		)
		(layer "Edge.Cuts")
	)
	(gr_arc
		(start 11.2649 -114.3)
		(mid 10.911422 -114.446573)
		(end 10.765028 -114.800126)
		(stroke
			(width 0.05)
			(type default)
		)
		(layer "Edge.Cuts")
	)
	(gr_line
		(start 12.765024 -114.3)
		(end 11.2649 -114.3)
		(stroke
			(width 0.05)
			(type default)
		)
		(layer "Edge.Cuts")
	)
	(gr_line
		(start 13.264896 -119.650002)
		(end 13.264896 -114.800126)
		(stroke
			(width 0.05)
			(type default)
		)
		(layer "Edge.Cuts")
	)
	(gr_arc
		(start 13.264896 -114.800126)
		(mid 13.118487 -114.446663)
		(end 12.765024 -114.3)
		(stroke
			(width 0.05)
			(type default)
		)
		(layer "Edge.Cuts")
	)
	(gr_line
		(start 14.014958 -120.400064)
		(end 13.264896 -119.650002)
		(stroke
			(width 0.05)
			(type default)
		)
		(layer "Edge.Cuts")
	)
	(gr_line
		(start 30.87497 -120.400064)
		(end 14.014958 -120.400064)
		(stroke
			(width 0.05)
			(type default)
		)
		(layer "Edge.Cuts")
	)
	(gr_line
		(start 31.625032 -119.650002)
		(end 30.87497 -120.400064)
		(stroke
			(width 0.05)
			(type default)
		)
		(layer "Edge.Cuts")
	)
	(gr_line
		(start 31.625032 -114.77498)
		(end 31.625032 -119.650002)
		(stroke
			(width 0.05)
			(type default)
		)
		(layer "Edge.Cuts")
	)
	(gr_line
		(start 34.37509 -119.650002)
		(end 34.37509 -114.77498)
		(stroke
			(width 0.05)
			(type default)
		)
		(layer "Edge.Cuts")
	)
	(gr_arc
		(start 34.37509 -114.77498)
		(mid 33.000188 -113.400078)
		(end 31.625032 -114.77498)
		(stroke
			(width 0.05)
			(type default)
		)
		(layer "Edge.Cuts")
	)
	(gr_line
		(start 35.124898 -120.400064)
		(end 34.37509 -119.650002)
		(stroke
			(width 0.05)
			(type default)
		)
		(layer "Edge.Cuts")
	)
	(gr_line
		(start 43.584876 -120.400064)
		(end 35.124898 -120.400064)
		(stroke
			(width 0.05)
			(type default)
		)
		(layer "Edge.Cuts")
	)
	(gr_line
		(start 44.334938 -119.650002)
		(end 43.584876 -120.400064)
		(stroke
			(width 0.05)
			(type default)
		)
		(layer "Edge.Cuts")
	)
	(gr_line
		(start 44.334938 -114.324892)
		(end 44.334938 -119.650002)
		(stroke
			(width 0.05)
			(type default)
		)
		(layer "Edge.Cuts")
	)
	(gr_line
		(start 46.185074 -119.650002)
		(end 46.185074 -114.324892)
		(stroke
			(width 0.05)
			(type default)
		)
		(layer "Edge.Cuts")
	)
	(gr_arc
		(start 46.185074 -114.324892)
		(mid 45.260006 -113.399824)
		(end 44.334938 -114.324892)
		(stroke
			(width 0.05)
			(type default)
		)
		(layer "Edge.Cuts")
	)
	(gr_line
		(start 46.934882 -120.400064)
		(end 46.185074 -119.650002)
		(stroke
			(width 0.05)
			(type default)
		)
		(layer "Edge.Cuts")
	)
	(gr_line
		(start 63.784988 -120.400064)
		(end 46.934882 -120.400064)
		(stroke
			(width 0.05)
			(type default)
		)
		(layer "Edge.Cuts")
	)
	(gr_line
		(start 64.53505 -119.650002)
		(end 63.784988 -120.400064)
		(stroke
			(width 0.05)
			(type default)
		)
		(layer "Edge.Cuts")
	)
	(gr_line
		(start 64.53505 -114.525044)
		(end 64.53505 -119.650002)
		(stroke
			(width 0.05)
			(type default)
		)
		(layer "Edge.Cuts")
	)
	(gr_line
		(start 66.784982 -119.650002)
		(end 66.784982 -114.525044)
		(stroke
			(width 0.05)
			(type default)
		)
		(layer "Edge.Cuts")
	)
	(gr_arc
		(start 66.784982 -114.525044)
		(mid 65.660016 -113.400078)
		(end 64.53505 -114.525044)
		(stroke
			(width 0.05)
			(type default)
		)
		(layer "Edge.Cuts")
	)
	(gr_line
		(start 67.535044 -120.400064)
		(end 66.784982 -119.650002)
		(stroke
			(width 0.05)
			(type default)
		)
		(layer "Edge.Cuts")
	)
	(gr_line
		(start 75.989942 -120.400064)
		(end 67.535044 -120.400064)
		(stroke
			(width 0.05)
			(type default)
		)
		(layer "Edge.Cuts")
	)
	(gr_line
		(start 76.740004 -119.650002)
		(end 75.989942 -120.400064)
		(stroke
			(width 0.05)
			(type default)
		)
		(layer "Edge.Cuts")
	)
	(gr_line
		(start 76.740004 -114.800126)
		(end 76.740004 -119.650002)
		(stroke
			(width 0.05)
			(type default)
		)
		(layer "Edge.Cuts")
	)
	(gr_arc
		(start 77.239876 -114.3)
		(mid 76.886398 -114.446573)
		(end 76.740004 -114.800126)
		(stroke
			(width 0.05)
			(type default)
		)
		(layer "Edge.Cuts")
	)
	(gr_line
		(start 78.74 -114.3)
		(end 77.239876 -114.3)
		(stroke
			(width 0.05)
			(type default)
		)
		(layer "Edge.Cuts")
	)
	(gr_line
		(start 79.240126 -119.650002)
		(end 79.240126 -114.800126)
		(stroke
			(width 0.05)
			(type default)
		)
		(layer "Edge.Cuts")
	)
	(gr_arc
		(start 79.240126 -114.800126)
		(mid 79.093642 -114.446484)
		(end 78.74 -114.3)
		(stroke
			(width 0.05)
			(type default)
		)
		(layer "Edge.Cuts")
	)
	(gr_line
		(start 79.989934 -120.400064)
		(end 79.240126 -119.650002)
		(stroke
			(width 0.05)
			(type default)
		)
		(layer "Edge.Cuts")
	)
	(gr_line
		(start 84.268056 -120.400064)
		(end 79.989934 -120.400064)
		(stroke
			(width 0.05)
			(type default)
		)
		(layer "Edge.Cuts")
	)
	(gr_line
		(start 85.000084 -119.132096)
		(end 84.268056 -120.400064)
		(stroke
			(width 0.05)
			(type default)
		)
		(layer "Edge.Cuts")
	)
	(gr_line
		(start 85.000084 -114.800126)
		(end 85.000084 -119.132096)
		(stroke
			(width 0.05)
			(type default)
		)
		(layer "Edge.Cuts")
	)
	(gr_arc
		(start 85.499956 -114.3)
		(mid 85.146478 -114.446573)
		(end 85.000084 -114.800126)
		(stroke
			(width 0.05)
			(type default)
		)
		(layer "Edge.Cuts")
	)
	(gr_arc
		(start 87.250016 -84.499958)
		(mid 87.39632 -84.853675)
		(end 87.749888 -85.000084)
		(stroke
			(width 0.05)
			(type default)
		)
		(layer "Edge.Cuts")
	)
	(gr_line
		(start 87.250016 -82.00009)
		(end 87.250016 -84.499958)
		(stroke
			(width 0.05)
			(type default)
		)
		(layer "Edge.Cuts")
	)
	(gr_line
		(start 87.749888 -85.000084)
		(end 89.749884 -85.000084)
		(stroke
			(width 0.05)
			(type default)
		)
		(layer "Edge.Cuts")
	)
	(gr_arc
		(start 87.749888 -81.499964)
		(mid 87.39641 -81.646537)
		(end 87.250016 -82.00009)
		(stroke
			(width 0.05)
			(type default)
		)
		(layer "Edge.Cuts")
	)
	(gr_line
		(start 88.000078 -114.3)
		(end 85.499956 -114.3)
		(stroke
			(width 0.05)
			(type default)
		)
		(layer "Edge.Cuts")
	)
	(gr_arc
		(start 88.000078 -114.3)
		(mid 89.414304 -113.714223)
		(end 90.000074 -112.300004)
		(stroke
			(width 0.05)
			(type default)
		)
		(layer "Edge.Cuts")
	)
	(gr_line
		(start 89.749884 -81.499964)
		(end 87.749888 -81.499964)
		(stroke
			(width 0.05)
			(type default)
		)
		(layer "Edge.Cuts")
	)
	(gr_arc
		(start 89.749884 -81.499964)
		(mid 89.926765 -81.426838)
		(end 90.000074 -81.250028)
		(stroke
			(width 0.05)
			(type default)
		)
		(layer "Edge.Cuts")
	)
	(gr_arc
		(start 90.000074 -85.25002)
		(mid 89.926789 -85.073172)
		(end 89.749884 -85.000084)
		(stroke
			(width 0.05)
			(type default)
		)
		(layer "Edge.Cuts")
	)
	(gr_line
		(start 90.000074 -85.25002)
		(end 90.000074 -112.300004)
		(stroke
			(width 0.05)
			(type default)
		)
		(layer "Edge.Cuts")
	)
	(gr_arc
		(start 90.000074 -1.999996)
		(mid 89.414286 -0.585796)
		(end 88.000078 0)
		(stroke
			(width 0.05)
			(type default)
		)
		(layer "Edge.Cuts")
	)
	(gr_line
		(start 90.000074 -1.999996)
		(end 90.000074 -81.250028)
		(stroke
			(width 0.05)
			(type default)
		)
		(layer "Edge.Cuts")
	)
	(via
		(at 34.1376 -100.2284)
		(size 0.6604)
		(drill 0.3302)
		(layers "F.Cu" "B.Cu")
		(net "RST_BMC_HW_R1")
	)
	(segment
		(start 33.02 -101.45395)
		(end 34.1376 -100.33635)
		(width 0.11684)
		(layer "B.Cu")
		(net "RST_BMC_HW_R1")
	)
	(segment
		(start 34.1376 -100.2284)
		(end 33.1089 -99.1997)
		(width 0.11684)
		(layer "B.Cu")
		(net "RST_BMC_HW_R1")
	)
	(segment
		(start 33.1089 -99.1997)
		(end 33.1089 -98.304096)
		(width 0.11684)
		(layer "B.Cu")
		(net "RST_BMC_HW_R1")
	)
	(segment
		(start 34.1376 -100.33635)
		(end 34.1376 -100.2284)
		(width 0.11684)
		(layer "B.Cu")
		(net "RST_BMC_HW_R1")
	)
	(segment
		(start 33.7058 -102.2858)
		(end 33.5788 -102.4128)
		(width 0.11684)
		(layer "F.Cu")
		(net "RST_BMC_HW_OUT")
	)
	(segment
		(start 28.650184 -104.77246)
		(end 28.80741 -104.77246)
		(width 0.11684)
		(layer "F.Cu")
		(net "RST_BMC_HW_OUT")
	)
	(segment
		(start 28.80741 -104.77246)
		(end 29.44495 -105.41)
		(width 0.11684)
		(layer "F.Cu")
		(net "RST_BMC_HW_OUT")
	)
	(segment
		(start 27.539696 -105.442004)
		(end 28.20924 -104.77246)
		(width 0.11684)
		(layer "F.Cu")
		(net "RST_BMC_HW_OUT")
	)
	(segment
		(start 31.1912 -102.4128)
		(end 30.861 -102.743)
		(width 0.11684)
		(layer "F.Cu")
		(net "RST_BMC_HW_OUT")
	)
	(segment
		(start 30.861 -102.743)
		(end 30.861 -103.378)
		(width 0.11684)
		(layer "F.Cu")
		(net "RST_BMC_HW_OUT")
	)
	(segment
		(start 30.48 -103.759)
		(end 29.663644 -103.759)
		(width 0.11684)
		(layer "F.Cu")
		(net "RST_BMC_HW_OUT")
	)
	(segment
		(start 33.5788 -102.4128)
		(end 31.1912 -102.4128)
		(width 0.11684)
		(layer "F.Cu")
		(net "RST_BMC_HW_OUT")
	)
	(segment
		(start 29.663644 -103.759)
		(end 28.650184 -104.77246)
		(width 0.11684)
		(layer "F.Cu")
		(net "RST_BMC_HW_OUT")
	)
	(segment
		(start 30.861 -103.378)
		(end 30.48 -103.759)
		(width 0.11684)
		(layer "F.Cu")
		(net "RST_BMC_HW_OUT")
	)
	(segment
		(start 28.20924 -104.77246)
		(end 28.650184 -104.77246)
		(width 0.11684)
		(layer "F.Cu")
		(net "RST_BMC_HW_OUT")
	)
	(segment
		(start 27.539696 -105.4608)
		(end 27.539696 -105.442004)
		(width 0.11684)
		(layer "F.Cu")
		(net "RST_BMC_HW_OUT")
	)
	(via
		(at 28.650184 -104.77246)
		(size 0.508)
		(drill 0.254)
		(layers "F.Cu" "B.Cu")
		(net "RST_BMC_HW_OUT")
	)
	(via
		(at 33.7058 -102.2858)
		(size 0.508)
		(drill 0.254)
		(layers "F.Cu" "B.Cu")
		(net "RST_BMC_HW_OUT")
	)
	(segment
		(start 34.798 -100.457)
		(end 33.7058 -101.5492)
		(width 0.11684)
		(layer "B.Cu")
		(net "RST_BMC_HW_OUT")
	)
	(segment
		(start 34.05886 -95.904304)
		(end 34.798 -96.643444)
		(width 0.11684)
		(layer "B.Cu")
		(net "RST_BMC_HW_OUT")
	)
	(segment
		(start 34.798 -96.643444)
		(end 34.798 -100.457)
		(width 0.11684)
		(layer "B.Cu")
		(net "RST_BMC_HW_OUT")
	)
	(segment
		(start 33.7058 -101.5492)
		(end 33.7058 -102.2858)
		(width 0.11684)
		(layer "B.Cu")
		(net "RST_BMC_HW_OUT")
	)
	(segment
		(start 68.072 -11.43)
		(end 68.199 -11.557)
		(width 0.11684)
		(layer "F.Cu")
		(net "REAR_AC_PWR_BMC_BTN_N")
	)
	(segment
		(start 67.183 -11.43)
		(end 68.072 -11.43)
		(width 0.11684)
		(layer "F.Cu")
		(net "REAR_AC_PWR_BMC_BTN_N")
	)
	(via
		(at 68.199 -11.557)
		(size 0.508)
		(drill 0.254)
		(layers "F.Cu" "B.Cu")
		(net "REAR_AC_PWR_BMC_BTN_N")
	)
	(segment
		(start 68.199 -12.42695)
		(end 68.17995 -12.446)
		(width 0.11684)
		(layer "B.Cu")
		(net "REAR_AC_PWR_BMC_BTN_N")
	)
	(segment
		(start 68.199 -11.557)
		(end 68.199 -12.42695)
		(width 0.11684)
		(layer "B.Cu")
		(net "REAR_AC_PWR_BMC_BTN_N")
	)
	(segment
		(start 68.17995 -13.462)
		(end 68.17995 -12.446)
		(width 0.11684)
		(layer "B.Cu")
		(net "REAR_AC_PWR_BMC_BTN_N")
	)
	(segment
		(start 68.17995 -14.478)
		(end 68.17995 -13.462)
		(width 0.11684)
		(layer "B.Cu")
		(net "REAR_AC_PWR_BMC_BTN_N")
	)
	(segment
		(start 60.894976 -40.971216)
		(end 61.2902 -40.575992)
		(width 0.11684)
		(layer "F.Cu")
		(net "AC_PWR_BMC_BTN_R_N")
	)
	(via
		(at 66.0527 -22.104604)
		(size 0.508)
		(drill 0.254)
		(layers "F.Cu" "B.Cu")
		(net "AC_PWR_BMC_BTN_R_N")
	)
	(via
		(at 61.2902 -40.575992)
		(size 0.4572)
		(drill 0.254)
		(layers "F.Cu" "B.Cu")
		(net "AC_PWR_BMC_BTN_R_N")
	)
	(via
		(at 65.812924 -16.764)
		(size 0.6604)
		(drill 0.3302)
		(layers "F.Cu" "B.Cu")
		(net "AC_PWR_BMC_BTN_R_N")
	)
	(segment
		(start 65.812924 -16.764)
		(end 65.812924 -14.166342)
		(width 0.11684)
		(layer "B.Cu")
		(net "AC_PWR_BMC_BTN_R_N")
	)
	(segment
		(start 65.812924 -19.219164)
		(end 65.812924 -16.764)
		(width 0.11684)
		(layer "B.Cu")
		(net "AC_PWR_BMC_BTN_R_N")
	)
	(segment
		(start 66.0527 -22.104604)
		(end 66.0527 -19.45894)
		(width 0.11684)
		(layer "B.Cu")
		(net "AC_PWR_BMC_BTN_R_N")
	)
	(segment
		(start 66.40195 -13.577316)
		(end 66.40195 -13.462)
		(width 0.11684)
		(layer "B.Cu")
		(net "AC_PWR_BMC_BTN_R_N")
	)
	(segment
		(start 66.0527 -19.45894)
		(end 65.812924 -19.219164)
		(width 0.11684)
		(layer "B.Cu")
		(net "AC_PWR_BMC_BTN_R_N")
	)
	(segment
		(start 65.812924 -14.166342)
		(end 66.40195 -13.577316)
		(width 0.11684)
		(layer "B.Cu")
		(net "AC_PWR_BMC_BTN_R_N")
	)
	(segment
		(start 64.94526 -32.300164)
		(end 65.604644 -32.959548)
		(width 0.10668)
		(layer "In4.Cu")
		(net "AC_PWR_BMC_BTN_R_N")
	)
	(segment
		(start 61.2902 -38.699948)
		(end 61.2902 -40.575992)
		(width 0.10668)
		(layer "In4.Cu")
		(net "AC_PWR_BMC_BTN_R_N")
	)
	(segment
		(start 67.000374 -24.968962)
		(end 67.000374 -25.369266)
		(width 0.10668)
		(layer "In4.Cu")
		(net "AC_PWR_BMC_BTN_R_N")
	)
	(segment
		(start 65.045844 -23.11146)
		(end 65.045844 -23.90013)
		(width 0.10668)
		(layer "In4.Cu")
		(net "AC_PWR_BMC_BTN_R_N")
	)
	(segment
		(start 65.604644 -32.959548)
		(end 65.604644 -34.385504)
		(width 0.10668)
		(layer "In4.Cu")
		(net "AC_PWR_BMC_BTN_R_N")
	)
	(segment
		(start 66.0527 -22.104604)
		(end 65.045844 -23.11146)
		(width 0.10668)
		(layer "In4.Cu")
		(net "AC_PWR_BMC_BTN_R_N")
	)
	(segment
		(start 65.604644 -34.385504)
		(end 61.2902 -38.699948)
		(width 0.10668)
		(layer "In4.Cu")
		(net "AC_PWR_BMC_BTN_R_N")
	)
	(segment
		(start 65.045844 -23.90013)
		(end 65.629282 -24.483568)
		(width 0.10668)
		(layer "In4.Cu")
		(net "AC_PWR_BMC_BTN_R_N")
	)
	(segment
		(start 66.51498 -24.483568)
		(end 67.000374 -24.968962)
		(width 0.10668)
		(layer "In4.Cu")
		(net "AC_PWR_BMC_BTN_R_N")
	)
	(segment
		(start 64.94526 -31.26867)
		(end 64.94526 -32.300164)
		(width 0.10668)
		(layer "In4.Cu")
		(net "AC_PWR_BMC_BTN_R_N")
	)
	(segment
		(start 66.7131 -25.65654)
		(end 66.7131 -26.92654)
		(width 0.10668)
		(layer "In4.Cu")
		(net "AC_PWR_BMC_BTN_R_N")
	)
	(segment
		(start 65.570354 -28.069286)
		(end 65.570354 -30.643576)
		(width 0.10668)
		(layer "In4.Cu")
		(net "AC_PWR_BMC_BTN_R_N")
	)
	(segment
		(start 65.570354 -30.643576)
		(end 64.94526 -31.26867)
		(width 0.10668)
		(layer "In4.Cu")
		(net "AC_PWR_BMC_BTN_R_N")
	)
	(segment
		(start 66.7131 -26.92654)
		(end 65.570354 -28.069286)
		(width 0.10668)
		(layer "In4.Cu")
		(net "AC_PWR_BMC_BTN_R_N")
	)
	(segment
		(start 67.000374 -25.369266)
		(end 66.7131 -25.65654)
		(width 0.10668)
		(layer "In4.Cu")
		(net "AC_PWR_BMC_BTN_R_N")
	)
	(segment
		(start 65.629282 -24.483568)
		(end 66.51498 -24.483568)
		(width 0.10668)
		(layer "In4.Cu")
		(net "AC_PWR_BMC_BTN_R_N")
	)
	(segment
		(start 68.391532 -10.780014)
		(end 68.961 -10.780014)
		(width 0.11684)
		(layer "F.Cu")
		(net "AC_PWR_BMC_BTN_N")
	)
	(segment
		(start 68.056506 -10.444988)
		(end 68.391532 -10.780014)
		(width 0.11684)
		(layer "F.Cu")
		(net "AC_PWR_BMC_BTN_N")
	)
	(via
		(at 68.056506 -10.444988)
		(size 0.508)
		(drill 0.254)
		(layers "F.Cu" "B.Cu")
		(net "AC_PWR_BMC_BTN_N")
	)
	(segment
		(start 68.056506 -10.444988)
		(end 67.20205 -11.299444)
		(width 0.11684)
		(layer "B.Cu")
		(net "AC_PWR_BMC_BTN_N")
	)
	(segment
		(start 67.20205 -11.299444)
		(end 67.20205 -12.446)
		(width 0.11684)
		(layer "B.Cu")
		(net "AC_PWR_BMC_BTN_N")
	)
	(segment
		(start 67.20205 -13.462)
		(end 67.20205 -12.446)
		(width 0.11684)
		(layer "B.Cu")
		(net "AC_PWR_BMC_BTN_N")
	)
	(segment
		(start 64.32296 -11.825986)
		(end 63.987172 -11.825986)
		(width 0.11684)
		(layer "F.Cu")
		(net "LED_D22_R1")
	)
	(segment
		(start 62.920118 -9.425686)
		(end 62.920118 -6.290056)
		(width 0.11684)
		(layer "F.Cu")
		(net "LED_D22_R1")
	)
	(segment
		(start 63.987172 -11.825986)
		(end 63.447676 -11.28649)
		(width 0.11684)
		(layer "F.Cu")
		(net "LED_D22_R1")
	)
	(segment
		(start 63.447676 -9.953244)
		(end 62.920118 -9.425686)
		(width 0.11684)
		(layer "F.Cu")
		(net "LED_D22_R1")
	)
	(segment
		(start 63.447676 -11.28649)
		(end 63.447676 -9.953244)
		(width 0.11684)
		(layer "F.Cu")
		(net "LED_D22_R1")
	)
	(segment
		(start 60.380118 -10.339832)
		(end 60.380118 -6.290056)
		(width 0.11684)
		(layer "F.Cu")
		(net "LED_D22_R")
	)
	(segment
		(start 59.182 -10.52195)
		(end 60.198 -10.52195)
		(width 0.11684)
		(layer "F.Cu")
		(net "LED_D22_R")
	)
	(segment
		(start 60.198 -10.52195)
		(end 60.380118 -10.339832)
		(width 0.11684)
		(layer "F.Cu")
		(net "LED_D22_R")
	)
	(segment
		(start 32.893 -6.913118)
		(end 32.893 -10.8458)
		(width 0.11684)
		(layer "F.Cu")
		(net "ID_LED_D_P3V3_AUX")
	)
	(segment
		(start 33.339786 -11.292586)
		(end 33.71596 -11.292586)
		(width 0.11684)
		(layer "F.Cu")
		(net "ID_LED_D_P3V3_AUX")
	)
	(segment
		(start 32.269938 -6.290056)
		(end 32.893 -6.913118)
		(width 0.11684)
		(layer "F.Cu")
		(net "ID_LED_D_P3V3_AUX")
	)
	(segment
		(start 32.893 -10.8458)
		(end 33.339786 -11.292586)
		(width 0.11684)
		(layer "F.Cu")
		(net "ID_LED_D_P3V3_AUX")
	)
	(segment
		(start 73.188576 -9.017)
		(end 72.849994 -8.678418)
		(width 0.11684)
		(layer "F.Cu")
		(net "REAR_AC_PWR_BTN")
	)
	(segment
		(start 70.931786 -12.517882)
		(end 71.103236 -12.689332)
		(width 0.11684)
		(layer "F.Cu")
		(net "REAR_AC_PWR_BTN")
	)
	(segment
		(start 73.72223 -10.522712)
		(end 73.83653 -10.637012)
		(width 0.11684)
		(layer "F.Cu")
		(net "REAR_AC_PWR_BTN")
	)
	(segment
		(start 70.931786 -11.091164)
		(end 70.931786 -12.517882)
		(width 0.11684)
		(layer "F.Cu")
		(net "REAR_AC_PWR_BTN")
	)
	(segment
		(start 72.849994 -8.678418)
		(end 72.849994 -7.39013)
		(width 0.11684)
		(layer "F.Cu")
		(net "REAR_AC_PWR_BTN")
	)
	(segment
		(start 71.501 -10.52195)
		(end 70.931786 -11.091164)
		(width 0.11684)
		(layer "F.Cu")
		(net "REAR_AC_PWR_BTN")
	)
	(segment
		(start 73.72223 -10.522712)
		(end 73.721468 -10.52195)
		(width 0.11684)
		(layer "F.Cu")
		(net "REAR_AC_PWR_BTN")
	)
	(segment
		(start 75.032108 -10.637012)
		(end 73.412096 -9.017)
		(width 0.11684)
		(layer "F.Cu")
		(net "REAR_AC_PWR_BTN")
	)
	(segment
		(start 71.103236 -12.689332)
		(end 71.103236 -13.128752)
		(width 0.11684)
		(layer "F.Cu")
		(net "REAR_AC_PWR_BTN")
	)
	(segment
		(start 72.644 -10.52195)
		(end 71.501 -10.52195)
		(width 0.11684)
		(layer "F.Cu")
		(net "REAR_AC_PWR_BTN")
	)
	(segment
		(start 73.83653 -10.637012)
		(end 75.032108 -10.637012)
		(width 0.11684)
		(layer "F.Cu")
		(net "REAR_AC_PWR_BTN")
	)
	(segment
		(start 73.412096 -9.017)
		(end 73.188576 -9.017)
		(width 0.11684)
		(layer "F.Cu")
		(net "REAR_AC_PWR_BTN")
	)
	(segment
		(start 73.721468 -10.52195)
		(end 72.644 -10.52195)
		(width 0.11684)
		(layer "F.Cu")
		(net "REAR_AC_PWR_BTN")
	)
	(via
		(at 71.103236 -13.128752)
		(size 0.508)
		(drill 0.254)
		(layers "F.Cu" "B.Cu")
		(net "REAR_AC_PWR_BTN")
	)
	(segment
		(start 70.520814 -13.711174)
		(end 71.103236 -13.128752)
		(width 0.11684)
		(layer "B.Cu")
		(net "REAR_AC_PWR_BTN")
	)
	(segment
		(start 68.98005 -13.462)
		(end 69.229224 -13.711174)
		(width 0.11684)
		(layer "B.Cu")
		(net "REAR_AC_PWR_BTN")
	)
	(segment
		(start 69.229224 -13.711174)
		(end 70.520814 -13.711174)
		(width 0.11684)
		(layer "B.Cu")
		(net "REAR_AC_PWR_BTN")
	)
	(segment
		(start 71.286624 -15.257018)
		(end 71.483982 -15.257018)
		(width 0.11684)
		(layer "F.Cu")
		(net "NC_U16_P1")
	)
	(segment
		(start 71.483982 -15.257018)
		(end 72.248014 -14.492986)
		(width 0.11684)
		(layer "F.Cu")
		(net "NC_U16_P1")
	)
	(segment
		(start 71.194422 -15.34922)
		(end 71.286624 -15.257018)
		(width 0.11684)
		(layer "F.Cu")
		(net "NC_U16_P1")
	)
	(segment
		(start 72.248014 -14.492986)
		(end 72.644 -14.492986)
		(width 0.11684)
		(layer "F.Cu")
		(net "NC_U16_P1")
	)
	(via
		(at 71.194422 -15.34922)
		(size 0.762)
		(drill 0.381)
		(layers "F.Cu" "B.Cu")
		(net "NC_U16_P1")
	)
	(segment
		(start 22.254718 -91.191842)
		(end 21.859494 -91.587066)
		(width 0.11684)
		(layer "F.Cu")
		(net "RST_SRST_PLD_BMC_R2_N")
	)
	(via
		(at 7.3914 -83.058)
		(size 0.6604)
		(drill 0.3302)
		(layers "F.Cu" "B.Cu")
		(net "RST_SRST_PLD_BMC_R2_N")
	)
	(via
		(at 22.254718 -91.191842)
		(size 0.4572)
		(drill 0.254)
		(layers "F.Cu" "B.Cu")
		(net "RST_SRST_PLD_BMC_R2_N")
	)
	(via
		(at 8.3058 -100.426774)
		(size 0.508)
		(drill 0.254)
		(layers "F.Cu" "B.Cu")
		(net "RST_SRST_PLD_BMC_R2_N")
	)
	(segment
		(start 8.128 -95.4532)
		(end 7.366 -96.2152)
		(width 0.11684)
		(layer "B.Cu")
		(net "RST_SRST_PLD_BMC_R2_N")
	)
	(segment
		(start 7.3914 -84.118704)
		(end 7.737348 -84.464652)
		(width 0.11684)
		(layer "B.Cu")
		(net "RST_SRST_PLD_BMC_R2_N")
	)
	(segment
		(start 10.287 -85.217)
		(end 10.287 -93.091)
		(width 0.11684)
		(layer "B.Cu")
		(net "RST_SRST_PLD_BMC_R2_N")
	)
	(segment
		(start 7.3914 -82.55)
		(end 7.3914 -83.058)
		(width 0.11684)
		(layer "B.Cu")
		(net "RST_SRST_PLD_BMC_R2_N")
	)
	(segment
		(start 6.604 -82.296)
		(end 6.731 -82.423)
		(width 0.11684)
		(layer "B.Cu")
		(net "RST_SRST_PLD_BMC_R2_N")
	)
	(segment
		(start 7.3914 -83.058)
		(end 7.3914 -84.118704)
		(width 0.11684)
		(layer "B.Cu")
		(net "RST_SRST_PLD_BMC_R2_N")
	)
	(segment
		(start 8.763 -92.964)
		(end 8.509 -93.218)
		(width 0.11684)
		(layer "B.Cu")
		(net "RST_SRST_PLD_BMC_R2_N")
	)
	(segment
		(start 10.16 -93.218)
		(end 9.7663 -93.218)
		(width 0.11684)
		(layer "B.Cu")
		(net "RST_SRST_PLD_BMC_R2_N")
	)
	(segment
		(start 6.426962 -81.610962)
		(end 6.604 -81.788)
		(width 0.11684)
		(layer "B.Cu")
		(net "RST_SRST_PLD_BMC_R2_N")
	)
	(segment
		(start 8.509 -94.107)
		(end 8.128 -94.488)
		(width 0.11684)
		(layer "B.Cu")
		(net "RST_SRST_PLD_BMC_R2_N")
	)
	(segment
		(start 8.509 -93.218)
		(end 8.509 -94.107)
		(width 0.11684)
		(layer "B.Cu")
		(net "RST_SRST_PLD_BMC_R2_N")
	)
	(segment
		(start 8.128 -94.488)
		(end 8.128 -95.4532)
		(width 0.11684)
		(layer "B.Cu")
		(net "RST_SRST_PLD_BMC_R2_N")
	)
	(segment
		(start 9.7663 -93.218)
		(end 9.15289 -92.964)
		(width 0.11684)
		(layer "B.Cu")
		(net "RST_SRST_PLD_BMC_R2_N")
	)
	(segment
		(start 6.731 -82.423)
		(end 7.2644 -82.423)
		(width 0.11684)
		(layer "B.Cu")
		(net "RST_SRST_PLD_BMC_R2_N")
	)
	(segment
		(start 6.604 -81.788)
		(end 6.604 -82.296)
		(width 0.11684)
		(layer "B.Cu")
		(net "RST_SRST_PLD_BMC_R2_N")
	)
	(segment
		(start 9.534652 -84.464652)
		(end 10.287 -85.217)
		(width 0.11684)
		(layer "B.Cu")
		(net "RST_SRST_PLD_BMC_R2_N")
	)
	(segment
		(start 5.43687 -81.13395)
		(end 6.164072 -81.435194)
		(width 0.11684)
		(layer "B.Cu")
		(net "RST_SRST_PLD_BMC_R2_N")
	)
	(segment
		(start 7.737348 -84.464652)
		(end 9.534652 -84.464652)
		(width 0.11684)
		(layer "B.Cu")
		(net "RST_SRST_PLD_BMC_R2_N")
	)
	(segment
		(start 6.164072 -81.435194)
		(end 6.426962 -81.610962)
		(width 0.11684)
		(layer "B.Cu")
		(net "RST_SRST_PLD_BMC_R2_N")
	)
	(segment
		(start 7.2644 -82.423)
		(end 7.3914 -82.55)
		(width 0.11684)
		(layer "B.Cu")
		(net "RST_SRST_PLD_BMC_R2_N")
	)
	(segment
		(start 9.15289 -92.964)
		(end 8.763 -92.964)
		(width 0.11684)
		(layer "B.Cu")
		(net "RST_SRST_PLD_BMC_R2_N")
	)
	(segment
		(start 5.334 -81.13395)
		(end 5.43687 -81.13395)
		(width 0.11684)
		(layer "B.Cu")
		(net "RST_SRST_PLD_BMC_R2_N")
	)
	(segment
		(start 7.366 -99.486974)
		(end 8.3058 -100.426774)
		(width 0.11684)
		(layer "B.Cu")
		(net "RST_SRST_PLD_BMC_R2_N")
	)
	(segment
		(start 10.287 -93.091)
		(end 10.16 -93.218)
		(width 0.11684)
		(layer "B.Cu")
		(net "RST_SRST_PLD_BMC_R2_N")
	)
	(segment
		(start 7.366 -96.2152)
		(end 7.366 -99.486974)
		(width 0.11684)
		(layer "B.Cu")
		(net "RST_SRST_PLD_BMC_R2_N")
	)
	(segment
		(start 11.94689 -98.94951)
		(end 12.573 -98.3234)
		(width 0.08382)
		(layer "In2.Cu")
		(net "RST_SRST_PLD_BMC_R2_N")
	)
	(segment
		(start 8.509 -101.8794)
		(end 9.598406 -101.8794)
		(width 0.08382)
		(layer "In2.Cu")
		(net "RST_SRST_PLD_BMC_R2_N")
	)
	(segment
		(start 12.573 -94.4118)
		(end 14.620748 -92.364052)
		(width 0.08382)
		(layer "In2.Cu")
		(net "RST_SRST_PLD_BMC_R2_N")
	)
	(segment
		(start 17.36598 -91.563952)
		(end 21.882608 -91.563952)
		(width 0.08382)
		(layer "In2.Cu")
		(net "RST_SRST_PLD_BMC_R2_N")
	)
	(segment
		(start 17.092168 -92.09024)
		(end 17.092168 -91.837764)
		(width 0.08382)
		(layer "In2.Cu")
		(net "RST_SRST_PLD_BMC_R2_N")
	)
	(segment
		(start 8.3058 -100.426774)
		(end 8.3058 -101.6762)
		(width 0.08382)
		(layer "In2.Cu")
		(net "RST_SRST_PLD_BMC_R2_N")
	)
	(segment
		(start 10.8458 -99.911916)
		(end 10.8458 -99.0854)
		(width 0.08382)
		(layer "In2.Cu")
		(net "RST_SRST_PLD_BMC_R2_N")
	)
	(segment
		(start 16.818356 -92.364052)
		(end 17.092168 -92.09024)
		(width 0.08382)
		(layer "In2.Cu")
		(net "RST_SRST_PLD_BMC_R2_N")
	)
	(segment
		(start 17.092168 -91.837764)
		(end 17.36598 -91.563952)
		(width 0.08382)
		(layer "In2.Cu")
		(net "RST_SRST_PLD_BMC_R2_N")
	)
	(segment
		(start 12.573 -98.3234)
		(end 12.573 -94.4118)
		(width 0.08382)
		(layer "In2.Cu")
		(net "RST_SRST_PLD_BMC_R2_N")
	)
	(segment
		(start 9.598406 -101.8794)
		(end 9.98728 -101.490526)
		(width 0.08382)
		(layer "In2.Cu")
		(net "RST_SRST_PLD_BMC_R2_N")
	)
	(segment
		(start 8.3058 -101.6762)
		(end 8.509 -101.8794)
		(width 0.08382)
		(layer "In2.Cu")
		(net "RST_SRST_PLD_BMC_R2_N")
	)
	(segment
		(start 10.98169 -98.94951)
		(end 11.94689 -98.94951)
		(width 0.08382)
		(layer "In2.Cu")
		(net "RST_SRST_PLD_BMC_R2_N")
	)
	(segment
		(start 9.98728 -100.770436)
		(end 10.8458 -99.911916)
		(width 0.08382)
		(layer "In2.Cu")
		(net "RST_SRST_PLD_BMC_R2_N")
	)
	(segment
		(start 9.98728 -101.490526)
		(end 9.98728 -100.770436)
		(width 0.08382)
		(layer "In2.Cu")
		(net "RST_SRST_PLD_BMC_R2_N")
	)
	(segment
		(start 10.8458 -99.0854)
		(end 10.98169 -98.94951)
		(width 0.08382)
		(layer "In2.Cu")
		(net "RST_SRST_PLD_BMC_R2_N")
	)
	(segment
		(start 21.882608 -91.563952)
		(end 22.254718 -91.191842)
		(width 0.08382)
		(layer "In2.Cu")
		(net "RST_SRST_PLD_BMC_R2_N")
	)
	(segment
		(start 14.620748 -92.364052)
		(end 16.818356 -92.364052)
		(width 0.08382)
		(layer "In2.Cu")
		(net "RST_SRST_PLD_BMC_R2_N")
	)
	(segment
		(start 4.5339 -80.49895)
		(end 5.334 -81.29905)
		(width 0.11684)
		(layer "F.Cu")
		(net "RST_SRST_PLD_BMC_R1_N")
	)
	(segment
		(start 4.318 -80.49895)
		(end 4.5339 -80.49895)
		(width 0.11684)
		(layer "F.Cu")
		(net "RST_SRST_PLD_BMC_R1_N")
	)
	(segment
		(start 6.46303 -81.59242)
		(end 6.789166 -81.59242)
		(width 0.11684)
		(layer "F.Cu")
		(net "RST_SRST_PLD_BMC_R1_N")
	)
	(segment
		(start 6.789166 -81.59242)
		(end 7.09676 -81.900014)
		(width 0.11684)
		(layer "F.Cu")
		(net "RST_SRST_PLD_BMC_R1_N")
	)
	(segment
		(start 6.076696 -81.4324)
		(end 6.46303 -81.59242)
		(width 0.11684)
		(layer "F.Cu")
		(net "RST_SRST_PLD_BMC_R1_N")
	)
	(segment
		(start 7.09676 -81.900014)
		(end 7.17804 -81.900014)
		(width 0.11684)
		(layer "F.Cu")
		(net "RST_SRST_PLD_BMC_R1_N")
	)
	(segment
		(start 5.334 -81.29905)
		(end 5.46735 -81.4324)
		(width 0.11684)
		(layer "F.Cu")
		(net "RST_SRST_PLD_BMC_R1_N")
	)
	(segment
		(start 5.46735 -81.4324)
		(end 6.076696 -81.4324)
		(width 0.11684)
		(layer "F.Cu")
		(net "RST_SRST_PLD_BMC_R1_N")
	)
	(segment
		(start 45.695108 -40.971216)
		(end 45.299884 -40.575992)
		(width 0.11684)
		(layer "F.Cu")
		(net "RMII_OCP_RCLKI_R_ISO")
	)
	(segment
		(start 39.4462 -26.51125)
		(end 39.4462 -27.7114)
		(width 0.11684)
		(layer "F.Cu")
		(net "RMII_OCP_RCLKI_R_ISO")
	)
	(segment
		(start 39.4462 -27.7114)
		(end 38.8112 -28.3464)
		(width 0.11684)
		(layer "F.Cu")
		(net "RMII_OCP_RCLKI_R_ISO")
	)
	(via
		(at 38.8112 -28.3464)
		(size 0.508)
		(drill 0.254)
		(layers "F.Cu" "B.Cu")
		(net "RMII_OCP_RCLKI_R_ISO")
	)
	(via
		(at 45.299884 -40.575992)
		(size 0.4572)
		(drill 0.254)
		(layers "F.Cu" "B.Cu")
		(net "RMII_OCP_RCLKI_R_ISO")
	)
	(segment
		(start 39.0906 -33.0708)
		(end 39.0906 -30.7086)
		(width 0.11684)
		(layer "B.Cu")
		(net "RMII_OCP_RCLKI_R_ISO")
	)
	(segment
		(start 43.27906 -39.243)
		(end 43.27906 -38.75786)
		(width 0.11684)
		(layer "B.Cu")
		(net "RMII_OCP_RCLKI_R_ISO")
	)
	(segment
		(start 39.8526 -33.8328)
		(end 39.0906 -33.0708)
		(width 0.11684)
		(layer "B.Cu")
		(net "RMII_OCP_RCLKI_R_ISO")
	)
	(segment
		(start 44.09948 -39.529766)
		(end 43.95724 -39.387526)
		(width 0.11684)
		(layer "B.Cu")
		(net "RMII_OCP_RCLKI_R_ISO")
	)
	(segment
		(start 42.8117 -37.8079)
		(end 40.4876 -35.4838)
		(width 0.11684)
		(layer "B.Cu")
		(net "RMII_OCP_RCLKI_R_ISO")
	)
	(segment
		(start 39.8526 -34.4678)
		(end 39.8526 -33.8328)
		(width 0.11684)
		(layer "B.Cu")
		(net "RMII_OCP_RCLKI_R_ISO")
	)
	(segment
		(start 38.0492 -30.0736)
		(end 38.0492 -29.1084)
		(width 0.11684)
		(layer "B.Cu")
		(net "RMII_OCP_RCLKI_R_ISO")
	)
	(segment
		(start 44.75988 -40.1828)
		(end 44.25696 -40.1828)
		(width 0.11684)
		(layer "B.Cu")
		(net "RMII_OCP_RCLKI_R_ISO")
	)
	(segment
		(start 40.4876 -35.4838)
		(end 40.4876 -35.1028)
		(width 0.11684)
		(layer "B.Cu")
		(net "RMII_OCP_RCLKI_R_ISO")
	)
	(segment
		(start 38.6588 -30.2768)
		(end 38.2524 -30.2768)
		(width 0.11684)
		(layer "B.Cu")
		(net "RMII_OCP_RCLKI_R_ISO")
	)
	(segment
		(start 45.299884 -40.575992)
		(end 45.153072 -40.575992)
		(width 0.11684)
		(layer "B.Cu")
		(net "RMII_OCP_RCLKI_R_ISO")
	)
	(segment
		(start 44.25696 -40.1828)
		(end 44.09948 -40.02532)
		(width 0.11684)
		(layer "B.Cu")
		(net "RMII_OCP_RCLKI_R_ISO")
	)
	(segment
		(start 38.2524 -30.2768)
		(end 38.0492 -30.0736)
		(width 0.11684)
		(layer "B.Cu")
		(net "RMII_OCP_RCLKI_R_ISO")
	)
	(segment
		(start 40.4876 -35.1028)
		(end 39.8526 -34.4678)
		(width 0.11684)
		(layer "B.Cu")
		(net "RMII_OCP_RCLKI_R_ISO")
	)
	(segment
		(start 43.95724 -39.387526)
		(end 43.423586 -39.387526)
		(width 0.11684)
		(layer "B.Cu")
		(net "RMII_OCP_RCLKI_R_ISO")
	)
	(segment
		(start 39.0906 -30.7086)
		(end 38.6588 -30.2768)
		(width 0.11684)
		(layer "B.Cu")
		(net "RMII_OCP_RCLKI_R_ISO")
	)
	(segment
		(start 45.153072 -40.575992)
		(end 44.75988 -40.1828)
		(width 0.11684)
		(layer "B.Cu")
		(net "RMII_OCP_RCLKI_R_ISO")
	)
	(segment
		(start 43.27906 -38.75786)
		(end 42.8117 -38.2905)
		(width 0.11684)
		(layer "B.Cu")
		(net "RMII_OCP_RCLKI_R_ISO")
	)
	(segment
		(start 42.8117 -38.2905)
		(end 42.8117 -37.8079)
		(width 0.11684)
		(layer "B.Cu")
		(net "RMII_OCP_RCLKI_R_ISO")
	)
	(segment
		(start 44.09948 -40.02532)
		(end 44.09948 -39.529766)
		(width 0.11684)
		(layer "B.Cu")
		(net "RMII_OCP_RCLKI_R_ISO")
	)
	(segment
		(start 43.423586 -39.387526)
		(end 43.27906 -39.243)
		(width 0.11684)
		(layer "B.Cu")
		(net "RMII_OCP_RCLKI_R_ISO")
	)
	(segment
		(start 38.0492 -29.1084)
		(end 38.8112 -28.3464)
		(width 0.11684)
		(layer "B.Cu")
		(net "RMII_OCP_RCLKI_R_ISO")
	)
	(segment
		(start 39.97325 -26.2636)
		(end 41.116758 -26.2636)
		(width 0.11684)
		(layer "F.Cu")
		(net "RMII_OCP_RCLKI_ISO")
	)
	(segment
		(start 39.4462 -25.73655)
		(end 39.97325 -26.2636)
		(width 0.11684)
		(layer "F.Cu")
		(net "RMII_OCP_RCLKI_ISO")
	)
	(segment
		(start 39.4462 -25.71115)
		(end 39.4462 -25.73655)
		(width 0.11684)
		(layer "F.Cu")
		(net "RMII_OCP_RCLKI_ISO")
	)
	(segment
		(start 70.52945 -15.60068)
		(end 70.52945 -14.6431)
		(width 0.11684)
		(layer "F.Cu")
		(net "REAR_AC_PWR_BTN_N")
	)
	(segment
		(start 72.644 -15.85595)
		(end 72.37095 -16.129)
		(width 0.11684)
		(layer "F.Cu")
		(net "REAR_AC_PWR_BTN_N")
	)
	(segment
		(start 72.008746 -12.572746)
		(end 73.152 -12.572746)
		(width 0.11684)
		(layer "F.Cu")
		(net "REAR_AC_PWR_BTN_N")
	)
	(segment
		(start 73.152 -12.572746)
		(end 73.46315 -12.883896)
		(width 0.11684)
		(layer "F.Cu")
		(net "REAR_AC_PWR_BTN_N")
	)
	(segment
		(start 71.501 -12.065)
		(end 72.008746 -12.572746)
		(width 0.11684)
		(layer "F.Cu")
		(net "REAR_AC_PWR_BTN_N")
	)
	(segment
		(start 70.52945 -14.6431)
		(end 71.15175 -14.0208)
		(width 0.11684)
		(layer "F.Cu")
		(net "REAR_AC_PWR_BTN_N")
	)
	(segment
		(start 71.15175 -13.97)
		(end 71.15175 -14.0208)
		(width 0.11684)
		(layer "F.Cu")
		(net "REAR_AC_PWR_BTN_N")
	)
	(segment
		(start 73.46315 -12.883896)
		(end 73.46315 -13.429488)
		(width 0.11684)
		(layer "F.Cu")
		(net "REAR_AC_PWR_BTN_N")
	)
	(segment
		(start 72.644 -13.843)
		(end 71.27875 -13.843)
		(width 0.11684)
		(layer "F.Cu")
		(net "REAR_AC_PWR_BTN_N")
	)
	(segment
		(start 73.66 -13.626338)
		(end 73.66 -15.85595)
		(width 0.11684)
		(layer "F.Cu")
		(net "REAR_AC_PWR_BTN_N")
	)
	(segment
		(start 73.66 -15.85595)
		(end 72.644 -15.85595)
		(width 0.11684)
		(layer "F.Cu")
		(net "REAR_AC_PWR_BTN_N")
	)
	(segment
		(start 71.27875 -13.843)
		(end 71.15175 -13.97)
		(width 0.11684)
		(layer "F.Cu")
		(net "REAR_AC_PWR_BTN_N")
	)
	(segment
		(start 73.46315 -13.429488)
		(end 73.66 -13.626338)
		(width 0.11684)
		(layer "F.Cu")
		(net "REAR_AC_PWR_BTN_N")
	)
	(segment
		(start 71.05777 -16.129)
		(end 70.52945 -15.60068)
		(width 0.11684)
		(layer "F.Cu")
		(net "REAR_AC_PWR_BTN_N")
	)
	(segment
		(start 71.501 -11.32205)
		(end 71.501 -12.065)
		(width 0.11684)
		(layer "F.Cu")
		(net "REAR_AC_PWR_BTN_N")
	)
	(segment
		(start 72.37095 -16.129)
		(end 71.05777 -16.129)
		(width 0.11684)
		(layer "F.Cu")
		(net "REAR_AC_PWR_BTN_N")
	)
	(via
		(at 71.15175 -14.0208)
		(size 0.762)
		(drill 0.381)
		(layers "F.Cu" "B.Cu")
		(net "REAR_AC_PWR_BTN_N")
	)
	(segment
		(start 45.212 -26.2128)
		(end 44.31284 -25.31364)
		(width 0.11684)
		(layer "F.Cu")
		(net "PWRGD_P1V0_AUX_DELAY_R")
	)
	(segment
		(start 45.212 -26.47315)
		(end 45.212 -26.2128)
		(width 0.11684)
		(layer "F.Cu")
		(net "PWRGD_P1V0_AUX_DELAY_R")
	)
	(segment
		(start 44.31284 -25.31364)
		(end 43.566842 -25.31364)
		(width 0.11684)
		(layer "F.Cu")
		(net "PWRGD_P1V0_AUX_DELAY_R")
	)
	(segment
		(start 23.499318 -17.422114)
		(end 23.499318 -17.756632)
		(width 0.11684)
		(layer "B.Cu")
		(net "HDD_LED_P5V_AUX")
	)
	(segment
		(start 23.241 -6.551168)
		(end 23.241 -15.971774)
		(width 0.11684)
		(layer "B.Cu")
		(net "HDD_LED_P5V_AUX")
	)
	(segment
		(start 22.979888 -6.290056)
		(end 23.241 -6.551168)
		(width 0.11684)
		(layer "B.Cu")
		(net "HDD_LED_P5V_AUX")
	)
	(segment
		(start 23.764494 -17.156938)
		(end 23.499318 -17.422114)
		(width 0.11684)
		(layer "B.Cu")
		(net "HDD_LED_P5V_AUX")
	)
	(segment
		(start 23.499318 -17.756632)
		(end 22.987 -18.26895)
		(width 0.11684)
		(layer "B.Cu")
		(net "HDD_LED_P5V_AUX")
	)
	(segment
		(start 23.764494 -16.495268)
		(end 23.764494 -17.156938)
		(width 0.11684)
		(layer "B.Cu")
		(net "HDD_LED_P5V_AUX")
	)
	(segment
		(start 21.971 -18.30705)
		(end 22.9489 -18.30705)
		(width 0.11684)
		(layer "B.Cu")
		(net "HDD_LED_P5V_AUX")
	)
	(segment
		(start 22.9489 -18.30705)
		(end 22.987 -18.26895)
		(width 0.11684)
		(layer "B.Cu")
		(net "HDD_LED_P5V_AUX")
	)
	(segment
		(start 23.241 -15.971774)
		(end 23.764494 -16.495268)
		(width 0.11684)
		(layer "B.Cu")
		(net "HDD_LED_P5V_AUX")
	)
	(segment
		(start 53.594 -6.326124)
		(end 53.594 -10.39495)
		(width 0.11684)
		(layer "F.Cu")
		(net "LED_D21_R3")
	)
	(segment
		(start 53.630068 -6.290056)
		(end 53.594 -6.326124)
		(width 0.11684)
		(layer "F.Cu")
		(net "LED_D21_R3")
	)
	(segment
		(start 54.61 -11.19505)
		(end 54.61 -11.85291)
		(width 0.11684)
		(layer "F.Cu")
		(net "LED_D21_R2")
	)
	(segment
		(start 53.594 -11.917934)
		(end 53.594 -11.19505)
		(width 0.11684)
		(layer "F.Cu")
		(net "LED_D21_R2")
	)
	(segment
		(start 54.61 -11.85291)
		(end 54.069488 -12.393422)
		(width 0.11684)
		(layer "F.Cu")
		(net "LED_D21_R2")
	)
	(segment
		(start 54.069488 -12.393422)
		(end 53.594 -11.917934)
		(width 0.11684)
		(layer "F.Cu")
		(net "LED_D21_R2")
	)
	(via
		(at 54.069488 -12.393422)
		(size 0.762)
		(drill 0.381)
		(layers "F.Cu" "B.Cu")
		(net "LED_D21_R2")
	)
	(segment
		(start 54.61 -10.39495)
		(end 55.626 -10.39495)
		(width 0.11684)
		(layer "F.Cu")
		(net "LED_D21_R1")
	)
	(segment
		(start 27.629104 -13.081)
		(end 28.194 -13.081)
		(width 0.11684)
		(layer "F.Cu")
		(net "FM_ID_R_LED")
	)
	(segment
		(start 28.194 -13.081)
		(end 28.5496 -12.7254)
		(width 0.11684)
		(layer "F.Cu")
		(net "FM_ID_R_LED")
	)
	(segment
		(start 28.5496 -12.7254)
		(end 31.496 -12.7254)
		(width 0.11684)
		(layer "F.Cu")
		(net "FM_ID_R_LED")
	)
	(segment
		(start 32.34055 -12.7254)
		(end 32.36595 -12.7)
		(width 0.11684)
		(layer "F.Cu")
		(net "FM_ID_R_LED")
	)
	(segment
		(start 31.496 -12.7254)
		(end 32.34055 -12.7254)
		(width 0.11684)
		(layer "F.Cu")
		(net "FM_ID_R_LED")
	)
	(via
		(at 31.496 -12.7254)
		(size 0.762)
		(drill 0.381)
		(layers "F.Cu" "B.Cu")
		(net "FM_ID_R_LED")
	)
	(segment
		(start 16.259556 -97.187004)
		(end 15.8496 -97.59696)
		(width 0.11684)
		(layer "F.Cu")
		(net "AC_PWR_BTN_R2_N")
	)
	(segment
		(start 14.0716 -101.473)
		(end 13.6017 -101.9429)
		(width 0.11684)
		(layer "F.Cu")
		(net "AC_PWR_BTN_R2_N")
	)
	(segment
		(start 15.29842 -98.39198)
		(end 14.0716 -99.6188)
		(width 0.11684)
		(layer "F.Cu")
		(net "AC_PWR_BTN_R2_N")
	)
	(segment
		(start 15.7226 -98.39198)
		(end 15.29842 -98.39198)
		(width 0.11684)
		(layer "F.Cu")
		(net "AC_PWR_BTN_R2_N")
	)
	(segment
		(start 15.8496 -97.59696)
		(end 15.8496 -98.26498)
		(width 0.11684)
		(layer "F.Cu")
		(net "AC_PWR_BTN_R2_N")
	)
	(segment
		(start 15.8496 -98.26498)
		(end 15.7226 -98.39198)
		(width 0.11684)
		(layer "F.Cu")
		(net "AC_PWR_BTN_R2_N")
	)
	(segment
		(start 14.0716 -99.6188)
		(end 14.0716 -101.473)
		(width 0.11684)
		(layer "F.Cu")
		(net "AC_PWR_BTN_R2_N")
	)
	(segment
		(start 13.6017 -101.9429)
		(end 12.82065 -101.9429)
		(width 0.11684)
		(layer "F.Cu")
		(net "AC_PWR_BTN_R2_N")
	)
	(segment
		(start 12.728448 -101.495352)
		(end 12.468098 -101.495352)
		(width 0.11684)
		(layer "F.Cu")
		(net "AC_PWR_BTN_R1_N")
	)
	(segment
		(start 75.556364 -13.086334)
		(end 75.449684 -13.193014)
		(width 0.11684)
		(layer "F.Cu")
		(net "AC_PWR_BTN_R1_N")
	)
	(segment
		(start 11.99515 -101.9683)
		(end 12.02055 -101.9429)
		(width 0.11684)
		(layer "F.Cu")
		(net "AC_PWR_BTN_R1_N")
	)
	(segment
		(start 12.82065 -101.0539)
		(end 12.82065 -101.40315)
		(width 0.11684)
		(layer "F.Cu")
		(net "AC_PWR_BTN_R1_N")
	)
	(segment
		(start 12.468098 -101.495352)
		(end 12.02055 -101.9429)
		(width 0.11684)
		(layer "F.Cu")
		(net "AC_PWR_BTN_R1_N")
	)
	(segment
		(start 12.82065 -101.40315)
		(end 12.728448 -101.495352)
		(width 0.11684)
		(layer "F.Cu")
		(net "AC_PWR_BTN_R1_N")
	)
	(segment
		(start 11.25982 -101.9683)
		(end 11.99515 -101.9683)
		(width 0.11684)
		(layer "F.Cu")
		(net "AC_PWR_BTN_R1_N")
	)
	(segment
		(start 75.449684 -13.193014)
		(end 74.422 -13.193014)
		(width 0.11684)
		(layer "F.Cu")
		(net "AC_PWR_BTN_R1_N")
	)
	(via
		(at 75.556364 -13.086334)
		(size 0.508)
		(drill 0.254)
		(layers "F.Cu" "B.Cu")
		(net "AC_PWR_BTN_R1_N")
	)
	(via
		(at 13.31214 -48.30826)
		(size 0.508)
		(drill 0.254)
		(layers "F.Cu" "B.Cu")
		(net "AC_PWR_BTN_R1_N")
	)
	(via
		(at 53.122068 -13.630656)
		(size 0.508)
		(drill 0.254)
		(layers "F.Cu" "B.Cu")
		(net "AC_PWR_BTN_R1_N")
	)
	(via
		(at 11.25982 -101.9683)
		(size 0.508)
		(drill 0.254)
		(layers "F.Cu" "B.Cu")
		(net "AC_PWR_BTN_R1_N")
	)
	(via
		(at 16.31442 -77.01534)
		(size 0.508)
		(drill 0.254)
		(layers "F.Cu" "B.Cu")
		(net "AC_PWR_BTN_R1_N")
	)
	(segment
		(start 75.556364 -13.086334)
		(end 75.132184 -12.662154)
		(width 0.08382)
		(layer "In2.Cu")
		(net "AC_PWR_BTN_R1_N")
	)
	(segment
		(start 62.275212 -12.591796)
		(end 54.160928 -12.591796)
		(width 0.08382)
		(layer "In2.Cu")
		(net "AC_PWR_BTN_R1_N")
	)
	(segment
		(start 62.556898 -12.31011)
		(end 62.275212 -12.591796)
		(width 0.08382)
		(layer "In2.Cu")
		(net "AC_PWR_BTN_R1_N")
	)
	(segment
		(start 75.132184 -12.662154)
		(end 65.655444 -12.662154)
		(width 0.08382)
		(layer "In2.Cu")
		(net "AC_PWR_BTN_R1_N")
	)
	(segment
		(start 65.655444 -12.662154)
		(end 65.3034 -12.31011)
		(width 0.08382)
		(layer "In2.Cu")
		(net "AC_PWR_BTN_R1_N")
	)
	(segment
		(start 65.3034 -12.31011)
		(end 62.556898 -12.31011)
		(width 0.08382)
		(layer "In2.Cu")
		(net "AC_PWR_BTN_R1_N")
	)
	(segment
		(start 54.160928 -12.591796)
		(end 53.122068 -13.630656)
		(width 0.08382)
		(layer "In2.Cu")
		(net "AC_PWR_BTN_R1_N")
	)
	(segment
		(start 16.87576 -78.70698)
		(end 16.87576 -77.57668)
		(width 0.10668)
		(layer "In4.Cu")
		(net "AC_PWR_BTN_R1_N")
	)
	(segment
		(start 13.46454 -101.9683)
		(end 14.15034 -101.2825)
		(width 0.10668)
		(layer "In4.Cu")
		(net "AC_PWR_BTN_R1_N")
	)
	(segment
		(start 16.87576 -77.57668)
		(end 16.31442 -77.01534)
		(width 0.10668)
		(layer "In4.Cu")
		(net "AC_PWR_BTN_R1_N")
	)
	(segment
		(start 11.25982 -101.9683)
		(end 13.46454 -101.9683)
		(width 0.10668)
		(layer "In4.Cu")
		(net "AC_PWR_BTN_R1_N")
	)
	(segment
		(start 14.15034 -97.61728)
		(end 16.1925 -95.57512)
		(width 0.10668)
		(layer "In4.Cu")
		(net "AC_PWR_BTN_R1_N")
	)
	(segment
		(start 16.1925 -95.57512)
		(end 17.71396 -95.57512)
		(width 0.10668)
		(layer "In4.Cu")
		(net "AC_PWR_BTN_R1_N")
	)
	(segment
		(start 17.87906 -94.234)
		(end 17.07896 -93.4339)
		(width 0.10668)
		(layer "In4.Cu")
		(net "AC_PWR_BTN_R1_N")
	)
	(segment
		(start 17.87906 -81.82864)
		(end 17.26692 -81.2165)
		(width 0.10668)
		(layer "In4.Cu")
		(net "AC_PWR_BTN_R1_N")
	)
	(segment
		(start 17.3609 -83.27898)
		(end 17.87906 -82.76082)
		(width 0.10668)
		(layer "In4.Cu")
		(net "AC_PWR_BTN_R1_N")
	)
	(segment
		(start 17.71396 -95.57512)
		(end 17.87906 -95.41002)
		(width 0.10668)
		(layer "In4.Cu")
		(net "AC_PWR_BTN_R1_N")
	)
	(segment
		(start 17.26692 -81.2165)
		(end 17.26692 -79.09814)
		(width 0.10668)
		(layer "In4.Cu")
		(net "AC_PWR_BTN_R1_N")
	)
	(segment
		(start 17.07896 -93.4339)
		(end 17.07896 -87.7951)
		(width 0.10668)
		(layer "In4.Cu")
		(net "AC_PWR_BTN_R1_N")
	)
	(segment
		(start 17.87906 -95.41002)
		(end 17.87906 -94.234)
		(width 0.10668)
		(layer "In4.Cu")
		(net "AC_PWR_BTN_R1_N")
	)
	(segment
		(start 17.3609 -87.51316)
		(end 17.3609 -83.27898)
		(width 0.10668)
		(layer "In4.Cu")
		(net "AC_PWR_BTN_R1_N")
	)
	(segment
		(start 14.15034 -101.2825)
		(end 14.15034 -97.61728)
		(width 0.10668)
		(layer "In4.Cu")
		(net "AC_PWR_BTN_R1_N")
	)
	(segment
		(start 17.87906 -82.76082)
		(end 17.87906 -81.82864)
		(width 0.10668)
		(layer "In4.Cu")
		(net "AC_PWR_BTN_R1_N")
	)
	(segment
		(start 17.07896 -87.7951)
		(end 17.3609 -87.51316)
		(width 0.10668)
		(layer "In4.Cu")
		(net "AC_PWR_BTN_R1_N")
	)
	(segment
		(start 17.26692 -79.09814)
		(end 16.87576 -78.70698)
		(width 0.10668)
		(layer "In4.Cu")
		(net "AC_PWR_BTN_R1_N")
	)
	(segment
		(start 13.36294 -66.72072)
		(end 13.36294 -76.0857)
		(width 0.10668)
		(layer "In7.Cu")
		(net "AC_PWR_BTN_R1_N")
	)
	(segment
		(start 13.36294 -76.0857)
		(end 14.29258 -77.01534)
		(width 0.10668)
		(layer "In7.Cu")
		(net "AC_PWR_BTN_R1_N")
	)
	(segment
		(start 13.31214 -48.30826)
		(end 13.31214 -49.00168)
		(width 0.10668)
		(layer "In7.Cu")
		(net "AC_PWR_BTN_R1_N")
	)
	(segment
		(start 12.8905 -51.5874)
		(end 13.86332 -52.56022)
		(width 0.10668)
		(layer "In7.Cu")
		(net "AC_PWR_BTN_R1_N")
	)
	(segment
		(start 12.8905 -49.42332)
		(end 12.8905 -51.5874)
		(width 0.10668)
		(layer "In7.Cu")
		(net "AC_PWR_BTN_R1_N")
	)
	(segment
		(start 13.86332 -66.22034)
		(end 13.36294 -66.72072)
		(width 0.10668)
		(layer "In7.Cu")
		(net "AC_PWR_BTN_R1_N")
	)
	(segment
		(start 13.86332 -52.56022)
		(end 13.86332 -66.22034)
		(width 0.10668)
		(layer "In7.Cu")
		(net "AC_PWR_BTN_R1_N")
	)
	(segment
		(start 14.29258 -77.01534)
		(end 16.31442 -77.01534)
		(width 0.10668)
		(layer "In7.Cu")
		(net "AC_PWR_BTN_R1_N")
	)
	(segment
		(start 13.31214 -49.00168)
		(end 12.8905 -49.42332)
		(width 0.10668)
		(layer "In7.Cu")
		(net "AC_PWR_BTN_R1_N")
	)
	(segment
		(start 15.663926 -9.35228)
		(end 43.789092 -9.35228)
		(width 0.08382)
		(layer "In9.Cu")
		(net "AC_PWR_BTN_R1_N")
	)
	(segment
		(start 11.2014 -21.69414)
		(end 11.2014 -16.840962)
		(width 0.08382)
		(layer "In9.Cu")
		(net "AC_PWR_BTN_R1_N")
	)
	(segment
		(start 12.989814 -26.186638)
		(end 12.77112 -25.967944)
		(width 0.08382)
		(layer "In9.Cu")
		(net "AC_PWR_BTN_R1_N")
	)
	(segment
		(start 12.77112 -25.967944)
		(end 12.77112 -23.26386)
		(width 0.08382)
		(layer "In9.Cu")
		(net "AC_PWR_BTN_R1_N")
	)
	(segment
		(start 12.966192 -9.915652)
		(end 15.100554 -9.915652)
		(width 0.08382)
		(layer "In9.Cu")
		(net "AC_PWR_BTN_R1_N")
	)
	(segment
		(start 43.789092 -9.35228)
		(end 48.067468 -13.630656)
		(width 0.08382)
		(layer "In9.Cu")
		(net "AC_PWR_BTN_R1_N")
	)
	(segment
		(start 14.45895 -33.83915)
		(end 14.45895 -29.50083)
		(width 0.08382)
		(layer "In9.Cu")
		(net "AC_PWR_BTN_R1_N")
	)
	(segment
		(start 15.100554 -9.915652)
		(end 15.663926 -9.35228)
		(width 0.08382)
		(layer "In9.Cu")
		(net "AC_PWR_BTN_R1_N")
	)
	(segment
		(start 12.77112 -23.26386)
		(end 11.2014 -21.69414)
		(width 0.08382)
		(layer "In9.Cu")
		(net "AC_PWR_BTN_R1_N")
	)
	(segment
		(start 13.770102 -47.850298)
		(end 13.770102 -46.478698)
		(width 0.08382)
		(layer "In9.Cu")
		(net "AC_PWR_BTN_R1_N")
	)
	(segment
		(start 12.989814 -28.031694)
		(end 12.989814 -26.186638)
		(width 0.08382)
		(layer "In9.Cu")
		(net "AC_PWR_BTN_R1_N")
	)
	(segment
		(start 13.770102 -46.478698)
		(end 14.6939 -45.5549)
		(width 0.08382)
		(layer "In9.Cu")
		(net "AC_PWR_BTN_R1_N")
	)
	(segment
		(start 11.612372 -11.269472)
		(end 12.966192 -9.915652)
		(width 0.08382)
		(layer "In9.Cu")
		(net "AC_PWR_BTN_R1_N")
	)
	(segment
		(start 11.2014 -16.840962)
		(end 11.612372 -16.42999)
		(width 0.08382)
		(layer "In9.Cu")
		(net "AC_PWR_BTN_R1_N")
	)
	(segment
		(start 48.067468 -13.630656)
		(end 53.122068 -13.630656)
		(width 0.08382)
		(layer "In9.Cu")
		(net "AC_PWR_BTN_R1_N")
	)
	(segment
		(start 14.6939 -45.5549)
		(end 14.6939 -34.0741)
		(width 0.08382)
		(layer "In9.Cu")
		(net "AC_PWR_BTN_R1_N")
	)
	(segment
		(start 11.612372 -16.42999)
		(end 11.612372 -11.269472)
		(width 0.08382)
		(layer "In9.Cu")
		(net "AC_PWR_BTN_R1_N")
	)
	(segment
		(start 14.6939 -34.0741)
		(end 14.45895 -33.83915)
		(width 0.08382)
		(layer "In9.Cu")
		(net "AC_PWR_BTN_R1_N")
	)
	(segment
		(start 14.45895 -29.50083)
		(end 12.989814 -28.031694)
		(width 0.08382)
		(layer "In9.Cu")
		(net "AC_PWR_BTN_R1_N")
	)
	(segment
		(start 13.31214 -48.30826)
		(end 13.770102 -47.850298)
		(width 0.08382)
		(layer "In9.Cu")
		(net "AC_PWR_BTN_R1_N")
	)
	(segment
		(start 72.644 -11.32205)
		(end 72.644 -11.938)
		(width 0.11684)
		(layer "F.Cu")
		(net "AC_PWR_BTN_N")
	)
	(segment
		(start 75.045316 -70.058534)
		(end 73.213214 -71.890636)
		(width 0.11684)
		(layer "F.Cu")
		(net "AC_PWR_BTN_N")
	)
	(segment
		(start 70.943978 -90.091006)
		(end 70.943978 -98.681794)
		(width 0.11684)
		(layer "F.Cu")
		(net "AC_PWR_BTN_N")
	)
	(segment
		(start 35.72764 -116.3193)
		(end 35.455098 -116.591842)
		(width 0.11684)
		(layer "F.Cu")
		(net "AC_PWR_BTN_N")
	)
	(segment
		(start 70.943978 -72.800464)
		(end 70.943978 -87.433658)
		(width 0.11684)
		(layer "F.Cu")
		(net "AC_PWR_BTN_N")
	)
	(segment
		(start 75.045316 -63.042038)
		(end 75.045316 -70.058534)
		(width 0.11684)
		(layer "F.Cu")
		(net "AC_PWR_BTN_N")
	)
	(segment
		(start 71.308214 -89.72677)
		(end 70.943978 -90.091006)
		(width 0.11684)
		(layer "F.Cu")
		(net "AC_PWR_BTN_N")
	)
	(segment
		(start 70.943978 -98.681794)
		(end 73.018904 -100.75672)
		(width 0.11684)
		(layer "F.Cu")
		(net "AC_PWR_BTN_N")
	)
	(segment
		(start 35.455098 -116.591842)
		(end 35.455098 -118.460012)
		(width 0.11684)
		(layer "F.Cu")
		(net "AC_PWR_BTN_N")
	)
	(segment
		(start 31.98622 -110.00994)
		(end 35.72764 -113.75136)
		(width 0.11684)
		(layer "F.Cu")
		(net "AC_PWR_BTN_N")
	)
	(segment
		(start 71.853806 -71.890636)
		(end 70.943978 -72.800464)
		(width 0.11684)
		(layer "F.Cu")
		(net "AC_PWR_BTN_N")
	)
	(segment
		(start 70.943978 -87.433658)
		(end 71.308214 -87.797894)
		(width 0.11684)
		(layer "F.Cu")
		(net "AC_PWR_BTN_N")
	)
	(segment
		(start 35.72764 -113.75136)
		(end 35.72764 -116.3193)
		(width 0.11684)
		(layer "F.Cu")
		(net "AC_PWR_BTN_N")
	)
	(segment
		(start 73.213214 -71.890636)
		(end 71.853806 -71.890636)
		(width 0.11684)
		(layer "F.Cu")
		(net "AC_PWR_BTN_N")
	)
	(segment
		(start 75.981052 -62.106302)
		(end 75.045316 -63.042038)
		(width 0.11684)
		(layer "F.Cu")
		(net "AC_PWR_BTN_N")
	)
	(segment
		(start 71.308214 -87.797894)
		(end 71.308214 -89.72677)
		(width 0.11684)
		(layer "F.Cu")
		(net "AC_PWR_BTN_N")
	)
	(via
		(at 72.644 -11.938)
		(size 0.508)
		(drill 0.254)
		(layers "F.Cu" "B.Cu")
		(net "AC_PWR_BTN_N")
	)
	(via
		(at 75.981052 -62.106302)
		(size 0.508)
		(drill 0.254)
		(layers "F.Cu" "B.Cu")
		(net "AC_PWR_BTN_N")
	)
	(via
		(at 31.98622 -110.00994)
		(size 0.508)
		(drill 0.254)
		(layers "F.Cu" "B.Cu")
		(net "AC_PWR_BTN_N")
	)
	(via
		(at 73.018904 -100.75672)
		(size 0.508)
		(drill 0.254)
		(layers "F.Cu" "B.Cu")
		(net "AC_PWR_BTN_N")
	)
	(segment
		(start 53.78196 -106.56316)
		(end 51.02098 -106.56316)
		(width 0.08382)
		(layer "In2.Cu")
		(net "AC_PWR_BTN_N")
	)
	(segment
		(start 32.7914 -108.97616)
		(end 31.98622 -109.78134)
		(width 0.08382)
		(layer "In2.Cu")
		(net "AC_PWR_BTN_N")
	)
	(segment
		(start 73.018904 -101.192076)
		(end 72.7456 -101.46538)
		(width 0.08382)
		(layer "In2.Cu")
		(net "AC_PWR_BTN_N")
	)
	(segment
		(start 68.707 -101.91242)
		(end 59.2963 -101.91242)
		(width 0.08382)
		(layer "In2.Cu")
		(net "AC_PWR_BTN_N")
	)
	(segment
		(start 57.38876 -103.81996)
		(end 57.38876 -104.2416)
		(width 0.08382)
		(layer "In2.Cu")
		(net "AC_PWR_BTN_N")
	)
	(segment
		(start 39.63162 -108.97616)
		(end 32.7914 -108.97616)
		(width 0.08382)
		(layer "In2.Cu")
		(net "AC_PWR_BTN_N")
	)
	(segment
		(start 47.7647 -107.5817)
		(end 43.688 -107.5817)
		(width 0.08382)
		(layer "In2.Cu")
		(net "AC_PWR_BTN_N")
	)
	(segment
		(start 43.688 -107.5817)
		(end 42.80154 -106.69524)
		(width 0.08382)
		(layer "In2.Cu")
		(net "AC_PWR_BTN_N")
	)
	(segment
		(start 73.018904 -100.75672)
		(end 73.018904 -101.192076)
		(width 0.08382)
		(layer "In2.Cu")
		(net "AC_PWR_BTN_N")
	)
	(segment
		(start 40.88638 -107.20832)
		(end 40.88638 -107.7214)
		(width 0.08382)
		(layer "In2.Cu")
		(net "AC_PWR_BTN_N")
	)
	(segment
		(start 40.88638 -107.7214)
		(end 39.63162 -108.97616)
		(width 0.08382)
		(layer "In2.Cu")
		(net "AC_PWR_BTN_N")
	)
	(segment
		(start 59.2963 -101.91242)
		(end 57.38876 -103.81996)
		(width 0.08382)
		(layer "In2.Cu")
		(net "AC_PWR_BTN_N")
	)
	(segment
		(start 48.23714 -108.05414)
		(end 47.7647 -107.5817)
		(width 0.08382)
		(layer "In2.Cu")
		(net "AC_PWR_BTN_N")
	)
	(segment
		(start 42.80154 -106.69524)
		(end 41.39946 -106.69524)
		(width 0.08382)
		(layer "In2.Cu")
		(net "AC_PWR_BTN_N")
	)
	(segment
		(start 55.20944 -105.13568)
		(end 53.78196 -106.56316)
		(width 0.08382)
		(layer "In2.Cu")
		(net "AC_PWR_BTN_N")
	)
	(segment
		(start 41.39946 -106.69524)
		(end 40.88638 -107.20832)
		(width 0.08382)
		(layer "In2.Cu")
		(net "AC_PWR_BTN_N")
	)
	(segment
		(start 57.38876 -104.2416)
		(end 56.49468 -105.13568)
		(width 0.08382)
		(layer "In2.Cu")
		(net "AC_PWR_BTN_N")
	)
	(segment
		(start 69.15404 -101.46538)
		(end 68.707 -101.91242)
		(width 0.08382)
		(layer "In2.Cu")
		(net "AC_PWR_BTN_N")
	)
	(segment
		(start 72.7456 -101.46538)
		(end 69.15404 -101.46538)
		(width 0.08382)
		(layer "In2.Cu")
		(net "AC_PWR_BTN_N")
	)
	(segment
		(start 56.49468 -105.13568)
		(end 55.20944 -105.13568)
		(width 0.08382)
		(layer "In2.Cu")
		(net "AC_PWR_BTN_N")
	)
	(segment
		(start 31.98622 -109.78134)
		(end 31.98622 -110.00994)
		(width 0.08382)
		(layer "In2.Cu")
		(net "AC_PWR_BTN_N")
	)
	(segment
		(start 49.53 -108.05414)
		(end 48.23714 -108.05414)
		(width 0.08382)
		(layer "In2.Cu")
		(net "AC_PWR_BTN_N")
	)
	(segment
		(start 51.02098 -106.56316)
		(end 49.53 -108.05414)
		(width 0.08382)
		(layer "In2.Cu")
		(net "AC_PWR_BTN_N")
	)
	(segment
		(start 80.741774 -37.808154)
		(end 80.741774 -38.623494)
		(width 0.08382)
		(layer "In9.Cu")
		(net "AC_PWR_BTN_N")
	)
	(segment
		(start 80.741774 -38.623494)
		(end 81.557114 -39.438834)
		(width 0.08382)
		(layer "In9.Cu")
		(net "AC_PWR_BTN_N")
	)
	(segment
		(start 80.753966 -54.991508)
		(end 77.212698 -54.991508)
		(width 0.08382)
		(layer "In9.Cu")
		(net "AC_PWR_BTN_N")
	)
	(segment
		(start 81.36255 -36.50615)
		(end 81.36255 -37.187378)
		(width 0.08382)
		(layer "In9.Cu")
		(net "AC_PWR_BTN_N")
	)
	(segment
		(start 79.062326 -24.945594)
		(end 79.062326 -34.205926)
		(width 0.08382)
		(layer "In9.Cu")
		(net "AC_PWR_BTN_N")
	)
	(segment
		(start 71.550784 -17.434052)
		(end 79.062326 -24.945594)
		(width 0.08382)
		(layer "In9.Cu")
		(net "AC_PWR_BTN_N")
	)
	(segment
		(start 72.644 -13.574268)
		(end 71.550784 -14.667484)
		(width 0.08382)
		(layer "In9.Cu")
		(net "AC_PWR_BTN_N")
	)
	(segment
		(start 82.289142 -54.954932)
		(end 81.997042 -55.247032)
		(width 0.08382)
		(layer "In9.Cu")
		(net "AC_PWR_BTN_N")
	)
	(segment
		(start 81.557114 -49.03851)
		(end 82.289142 -49.770538)
		(width 0.08382)
		(layer "In9.Cu")
		(net "AC_PWR_BTN_N")
	)
	(segment
		(start 81.557114 -39.438834)
		(end 81.557114 -49.03851)
		(width 0.08382)
		(layer "In9.Cu")
		(net "AC_PWR_BTN_N")
	)
	(segment
		(start 82.289142 -49.770538)
		(end 82.289142 -54.954932)
		(width 0.08382)
		(layer "In9.Cu")
		(net "AC_PWR_BTN_N")
	)
	(segment
		(start 79.062326 -34.205926)
		(end 81.36255 -36.50615)
		(width 0.08382)
		(layer "In9.Cu")
		(net "AC_PWR_BTN_N")
	)
	(segment
		(start 72.644 -11.938)
		(end 72.644 -13.574268)
		(width 0.08382)
		(layer "In9.Cu")
		(net "AC_PWR_BTN_N")
	)
	(segment
		(start 81.36255 -37.187378)
		(end 80.741774 -37.808154)
		(width 0.08382)
		(layer "In9.Cu")
		(net "AC_PWR_BTN_N")
	)
	(segment
		(start 81.997042 -55.247032)
		(end 81.00949 -55.247032)
		(width 0.08382)
		(layer "In9.Cu")
		(net "AC_PWR_BTN_N")
	)
	(segment
		(start 81.00949 -55.247032)
		(end 80.753966 -54.991508)
		(width 0.08382)
		(layer "In9.Cu")
		(net "AC_PWR_BTN_N")
	)
	(segment
		(start 77.212698 -54.991508)
		(end 75.981052 -56.223154)
		(width 0.08382)
		(layer "In9.Cu")
		(net "AC_PWR_BTN_N")
	)
	(segment
		(start 75.981052 -56.223154)
		(end 75.981052 -62.106302)
		(width 0.08382)
		(layer "In9.Cu")
		(net "AC_PWR_BTN_N")
	)
	(segment
		(start 71.550784 -14.667484)
		(end 71.550784 -17.434052)
		(width 0.08382)
		(layer "In9.Cu")
		(net "AC_PWR_BTN_N")
	)
	(segment
		(start 40.767 -51.44135)
		(end 40.25265 -50.927)
		(width 0.11684)
		(layer "F.Cu")
		(net "FM_INTRUDER_R_N")
	)
	(segment
		(start 38.989 -50.927)
		(end 38.735 -50.673)
		(width 0.11684)
		(layer "F.Cu")
		(net "FM_INTRUDER_R_N")
	)
	(segment
		(start 40.25265 -50.927)
		(end 39.497 -50.927)
		(width 0.11684)
		(layer "F.Cu")
		(net "FM_INTRUDER_R_N")
	)
	(segment
		(start 48.895 -56.171338)
		(end 49.299876 -55.766462)
		(width 0.11684)
		(layer "F.Cu")
		(net "FM_INTRUDER_R_N")
	)
	(segment
		(start 39.497 -50.927)
		(end 38.989 -50.927)
		(width 0.11684)
		(layer "F.Cu")
		(net "FM_INTRUDER_R_N")
	)
	(via
		(at 38.735 -50.673)
		(size 0.508)
		(drill 0.254)
		(layers "F.Cu" "B.Cu")
		(net "FM_INTRUDER_R_N")
	)
	(via
		(at 49.299876 -55.766462)
		(size 0.4572)
		(drill 0.254)
		(layers "F.Cu" "B.Cu")
		(net "FM_INTRUDER_R_N")
	)
	(via
		(at 39.497 -50.927)
		(size 0.762)
		(drill 0.381)
		(layers "F.Cu" "B.Cu")
		(net "FM_INTRUDER_R_N")
	)
	(segment
		(start 39.1414 -51.0794)
		(end 40.1066 -51.0794)
		(width 0.08382)
		(layer "In9.Cu")
		(net "FM_INTRUDER_R_N")
	)
	(segment
		(start 46.5074 -51.2064)
		(end 46.6598 -51.3588)
		(width 0.08382)
		(layer "In9.Cu")
		(net "FM_INTRUDER_R_N")
	)
	(segment
		(start 47.3456 -52.7304)
		(end 47.0916 -52.9844)
		(width 0.08382)
		(layer "In9.Cu")
		(net "FM_INTRUDER_R_N")
	)
	(segment
		(start 46.5074 -49.9872)
		(end 46.5074 -51.2064)
		(width 0.08382)
		(layer "In9.Cu")
		(net "FM_INTRUDER_R_N")
	)
	(segment
		(start 47.39005 -55.1942)
		(end 48.9712 -55.1942)
		(width 0.08382)
		(layer "In9.Cu")
		(net "FM_INTRUDER_R_N")
	)
	(segment
		(start 46.402498 -53.190902)
		(end 46.402498 -54.206648)
		(width 0.08382)
		(layer "In9.Cu")
		(net "FM_INTRUDER_R_N")
	)
	(segment
		(start 40.1066 -51.0794)
		(end 40.4114 -50.7746)
		(width 0.08382)
		(layer "In9.Cu")
		(net "FM_INTRUDER_R_N")
	)
	(segment
		(start 38.735 -50.673)
		(end 39.1414 -51.0794)
		(width 0.08382)
		(layer "In9.Cu")
		(net "FM_INTRUDER_R_N")
	)
	(segment
		(start 46.2534 -49.7332)
		(end 46.5074 -49.9872)
		(width 0.08382)
		(layer "In9.Cu")
		(net "FM_INTRUDER_R_N")
	)
	(segment
		(start 46.6598 -51.3588)
		(end 47.1424 -51.3588)
		(width 0.08382)
		(layer "In9.Cu")
		(net "FM_INTRUDER_R_N")
	)
	(segment
		(start 40.4622 -50.7746)
		(end 41.563036 -49.673764)
		(width 0.08382)
		(layer "In9.Cu")
		(net "FM_INTRUDER_R_N")
	)
	(segment
		(start 47.0916 -52.9844)
		(end 46.609 -52.9844)
		(width 0.08382)
		(layer "In9.Cu")
		(net "FM_INTRUDER_R_N")
	)
	(segment
		(start 46.609 -52.9844)
		(end 46.402498 -53.190902)
		(width 0.08382)
		(layer "In9.Cu")
		(net "FM_INTRUDER_R_N")
	)
	(segment
		(start 47.1424 -51.3588)
		(end 47.3456 -51.562)
		(width 0.08382)
		(layer "In9.Cu")
		(net "FM_INTRUDER_R_N")
	)
	(segment
		(start 46.402498 -54.206648)
		(end 47.39005 -55.1942)
		(width 0.08382)
		(layer "In9.Cu")
		(net "FM_INTRUDER_R_N")
	)
	(segment
		(start 48.9712 -55.1942)
		(end 49.299876 -55.522876)
		(width 0.08382)
		(layer "In9.Cu")
		(net "FM_INTRUDER_R_N")
	)
	(segment
		(start 47.3456 -51.562)
		(end 47.3456 -52.7304)
		(width 0.08382)
		(layer "In9.Cu")
		(net "FM_INTRUDER_R_N")
	)
	(segment
		(start 41.563036 -49.673764)
		(end 43.933364 -49.673764)
		(width 0.08382)
		(layer "In9.Cu")
		(net "FM_INTRUDER_R_N")
	)
	(segment
		(start 43.9928 -49.7332)
		(end 46.2534 -49.7332)
		(width 0.08382)
		(layer "In9.Cu")
		(net "FM_INTRUDER_R_N")
	)
	(segment
		(start 49.299876 -55.522876)
		(end 49.299876 -55.766462)
		(width 0.08382)
		(layer "In9.Cu")
		(net "FM_INTRUDER_R_N")
	)
	(segment
		(start 40.4114 -50.7746)
		(end 40.4622 -50.7746)
		(width 0.08382)
		(layer "In9.Cu")
		(net "FM_INTRUDER_R_N")
	)
	(segment
		(start 43.933364 -49.673764)
		(end 43.9928 -49.7332)
		(width 0.08382)
		(layer "In9.Cu")
		(net "FM_INTRUDER_R_N")
	)
	(segment
		(start 24.892 -84.430616)
		(end 23.864316 -85.4583)
		(width 0.11684)
		(layer "F.Cu")
		(net "FM_TPM_PRSNT_1_R_N")
	)
	(segment
		(start 23.864316 -87.99195)
		(end 24.25954 -88.387174)
		(width 0.11684)
		(layer "F.Cu")
		(net "FM_TPM_PRSNT_1_R_N")
	)
	(segment
		(start 23.864316 -85.4583)
		(end 23.864316 -87.99195)
		(width 0.11684)
		(layer "F.Cu")
		(net "FM_TPM_PRSNT_1_R_N")
	)
	(segment
		(start 24.892 -84.14385)
		(end 24.892 -84.430616)
		(width 0.11684)
		(layer "F.Cu")
		(net "FM_TPM_PRSNT_1_R_N")
	)
	(segment
		(start 25.45461 -88.791796)
		(end 25.059386 -89.18702)
		(width 0.11684)
		(layer "F.Cu")
		(net "FM_TPM_PRSNT_0_R_N")
	)
	(via
		(at 30.31998 -87.3887)
		(size 0.6604)
		(drill 0.3302)
		(layers "F.Cu" "B.Cu")
		(net "FM_TPM_PRSNT_0_R_N")
	)
	(via
		(at 25.45461 -88.791796)
		(size 0.4572)
		(drill 0.254)
		(layers "F.Cu" "B.Cu")
		(net "FM_TPM_PRSNT_0_R_N")
	)
	(segment
		(start 30.31998 -87.3887)
		(end 30.31998 -88.57107)
		(width 0.11684)
		(layer "B.Cu")
		(net "FM_TPM_PRSNT_0_R_N")
	)
	(segment
		(start 25.8572 -87.808054)
		(end 26.276554 -87.3887)
		(width 0.11684)
		(layer "B.Cu")
		(net "FM_TPM_PRSNT_0_R_N")
	)
	(segment
		(start 26.276554 -87.3887)
		(end 30.31998 -87.3887)
		(width 0.11684)
		(layer "B.Cu")
		(net "FM_TPM_PRSNT_0_R_N")
	)
	(segment
		(start 25.8572 -88.389206)
		(end 25.8572 -87.808054)
		(width 0.11684)
		(layer "B.Cu")
		(net "FM_TPM_PRSNT_0_R_N")
	)
	(segment
		(start 25.45461 -88.791796)
		(end 25.8572 -88.389206)
		(width 0.11684)
		(layer "B.Cu")
		(net "FM_TPM_PRSNT_0_R_N")
	)
	(segment
		(start 25.859486 -87.587074)
		(end 25.464262 -87.982298)
		(width 0.11684)
		(layer "F.Cu")
		(net "BSM_PRSNT_R1_N")
	)
	(via
		(at 25.464262 -87.982298)
		(size 0.4572)
		(drill 0.254)
		(layers "F.Cu" "B.Cu")
		(net "BSM_PRSNT_R1_N")
	)
	(segment
		(start 25.464262 -87.565738)
		(end 25.464262 -87.982298)
		(width 0.11684)
		(layer "B.Cu")
		(net "BSM_PRSNT_R1_N")
	)
	(segment
		(start 26.251154 -86.778846)
		(end 25.464262 -87.565738)
		(width 0.11684)
		(layer "B.Cu")
		(net "BSM_PRSNT_R1_N")
	)
	(segment
		(start 26.9113 -86.778846)
		(end 26.251154 -86.778846)
		(width 0.11684)
		(layer "B.Cu")
		(net "BSM_PRSNT_R1_N")
	)
	(segment
		(start 23.854664 -90.391742)
		(end 23.45944 -90.786966)
		(width 0.11684)
		(layer "F.Cu")
		(net "BMC_CPLD_GPIO_2_R2")
	)
	(via
		(at 28.31084 -91.88958)
		(size 0.508)
		(drill 0.254)
		(layers "F.Cu" "B.Cu")
		(net "BMC_CPLD_GPIO_2_R2")
	)
	(via
		(at 23.854664 -90.391742)
		(size 0.4572)
		(drill 0.254)
		(layers "F.Cu" "B.Cu")
		(net "BMC_CPLD_GPIO_2_R2")
	)
	(segment
		(start 29.068776 -92.106242)
		(end 28.984702 -92.190316)
		(width 0.11684)
		(layer "B.Cu")
		(net "BMC_CPLD_GPIO_2_R2")
	)
	(segment
		(start 28.984702 -92.190316)
		(end 28.611576 -92.190316)
		(width 0.11684)
		(layer "B.Cu")
		(net "BMC_CPLD_GPIO_2_R2")
	)
	(segment
		(start 28.611576 -92.190316)
		(end 28.31084 -91.88958)
		(width 0.11684)
		(layer "B.Cu")
		(net "BMC_CPLD_GPIO_2_R2")
	)
	(segment
		(start 24.285956 -90.823034)
		(end 23.854664 -90.391742)
		(width 0.10414)
		(layer "In2.Cu")
		(net "BMC_CPLD_GPIO_2_R2")
	)
	(segment
		(start 28.31084 -91.88958)
		(end 28.010104 -92.190316)
		(width 0.10414)
		(layer "In2.Cu")
		(net "BMC_CPLD_GPIO_2_R2")
	)
	(segment
		(start 27.64917 -92.190316)
		(end 26.281888 -90.823034)
		(width 0.10414)
		(layer "In2.Cu")
		(net "BMC_CPLD_GPIO_2_R2")
	)
	(segment
		(start 28.010104 -92.190316)
		(end 27.64917 -92.190316)
		(width 0.10414)
		(layer "In2.Cu")
		(net "BMC_CPLD_GPIO_2_R2")
	)
	(segment
		(start 26.281888 -90.823034)
		(end 24.285956 -90.823034)
		(width 0.10414)
		(layer "In2.Cu")
		(net "BMC_CPLD_GPIO_2_R2")
	)
	(segment
		(start 35.941 -60.071254)
		(end 35.941 -60.55995)
		(width 0.11684)
		(layer "F.Cu")
		(net "BMC_CPLD_GPIO_2_R1")
	)
	(segment
		(start 46.09973 -50.96637)
		(end 46.494954 -51.361594)
		(width 0.11684)
		(layer "F.Cu")
		(net "BMC_CPLD_GPIO_2_R1")
	)
	(segment
		(start 36.246308 -57.865518)
		(end 36.246308 -57.94883)
		(width 0.11684)
		(layer "F.Cu")
		(net "BMC_CPLD_GPIO_2_R1")
	)
	(segment
		(start 36.721796 -59.290458)
		(end 35.941 -60.071254)
		(width 0.11684)
		(layer "F.Cu")
		(net "BMC_CPLD_GPIO_2_R1")
	)
	(segment
		(start 36.721796 -58.424318)
		(end 36.721796 -59.290458)
		(width 0.11684)
		(layer "F.Cu")
		(net "BMC_CPLD_GPIO_2_R1")
	)
	(segment
		(start 46.494954 -51.361594)
		(end 46.494954 -51.371246)
		(width 0.11684)
		(layer "F.Cu")
		(net "BMC_CPLD_GPIO_2_R1")
	)
	(segment
		(start 36.246308 -57.94883)
		(end 36.721796 -58.424318)
		(width 0.11684)
		(layer "F.Cu")
		(net "BMC_CPLD_GPIO_2_R1")
	)
	(via
		(at 46.09973 -50.96637)
		(size 0.4572)
		(drill 0.254)
		(layers "F.Cu" "B.Cu")
		(net "BMC_CPLD_GPIO_2_R1")
	)
	(via
		(at 36.246308 -57.865518)
		(size 0.508)
		(drill 0.254)
		(layers "F.Cu" "B.Cu")
		(net "BMC_CPLD_GPIO_2_R1")
	)
	(segment
		(start 36.246308 -57.865518)
		(end 36.246308 -57.530492)
		(width 0.08382)
		(layer "In9.Cu")
		(net "BMC_CPLD_GPIO_2_R1")
	)
	(segment
		(start 45.72762 -50.59426)
		(end 46.09973 -50.96637)
		(width 0.08382)
		(layer "In9.Cu")
		(net "BMC_CPLD_GPIO_2_R1")
	)
	(segment
		(start 41.675558 -49.9364)
		(end 43.8658 -49.9364)
		(width 0.08382)
		(layer "In9.Cu")
		(net "BMC_CPLD_GPIO_2_R1")
	)
	(segment
		(start 40.44696 -51.626516)
		(end 40.44696 -51.164998)
		(width 0.08382)
		(layer "In9.Cu")
		(net "BMC_CPLD_GPIO_2_R1")
	)
	(segment
		(start 44.32046 -50.59426)
		(end 45.72762 -50.59426)
		(width 0.08382)
		(layer "In9.Cu")
		(net "BMC_CPLD_GPIO_2_R1")
	)
	(segment
		(start 40.44696 -51.164998)
		(end 41.675558 -49.9364)
		(width 0.08382)
		(layer "In9.Cu")
		(net "BMC_CPLD_GPIO_2_R1")
	)
	(segment
		(start 36.504626 -56.789574)
		(end 37.8333 -55.4609)
		(width 0.08382)
		(layer "In9.Cu")
		(net "BMC_CPLD_GPIO_2_R1")
	)
	(segment
		(start 43.8658 -49.9364)
		(end 44.0944 -50.165)
		(width 0.08382)
		(layer "In9.Cu")
		(net "BMC_CPLD_GPIO_2_R1")
	)
	(segment
		(start 36.504626 -57.272174)
		(end 36.504626 -56.789574)
		(width 0.08382)
		(layer "In9.Cu")
		(net "BMC_CPLD_GPIO_2_R1")
	)
	(segment
		(start 37.8333 -55.4609)
		(end 37.8333 -54.240176)
		(width 0.08382)
		(layer "In9.Cu")
		(net "BMC_CPLD_GPIO_2_R1")
	)
	(segment
		(start 37.8333 -54.240176)
		(end 40.44696 -51.626516)
		(width 0.08382)
		(layer "In9.Cu")
		(net "BMC_CPLD_GPIO_2_R1")
	)
	(segment
		(start 44.0944 -50.165)
		(end 44.0944 -50.3682)
		(width 0.08382)
		(layer "In9.Cu")
		(net "BMC_CPLD_GPIO_2_R1")
	)
	(segment
		(start 36.246308 -57.530492)
		(end 36.504626 -57.272174)
		(width 0.08382)
		(layer "In9.Cu")
		(net "BMC_CPLD_GPIO_2_R1")
	)
	(segment
		(start 44.0944 -50.3682)
		(end 44.32046 -50.59426)
		(width 0.08382)
		(layer "In9.Cu")
		(net "BMC_CPLD_GPIO_2_R1")
	)
	(segment
		(start 24.6634 -70.3326)
		(end 24.249888 -70.746112)
		(width 0.11684)
		(layer "F.Cu")
		(net "SPI_BMC_HOLD0_N")
	)
	(segment
		(start 25.19045 -70.3326)
		(end 24.6634 -70.3326)
		(width 0.11684)
		(layer "F.Cu")
		(net "SPI_BMC_HOLD0_N")
	)
	(segment
		(start 26.289 -69.23405)
		(end 25.19045 -70.3326)
		(width 0.11684)
		(layer "F.Cu")
		(net "SPI_BMC_HOLD0_N")
	)
	(segment
		(start 24.249888 -70.746112)
		(end 24.249888 -73.360534)
		(width 0.11684)
		(layer "F.Cu")
		(net "SPI_BMC_HOLD0_N")
	)
	(segment
		(start 23.241 -68.43395)
		(end 23.241 -67.818)
		(width 0.11684)
		(layer "F.Cu")
		(net "BSM_PRSNT_R_N")
	)
	(segment
		(start 52.894992 -56.971184)
		(end 52.499768 -57.366408)
		(width 0.11684)
		(layer "F.Cu")
		(net "BSM_PRSNT_R_N")
	)
	(via
		(at 52.499768 -57.366408)
		(size 0.4572)
		(drill 0.254)
		(layers "F.Cu" "B.Cu")
		(net "BSM_PRSNT_R_N")
	)
	(via
		(at 29.3624 -85.8266)
		(size 0.508)
		(drill 0.254)
		(layers "F.Cu" "B.Cu")
		(net "BSM_PRSNT_R_N")
	)
	(via
		(at 35.2044 -75.1586)
		(size 0.508)
		(drill 0.254)
		(layers "F.Cu" "B.Cu")
		(net "BSM_PRSNT_R_N")
	)
	(via
		(at 28.97124 -86.52256)
		(size 0.6604)
		(drill 0.3302)
		(layers "F.Cu" "B.Cu")
		(net "BSM_PRSNT_R_N")
	)
	(via
		(at 32.9692 -82.7532)
		(size 0.508)
		(drill 0.254)
		(layers "F.Cu" "B.Cu")
		(net "BSM_PRSNT_R_N")
	)
	(via
		(at 23.241 -67.818)
		(size 0.508)
		(drill 0.254)
		(layers "F.Cu" "B.Cu")
		(net "BSM_PRSNT_R_N")
	)
	(segment
		(start 29.3624 -85.8266)
		(end 29.3624 -86.1314)
		(width 0.11684)
		(layer "B.Cu")
		(net "BSM_PRSNT_R_N")
	)
	(segment
		(start 29.3624 -86.1314)
		(end 28.97124 -86.52256)
		(width 0.11684)
		(layer "B.Cu")
		(net "BSM_PRSNT_R_N")
	)
	(segment
		(start 27.7114 -86.778846)
		(end 28.714954 -86.778846)
		(width 0.11684)
		(layer "B.Cu")
		(net "BSM_PRSNT_R_N")
	)
	(segment
		(start 28.714954 -86.778846)
		(end 28.97124 -86.52256)
		(width 0.11684)
		(layer "B.Cu")
		(net "BSM_PRSNT_R_N")
	)
	(segment
		(start 27.64282 -71.52259)
		(end 27.754326 -71.411084)
		(width 0.08382)
		(layer "In2.Cu")
		(net "BSM_PRSNT_R_N")
	)
	(segment
		(start 27.754326 -70.84314)
		(end 26.430986 -69.5198)
		(width 0.08382)
		(layer "In2.Cu")
		(net "BSM_PRSNT_R_N")
	)
	(segment
		(start 31.2928 -83.8962)
		(end 29.3624 -85.8266)
		(width 0.08382)
		(layer "In2.Cu")
		(net "BSM_PRSNT_R_N")
	)
	(segment
		(start 27.754326 -71.411084)
		(end 27.754326 -70.84314)
		(width 0.08382)
		(layer "In2.Cu")
		(net "BSM_PRSNT_R_N")
	)
	(segment
		(start 32.3596 -83.8962)
		(end 31.2928 -83.8962)
		(width 0.08382)
		(layer "In2.Cu")
		(net "BSM_PRSNT_R_N")
	)
	(segment
		(start 35.2044 -75.1586)
		(end 33.013396 -72.967596)
		(width 0.08382)
		(layer "In2.Cu")
		(net "BSM_PRSNT_R_N")
	)
	(segment
		(start 27.64282 -72.664828)
		(end 27.64282 -71.52259)
		(width 0.08382)
		(layer "In2.Cu")
		(net "BSM_PRSNT_R_N")
	)
	(segment
		(start 26.430986 -69.5198)
		(end 24.9428 -69.5198)
		(width 0.08382)
		(layer "In2.Cu")
		(net "BSM_PRSNT_R_N")
	)
	(segment
		(start 33.013396 -72.967596)
		(end 27.945588 -72.967596)
		(width 0.08382)
		(layer "In2.Cu")
		(net "BSM_PRSNT_R_N")
	)
	(segment
		(start 32.9692 -82.7532)
		(end 32.9692 -83.2866)
		(width 0.08382)
		(layer "In2.Cu")
		(net "BSM_PRSNT_R_N")
	)
	(segment
		(start 24.9428 -69.5198)
		(end 23.241 -67.818)
		(width 0.08382)
		(layer "In2.Cu")
		(net "BSM_PRSNT_R_N")
	)
	(segment
		(start 32.9692 -83.2866)
		(end 32.3596 -83.8962)
		(width 0.08382)
		(layer "In2.Cu")
		(net "BSM_PRSNT_R_N")
	)
	(segment
		(start 27.945588 -72.967596)
		(end 27.64282 -72.664828)
		(width 0.08382)
		(layer "In2.Cu")
		(net "BSM_PRSNT_R_N")
	)
	(segment
		(start 42.98823 -62.736984)
		(end 43.75404 -61.971174)
		(width 0.08382)
		(layer "In9.Cu")
		(net "BSM_PRSNT_R_N")
	)
	(segment
		(start 49.671986 -56.398414)
		(end 49.877218 -56.193182)
		(width 0.08382)
		(layer "In9.Cu")
		(net "BSM_PRSNT_R_N")
	)
	(segment
		(start 49.877218 -56.193182)
		(end 51.951382 -56.193182)
		(width 0.08382)
		(layer "In9.Cu")
		(net "BSM_PRSNT_R_N")
	)
	(segment
		(start 35.2044 -75.1586)
		(end 35.2044 -77.266546)
		(width 0.08382)
		(layer "In9.Cu")
		(net "BSM_PRSNT_R_N")
	)
	(segment
		(start 47.38624 -59.52236)
		(end 48.641 -58.2676)
		(width 0.08382)
		(layer "In9.Cu")
		(net "BSM_PRSNT_R_N")
	)
	(segment
		(start 42.98823 -65.54851)
		(end 42.98823 -62.736984)
		(width 0.08382)
		(layer "In9.Cu")
		(net "BSM_PRSNT_R_N")
	)
	(segment
		(start 42.435018 -68.01231)
		(end 42.435018 -66.101722)
		(width 0.08382)
		(layer "In9.Cu")
		(net "BSM_PRSNT_R_N")
	)
	(segment
		(start 45.486066 -61.971174)
		(end 47.38624 -60.071)
		(width 0.08382)
		(layer "In9.Cu")
		(net "BSM_PRSNT_R_N")
	)
	(segment
		(start 40.30218 -70.145148)
		(end 42.435018 -68.01231)
		(width 0.08382)
		(layer "In9.Cu")
		(net "BSM_PRSNT_R_N")
	)
	(segment
		(start 35.2044 -75.1586)
		(end 35.2044 -75.135232)
		(width 0.08382)
		(layer "In9.Cu")
		(net "BSM_PRSNT_R_N")
	)
	(segment
		(start 38.843458 -72.73798)
		(end 40.30218 -71.279258)
		(width 0.08382)
		(layer "In9.Cu")
		(net "BSM_PRSNT_R_N")
	)
	(segment
		(start 48.641 -58.2676)
		(end 48.641 -57.4294)
		(width 0.08382)
		(layer "In9.Cu")
		(net "BSM_PRSNT_R_N")
	)
	(segment
		(start 47.38624 -60.071)
		(end 47.38624 -59.52236)
		(width 0.08382)
		(layer "In9.Cu")
		(net "BSM_PRSNT_R_N")
	)
	(segment
		(start 33.4518 -82.2706)
		(end 32.9692 -82.7532)
		(width 0.08382)
		(layer "In9.Cu")
		(net "BSM_PRSNT_R_N")
	)
	(segment
		(start 35.2044 -77.266546)
		(end 33.4518 -79.019146)
		(width 0.08382)
		(layer "In9.Cu")
		(net "BSM_PRSNT_R_N")
	)
	(segment
		(start 37.601652 -72.73798)
		(end 38.843458 -72.73798)
		(width 0.08382)
		(layer "In9.Cu")
		(net "BSM_PRSNT_R_N")
	)
	(segment
		(start 51.951382 -56.193182)
		(end 52.090066 -56.331866)
		(width 0.08382)
		(layer "In9.Cu")
		(net "BSM_PRSNT_R_N")
	)
	(segment
		(start 42.435018 -66.101722)
		(end 42.98823 -65.54851)
		(width 0.08382)
		(layer "In9.Cu")
		(net "BSM_PRSNT_R_N")
	)
	(segment
		(start 49.131728 -56.938672)
		(end 49.454054 -56.938672)
		(width 0.08382)
		(layer "In9.Cu")
		(net "BSM_PRSNT_R_N")
	)
	(segment
		(start 35.2044 -75.135232)
		(end 37.601652 -72.73798)
		(width 0.08382)
		(layer "In9.Cu")
		(net "BSM_PRSNT_R_N")
	)
	(segment
		(start 52.090066 -56.956706)
		(end 52.499768 -57.366408)
		(width 0.08382)
		(layer "In9.Cu")
		(net "BSM_PRSNT_R_N")
	)
	(segment
		(start 43.75404 -61.971174)
		(end 45.486066 -61.971174)
		(width 0.08382)
		(layer "In9.Cu")
		(net "BSM_PRSNT_R_N")
	)
	(segment
		(start 52.090066 -56.331866)
		(end 52.090066 -56.956706)
		(width 0.08382)
		(layer "In9.Cu")
		(net "BSM_PRSNT_R_N")
	)
	(segment
		(start 49.454054 -56.938672)
		(end 49.671986 -56.72074)
		(width 0.08382)
		(layer "In9.Cu")
		(net "BSM_PRSNT_R_N")
	)
	(segment
		(start 33.4518 -79.019146)
		(end 33.4518 -82.2706)
		(width 0.08382)
		(layer "In9.Cu")
		(net "BSM_PRSNT_R_N")
	)
	(segment
		(start 49.671986 -56.72074)
		(end 49.671986 -56.398414)
		(width 0.08382)
		(layer "In9.Cu")
		(net "BSM_PRSNT_R_N")
	)
	(segment
		(start 48.641 -57.4294)
		(end 49.131728 -56.938672)
		(width 0.08382)
		(layer "In9.Cu")
		(net "BSM_PRSNT_R_N")
	)
	(segment
		(start 40.30218 -71.279258)
		(end 40.30218 -70.145148)
		(width 0.08382)
		(layer "In9.Cu")
		(net "BSM_PRSNT_R_N")
	)
	(segment
		(start 22.8346 -70.0532)
		(end 22.8346 -69.64045)
		(width 0.11684)
		(layer "F.Cu")
		(net "BSM_PRSNT_N")
	)
	(segment
		(start 24.257 -69.23405)
		(end 23.241 -69.23405)
		(width 0.11684)
		(layer "F.Cu")
		(net "BSM_PRSNT_N")
	)
	(segment
		(start 22.8346 -69.64045)
		(end 23.241 -69.23405)
		(width 0.11684)
		(layer "F.Cu")
		(net "BSM_PRSNT_N")
	)
	(segment
		(start 21.249894 -72.136254)
		(end 21.602446 -71.285354)
		(width 0.11684)
		(layer "F.Cu")
		(net "BSM_PRSNT_N")
	)
	(segment
		(start 21.249894 -73.360534)
		(end 21.249894 -72.136254)
		(width 0.11684)
		(layer "F.Cu")
		(net "BSM_PRSNT_N")
	)
	(segment
		(start 21.602446 -71.285354)
		(end 22.8346 -70.0532)
		(width 0.11684)
		(layer "F.Cu")
		(net "BSM_PRSNT_N")
	)
	(segment
		(start 75.54595 -79.121)
		(end 75.54595 -77.978)
		(width 0.11684)
		(layer "F.Cu")
		(net "U56_ADJ_1")
	)
	(segment
		(start 75.63104 -79.20609)
		(end 75.54595 -79.121)
		(width 0.11684)
		(layer "F.Cu")
		(net "U56_ADJ_1")
	)
	(segment
		(start 75.63104 -81.377028)
		(end 75.63104 -79.20609)
		(width 0.11684)
		(layer "F.Cu")
		(net "U56_ADJ_1")
	)
	(segment
		(start 15.113 -48.48225)
		(end 15.3416 -48.25365)
		(width 0.381)
		(layer "F.Cu")
		(net "P3V3_LDO")
	)
	(segment
		(start 16.397986 -34.755836)
		(end 16.256 -34.61385)
		(width 0.3556)
		(layer "F.Cu")
		(net "P3V3_LDO")
	)
	(segment
		(start 15.813786 -50.142394)
		(end 15.813786 -48.725836)
		(width 0.3048)
		(layer "F.Cu")
		(net "P3V3_LDO")
	)
	(segment
		(start 11.80465 -60.149486)
		(end 12.13104 -59.823096)
		(width 0.4572)
		(layer "F.Cu")
		(net "P3V3_LDO")
	)
	(segment
		(start 42.25925 -27.64155)
		(end 42.25925 -28.6512)
		(width 0.4572)
		(layer "F.Cu")
		(net "P3V3_LDO")
	)
	(segment
		(start 42.9514 -28.9306)
		(end 42.672 -28.6512)
		(width 0.4572)
		(layer "F.Cu")
		(net "P3V3_LDO")
	)
	(segment
		(start 12.166854 -61.214)
		(end 12.768834 -60.61202)
		(width 0.4572)
		(layer "F.Cu")
		(net "P3V3_LDO")
	)
	(segment
		(start 11.80465 -61.1632)
		(end 11.80465 -60.149486)
		(width 0.4572)
		(layer "F.Cu")
		(net "P3V3_LDO")
	)
	(segment
		(start 16.256 -34.61385)
		(end 16.256 -33.85185)
		(width 0.3556)
		(layer "F.Cu")
		(net "P3V3_LDO")
	)
	(segment
		(start 34.499296 -62.92596)
		(end 34.499296 -63.868554)
		(width 0.4572)
		(layer "F.Cu")
		(net "P3V3_LDO")
	)
	(segment
		(start 12.768834 -60.61202)
		(end 12.844018 -60.61202)
		(width 0.4572)
		(layer "F.Cu")
		(net "P3V3_LDO")
	)
	(segment
		(start 34.499296 -63.868554)
		(end 33.92805 -64.4398)
		(width 0.4572)
		(layer "F.Cu")
		(net "P3V3_LDO")
	)
	(segment
		(start 33.92805 -64.90335)
		(end 33.782 -65.0494)
		(width 0.4572)
		(layer "F.Cu")
		(net "P3V3_LDO")
	)
	(segment
		(start 15.813786 -48.725836)
		(end 15.3416 -48.25365)
		(width 0.3048)
		(layer "F.Cu")
		(net "P3V3_LDO")
	)
	(segment
		(start 43.566842 -27.21356)
		(end 42.68724 -27.21356)
		(width 0.4572)
		(layer "F.Cu")
		(net "P3V3_LDO")
	)
	(segment
		(start 15.84833 -33.79978)
		(end 15.525242 -33.79978)
		(width 0.3556)
		(layer "F.Cu")
		(net "P3V3_LDO")
	)
	(segment
		(start 15.1638 -49.8348)
		(end 15.113 -49.784)
		(width 0.381)
		(layer "F.Cu")
		(net "P3V3_LDO")
	)
	(segment
		(start 15.113 -49.784)
		(end 15.113 -48.48225)
		(width 0.381)
		(layer "F.Cu")
		(net "P3V3_LDO")
	)
	(segment
		(start 33.92805 -64.4398)
		(end 33.92805 -64.90335)
		(width 0.4572)
		(layer "F.Cu")
		(net "P3V3_LDO")
	)
	(segment
		(start 16.256 -33.85185)
		(end 15.9004 -33.85185)
		(width 0.3556)
		(layer "F.Cu")
		(net "P3V3_LDO")
	)
	(segment
		(start 16.397986 -35.816794)
		(end 16.397986 -34.755836)
		(width 0.3556)
		(layer "F.Cu")
		(net "P3V3_LDO")
	)
	(segment
		(start 11.85545 -61.214)
		(end 11.80465 -61.1632)
		(width 0.4572)
		(layer "F.Cu")
		(net "P3V3_LDO")
	)
	(segment
		(start 42.68724 -27.21356)
		(end 42.25925 -27.64155)
		(width 0.4572)
		(layer "F.Cu")
		(net "P3V3_LDO")
	)
	(segment
		(start 11.85545 -61.214)
		(end 12.166854 -61.214)
		(width 0.4572)
		(layer "F.Cu")
		(net "P3V3_LDO")
	)
	(segment
		(start 42.672 -28.6512)
		(end 42.25925 -28.6512)
		(width 0.4572)
		(layer "F.Cu")
		(net "P3V3_LDO")
	)
	(segment
		(start 15.9004 -33.85185)
		(end 15.84833 -33.79978)
		(width 0.3556)
		(layer "F.Cu")
		(net "P3V3_LDO")
	)
	(via
		(at 77.7748 -78.4352)
		(size 0.508)
		(drill 0.254)
		(layers "F.Cu" "B.Cu")
		(net "P3V3_LDO")
	)
	(via
		(at 15.1638 -49.8348)
		(size 0.508)
		(drill 0.254)
		(layers "F.Cu" "B.Cu")
		(net "P3V3_LDO")
	)
	(via
		(at 12.844018 -60.61202)
		(size 0.508)
		(drill 0.254)
		(layers "F.Cu" "B.Cu")
		(net "P3V3_LDO")
	)
	(via
		(at 33.782 -65.0494)
		(size 0.508)
		(drill 0.254)
		(layers "F.Cu" "B.Cu")
		(net "P3V3_LDO")
	)
	(via
		(at 76.962 -78.5368)
		(size 0.508)
		(drill 0.254)
		(layers "F.Cu" "B.Cu")
		(net "P3V3_LDO")
	)
	(via
		(at 42.9514 -28.9306)
		(size 0.508)
		(drill 0.254)
		(layers "F.Cu" "B.Cu")
		(net "P3V3_LDO")
	)
	(via
		(at 15.525242 -33.79978)
		(size 0.508)
		(drill 0.254)
		(layers "F.Cu" "B.Cu")
		(net "P3V3_LDO")
	)
	(via
		(at 42.2148 -26.797)
		(size 0.508)
		(drill 0.254)
		(layers "F.Cu" "B.Cu")
		(net "P3V3_LDO")
	)
	(via
		(at 78.1812 -65.8368)
		(size 0.508)
		(drill 0.254)
		(layers "F.Cu" "B.Cu")
		(net "P3V3_LDO")
	)
	(segment
		(start 79.131414 -66.196464)
		(end 79.05115 -66.1162)
		(width 0.3048)
		(layer "B.Cu")
		(net "P3V3_LDO")
	)
	(segment
		(start 78.77175 -65.8368)
		(end 79.05115 -66.1162)
		(width 0.4572)
		(layer "B.Cu")
		(net "P3V3_LDO")
	)
	(segment
		(start 78.1812 -65.8368)
		(end 78.77175 -65.8368)
		(width 0.4572)
		(layer "B.Cu")
		(net "P3V3_LDO")
	)
	(segment
		(start 79.131414 -67.693794)
		(end 79.131414 -66.196464)
		(width 0.3048)
		(layer "B.Cu")
		(net "P3V3_LDO")
	)
	(segment
		(start 36.358322 -20.96389)
		(end 37.075872 -21.26107)
		(width 0.4572)
		(layer "In2.Cu")
		(net "P3V3_LDO")
	)
	(segment
		(start 76.60005 -78.37805)
		(end 75.184 -76.962)
		(width 0.381)
		(layer "In2.Cu")
		(net "P3V3_LDO")
	)
	(segment
		(start 75.184 -76.962)
		(end 75.184 -67.818)
		(width 0.381)
		(layer "In2.Cu")
		(net "P3V3_LDO")
	)
	(segment
		(start 15.5956 -23.317454)
		(end 18.276824 -20.63623)
		(width 0.4572)
		(layer "In2.Cu")
		(net "P3V3_LDO")
	)
	(segment
		(start 29.340302 -23.3172)
		(end 31.092394 -23.3172)
		(width 0.4572)
		(layer "In2.Cu")
		(net "P3V3_LDO")
	)
	(segment
		(start 31.092394 -23.3172)
		(end 32.160464 -22.24913)
		(width 0.4572)
		(layer "In2.Cu")
		(net "P3V3_LDO")
	)
	(segment
		(start 32.160464 -22.24913)
		(end 34.042604 -22.24913)
		(width 0.4572)
		(layer "In2.Cu")
		(net "P3V3_LDO")
	)
	(segment
		(start 40.400732 -26.24455)
		(end 41.66235 -26.24455)
		(width 0.4572)
		(layer "In2.Cu")
		(net "P3V3_LDO")
	)
	(segment
		(start 76.962 -78.5368)
		(end 76.80325 -78.37805)
		(width 0.381)
		(layer "In2.Cu")
		(net "P3V3_LDO")
	)
	(segment
		(start 37.624766 -21.4884)
		(end 38.83787 -22.701504)
		(width 0.4572)
		(layer "In2.Cu")
		(net "P3V3_LDO")
	)
	(segment
		(start 25.672034 -22.06244)
		(end 28.085542 -22.06244)
		(width 0.4572)
		(layer "In2.Cu")
		(net "P3V3_LDO")
	)
	(segment
		(start 41.66235 -26.24455)
		(end 42.2148 -26.797)
		(width 0.4572)
		(layer "In2.Cu")
		(net "P3V3_LDO")
	)
	(segment
		(start 34.042604 -22.24913)
		(end 35.327844 -20.96389)
		(width 0.4572)
		(layer "In2.Cu")
		(net "P3V3_LDO")
	)
	(segment
		(start 37.075872 -21.26107)
		(end 37.624766 -21.4884)
		(width 0.4572)
		(layer "In2.Cu")
		(net "P3V3_LDO")
	)
	(segment
		(start 38.83787 -24.681688)
		(end 40.400732 -26.24455)
		(width 0.4572)
		(layer "In2.Cu")
		(net "P3V3_LDO")
	)
	(segment
		(start 28.085542 -22.06244)
		(end 29.340302 -23.3172)
		(width 0.4572)
		(layer "In2.Cu")
		(net "P3V3_LDO")
	)
	(segment
		(start 24.245824 -20.63623)
		(end 25.672034 -22.06244)
		(width 0.4572)
		(layer "In2.Cu")
		(net "P3V3_LDO")
	)
	(segment
		(start 35.327844 -20.96389)
		(end 36.358322 -20.96389)
		(width 0.4572)
		(layer "In2.Cu")
		(net "P3V3_LDO")
	)
	(segment
		(start 16.256 -28.354274)
		(end 15.5956 -26.759916)
		(width 0.4572)
		(layer "In2.Cu")
		(net "P3V3_LDO")
	)
	(segment
		(start 16.256 -33.069022)
		(end 16.256 -28.354274)
		(width 0.4572)
		(layer "In2.Cu")
		(net "P3V3_LDO")
	)
	(segment
		(start 18.276824 -20.63623)
		(end 24.245824 -20.63623)
		(width 0.4572)
		(layer "In2.Cu")
		(net "P3V3_LDO")
	)
	(segment
		(start 76.80325 -78.37805)
		(end 76.60005 -78.37805)
		(width 0.381)
		(layer "In2.Cu")
		(net "P3V3_LDO")
	)
	(segment
		(start 75.184 -67.818)
		(end 77.1652 -65.8368)
		(width 0.381)
		(layer "In2.Cu")
		(net "P3V3_LDO")
	)
	(segment
		(start 77.1652 -65.8368)
		(end 78.1812 -65.8368)
		(width 0.381)
		(layer "In2.Cu")
		(net "P3V3_LDO")
	)
	(segment
		(start 15.5956 -26.759916)
		(end 15.5956 -23.317454)
		(width 0.4572)
		(layer "In2.Cu")
		(net "P3V3_LDO")
	)
	(segment
		(start 38.83787 -22.701504)
		(end 38.83787 -24.681688)
		(width 0.4572)
		(layer "In2.Cu")
		(net "P3V3_LDO")
	)
	(segment
		(start 15.525242 -33.79978)
		(end 16.256 -33.069022)
		(width 0.4572)
		(layer "In2.Cu")
		(net "P3V3_LDO")
	)
	(segment
		(start 15.64386 -40.989758)
		(end 15.64386 -45.623226)
		(width 0.4572)
		(layer "In4.Cu")
		(net "P3V3_LDO")
	)
	(segment
		(start 13.878814 -51.445922)
		(end 13.878814 -53.81879)
		(width 0.4572)
		(layer "In4.Cu")
		(net "P3V3_LDO")
	)
	(segment
		(start 16.078708 -40.55491)
		(end 15.64386 -40.989758)
		(width 0.4572)
		(layer "In4.Cu")
		(net "P3V3_LDO")
	)
	(segment
		(start 14.43482 -49.10582)
		(end 15.1638 -49.8348)
		(width 0.4572)
		(layer "In4.Cu")
		(net "P3V3_LDO")
	)
	(segment
		(start 13.74394 -59.78906)
		(end 12.92098 -60.61202)
		(width 0.4572)
		(layer "In4.Cu")
		(net "P3V3_LDO")
	)
	(segment
		(start 13.66266 -57.74563)
		(end 13.995146 -58.078116)
		(width 0.4572)
		(layer "In4.Cu")
		(net "P3V3_LDO")
	)
	(segment
		(start 14.083792 -51.240944)
		(end 13.878814 -51.445922)
		(width 0.4572)
		(layer "In4.Cu")
		(net "P3V3_LDO")
	)
	(segment
		(start 15.525242 -33.79978)
		(end 15.621508 -33.79978)
		(width 0.4572)
		(layer "In4.Cu")
		(net "P3V3_LDO")
	)
	(segment
		(start 14.43482 -46.832266)
		(end 14.43482 -49.10582)
		(width 0.4572)
		(layer "In4.Cu")
		(net "P3V3_LDO")
	)
	(segment
		(start 13.878814 -53.81879)
		(end 13.66266 -54.034944)
		(width 0.4572)
		(layer "In4.Cu")
		(net "P3V3_LDO")
	)
	(segment
		(start 15.621508 -33.79978)
		(end 16.078708 -34.25698)
		(width 0.4572)
		(layer "In4.Cu")
		(net "P3V3_LDO")
	)
	(segment
		(start 16.078708 -34.25698)
		(end 16.078708 -40.55491)
		(width 0.4572)
		(layer "In4.Cu")
		(net "P3V3_LDO")
	)
	(segment
		(start 15.1638 -49.8348)
		(end 14.083792 -50.914808)
		(width 0.4572)
		(layer "In4.Cu")
		(net "P3V3_LDO")
	)
	(segment
		(start 12.92098 -60.61202)
		(end 12.844018 -60.61202)
		(width 0.4572)
		(layer "In4.Cu")
		(net "P3V3_LDO")
	)
	(segment
		(start 13.9954 -59.04484)
		(end 13.74394 -59.2963)
		(width 0.4572)
		(layer "In4.Cu")
		(net "P3V3_LDO")
	)
	(segment
		(start 13.74394 -59.2963)
		(end 13.74394 -59.78906)
		(width 0.4572)
		(layer "In4.Cu")
		(net "P3V3_LDO")
	)
	(segment
		(start 15.64386 -45.623226)
		(end 14.43482 -46.832266)
		(width 0.4572)
		(layer "In4.Cu")
		(net "P3V3_LDO")
	)
	(segment
		(start 13.66266 -54.034944)
		(end 13.66266 -57.74563)
		(width 0.4572)
		(layer "In4.Cu")
		(net "P3V3_LDO")
	)
	(segment
		(start 14.083792 -50.914808)
		(end 14.083792 -51.240944)
		(width 0.4572)
		(layer "In4.Cu")
		(net "P3V3_LDO")
	)
	(segment
		(start 13.995146 -58.078116)
		(end 13.9954 -59.04484)
		(width 0.4572)
		(layer "In4.Cu")
		(net "P3V3_LDO")
	)
	(segment
		(start 42.2148 -26.797)
		(end 42.2148 -28.194)
		(width 0.4572)
		(layer "In9.Cu")
		(net "P3V3_LDO")
	)
	(segment
		(start 42.2148 -28.194)
		(end 42.9514 -28.9306)
		(width 0.4572)
		(layer "In9.Cu")
		(net "P3V3_LDO")
	)
	(segment
		(start 25.3492 -66.9544)
		(end 24.9428 -67.3608)
		(width 0.11684)
		(layer "F.Cu")
		(net "SMB_BMC_MM16_R5_SDA")
	)
	(segment
		(start 24.421846 -67.3608)
		(end 24.119586 -67.05854)
		(width 0.11684)
		(layer "F.Cu")
		(net "SMB_BMC_MM16_R5_SDA")
	)
	(segment
		(start 18.034 -103.505)
		(end 17.7038 -103.8352)
		(width 0.11684)
		(layer "F.Cu")
		(net "SMB_BMC_MM16_R5_SDA")
	)
	(segment
		(start 20.009104 -67.05854)
		(end 19.861784 -67.20586)
		(width 0.11684)
		(layer "F.Cu")
		(net "SMB_BMC_MM16_R5_SDA")
	)
	(segment
		(start 14.5034 -72.0344)
		(end 15.5448 -73.0758)
		(width 0.11684)
		(layer "F.Cu")
		(net "SMB_BMC_MM16_R5_SDA")
	)
	(segment
		(start 15.883128 -67.60464)
		(end 14.5034 -68.984368)
		(width 0.11684)
		(layer "F.Cu")
		(net "SMB_BMC_MM16_R5_SDA")
	)
	(segment
		(start 15.5448 -74.295)
		(end 14.9098 -74.93)
		(width 0.11684)
		(layer "F.Cu")
		(net "SMB_BMC_MM16_R5_SDA")
	)
	(segment
		(start 14.9098 -80.2894)
		(end 15.3924 -80.772)
		(width 0.11684)
		(layer "F.Cu")
		(net "SMB_BMC_MM16_R5_SDA")
	)
	(segment
		(start 14.5034 -68.984368)
		(end 14.5034 -72.0344)
		(width 0.11684)
		(layer "F.Cu")
		(net "SMB_BMC_MM16_R5_SDA")
	)
	(segment
		(start 19.771868 -67.20586)
		(end 19.373088 -67.60464)
		(width 0.11684)
		(layer "F.Cu")
		(net "SMB_BMC_MM16_R5_SDA")
	)
	(segment
		(start 24.9428 -67.3608)
		(end 24.421846 -67.3608)
		(width 0.11684)
		(layer "F.Cu")
		(net "SMB_BMC_MM16_R5_SDA")
	)
	(segment
		(start 26.252424 -66.9544)
		(end 25.3492 -66.9544)
		(width 0.11684)
		(layer "F.Cu")
		(net "SMB_BMC_MM16_R5_SDA")
	)
	(segment
		(start 14.9098 -74.93)
		(end 14.9098 -80.2894)
		(width 0.11684)
		(layer "F.Cu")
		(net "SMB_BMC_MM16_R5_SDA")
	)
	(segment
		(start 26.915618 -67.832478)
		(end 26.763726 -67.465702)
		(width 0.11684)
		(layer "F.Cu")
		(net "SMB_BMC_MM16_R5_SDA")
	)
	(segment
		(start 15.5448 -73.0758)
		(end 15.5448 -74.295)
		(width 0.11684)
		(layer "F.Cu")
		(net "SMB_BMC_MM16_R5_SDA")
	)
	(segment
		(start 73.05802 -98.902012)
		(end 73.05802 -98.944176)
		(width 0.11684)
		(layer "F.Cu")
		(net "SMB_BMC_MM16_R5_SDA")
	)
	(segment
		(start 26.763726 -67.465702)
		(end 26.252424 -66.9544)
		(width 0.11684)
		(layer "F.Cu")
		(net "SMB_BMC_MM16_R5_SDA")
	)
	(segment
		(start 27.13609 -68.05295)
		(end 26.915618 -67.832478)
		(width 0.11684)
		(layer "F.Cu")
		(net "SMB_BMC_MM16_R5_SDA")
	)
	(segment
		(start 18.034 -103.14305)
		(end 18.034 -103.505)
		(width 0.11684)
		(layer "F.Cu")
		(net "SMB_BMC_MM16_R5_SDA")
	)
	(segment
		(start 19.861784 -67.20586)
		(end 19.771868 -67.20586)
		(width 0.11684)
		(layer "F.Cu")
		(net "SMB_BMC_MM16_R5_SDA")
	)
	(segment
		(start 19.373088 -67.60464)
		(end 15.883128 -67.60464)
		(width 0.11684)
		(layer "F.Cu")
		(net "SMB_BMC_MM16_R5_SDA")
	)
	(segment
		(start 24.119586 -67.05854)
		(end 20.009104 -67.05854)
		(width 0.11684)
		(layer "F.Cu")
		(net "SMB_BMC_MM16_R5_SDA")
	)
	(segment
		(start 28.321 -68.05295)
		(end 27.13609 -68.05295)
		(width 0.11684)
		(layer "F.Cu")
		(net "SMB_BMC_MM16_R5_SDA")
	)
	(segment
		(start 73.05802 -98.944176)
		(end 73.580244 -99.4664)
		(width 0.11684)
		(layer "F.Cu")
		(net "SMB_BMC_MM16_R5_SDA")
	)
	(via
		(at 15.3924 -80.772)
		(size 0.508)
		(drill 0.254)
		(layers "F.Cu" "B.Cu")
		(net "SMB_BMC_MM16_R5_SDA")
	)
	(via
		(at 86.91372 -27.1526)
		(size 0.508)
		(drill 0.254)
		(layers "F.Cu" "B.Cu")
		(net "SMB_BMC_MM16_R5_SDA")
	)
	(via
		(at 49.403 -26.9748)
		(size 0.6604)
		(drill 0.3302)
		(layers "F.Cu" "B.Cu")
		(net "SMB_BMC_MM16_R5_SDA")
	)
	(via
		(at 51.181 -15.494)
		(size 0.508)
		(drill 0.254)
		(layers "F.Cu" "B.Cu")
		(net "SMB_BMC_MM16_R5_SDA")
	)
	(via
		(at 73.05802 -98.902012)
		(size 0.508)
		(drill 0.254)
		(layers "F.Cu" "B.Cu")
		(net "SMB_BMC_MM16_R5_SDA")
	)
	(via
		(at 17.7038 -103.8352)
		(size 0.508)
		(drill 0.254)
		(layers "F.Cu" "B.Cu")
		(net "SMB_BMC_MM16_R5_SDA")
	)
	(segment
		(start 17.257268 -81.9404)
		(end 16.088868 -80.772)
		(width 0.11684)
		(layer "B.Cu")
		(net "SMB_BMC_MM16_R5_SDA")
	)
	(segment
		(start 49.403 -24.4602)
		(end 52.1462 -21.717)
		(width 0.11684)
		(layer "B.Cu")
		(net "SMB_BMC_MM16_R5_SDA")
	)
	(segment
		(start 49.784 -28.42895)
		(end 49.403 -28.04795)
		(width 0.11684)
		(layer "B.Cu")
		(net "SMB_BMC_MM16_R5_SDA")
	)
	(segment
		(start 16.088868 -80.772)
		(end 15.3924 -80.772)
		(width 0.11684)
		(layer "B.Cu")
		(net "SMB_BMC_MM16_R5_SDA")
	)
	(segment
		(start 50.3682 -16.3068)
		(end 51.181 -15.494)
		(width 0.11684)
		(layer "B.Cu")
		(net "SMB_BMC_MM16_R5_SDA")
	)
	(segment
		(start 18.288 -83.29295)
		(end 18.288 -82.6516)
		(width 0.11684)
		(layer "B.Cu")
		(net "SMB_BMC_MM16_R5_SDA")
	)
	(segment
		(start 52.1462 -21.717)
		(end 52.1462 -19.3548)
		(width 0.11684)
		(layer "B.Cu")
		(net "SMB_BMC_MM16_R5_SDA")
	)
	(segment
		(start 49.403 -26.9748)
		(end 49.403 -24.4602)
		(width 0.11684)
		(layer "B.Cu")
		(net "SMB_BMC_MM16_R5_SDA")
	)
	(segment
		(start 50.3682 -17.5768)
		(end 50.3682 -16.3068)
		(width 0.11684)
		(layer "B.Cu")
		(net "SMB_BMC_MM16_R5_SDA")
	)
	(segment
		(start 18.288 -82.6516)
		(end 17.5768 -81.9404)
		(width 0.11684)
		(layer "B.Cu")
		(net "SMB_BMC_MM16_R5_SDA")
	)
	(segment
		(start 52.1462 -19.3548)
		(end 50.3682 -17.5768)
		(width 0.11684)
		(layer "B.Cu")
		(net "SMB_BMC_MM16_R5_SDA")
	)
	(segment
		(start 49.403 -28.04795)
		(end 49.403 -26.9748)
		(width 0.11684)
		(layer "B.Cu")
		(net "SMB_BMC_MM16_R5_SDA")
	)
	(segment
		(start 17.5768 -81.9404)
		(end 17.257268 -81.9404)
		(width 0.11684)
		(layer "B.Cu")
		(net "SMB_BMC_MM16_R5_SDA")
	)
	(segment
		(start 72.722486 -98.902012)
		(end 73.05802 -98.902012)
		(width 0.08382)
		(layer "In2.Cu")
		(net "SMB_BMC_MM16_R5_SDA")
	)
	(segment
		(start 45.616368 -97.12833)
		(end 47.915068 -97.12833)
		(width 0.08382)
		(layer "In2.Cu")
		(net "SMB_BMC_MM16_R5_SDA")
	)
	(segment
		(start 48.142398 -96.901)
		(end 53.67782 -96.901)
		(width 0.08382)
		(layer "In2.Cu")
		(net "SMB_BMC_MM16_R5_SDA")
	)
	(segment
		(start 33.903412 -100.437188)
		(end 35.10407 -99.23653)
		(width 0.08382)
		(layer "In2.Cu")
		(net "SMB_BMC_MM16_R5_SDA")
	)
	(segment
		(start 33.85947 -100.437188)
		(end 33.903412 -100.437188)
		(width 0.08382)
		(layer "In2.Cu")
		(net "SMB_BMC_MM16_R5_SDA")
	)
	(segment
		(start 24.20112 -101.8032)
		(end 28.782518 -101.8032)
		(width 0.08382)
		(layer "In2.Cu")
		(net "SMB_BMC_MM16_R5_SDA")
	)
	(segment
		(start 56.40832 -99.6315)
		(end 59.55284 -99.6315)
		(width 0.08382)
		(layer "In2.Cu")
		(net "SMB_BMC_MM16_R5_SDA")
	)
	(segment
		(start 63.93434 -97.40646)
		(end 64.48044 -97.95256)
		(width 0.08382)
		(layer "In2.Cu")
		(net "SMB_BMC_MM16_R5_SDA")
	)
	(segment
		(start 17.7038 -103.8352)
		(end 17.7038 -103.47452)
		(width 0.08382)
		(layer "In2.Cu")
		(net "SMB_BMC_MM16_R5_SDA")
	)
	(segment
		(start 60.187332 -98.997008)
		(end 61.373512 -98.997008)
		(width 0.08382)
		(layer "In2.Cu")
		(net "SMB_BMC_MM16_R5_SDA")
	)
	(segment
		(start 62.96406 -97.40646)
		(end 63.93434 -97.40646)
		(width 0.08382)
		(layer "In2.Cu")
		(net "SMB_BMC_MM16_R5_SDA")
	)
	(segment
		(start 53.67782 -96.901)
		(end 56.40832 -99.6315)
		(width 0.08382)
		(layer "In2.Cu")
		(net "SMB_BMC_MM16_R5_SDA")
	)
	(segment
		(start 72.611488 -98.791014)
		(end 72.722486 -98.902012)
		(width 0.08382)
		(layer "In2.Cu")
		(net "SMB_BMC_MM16_R5_SDA")
	)
	(segment
		(start 31.935928 -100.98913)
		(end 32.225488 -100.69957)
		(width 0.08382)
		(layer "In2.Cu")
		(net "SMB_BMC_MM16_R5_SDA")
	)
	(segment
		(start 23.47976 -102.52456)
		(end 24.20112 -101.8032)
		(width 0.08382)
		(layer "In2.Cu")
		(net "SMB_BMC_MM16_R5_SDA")
	)
	(segment
		(start 61.373512 -98.997008)
		(end 62.96406 -97.40646)
		(width 0.08382)
		(layer "In2.Cu")
		(net "SMB_BMC_MM16_R5_SDA")
	)
	(segment
		(start 64.48044 -97.95256)
		(end 71.043546 -97.95256)
		(width 0.08382)
		(layer "In2.Cu")
		(net "SMB_BMC_MM16_R5_SDA")
	)
	(segment
		(start 35.10407 -99.23653)
		(end 36.604448 -99.23653)
		(width 0.08382)
		(layer "In2.Cu")
		(net "SMB_BMC_MM16_R5_SDA")
	)
	(segment
		(start 32.225488 -100.69957)
		(end 33.597088 -100.69957)
		(width 0.08382)
		(layer "In2.Cu")
		(net "SMB_BMC_MM16_R5_SDA")
	)
	(segment
		(start 29.596588 -100.98913)
		(end 31.935928 -100.98913)
		(width 0.08382)
		(layer "In2.Cu")
		(net "SMB_BMC_MM16_R5_SDA")
	)
	(segment
		(start 47.915068 -97.12833)
		(end 48.142398 -96.901)
		(width 0.08382)
		(layer "In2.Cu")
		(net "SMB_BMC_MM16_R5_SDA")
	)
	(segment
		(start 71.043546 -97.95256)
		(end 71.882 -98.791014)
		(width 0.08382)
		(layer "In2.Cu")
		(net "SMB_BMC_MM16_R5_SDA")
	)
	(segment
		(start 42.52722 -100.217478)
		(end 45.616368 -97.12833)
		(width 0.08382)
		(layer "In2.Cu")
		(net "SMB_BMC_MM16_R5_SDA")
	)
	(segment
		(start 59.55284 -99.6315)
		(end 60.187332 -98.997008)
		(width 0.08382)
		(layer "In2.Cu")
		(net "SMB_BMC_MM16_R5_SDA")
	)
	(segment
		(start 17.7038 -103.47452)
		(end 18.577306 -102.601014)
		(width 0.08382)
		(layer "In2.Cu")
		(net "SMB_BMC_MM16_R5_SDA")
	)
	(segment
		(start 71.882 -98.791014)
		(end 72.611488 -98.791014)
		(width 0.08382)
		(layer "In2.Cu")
		(net "SMB_BMC_MM16_R5_SDA")
	)
	(segment
		(start 28.782518 -101.8032)
		(end 29.596588 -100.98913)
		(width 0.08382)
		(layer "In2.Cu")
		(net "SMB_BMC_MM16_R5_SDA")
	)
	(segment
		(start 21.53539 -102.52456)
		(end 23.47976 -102.52456)
		(width 0.08382)
		(layer "In2.Cu")
		(net "SMB_BMC_MM16_R5_SDA")
	)
	(segment
		(start 36.604448 -99.23653)
		(end 37.585396 -100.217478)
		(width 0.08382)
		(layer "In2.Cu")
		(net "SMB_BMC_MM16_R5_SDA")
	)
	(segment
		(start 18.577306 -102.601014)
		(end 21.458936 -102.601014)
		(width 0.08382)
		(layer "In2.Cu")
		(net "SMB_BMC_MM16_R5_SDA")
	)
	(segment
		(start 21.458936 -102.601014)
		(end 21.53539 -102.52456)
		(width 0.08382)
		(layer "In2.Cu")
		(net "SMB_BMC_MM16_R5_SDA")
	)
	(segment
		(start 37.585396 -100.217478)
		(end 42.52722 -100.217478)
		(width 0.08382)
		(layer "In2.Cu")
		(net "SMB_BMC_MM16_R5_SDA")
	)
	(segment
		(start 33.597088 -100.69957)
		(end 33.85947 -100.437188)
		(width 0.08382)
		(layer "In2.Cu")
		(net "SMB_BMC_MM16_R5_SDA")
	)
	(segment
		(start 88.30564 -25.76068)
		(end 88.30564 -20.48764)
		(width 0.10668)
		(layer "In4.Cu")
		(net "SMB_BMC_MM16_R5_SDA")
	)
	(segment
		(start 74.69632 -13.73632)
		(end 67.442842 -13.73632)
		(width 0.10668)
		(layer "In4.Cu")
		(net "SMB_BMC_MM16_R5_SDA")
	)
	(segment
		(start 52.64785 -12.72032)
		(end 51.403504 -13.964666)
		(width 0.10668)
		(layer "In4.Cu")
		(net "SMB_BMC_MM16_R5_SDA")
	)
	(segment
		(start 66.426842 -12.72032)
		(end 52.64785 -12.72032)
		(width 0.10668)
		(layer "In4.Cu")
		(net "SMB_BMC_MM16_R5_SDA")
	)
	(segment
		(start 77.597 -16.637)
		(end 74.69632 -13.73632)
		(width 0.10668)
		(layer "In4.Cu")
		(net "SMB_BMC_MM16_R5_SDA")
	)
	(segment
		(start 67.442842 -13.73632)
		(end 66.426842 -12.72032)
		(width 0.10668)
		(layer "In4.Cu")
		(net "SMB_BMC_MM16_R5_SDA")
	)
	(segment
		(start 51.403504 -14.222984)
		(end 51.173888 -14.4526)
		(width 0.10668)
		(layer "In4.Cu")
		(net "SMB_BMC_MM16_R5_SDA")
	)
	(segment
		(start 51.403504 -13.964666)
		(end 51.403504 -14.222984)
		(width 0.10668)
		(layer "In4.Cu")
		(net "SMB_BMC_MM16_R5_SDA")
	)
	(segment
		(start 51.173888 -15.486888)
		(end 51.181 -15.494)
		(width 0.10668)
		(layer "In4.Cu")
		(net "SMB_BMC_MM16_R5_SDA")
	)
	(segment
		(start 84.455 -16.637)
		(end 77.597 -16.637)
		(width 0.10668)
		(layer "In4.Cu")
		(net "SMB_BMC_MM16_R5_SDA")
	)
	(segment
		(start 86.91372 -27.1526)
		(end 88.30564 -25.76068)
		(width 0.10668)
		(layer "In4.Cu")
		(net "SMB_BMC_MM16_R5_SDA")
	)
	(segment
		(start 51.173888 -14.4526)
		(end 51.173888 -15.486888)
		(width 0.10668)
		(layer "In4.Cu")
		(net "SMB_BMC_MM16_R5_SDA")
	)
	(segment
		(start 88.30564 -20.48764)
		(end 84.455 -16.637)
		(width 0.10668)
		(layer "In4.Cu")
		(net "SMB_BMC_MM16_R5_SDA")
	)
	(segment
		(start 73.781158 -98.902012)
		(end 73.837292 -98.958146)
		(width 0.10668)
		(layer "In7.Cu")
		(net "SMB_BMC_MM16_R5_SDA")
	)
	(segment
		(start 84.78012 -81.292192)
		(end 88.15324 -77.919072)
		(width 0.10668)
		(layer "In7.Cu")
		(net "SMB_BMC_MM16_R5_SDA")
	)
	(segment
		(start 15.8623 -84.238846)
		(end 13.570458 -84.238846)
		(width 0.10668)
		(layer "In7.Cu")
		(net "SMB_BMC_MM16_R5_SDA")
	)
	(segment
		(start 75.3618 -98.3234)
		(end 78.6892 -98.3234)
		(width 0.10668)
		(layer "In7.Cu")
		(net "SMB_BMC_MM16_R5_SDA")
	)
	(segment
		(start 81.80578 -89.97442)
		(end 84.78012 -87.00008)
		(width 0.10668)
		(layer "In7.Cu")
		(net "SMB_BMC_MM16_R5_SDA")
	)
	(segment
		(start 13.1572 -94.1832)
		(end 13.35278 -94.37878)
		(width 0.10668)
		(layer "In7.Cu")
		(net "SMB_BMC_MM16_R5_SDA")
	)
	(segment
		(start 13.35278 -94.37878)
		(end 14.147038 -94.37878)
		(width 0.10668)
		(layer "In7.Cu")
		(net "SMB_BMC_MM16_R5_SDA")
	)
	(segment
		(start 14.1732 -89.6112)
		(end 14.1732 -92.5068)
		(width 0.10668)
		(layer "In7.Cu")
		(net "SMB_BMC_MM16_R5_SDA")
	)
	(segment
		(start 78.6892 -98.3234)
		(end 78.9178 -98.0948)
		(width 0.10668)
		(layer "In7.Cu")
		(net "SMB_BMC_MM16_R5_SDA")
	)
	(segment
		(start 81.80578 -96.29902)
		(end 81.80578 -89.97442)
		(width 0.10668)
		(layer "In7.Cu")
		(net "SMB_BMC_MM16_R5_SDA")
	)
	(segment
		(start 80.141572 -97.963228)
		(end 81.80578 -96.29902)
		(width 0.10668)
		(layer "In7.Cu")
		(net "SMB_BMC_MM16_R5_SDA")
	)
	(segment
		(start 78.9178 -98.0948)
		(end 78.9178 -98.069908)
		(width 0.10668)
		(layer "In7.Cu")
		(net "SMB_BMC_MM16_R5_SDA")
	)
	(segment
		(start 73.05802 -98.902012)
		(end 73.781158 -98.902012)
		(width 0.10668)
		(layer "In7.Cu")
		(net "SMB_BMC_MM16_R5_SDA")
	)
	(segment
		(start 13.1572 -93.5228)
		(end 13.1572 -94.1832)
		(width 0.10668)
		(layer "In7.Cu")
		(net "SMB_BMC_MM16_R5_SDA")
	)
	(segment
		(start 79.02448 -97.963228)
		(end 80.141572 -97.963228)
		(width 0.10668)
		(layer "In7.Cu")
		(net "SMB_BMC_MM16_R5_SDA")
	)
	(segment
		(start 14.06652 -101.34092)
		(end 15.4178 -102.6922)
		(width 0.10668)
		(layer "In7.Cu")
		(net "SMB_BMC_MM16_R5_SDA")
	)
	(segment
		(start 16.129 -80.772)
		(end 16.9164 -81.5594)
		(width 0.10668)
		(layer "In7.Cu")
		(net "SMB_BMC_MM16_R5_SDA")
	)
	(segment
		(start 15.3924 -80.772)
		(end 16.129 -80.772)
		(width 0.10668)
		(layer "In7.Cu")
		(net "SMB_BMC_MM16_R5_SDA")
	)
	(segment
		(start 14.06652 -99.94646)
		(end 14.06652 -101.34092)
		(width 0.10668)
		(layer "In7.Cu")
		(net "SMB_BMC_MM16_R5_SDA")
	)
	(segment
		(start 86.91372 -27.615642)
		(end 86.91372 -27.1526)
		(width 0.10668)
		(layer "In7.Cu")
		(net "SMB_BMC_MM16_R5_SDA")
	)
	(segment
		(start 16.9164 -81.5594)
		(end 16.9164 -83.184746)
		(width 0.10668)
		(layer "In7.Cu")
		(net "SMB_BMC_MM16_R5_SDA")
	)
	(segment
		(start 88.15324 -77.919072)
		(end 88.15324 -28.855162)
		(width 0.10668)
		(layer "In7.Cu")
		(net "SMB_BMC_MM16_R5_SDA")
	)
	(segment
		(start 12.95908 -88.39708)
		(end 14.1732 -89.6112)
		(width 0.10668)
		(layer "In7.Cu")
		(net "SMB_BMC_MM16_R5_SDA")
	)
	(segment
		(start 78.9178 -98.069908)
		(end 79.02448 -97.963228)
		(width 0.10668)
		(layer "In7.Cu")
		(net "SMB_BMC_MM16_R5_SDA")
	)
	(segment
		(start 17.7038 -103.4542)
		(end 17.7038 -103.8352)
		(width 0.10668)
		(layer "In7.Cu")
		(net "SMB_BMC_MM16_R5_SDA")
	)
	(segment
		(start 14.58468 -94.816422)
		(end 14.58468 -99.4283)
		(width 0.10668)
		(layer "In7.Cu")
		(net "SMB_BMC_MM16_R5_SDA")
	)
	(segment
		(start 74.727054 -98.958146)
		(end 75.3618 -98.3234)
		(width 0.10668)
		(layer "In7.Cu")
		(net "SMB_BMC_MM16_R5_SDA")
	)
	(segment
		(start 12.95908 -84.850224)
		(end 12.95908 -88.39708)
		(width 0.10668)
		(layer "In7.Cu")
		(net "SMB_BMC_MM16_R5_SDA")
	)
	(segment
		(start 13.570458 -84.238846)
		(end 12.95908 -84.850224)
		(width 0.10668)
		(layer "In7.Cu")
		(net "SMB_BMC_MM16_R5_SDA")
	)
	(segment
		(start 84.78012 -87.00008)
		(end 84.78012 -81.292192)
		(width 0.10668)
		(layer "In7.Cu")
		(net "SMB_BMC_MM16_R5_SDA")
	)
	(segment
		(start 15.4178 -102.6922)
		(end 16.9418 -102.6922)
		(width 0.10668)
		(layer "In7.Cu")
		(net "SMB_BMC_MM16_R5_SDA")
	)
	(segment
		(start 14.147038 -94.37878)
		(end 14.58468 -94.816422)
		(width 0.10668)
		(layer "In7.Cu")
		(net "SMB_BMC_MM16_R5_SDA")
	)
	(segment
		(start 73.837292 -98.958146)
		(end 74.727054 -98.958146)
		(width 0.10668)
		(layer "In7.Cu")
		(net "SMB_BMC_MM16_R5_SDA")
	)
	(segment
		(start 88.15324 -28.855162)
		(end 86.91372 -27.615642)
		(width 0.10668)
		(layer "In7.Cu")
		(net "SMB_BMC_MM16_R5_SDA")
	)
	(segment
		(start 14.1732 -92.5068)
		(end 13.1572 -93.5228)
		(width 0.10668)
		(layer "In7.Cu")
		(net "SMB_BMC_MM16_R5_SDA")
	)
	(segment
		(start 14.58468 -99.4283)
		(end 14.06652 -99.94646)
		(width 0.10668)
		(layer "In7.Cu")
		(net "SMB_BMC_MM16_R5_SDA")
	)
	(segment
		(start 16.9164 -83.184746)
		(end 15.8623 -84.238846)
		(width 0.10668)
		(layer "In7.Cu")
		(net "SMB_BMC_MM16_R5_SDA")
	)
	(segment
		(start 16.9418 -102.6922)
		(end 17.7038 -103.4542)
		(width 0.10668)
		(layer "In7.Cu")
		(net "SMB_BMC_MM16_R5_SDA")
	)
	(segment
		(start 25.0698 -67.6402)
		(end 24.140414 -67.6402)
		(width 0.11684)
		(layer "F.Cu")
		(net "SMB_BMC_MM16_R5_SCL")
	)
	(segment
		(start 19.973544 -67.4751)
		(end 19.883882 -67.4751)
		(width 0.11684)
		(layer "F.Cu")
		(net "SMB_BMC_MM16_R5_SCL")
	)
	(segment
		(start 20.120864 -67.32778)
		(end 19.973544 -67.4751)
		(width 0.11684)
		(layer "F.Cu")
		(net "SMB_BMC_MM16_R5_SCL")
	)
	(segment
		(start 15.396718 -75.128882)
		(end 15.396718 -79.250032)
		(width 0.11684)
		(layer "F.Cu")
		(net "SMB_BMC_MM16_R5_SCL")
	)
	(segment
		(start 19.883882 -67.4751)
		(end 19.358102 -68.00088)
		(width 0.11684)
		(layer "F.Cu")
		(net "SMB_BMC_MM16_R5_SCL")
	)
	(segment
		(start 27.2796 -68.590922)
		(end 26.63952 -67.950842)
		(width 0.11684)
		(layer "F.Cu")
		(net "SMB_BMC_MM16_R5_SCL")
	)
	(segment
		(start 24.140414 -67.6402)
		(end 23.827994 -67.32778)
		(width 0.11684)
		(layer "F.Cu")
		(net "SMB_BMC_MM16_R5_SCL")
	)
	(segment
		(start 16.04772 -68.00088)
		(end 14.9606 -69.088)
		(width 0.11684)
		(layer "F.Cu")
		(net "SMB_BMC_MM16_R5_SCL")
	)
	(segment
		(start 26.482802 -67.57289)
		(end 26.143712 -67.2338)
		(width 0.11684)
		(layer "F.Cu")
		(net "SMB_BMC_MM16_R5_SCL")
	)
	(segment
		(start 15.396718 -79.250032)
		(end 15.395702 -79.251048)
		(width 0.11684)
		(layer "F.Cu")
		(net "SMB_BMC_MM16_R5_SCL")
	)
	(segment
		(start 72.438514 -98.8441)
		(end 72.857614 -98.425)
		(width 0.11684)
		(layer "F.Cu")
		(net "SMB_BMC_MM16_R5_SCL")
	)
	(segment
		(start 14.9606 -69.088)
		(end 14.9606 -71.882)
		(width 0.11684)
		(layer "F.Cu")
		(net "SMB_BMC_MM16_R5_SCL")
	)
	(segment
		(start 17.018 -103.14305)
		(end 17.018 -103.8352)
		(width 0.11684)
		(layer "F.Cu")
		(net "SMB_BMC_MM16_R5_SCL")
	)
	(segment
		(start 72.438514 -99.27336)
		(end 72.438514 -98.8441)
		(width 0.11684)
		(layer "F.Cu")
		(net "SMB_BMC_MM16_R5_SCL")
	)
	(segment
		(start 14.9606 -71.882)
		(end 15.9766 -72.898)
		(width 0.11684)
		(layer "F.Cu")
		(net "SMB_BMC_MM16_R5_SCL")
	)
	(segment
		(start 27.2796 -68.66255)
		(end 27.2796 -68.590922)
		(width 0.11684)
		(layer "F.Cu")
		(net "SMB_BMC_MM16_R5_SCL")
	)
	(segment
		(start 23.827994 -67.32778)
		(end 20.120864 -67.32778)
		(width 0.11684)
		(layer "F.Cu")
		(net "SMB_BMC_MM16_R5_SCL")
	)
	(segment
		(start 26.63952 -67.950842)
		(end 26.482802 -67.57289)
		(width 0.11684)
		(layer "F.Cu")
		(net "SMB_BMC_MM16_R5_SCL")
	)
	(segment
		(start 15.9766 -72.898)
		(end 15.9766 -74.549)
		(width 0.11684)
		(layer "F.Cu")
		(net "SMB_BMC_MM16_R5_SCL")
	)
	(segment
		(start 15.9766 -74.549)
		(end 15.396718 -75.128882)
		(width 0.11684)
		(layer "F.Cu")
		(net "SMB_BMC_MM16_R5_SCL")
	)
	(segment
		(start 19.358102 -68.00088)
		(end 16.04772 -68.00088)
		(width 0.11684)
		(layer "F.Cu")
		(net "SMB_BMC_MM16_R5_SCL")
	)
	(segment
		(start 26.143712 -67.2338)
		(end 25.4762 -67.2338)
		(width 0.11684)
		(layer "F.Cu")
		(net "SMB_BMC_MM16_R5_SCL")
	)
	(segment
		(start 72.857614 -98.425)
		(end 73.580244 -98.425)
		(width 0.11684)
		(layer "F.Cu")
		(net "SMB_BMC_MM16_R5_SCL")
	)
	(segment
		(start 25.4762 -67.2338)
		(end 25.0698 -67.6402)
		(width 0.11684)
		(layer "F.Cu")
		(net "SMB_BMC_MM16_R5_SCL")
	)
	(via
		(at 51.8922 -15.3924)
		(size 0.508)
		(drill 0.254)
		(layers "F.Cu" "B.Cu")
		(net "SMB_BMC_MM16_R5_SCL")
	)
	(via
		(at 15.395702 -79.251048)
		(size 0.508)
		(drill 0.254)
		(layers "F.Cu" "B.Cu")
		(net "SMB_BMC_MM16_R5_SCL")
	)
	(via
		(at 17.018 -103.8352)
		(size 0.508)
		(drill 0.254)
		(layers "F.Cu" "B.Cu")
		(net "SMB_BMC_MM16_R5_SCL")
	)
	(via
		(at 72.438514 -99.27336)
		(size 0.508)
		(drill 0.254)
		(layers "F.Cu" "B.Cu")
		(net "SMB_BMC_MM16_R5_SCL")
	)
	(via
		(at 86.9188 -25.527)
		(size 0.508)
		(drill 0.254)
		(layers "F.Cu" "B.Cu")
		(net "SMB_BMC_MM16_R5_SCL")
	)
	(via
		(at 16.6116 -79.2226)
		(size 0.6604)
		(drill 0.3302)
		(layers "F.Cu" "B.Cu")
		(net "SMB_BMC_MM16_R5_SCL")
	)
	(segment
		(start 15.396718 -79.250032)
		(end 15.396718 -78.935326)
		(width 0.11684)
		(layer "B.Cu")
		(net "SMB_BMC_MM16_R5_SCL")
	)
	(segment
		(start 15.395702 -79.251048)
		(end 15.396718 -79.250032)
		(width 0.11684)
		(layer "B.Cu")
		(net "SMB_BMC_MM16_R5_SCL")
	)
	(segment
		(start 51.0286 -16.4846)
		(end 51.8922 -15.621)
		(width 0.11684)
		(layer "B.Cu")
		(net "SMB_BMC_MM16_R5_SCL")
	)
	(segment
		(start 50.8 -28.42895)
		(end 50.8 -27.025854)
		(width 0.11684)
		(layer "B.Cu")
		(net "SMB_BMC_MM16_R5_SCL")
	)
	(segment
		(start 17.272 -80.37195)
		(end 16.6116 -79.71155)
		(width 0.11684)
		(layer "B.Cu")
		(net "SMB_BMC_MM16_R5_SCL")
	)
	(segment
		(start 15.523972 -78.808072)
		(end 16.197072 -78.808072)
		(width 0.11684)
		(layer "B.Cu")
		(net "SMB_BMC_MM16_R5_SCL")
	)
	(segment
		(start 15.396718 -78.935326)
		(end 15.523972 -78.808072)
		(width 0.11684)
		(layer "B.Cu")
		(net "SMB_BMC_MM16_R5_SCL")
	)
	(segment
		(start 50.8 -27.025854)
		(end 49.8348 -26.060654)
		(width 0.11684)
		(layer "B.Cu")
		(net "SMB_BMC_MM16_R5_SCL")
	)
	(segment
		(start 16.197072 -78.808072)
		(end 16.6116 -79.2226)
		(width 0.11684)
		(layer "B.Cu")
		(net "SMB_BMC_MM16_R5_SCL")
	)
	(segment
		(start 51.0286 -17.5514)
		(end 51.0286 -16.4846)
		(width 0.11684)
		(layer "B.Cu")
		(net "SMB_BMC_MM16_R5_SCL")
	)
	(segment
		(start 52.5526 -21.844)
		(end 52.5526 -19.0754)
		(width 0.11684)
		(layer "B.Cu")
		(net "SMB_BMC_MM16_R5_SCL")
	)
	(segment
		(start 51.8922 -15.621)
		(end 51.8922 -15.3924)
		(width 0.11684)
		(layer "B.Cu")
		(net "SMB_BMC_MM16_R5_SCL")
	)
	(segment
		(start 52.5526 -19.0754)
		(end 51.0286 -17.5514)
		(width 0.11684)
		(layer "B.Cu")
		(net "SMB_BMC_MM16_R5_SCL")
	)
	(segment
		(start 16.6116 -79.71155)
		(end 16.6116 -79.2226)
		(width 0.11684)
		(layer "B.Cu")
		(net "SMB_BMC_MM16_R5_SCL")
	)
	(segment
		(start 49.8348 -26.060654)
		(end 49.8348 -24.5618)
		(width 0.11684)
		(layer "B.Cu")
		(net "SMB_BMC_MM16_R5_SCL")
	)
	(segment
		(start 49.8348 -24.5618)
		(end 52.5526 -21.844)
		(width 0.11684)
		(layer "B.Cu")
		(net "SMB_BMC_MM16_R5_SCL")
	)
	(segment
		(start 72.438514 -99.27336)
		(end 71.905622 -99.27336)
		(width 0.08382)
		(layer "In2.Cu")
		(net "SMB_BMC_MM16_R5_SCL")
	)
	(segment
		(start 33.726628 -101.01199)
		(end 32.355028 -101.01199)
		(width 0.08382)
		(layer "In2.Cu")
		(net "SMB_BMC_MM16_R5_SCL")
	)
	(segment
		(start 36.224718 -101.1682)
		(end 36.132008 -101.07549)
		(width 0.08382)
		(layer "In2.Cu")
		(net "SMB_BMC_MM16_R5_SCL")
	)
	(segment
		(start 21.66493 -102.83698)
		(end 21.588476 -102.913434)
		(width 0.08382)
		(layer "In2.Cu")
		(net "SMB_BMC_MM16_R5_SCL")
	)
	(segment
		(start 61.595254 -101.23932)
		(end 59.65698 -101.23932)
		(width 0.08382)
		(layer "In2.Cu")
		(net "SMB_BMC_MM16_R5_SCL")
	)
	(segment
		(start 70.965822 -98.33356)
		(end 64.501014 -98.33356)
		(width 0.08382)
		(layer "In2.Cu")
		(net "SMB_BMC_MM16_R5_SCL")
	)
	(segment
		(start 37.337746 -101.1682)
		(end 36.224718 -101.1682)
		(width 0.08382)
		(layer "In2.Cu")
		(net "SMB_BMC_MM16_R5_SCL")
	)
	(segment
		(start 35.722052 -101.07549)
		(end 35.332162 -100.6856)
		(width 0.08382)
		(layer "In2.Cu")
		(net "SMB_BMC_MM16_R5_SCL")
	)
	(segment
		(start 59.1312 -100.71354)
		(end 55.7276 -100.71354)
		(width 0.08382)
		(layer "In2.Cu")
		(net "SMB_BMC_MM16_R5_SCL")
	)
	(segment
		(start 54.96306 -99.949)
		(end 50.095912 -99.949)
		(width 0.08382)
		(layer "In2.Cu")
		(net "SMB_BMC_MM16_R5_SCL")
	)
	(segment
		(start 18.15211 -104.02189)
		(end 17.89049 -104.28351)
		(width 0.08382)
		(layer "In2.Cu")
		(net "SMB_BMC_MM16_R5_SCL")
	)
	(segment
		(start 48.540162 -98.39325)
		(end 48.086772 -98.39325)
		(width 0.08382)
		(layer "In2.Cu")
		(net "SMB_BMC_MM16_R5_SCL")
	)
	(segment
		(start 42.909998 -101.900736)
		(end 41.85158 -100.842318)
		(width 0.08382)
		(layer "In2.Cu")
		(net "SMB_BMC_MM16_R5_SCL")
	)
	(segment
		(start 41.85158 -100.842318)
		(end 37.663628 -100.842318)
		(width 0.08382)
		(layer "In2.Cu")
		(net "SMB_BMC_MM16_R5_SCL")
	)
	(segment
		(start 44.579286 -101.900736)
		(end 42.909998 -101.900736)
		(width 0.08382)
		(layer "In2.Cu")
		(net "SMB_BMC_MM16_R5_SCL")
	)
	(segment
		(start 18.706846 -102.913434)
		(end 18.15211 -103.46817)
		(width 0.08382)
		(layer "In2.Cu")
		(net "SMB_BMC_MM16_R5_SCL")
	)
	(segment
		(start 71.905622 -99.27336)
		(end 70.965822 -98.33356)
		(width 0.08382)
		(layer "In2.Cu")
		(net "SMB_BMC_MM16_R5_SCL")
	)
	(segment
		(start 17.46631 -104.28351)
		(end 17.018 -103.8352)
		(width 0.08382)
		(layer "In2.Cu")
		(net "SMB_BMC_MM16_R5_SCL")
	)
	(segment
		(start 23.6093 -102.83698)
		(end 21.66493 -102.83698)
		(width 0.08382)
		(layer "In2.Cu")
		(net "SMB_BMC_MM16_R5_SCL")
	)
	(segment
		(start 32.065468 -101.30155)
		(end 29.726382 -101.30155)
		(width 0.08382)
		(layer "In2.Cu")
		(net "SMB_BMC_MM16_R5_SCL")
	)
	(segment
		(start 37.663628 -100.842318)
		(end 37.337746 -101.1682)
		(width 0.08382)
		(layer "In2.Cu")
		(net "SMB_BMC_MM16_R5_SCL")
	)
	(segment
		(start 34.053018 -100.6856)
		(end 33.726628 -101.01199)
		(width 0.08382)
		(layer "In2.Cu")
		(net "SMB_BMC_MM16_R5_SCL")
	)
	(segment
		(start 64.501014 -98.33356)
		(end 61.595254 -101.23932)
		(width 0.08382)
		(layer "In2.Cu")
		(net "SMB_BMC_MM16_R5_SCL")
	)
	(segment
		(start 18.15211 -103.46817)
		(end 18.15211 -104.02189)
		(width 0.08382)
		(layer "In2.Cu")
		(net "SMB_BMC_MM16_R5_SCL")
	)
	(segment
		(start 59.65698 -101.23932)
		(end 59.1312 -100.71354)
		(width 0.08382)
		(layer "In2.Cu")
		(net "SMB_BMC_MM16_R5_SCL")
	)
	(segment
		(start 50.095912 -99.949)
		(end 48.540162 -98.39325)
		(width 0.08382)
		(layer "In2.Cu")
		(net "SMB_BMC_MM16_R5_SCL")
	)
	(segment
		(start 28.96108 -102.066852)
		(end 24.379428 -102.066852)
		(width 0.08382)
		(layer "In2.Cu")
		(net "SMB_BMC_MM16_R5_SCL")
	)
	(segment
		(start 55.7276 -100.71354)
		(end 54.96306 -99.949)
		(width 0.08382)
		(layer "In2.Cu")
		(net "SMB_BMC_MM16_R5_SCL")
	)
	(segment
		(start 36.132008 -101.07549)
		(end 35.722052 -101.07549)
		(width 0.08382)
		(layer "In2.Cu")
		(net "SMB_BMC_MM16_R5_SCL")
	)
	(segment
		(start 24.379428 -102.066852)
		(end 23.6093 -102.83698)
		(width 0.08382)
		(layer "In2.Cu")
		(net "SMB_BMC_MM16_R5_SCL")
	)
	(segment
		(start 17.89049 -104.28351)
		(end 17.46631 -104.28351)
		(width 0.08382)
		(layer "In2.Cu")
		(net "SMB_BMC_MM16_R5_SCL")
	)
	(segment
		(start 32.355028 -101.01199)
		(end 32.065468 -101.30155)
		(width 0.08382)
		(layer "In2.Cu")
		(net "SMB_BMC_MM16_R5_SCL")
	)
	(segment
		(start 29.726382 -101.30155)
		(end 28.96108 -102.066852)
		(width 0.08382)
		(layer "In2.Cu")
		(net "SMB_BMC_MM16_R5_SCL")
	)
	(segment
		(start 21.588476 -102.913434)
		(end 18.706846 -102.913434)
		(width 0.08382)
		(layer "In2.Cu")
		(net "SMB_BMC_MM16_R5_SCL")
	)
	(segment
		(start 48.086772 -98.39325)
		(end 44.579286 -101.900736)
		(width 0.08382)
		(layer "In2.Cu")
		(net "SMB_BMC_MM16_R5_SCL")
	)
	(segment
		(start 35.332162 -100.6856)
		(end 34.053018 -100.6856)
		(width 0.08382)
		(layer "In2.Cu")
		(net "SMB_BMC_MM16_R5_SCL")
	)
	(segment
		(start 84.347558 -16.89608)
		(end 77.489558 -16.89608)
		(width 0.10668)
		(layer "In4.Cu")
		(net "SMB_BMC_MM16_R5_SCL")
	)
	(segment
		(start 51.662584 -14.222984)
		(end 51.8922 -14.4526)
		(width 0.10668)
		(layer "In4.Cu")
		(net "SMB_BMC_MM16_R5_SCL")
	)
	(segment
		(start 77.489558 -16.89608)
		(end 74.588878 -13.9954)
		(width 0.10668)
		(layer "In4.Cu")
		(net "SMB_BMC_MM16_R5_SCL")
	)
	(segment
		(start 51.8922 -14.4526)
		(end 51.8922 -15.3924)
		(width 0.10668)
		(layer "In4.Cu")
		(net "SMB_BMC_MM16_R5_SCL")
	)
	(segment
		(start 88.04656 -20.595082)
		(end 84.347558 -16.89608)
		(width 0.10668)
		(layer "In4.Cu")
		(net "SMB_BMC_MM16_R5_SCL")
	)
	(segment
		(start 88.04656 -24.39924)
		(end 88.04656 -20.595082)
		(width 0.10668)
		(layer "In4.Cu")
		(net "SMB_BMC_MM16_R5_SCL")
	)
	(segment
		(start 74.588878 -13.9954)
		(end 67.3354 -13.9954)
		(width 0.10668)
		(layer "In4.Cu")
		(net "SMB_BMC_MM16_R5_SCL")
	)
	(segment
		(start 66.3194 -12.9794)
		(end 52.755292 -12.9794)
		(width 0.10668)
		(layer "In4.Cu")
		(net "SMB_BMC_MM16_R5_SCL")
	)
	(segment
		(start 86.9188 -25.527)
		(end 88.04656 -24.39924)
		(width 0.10668)
		(layer "In4.Cu")
		(net "SMB_BMC_MM16_R5_SCL")
	)
	(segment
		(start 52.755292 -12.9794)
		(end 51.662584 -14.072108)
		(width 0.10668)
		(layer "In4.Cu")
		(net "SMB_BMC_MM16_R5_SCL")
	)
	(segment
		(start 51.662584 -14.072108)
		(end 51.662584 -14.222984)
		(width 0.10668)
		(layer "In4.Cu")
		(net "SMB_BMC_MM16_R5_SCL")
	)
	(segment
		(start 67.3354 -13.9954)
		(end 66.3194 -12.9794)
		(width 0.10668)
		(layer "In4.Cu")
		(net "SMB_BMC_MM16_R5_SCL")
	)
	(segment
		(start 16.4846 -82.1182)
		(end 16.4846 -83.142328)
		(width 0.10668)
		(layer "In7.Cu")
		(net "SMB_BMC_MM16_R5_SCL")
	)
	(segment
		(start 12.6238 -84.711286)
		(end 12.6238 -94.2848)
		(width 0.10668)
		(layer "In7.Cu")
		(net "SMB_BMC_MM16_R5_SCL")
	)
	(segment
		(start 13.73124 -99.915218)
		(end 13.73124 -101.48824)
		(width 0.10668)
		(layer "In7.Cu")
		(net "SMB_BMC_MM16_R5_SCL")
	)
	(segment
		(start 14.3256 -95.03156)
		(end 14.3256 -99.320858)
		(width 0.10668)
		(layer "In7.Cu")
		(net "SMB_BMC_MM16_R5_SCL")
	)
	(segment
		(start 15.27048 -103.02748)
		(end 16.802862 -103.02748)
		(width 0.10668)
		(layer "In7.Cu")
		(net "SMB_BMC_MM16_R5_SCL")
	)
	(segment
		(start 15.723362 -83.903566)
		(end 13.43152 -83.903566)
		(width 0.10668)
		(layer "In7.Cu")
		(net "SMB_BMC_MM16_R5_SCL")
	)
	(segment
		(start 72.555354 -99.3902)
		(end 72.438514 -99.27336)
		(width 0.10668)
		(layer "In7.Cu")
		(net "SMB_BMC_MM16_R5_SCL")
	)
	(segment
		(start 13.73124 -101.48824)
		(end 15.27048 -103.02748)
		(width 0.10668)
		(layer "In7.Cu")
		(net "SMB_BMC_MM16_R5_SCL")
	)
	(segment
		(start 13.43152 -83.903566)
		(end 12.6238 -84.711286)
		(width 0.10668)
		(layer "In7.Cu")
		(net "SMB_BMC_MM16_R5_SCL")
	)
	(segment
		(start 14.0081 -94.71406)
		(end 14.3256 -95.03156)
		(width 0.10668)
		(layer "In7.Cu")
		(net "SMB_BMC_MM16_R5_SCL")
	)
	(segment
		(start 85.0392 -81.399634)
		(end 85.0392 -87.107522)
		(width 0.10668)
		(layer "In7.Cu")
		(net "SMB_BMC_MM16_R5_SCL")
	)
	(segment
		(start 13.05306 -94.71406)
		(end 14.0081 -94.71406)
		(width 0.10668)
		(layer "In7.Cu")
		(net "SMB_BMC_MM16_R5_SCL")
	)
	(segment
		(start 88.41232 -78.026514)
		(end 85.0392 -81.399634)
		(width 0.10668)
		(layer "In7.Cu")
		(net "SMB_BMC_MM16_R5_SCL")
	)
	(segment
		(start 15.84452 -81.47812)
		(end 16.4846 -82.1182)
		(width 0.10668)
		(layer "In7.Cu")
		(net "SMB_BMC_MM16_R5_SCL")
	)
	(segment
		(start 88.41232 -26.51252)
		(end 88.41232 -78.026514)
		(width 0.10668)
		(layer "In7.Cu")
		(net "SMB_BMC_MM16_R5_SCL")
	)
	(segment
		(start 82.06486 -96.406462)
		(end 80.249014 -98.222308)
		(width 0.10668)
		(layer "In7.Cu")
		(net "SMB_BMC_MM16_R5_SCL")
	)
	(segment
		(start 73.837292 -99.217226)
		(end 73.664318 -99.3902)
		(width 0.10668)
		(layer "In7.Cu")
		(net "SMB_BMC_MM16_R5_SCL")
	)
	(segment
		(start 16.802862 -103.02748)
		(end 17.018 -103.242618)
		(width 0.10668)
		(layer "In7.Cu")
		(net "SMB_BMC_MM16_R5_SCL")
	)
	(segment
		(start 14.3256 -99.320858)
		(end 13.73124 -99.915218)
		(width 0.10668)
		(layer "In7.Cu")
		(net "SMB_BMC_MM16_R5_SCL")
	)
	(segment
		(start 14.8844 -79.76235)
		(end 14.8844 -81.22412)
		(width 0.10668)
		(layer "In7.Cu")
		(net "SMB_BMC_MM16_R5_SCL")
	)
	(segment
		(start 75.469242 -98.58248)
		(end 74.834496 -99.217226)
		(width 0.10668)
		(layer "In7.Cu")
		(net "SMB_BMC_MM16_R5_SCL")
	)
	(segment
		(start 16.4846 -83.142328)
		(end 15.723362 -83.903566)
		(width 0.10668)
		(layer "In7.Cu")
		(net "SMB_BMC_MM16_R5_SCL")
	)
	(segment
		(start 73.664318 -99.3902)
		(end 72.555354 -99.3902)
		(width 0.10668)
		(layer "In7.Cu")
		(net "SMB_BMC_MM16_R5_SCL")
	)
	(segment
		(start 82.06486 -90.081862)
		(end 82.06486 -96.406462)
		(width 0.10668)
		(layer "In7.Cu")
		(net "SMB_BMC_MM16_R5_SCL")
	)
	(segment
		(start 85.0392 -87.107522)
		(end 82.06486 -90.081862)
		(width 0.10668)
		(layer "In7.Cu")
		(net "SMB_BMC_MM16_R5_SCL")
	)
	(segment
		(start 17.018 -103.242618)
		(end 17.018 -103.8352)
		(width 0.10668)
		(layer "In7.Cu")
		(net "SMB_BMC_MM16_R5_SCL")
	)
	(segment
		(start 14.8844 -81.22412)
		(end 15.1384 -81.47812)
		(width 0.10668)
		(layer "In7.Cu")
		(net "SMB_BMC_MM16_R5_SCL")
	)
	(segment
		(start 79.156814 -98.222308)
		(end 78.796642 -98.58248)
		(width 0.10668)
		(layer "In7.Cu")
		(net "SMB_BMC_MM16_R5_SCL")
	)
	(segment
		(start 87.4268 -25.527)
		(end 88.41232 -26.51252)
		(width 0.10668)
		(layer "In7.Cu")
		(net "SMB_BMC_MM16_R5_SCL")
	)
	(segment
		(start 86.9188 -25.527)
		(end 87.4268 -25.527)
		(width 0.10668)
		(layer "In7.Cu")
		(net "SMB_BMC_MM16_R5_SCL")
	)
	(segment
		(start 15.1384 -81.47812)
		(end 15.84452 -81.47812)
		(width 0.10668)
		(layer "In7.Cu")
		(net "SMB_BMC_MM16_R5_SCL")
	)
	(segment
		(start 15.395702 -79.251048)
		(end 14.8844 -79.76235)
		(width 0.10668)
		(layer "In7.Cu")
		(net "SMB_BMC_MM16_R5_SCL")
	)
	(segment
		(start 78.796642 -98.58248)
		(end 75.469242 -98.58248)
		(width 0.10668)
		(layer "In7.Cu")
		(net "SMB_BMC_MM16_R5_SCL")
	)
	(segment
		(start 80.249014 -98.222308)
		(end 79.156814 -98.222308)
		(width 0.10668)
		(layer "In7.Cu")
		(net "SMB_BMC_MM16_R5_SCL")
	)
	(segment
		(start 12.6238 -94.2848)
		(end 13.05306 -94.71406)
		(width 0.10668)
		(layer "In7.Cu")
		(net "SMB_BMC_MM16_R5_SCL")
	)
	(segment
		(start 74.834496 -99.217226)
		(end 73.837292 -99.217226)
		(width 0.10668)
		(layer "In7.Cu")
		(net "SMB_BMC_MM16_R5_SCL")
	)
	(segment
		(start 71.12508 -25.2349)
		(end 71.7804 -24.57958)
		(width 0.11684)
		(layer "F.Cu")
		(net "PWRGD_P3V3_RGM_R3")
	)
	(segment
		(start 71.07809 -27.51455)
		(end 70.88124 -27.3177)
		(width 0.11684)
		(layer "F.Cu")
		(net "PWRGD_P3V3_RGM_R3")
	)
	(segment
		(start 80.03032 -23.74138)
		(end 80.03032 -24.37892)
		(width 0.11684)
		(layer "F.Cu")
		(net "PWRGD_P3V3_RGM_R3")
	)
	(segment
		(start 71.4502 -27.51455)
		(end 71.07809 -27.51455)
		(width 0.11684)
		(layer "F.Cu")
		(net "PWRGD_P3V3_RGM_R3")
	)
	(segment
		(start 80.28432 -24.37892)
		(end 80.03032 -24.37892)
		(width 0.11684)
		(layer "F.Cu")
		(net "PWRGD_P3V3_RGM_R3")
	)
	(segment
		(start 70.88124 -27.3177)
		(end 70.88124 -25.81656)
		(width 0.11684)
		(layer "F.Cu")
		(net "PWRGD_P3V3_RGM_R3")
	)
	(segment
		(start 70.88124 -25.81656)
		(end 71.12508 -25.57272)
		(width 0.11684)
		(layer "F.Cu")
		(net "PWRGD_P3V3_RGM_R3")
	)
	(segment
		(start 81.407 -25.5016)
		(end 80.28432 -24.37892)
		(width 0.11684)
		(layer "F.Cu")
		(net "PWRGD_P3V3_RGM_R3")
	)
	(segment
		(start 72.5043 -24.57958)
		(end 73.86828 -23.2156)
		(width 0.11684)
		(layer "F.Cu")
		(net "PWRGD_P3V3_RGM_R3")
	)
	(segment
		(start 71.7804 -24.57958)
		(end 72.5043 -24.57958)
		(width 0.11684)
		(layer "F.Cu")
		(net "PWRGD_P3V3_RGM_R3")
	)
	(segment
		(start 77.446124 -70.485)
		(end 76.44892 -70.485)
		(width 0.11684)
		(layer "F.Cu")
		(net "PWRGD_P3V3_RGM_R3")
	)
	(segment
		(start 79.50454 -23.2156)
		(end 80.03032 -23.74138)
		(width 0.11684)
		(layer "F.Cu")
		(net "PWRGD_P3V3_RGM_R3")
	)
	(segment
		(start 76.44892 -70.485)
		(end 75.90536 -71.02856)
		(width 0.11684)
		(layer "F.Cu")
		(net "PWRGD_P3V3_RGM_R3")
	)
	(segment
		(start 73.86828 -23.2156)
		(end 79.50454 -23.2156)
		(width 0.11684)
		(layer "F.Cu")
		(net "PWRGD_P3V3_RGM_R3")
	)
	(segment
		(start 77.547724 -70.3834)
		(end 77.446124 -70.485)
		(width 0.11684)
		(layer "F.Cu")
		(net "PWRGD_P3V3_RGM_R3")
	)
	(segment
		(start 71.12508 -25.57272)
		(end 71.12508 -25.2349)
		(width 0.11684)
		(layer "F.Cu")
		(net "PWRGD_P3V3_RGM_R3")
	)
	(via
		(at 80.03032 -24.37892)
		(size 0.762)
		(drill 0.381)
		(layers "F.Cu" "B.Cu")
		(net "PWRGD_P3V3_RGM_R3")
	)
	(via
		(at 75.90536 -71.02856)
		(size 0.508)
		(drill 0.254)
		(layers "F.Cu" "B.Cu")
		(net "PWRGD_P3V3_RGM_R3")
	)
	(via
		(at 81.407 -25.5016)
		(size 0.508)
		(drill 0.254)
		(layers "F.Cu" "B.Cu")
		(net "PWRGD_P3V3_RGM_R3")
	)
	(segment
		(start 81.407 -26.602182)
		(end 81.407 -25.5016)
		(width 0.10668)
		(layer "In7.Cu")
		(net "PWRGD_P3V3_RGM_R3")
	)
	(segment
		(start 86.88832 -28.1178)
		(end 83.636866 -28.1178)
		(width 0.10668)
		(layer "In7.Cu")
		(net "PWRGD_P3V3_RGM_R3")
	)
	(segment
		(start 86.92515 -56.79567)
		(end 87.89416 -55.82666)
		(width 0.10668)
		(layer "In7.Cu")
		(net "PWRGD_P3V3_RGM_R3")
	)
	(segment
		(start 76.453238 -72.211438)
		(end 77.121766 -72.211438)
		(width 0.10668)
		(layer "In7.Cu")
		(net "PWRGD_P3V3_RGM_R3")
	)
	(segment
		(start 79.555594 -61.23559)
		(end 79.555594 -57.240424)
		(width 0.10668)
		(layer "In7.Cu")
		(net "PWRGD_P3V3_RGM_R3")
	)
	(segment
		(start 82.70113 -27.182064)
		(end 81.986882 -27.182064)
		(width 0.10668)
		(layer "In7.Cu")
		(net "PWRGD_P3V3_RGM_R3")
	)
	(segment
		(start 79.555594 -57.240424)
		(end 80.000348 -56.79567)
		(width 0.10668)
		(layer "In7.Cu")
		(net "PWRGD_P3V3_RGM_R3")
	)
	(segment
		(start 78.993238 -70.339966)
		(end 78.993238 -61.797946)
		(width 0.10668)
		(layer "In7.Cu")
		(net "PWRGD_P3V3_RGM_R3")
	)
	(segment
		(start 78.993238 -61.797946)
		(end 79.555594 -61.23559)
		(width 0.10668)
		(layer "In7.Cu")
		(net "PWRGD_P3V3_RGM_R3")
	)
	(segment
		(start 81.986882 -27.182064)
		(end 81.407 -26.602182)
		(width 0.10668)
		(layer "In7.Cu")
		(net "PWRGD_P3V3_RGM_R3")
	)
	(segment
		(start 83.636866 -28.1178)
		(end 82.70113 -27.182064)
		(width 0.10668)
		(layer "In7.Cu")
		(net "PWRGD_P3V3_RGM_R3")
	)
	(segment
		(start 80.000348 -56.79567)
		(end 86.92515 -56.79567)
		(width 0.10668)
		(layer "In7.Cu")
		(net "PWRGD_P3V3_RGM_R3")
	)
	(segment
		(start 87.89416 -55.82666)
		(end 87.89416 -29.12364)
		(width 0.10668)
		(layer "In7.Cu")
		(net "PWRGD_P3V3_RGM_R3")
	)
	(segment
		(start 87.89416 -29.12364)
		(end 86.88832 -28.1178)
		(width 0.10668)
		(layer "In7.Cu")
		(net "PWRGD_P3V3_RGM_R3")
	)
	(segment
		(start 75.90536 -71.66356)
		(end 76.453238 -72.211438)
		(width 0.10668)
		(layer "In7.Cu")
		(net "PWRGD_P3V3_RGM_R3")
	)
	(segment
		(start 75.90536 -71.02856)
		(end 75.90536 -71.66356)
		(width 0.10668)
		(layer "In7.Cu")
		(net "PWRGD_P3V3_RGM_R3")
	)
	(segment
		(start 77.121766 -72.211438)
		(end 78.993238 -70.339966)
		(width 0.10668)
		(layer "In7.Cu")
		(net "PWRGD_P3V3_RGM_R3")
	)
	(segment
		(start 32.69488 -57.85231)
		(end 32.51073 -57.85231)
		(width 0.11684)
		(layer "F.Cu")
		(net "PWRGD_P2V5_AUX_R3")
	)
	(segment
		(start 31.999936 -57.199276)
		(end 31.553404 -57.199276)
		(width 0.11684)
		(layer "F.Cu")
		(net "PWRGD_P2V5_AUX_R3")
	)
	(segment
		(start 32.1056 -57.44718)
		(end 32.1056 -57.30494)
		(width 0.11684)
		(layer "F.Cu")
		(net "PWRGD_P2V5_AUX_R3")
	)
	(segment
		(start 32.51073 -57.85231)
		(end 32.1056 -57.44718)
		(width 0.11684)
		(layer "F.Cu")
		(net "PWRGD_P2V5_AUX_R3")
	)
	(segment
		(start 32.1056 -57.30494)
		(end 31.999936 -57.199276)
		(width 0.11684)
		(layer "F.Cu")
		(net "PWRGD_P2V5_AUX_R3")
	)
	(via
		(at 67.307206 -25.839928)
		(size 0.762)
		(drill 0.254)
		(layers "F.Cu" "B.Cu")
		(net "PWRGD_P2V5_AUX_R3")
	)
	(via
		(at 31.553404 -57.199276)
		(size 0.508)
		(drill 0.254)
		(layers "F.Cu" "B.Cu")
		(net "PWRGD_P2V5_AUX_R3")
	)
	(segment
		(start 74.788014 -27.76982)
		(end 74.33564 -27.317446)
		(width 0.11684)
		(layer "B.Cu")
		(net "PWRGD_P2V5_AUX_R3")
	)
	(segment
		(start 74.33564 -27.317446)
		(end 74.33564 -25.806908)
		(width 0.11684)
		(layer "B.Cu")
		(net "PWRGD_P2V5_AUX_R3")
	)
	(segment
		(start 75.30846 -28.067)
		(end 75.01128 -27.76982)
		(width 0.11684)
		(layer "B.Cu")
		(net "PWRGD_P2V5_AUX_R3")
	)
	(segment
		(start 72.727058 -25.18156)
		(end 72.1741 -24.628602)
		(width 0.11684)
		(layer "B.Cu")
		(net "PWRGD_P2V5_AUX_R3")
	)
	(segment
		(start 74.33564 -25.806908)
		(end 73.710292 -25.18156)
		(width 0.11684)
		(layer "B.Cu")
		(net "PWRGD_P2V5_AUX_R3")
	)
	(segment
		(start 76.85786 -30.15234)
		(end 76.60386 -29.89834)
		(width 0.11684)
		(layer "B.Cu")
		(net "PWRGD_P2V5_AUX_R3")
	)
	(segment
		(start 77.91704 -30.15234)
		(end 76.85786 -30.15234)
		(width 0.11684)
		(layer "B.Cu")
		(net "PWRGD_P2V5_AUX_R3")
	)
	(segment
		(start 78.7908 -33.06445)
		(end 78.7908 -31.0261)
		(width 0.11684)
		(layer "B.Cu")
		(net "PWRGD_P2V5_AUX_R3")
	)
	(segment
		(start 68.518532 -24.628602)
		(end 67.307206 -25.839928)
		(width 0.11684)
		(layer "B.Cu")
		(net "PWRGD_P2V5_AUX_R3")
	)
	(segment
		(start 72.1741 -24.628602)
		(end 68.518532 -24.628602)
		(width 0.11684)
		(layer "B.Cu")
		(net "PWRGD_P2V5_AUX_R3")
	)
	(segment
		(start 76.60386 -28.92552)
		(end 75.74534 -28.067)
		(width 0.11684)
		(layer "B.Cu")
		(net "PWRGD_P2V5_AUX_R3")
	)
	(segment
		(start 73.710292 -25.18156)
		(end 72.727058 -25.18156)
		(width 0.11684)
		(layer "B.Cu")
		(net "PWRGD_P2V5_AUX_R3")
	)
	(segment
		(start 76.60386 -29.89834)
		(end 76.60386 -28.92552)
		(width 0.11684)
		(layer "B.Cu")
		(net "PWRGD_P2V5_AUX_R3")
	)
	(segment
		(start 75.01128 -27.76982)
		(end 74.788014 -27.76982)
		(width 0.11684)
		(layer "B.Cu")
		(net "PWRGD_P2V5_AUX_R3")
	)
	(segment
		(start 78.7908 -31.0261)
		(end 77.91704 -30.15234)
		(width 0.11684)
		(layer "B.Cu")
		(net "PWRGD_P2V5_AUX_R3")
	)
	(segment
		(start 75.74534 -28.067)
		(end 75.30846 -28.067)
		(width 0.11684)
		(layer "B.Cu")
		(net "PWRGD_P2V5_AUX_R3")
	)
	(segment
		(start 40.155622 -25.44318)
		(end 43.36923 -25.44318)
		(width 0.08382)
		(layer "In9.Cu")
		(net "PWRGD_P2V5_AUX_R3")
	)
	(segment
		(start 36.21786 -29.380942)
		(end 40.155622 -25.44318)
		(width 0.08382)
		(layer "In9.Cu")
		(net "PWRGD_P2V5_AUX_R3")
	)
	(segment
		(start 32.65424 -54.090824)
		(end 32.65424 -51.71313)
		(width 0.08382)
		(layer "In9.Cu")
		(net "PWRGD_P2V5_AUX_R3")
	)
	(segment
		(start 53.822346 -24.892)
		(end 55.108856 -26.17851)
		(width 0.08382)
		(layer "In9.Cu")
		(net "PWRGD_P2V5_AUX_R3")
	)
	(segment
		(start 43.36923 -25.44318)
		(end 44.21505 -26.289)
		(width 0.08382)
		(layer "In9.Cu")
		(net "PWRGD_P2V5_AUX_R3")
	)
	(segment
		(start 33.00349 -42.7482)
		(end 32.6898 -42.43451)
		(width 0.08382)
		(layer "In9.Cu")
		(net "PWRGD_P2V5_AUX_R3")
	)
	(segment
		(start 59.43981 -26.17851)
		(end 59.55157 -26.06675)
		(width 0.08382)
		(layer "In9.Cu")
		(net "PWRGD_P2V5_AUX_R3")
	)
	(segment
		(start 33.2486 -51.11877)
		(end 33.2486 -49.945798)
		(width 0.08382)
		(layer "In9.Cu")
		(net "PWRGD_P2V5_AUX_R3")
	)
	(segment
		(start 44.21505 -26.289)
		(end 48.183292 -26.289)
		(width 0.08382)
		(layer "In9.Cu")
		(net "PWRGD_P2V5_AUX_R3")
	)
	(segment
		(start 55.108856 -26.17851)
		(end 59.43981 -26.17851)
		(width 0.08382)
		(layer "In9.Cu")
		(net "PWRGD_P2V5_AUX_R3")
	)
	(segment
		(start 62.67958 -27.4828)
		(end 63.19266 -27.99588)
		(width 0.08382)
		(layer "In9.Cu")
		(net "PWRGD_P2V5_AUX_R3")
	)
	(segment
		(start 31.553404 -55.19166)
		(end 32.65424 -54.090824)
		(width 0.08382)
		(layer "In9.Cu")
		(net "PWRGD_P2V5_AUX_R3")
	)
	(segment
		(start 32.64789 -32.29991)
		(end 33.391856 -32.29991)
		(width 0.08382)
		(layer "In9.Cu")
		(net "PWRGD_P2V5_AUX_R3")
	)
	(segment
		(start 34.02584 -31.665926)
		(end 34.02584 -30.47746)
		(width 0.08382)
		(layer "In9.Cu")
		(net "PWRGD_P2V5_AUX_R3")
	)
	(segment
		(start 33.391856 -32.29991)
		(end 34.02584 -31.665926)
		(width 0.08382)
		(layer "In9.Cu")
		(net "PWRGD_P2V5_AUX_R3")
	)
	(segment
		(start 65.99174 -27.99588)
		(end 66.70294 -27.28468)
		(width 0.08382)
		(layer "In9.Cu")
		(net "PWRGD_P2V5_AUX_R3")
	)
	(segment
		(start 62.00521 -27.4828)
		(end 62.67958 -27.4828)
		(width 0.08382)
		(layer "In9.Cu")
		(net "PWRGD_P2V5_AUX_R3")
	)
	(segment
		(start 33.2486 -49.945798)
		(end 32.21101 -48.908208)
		(width 0.08382)
		(layer "In9.Cu")
		(net "PWRGD_P2V5_AUX_R3")
	)
	(segment
		(start 32.21101 -48.908208)
		(end 32.21101 -48.16729)
		(width 0.08382)
		(layer "In9.Cu")
		(net "PWRGD_P2V5_AUX_R3")
	)
	(segment
		(start 48.183292 -26.289)
		(end 49.580292 -24.892)
		(width 0.08382)
		(layer "In9.Cu")
		(net "PWRGD_P2V5_AUX_R3")
	)
	(segment
		(start 32.385 -39.5478)
		(end 32.385 -32.5628)
		(width 0.08382)
		(layer "In9.Cu")
		(net "PWRGD_P2V5_AUX_R3")
	)
	(segment
		(start 32.385 -32.5628)
		(end 32.64789 -32.29991)
		(width 0.08382)
		(layer "In9.Cu")
		(net "PWRGD_P2V5_AUX_R3")
	)
	(segment
		(start 32.21101 -48.16729)
		(end 33.00349 -47.37481)
		(width 0.08382)
		(layer "In9.Cu")
		(net "PWRGD_P2V5_AUX_R3")
	)
	(segment
		(start 59.55157 -26.06675)
		(end 60.58916 -26.06675)
		(width 0.08382)
		(layer "In9.Cu")
		(net "PWRGD_P2V5_AUX_R3")
	)
	(segment
		(start 33.00349 -47.37481)
		(end 33.00349 -42.7482)
		(width 0.08382)
		(layer "In9.Cu")
		(net "PWRGD_P2V5_AUX_R3")
	)
	(segment
		(start 34.02584 -30.47746)
		(end 35.122358 -29.380942)
		(width 0.08382)
		(layer "In9.Cu")
		(net "PWRGD_P2V5_AUX_R3")
	)
	(segment
		(start 63.19266 -27.99588)
		(end 65.99174 -27.99588)
		(width 0.08382)
		(layer "In9.Cu")
		(net "PWRGD_P2V5_AUX_R3")
	)
	(segment
		(start 32.65424 -51.71313)
		(end 33.2486 -51.11877)
		(width 0.08382)
		(layer "In9.Cu")
		(net "PWRGD_P2V5_AUX_R3")
	)
	(segment
		(start 66.70294 -27.28468)
		(end 66.70294 -26.444194)
		(width 0.08382)
		(layer "In9.Cu")
		(net "PWRGD_P2V5_AUX_R3")
	)
	(segment
		(start 32.6898 -39.8526)
		(end 32.385 -39.5478)
		(width 0.08382)
		(layer "In9.Cu")
		(net "PWRGD_P2V5_AUX_R3")
	)
	(segment
		(start 66.70294 -26.444194)
		(end 67.307206 -25.839928)
		(width 0.08382)
		(layer "In9.Cu")
		(net "PWRGD_P2V5_AUX_R3")
	)
	(segment
		(start 31.553404 -57.199276)
		(end 31.553404 -55.19166)
		(width 0.08382)
		(layer "In9.Cu")
		(net "PWRGD_P2V5_AUX_R3")
	)
	(segment
		(start 49.580292 -24.892)
		(end 53.822346 -24.892)
		(width 0.08382)
		(layer "In9.Cu")
		(net "PWRGD_P2V5_AUX_R3")
	)
	(segment
		(start 35.122358 -29.380942)
		(end 36.21786 -29.380942)
		(width 0.08382)
		(layer "In9.Cu")
		(net "PWRGD_P2V5_AUX_R3")
	)
	(segment
		(start 60.58916 -26.06675)
		(end 62.00521 -27.4828)
		(width 0.08382)
		(layer "In9.Cu")
		(net "PWRGD_P2V5_AUX_R3")
	)
	(segment
		(start 32.6898 -42.43451)
		(end 32.6898 -39.8526)
		(width 0.08382)
		(layer "In9.Cu")
		(net "PWRGD_P2V5_AUX_R3")
	)
	(segment
		(start 82.66176 -26.03754)
		(end 86.83244 -26.03754)
		(width 0.11684)
		(layer "F.Cu")
		(net "PWRGD_P1V8_AUX_R3")
	)
	(segment
		(start 88.642698 -54.8259)
		(end 87.807038 -55.66156)
		(width 0.11684)
		(layer "F.Cu")
		(net "PWRGD_P1V8_AUX_R3")
	)
	(segment
		(start 72.269096 -24.31034)
		(end 73.633076 -22.94636)
		(width 0.11684)
		(layer "F.Cu")
		(net "PWRGD_P1V8_AUX_R3")
	)
	(segment
		(start 80.630776 -23.960836)
		(end 80.902048 -24.615648)
		(width 0.11684)
		(layer "F.Cu")
		(net "PWRGD_P1V8_AUX_R3")
	)
	(segment
		(start 86.83244 -26.03754)
		(end 87.67953 -26.88463)
		(width 0.11684)
		(layer "F.Cu")
		(net "PWRGD_P1V8_AUX_R3")
	)
	(segment
		(start 70.4342 -25.8699)
		(end 70.85584 -25.44826)
		(width 0.11684)
		(layer "F.Cu")
		(net "PWRGD_P1V8_AUX_R3")
	)
	(segment
		(start 80.902048 -24.615648)
		(end 81.24698 -24.96058)
		(width 0.11684)
		(layer "F.Cu")
		(net "PWRGD_P1V8_AUX_R3")
	)
	(segment
		(start 81.24698 -24.96058)
		(end 81.5848 -24.96058)
		(width 0.11684)
		(layer "F.Cu")
		(net "PWRGD_P1V8_AUX_R3")
	)
	(segment
		(start 88.642698 -27.847798)
		(end 88.642698 -54.8259)
		(width 0.11684)
		(layer "F.Cu")
		(net "PWRGD_P1V8_AUX_R3")
	)
	(segment
		(start 81.5848 -24.96058)
		(end 82.66176 -26.03754)
		(width 0.11684)
		(layer "F.Cu")
		(net "PWRGD_P1V8_AUX_R3")
	)
	(segment
		(start 87.67953 -26.88463)
		(end 88.642698 -27.847798)
		(width 0.11684)
		(layer "F.Cu")
		(net "PWRGD_P1V8_AUX_R3")
	)
	(segment
		(start 70.85584 -25.44826)
		(end 70.85584 -25.12314)
		(width 0.11684)
		(layer "F.Cu")
		(net "PWRGD_P1V8_AUX_R3")
	)
	(segment
		(start 71.66864 -24.31034)
		(end 72.269096 -24.31034)
		(width 0.11684)
		(layer "F.Cu")
		(net "PWRGD_P1V8_AUX_R3")
	)
	(segment
		(start 79.6163 -22.94636)
		(end 80.630776 -23.960836)
		(width 0.11684)
		(layer "F.Cu")
		(net "PWRGD_P1V8_AUX_R3")
	)
	(segment
		(start 37.973 -59.07405)
		(end 37.973 -60.02782)
		(width 0.11684)
		(layer "F.Cu")
		(net "PWRGD_P1V8_AUX_R3")
	)
	(segment
		(start 73.633076 -22.94636)
		(end 79.6163 -22.94636)
		(width 0.11684)
		(layer "F.Cu")
		(net "PWRGD_P1V8_AUX_R3")
	)
	(segment
		(start 70.4342 -26.87955)
		(end 70.4342 -25.8699)
		(width 0.11684)
		(layer "F.Cu")
		(net "PWRGD_P1V8_AUX_R3")
	)
	(segment
		(start 87.807038 -55.66156)
		(end 80.54594 -55.66156)
		(width 0.11684)
		(layer "F.Cu")
		(net "PWRGD_P1V8_AUX_R3")
	)
	(segment
		(start 37.973 -60.02782)
		(end 38.36416 -60.41898)
		(width 0.11684)
		(layer "F.Cu")
		(net "PWRGD_P1V8_AUX_R3")
	)
	(segment
		(start 70.85584 -25.12314)
		(end 71.66864 -24.31034)
		(width 0.11684)
		(layer "F.Cu")
		(net "PWRGD_P1V8_AUX_R3")
	)
	(via
		(at 87.67953 -26.88463)
		(size 0.762)
		(drill 0.381)
		(layers "F.Cu" "B.Cu")
		(net "PWRGD_P1V8_AUX_R3")
	)
	(via
		(at 80.54594 -55.66156)
		(size 0.508)
		(drill 0.254)
		(layers "F.Cu" "B.Cu")
		(net "PWRGD_P1V8_AUX_R3")
	)
	(via
		(at 38.36416 -60.41898)
		(size 0.508)
		(drill 0.254)
		(layers "F.Cu" "B.Cu")
		(net "PWRGD_P1V8_AUX_R3")
	)
	(segment
		(start 51.73726 -65.76568)
		(end 51.28514 -66.2178)
		(width 0.08382)
		(layer "In2.Cu")
		(net "PWRGD_P1V8_AUX_R3")
	)
	(segment
		(start 75.06208 -64.74968)
		(end 75.06208 -58.12536)
		(width 0.08382)
		(layer "In2.Cu")
		(net "PWRGD_P1V8_AUX_R3")
	)
	(segment
		(start 76.297282 -56.890158)
		(end 77.447902 -56.4134)
		(width 0.08382)
		(layer "In2.Cu")
		(net "PWRGD_P1V8_AUX_R3")
	)
	(segment
		(start 47.98314 -69.140832)
		(end 48.735488 -69.89318)
		(width 0.08382)
		(layer "In2.Cu")
		(net "PWRGD_P1V8_AUX_R3")
	)
	(segment
		(start 63.44158 -68.8594)
		(end 68.509642 -68.8594)
		(width 0.08382)
		(layer "In2.Cu")
		(net "PWRGD_P1V8_AUX_R3")
	)
	(segment
		(start 74.450448 -65.361312)
		(end 75.06208 -64.74968)
		(width 0.08382)
		(layer "In2.Cu")
		(net "PWRGD_P1V8_AUX_R3")
	)
	(segment
		(start 69.119242 -68.2498)
		(end 69.119242 -67.242182)
		(width 0.08382)
		(layer "In2.Cu")
		(net "PWRGD_P1V8_AUX_R3")
	)
	(segment
		(start 52.179474 -69.89318)
		(end 52.954174 -70.66788)
		(width 0.08382)
		(layer "In2.Cu")
		(net "PWRGD_P1V8_AUX_R3")
	)
	(segment
		(start 71.000112 -65.361312)
		(end 74.450448 -65.361312)
		(width 0.08382)
		(layer "In2.Cu")
		(net "PWRGD_P1V8_AUX_R3")
	)
	(segment
		(start 62.71133 -69.13626)
		(end 63.16472 -69.13626)
		(width 0.08382)
		(layer "In2.Cu")
		(net "PWRGD_P1V8_AUX_R3")
	)
	(segment
		(start 80.54594 -55.96636)
		(end 80.54594 -55.66156)
		(width 0.08382)
		(layer "In2.Cu")
		(net "PWRGD_P1V8_AUX_R3")
	)
	(segment
		(start 48.735488 -69.89318)
		(end 52.179474 -69.89318)
		(width 0.08382)
		(layer "In2.Cu")
		(net "PWRGD_P1V8_AUX_R3")
	)
	(segment
		(start 47.32274 -61.85662)
		(end 48.76419 -63.29807)
		(width 0.08382)
		(layer "In2.Cu")
		(net "PWRGD_P1V8_AUX_R3")
	)
	(segment
		(start 43.541188 -61.85662)
		(end 47.32274 -61.85662)
		(width 0.08382)
		(layer "In2.Cu")
		(net "PWRGD_P1V8_AUX_R3")
	)
	(segment
		(start 47.98314 -68.40728)
		(end 47.98314 -69.140832)
		(width 0.08382)
		(layer "In2.Cu")
		(net "PWRGD_P1V8_AUX_R3")
	)
	(segment
		(start 58.23712 -70.66788)
		(end 58.89498 -70.01002)
		(width 0.08382)
		(layer "In2.Cu")
		(net "PWRGD_P1V8_AUX_R3")
	)
	(segment
		(start 75.06208 -58.12536)
		(end 76.297282 -56.890158)
		(width 0.08382)
		(layer "In2.Cu")
		(net "PWRGD_P1V8_AUX_R3")
	)
	(segment
		(start 51.73726 -64.745108)
		(end 51.73726 -65.76568)
		(width 0.08382)
		(layer "In2.Cu")
		(net "PWRGD_P1V8_AUX_R3")
	)
	(segment
		(start 69.119242 -67.242182)
		(end 71.000112 -65.361312)
		(width 0.08382)
		(layer "In2.Cu")
		(net "PWRGD_P1V8_AUX_R3")
	)
	(segment
		(start 38.36416 -61.053726)
		(end 39.607236 -62.296802)
		(width 0.08382)
		(layer "In2.Cu")
		(net "PWRGD_P1V8_AUX_R3")
	)
	(segment
		(start 77.447902 -56.4134)
		(end 80.0989 -56.4134)
		(width 0.08382)
		(layer "In2.Cu")
		(net "PWRGD_P1V8_AUX_R3")
	)
	(segment
		(start 43.101006 -62.296802)
		(end 43.541188 -61.85662)
		(width 0.08382)
		(layer "In2.Cu")
		(net "PWRGD_P1V8_AUX_R3")
	)
	(segment
		(start 39.607236 -62.296802)
		(end 43.101006 -62.296802)
		(width 0.08382)
		(layer "In2.Cu")
		(net "PWRGD_P1V8_AUX_R3")
	)
	(segment
		(start 38.36416 -60.41898)
		(end 38.36416 -61.053726)
		(width 0.08382)
		(layer "In2.Cu")
		(net "PWRGD_P1V8_AUX_R3")
	)
	(segment
		(start 58.89498 -70.01002)
		(end 61.83757 -70.01002)
		(width 0.08382)
		(layer "In2.Cu")
		(net "PWRGD_P1V8_AUX_R3")
	)
	(segment
		(start 48.76419 -63.29807)
		(end 50.16627 -63.29807)
		(width 0.08382)
		(layer "In2.Cu")
		(net "PWRGD_P1V8_AUX_R3")
	)
	(segment
		(start 63.16472 -69.13626)
		(end 63.44158 -68.8594)
		(width 0.08382)
		(layer "In2.Cu")
		(net "PWRGD_P1V8_AUX_R3")
	)
	(segment
		(start 52.954174 -70.66788)
		(end 58.23712 -70.66788)
		(width 0.08382)
		(layer "In2.Cu")
		(net "PWRGD_P1V8_AUX_R3")
	)
	(segment
		(start 50.16627 -63.29807)
		(end 50.377852 -63.3857)
		(width 0.08382)
		(layer "In2.Cu")
		(net "PWRGD_P1V8_AUX_R3")
	)
	(segment
		(start 68.509642 -68.8594)
		(end 69.119242 -68.2498)
		(width 0.08382)
		(layer "In2.Cu")
		(net "PWRGD_P1V8_AUX_R3")
	)
	(segment
		(start 80.0989 -56.4134)
		(end 80.54594 -55.96636)
		(width 0.08382)
		(layer "In2.Cu")
		(net "PWRGD_P1V8_AUX_R3")
	)
	(segment
		(start 61.83757 -70.01002)
		(end 62.71133 -69.13626)
		(width 0.08382)
		(layer "In2.Cu")
		(net "PWRGD_P1V8_AUX_R3")
	)
	(segment
		(start 50.377852 -63.3857)
		(end 51.73726 -64.745108)
		(width 0.08382)
		(layer "In2.Cu")
		(net "PWRGD_P1V8_AUX_R3")
	)
	(segment
		(start 51.28514 -66.2178)
		(end 50.17262 -66.2178)
		(width 0.08382)
		(layer "In2.Cu")
		(net "PWRGD_P1V8_AUX_R3")
	)
	(segment
		(start 50.17262 -66.2178)
		(end 47.98314 -68.40728)
		(width 0.08382)
		(layer "In2.Cu")
		(net "PWRGD_P1V8_AUX_R3")
	)
	(segment
		(start 74.97572 -24.28494)
		(end 74.09688 -24.28494)
		(width 0.11684)
		(layer "F.Cu")
		(net "PWRGD_P1V2_AUX_R2")
	)
	(segment
		(start 88.373458 -28.957778)
		(end 87.5411 -28.12542)
		(width 0.11684)
		(layer "F.Cu")
		(net "PWRGD_P1V2_AUX_R2")
	)
	(segment
		(start 79.85506 -55.29072)
		(end 80.15986 -54.98592)
		(width 0.11684)
		(layer "F.Cu")
		(net "PWRGD_P1V2_AUX_R2")
	)
	(segment
		(start 79.28864 -25.39492)
		(end 79.0702 -25.17648)
		(width 0.11684)
		(layer "F.Cu")
		(net "PWRGD_P1V2_AUX_R2")
	)
	(segment
		(start 80.75676 -25.39492)
		(end 79.28864 -25.39492)
		(width 0.11684)
		(layer "F.Cu")
		(net "PWRGD_P1V2_AUX_R2")
	)
	(segment
		(start 87.10549 -77.05725)
		(end 88.642698 -75.520042)
		(width 0.11684)
		(layer "F.Cu")
		(net "PWRGD_P1V2_AUX_R2")
	)
	(segment
		(start 71.35114 -25.79624)
		(end 71.35114 -26.13152)
		(width 0.11684)
		(layer "F.Cu")
		(net "PWRGD_P1V2_AUX_R2")
	)
	(segment
		(start 80.92948 -25.56764)
		(end 80.75676 -25.39492)
		(width 0.11684)
		(layer "F.Cu")
		(net "PWRGD_P1V2_AUX_R2")
	)
	(segment
		(start 82.93608 -27.35072)
		(end 81.8388 -27.35072)
		(width 0.11684)
		(layer "F.Cu")
		(net "PWRGD_P1V2_AUX_R2")
	)
	(segment
		(start 80.18272 -56.22798)
		(end 79.85506 -55.90032)
		(width 0.11684)
		(layer "F.Cu")
		(net "PWRGD_P1V2_AUX_R2")
	)
	(segment
		(start 88.642698 -75.520042)
		(end 88.642698 -57.454038)
		(width 0.11684)
		(layer "F.Cu")
		(net "PWRGD_P1V2_AUX_R2")
	)
	(segment
		(start 87.41664 -56.22798)
		(end 80.18272 -56.22798)
		(width 0.11684)
		(layer "F.Cu")
		(net "PWRGD_P1V2_AUX_R2")
	)
	(segment
		(start 80.15986 -54.98592)
		(end 80.81518 -54.98592)
		(width 0.11684)
		(layer "F.Cu")
		(net "PWRGD_P1V2_AUX_R2")
	)
	(segment
		(start 87.372698 -55.20436)
		(end 88.373458 -54.2036)
		(width 0.11684)
		(layer "F.Cu")
		(net "PWRGD_P1V2_AUX_R2")
	)
	(segment
		(start 80.92948 -26.4414)
		(end 80.92948 -25.56764)
		(width 0.11684)
		(layer "F.Cu")
		(net "PWRGD_P1V2_AUX_R2")
	)
	(segment
		(start 72.009 -25.13838)
		(end 71.35114 -25.79624)
		(width 0.11684)
		(layer "F.Cu")
		(net "PWRGD_P1V2_AUX_R2")
	)
	(segment
		(start 83.71078 -28.12542)
		(end 82.93608 -27.35072)
		(width 0.11684)
		(layer "F.Cu")
		(net "PWRGD_P1V2_AUX_R2")
	)
	(segment
		(start 15.22603 -31.22676)
		(end 15.22603 -30.64002)
		(width 0.11684)
		(layer "F.Cu")
		(net "PWRGD_P1V2_AUX_R2")
	)
	(segment
		(start 85.471 -77.05725)
		(end 87.10549 -77.05725)
		(width 0.11684)
		(layer "F.Cu")
		(net "PWRGD_P1V2_AUX_R2")
	)
	(segment
		(start 87.5411 -28.12542)
		(end 83.71078 -28.12542)
		(width 0.11684)
		(layer "F.Cu")
		(net "PWRGD_P1V2_AUX_R2")
	)
	(segment
		(start 15.26286 -31.26359)
		(end 15.22603 -31.22676)
		(width 0.11684)
		(layer "F.Cu")
		(net "PWRGD_P1V2_AUX_R2")
	)
	(segment
		(start 75.86726 -25.17648)
		(end 74.97572 -24.28494)
		(width 0.11684)
		(layer "F.Cu")
		(net "PWRGD_P1V2_AUX_R2")
	)
	(segment
		(start 79.0702 -25.17648)
		(end 75.86726 -25.17648)
		(width 0.11684)
		(layer "F.Cu")
		(net "PWRGD_P1V2_AUX_R2")
	)
	(segment
		(start 74.09688 -24.28494)
		(end 73.25106 -24.28494)
		(width 0.11684)
		(layer "F.Cu")
		(net "PWRGD_P1V2_AUX_R2")
	)
	(segment
		(start 73.25106 -24.28494)
		(end 72.39762 -25.13838)
		(width 0.11684)
		(layer "F.Cu")
		(net "PWRGD_P1V2_AUX_R2")
	)
	(segment
		(start 81.8388 -27.35072)
		(end 80.92948 -26.4414)
		(width 0.11684)
		(layer "F.Cu")
		(net "PWRGD_P1V2_AUX_R2")
	)
	(segment
		(start 88.642698 -57.454038)
		(end 87.41664 -56.22798)
		(width 0.11684)
		(layer "F.Cu")
		(net "PWRGD_P1V2_AUX_R2")
	)
	(segment
		(start 72.39762 -25.13838)
		(end 72.009 -25.13838)
		(width 0.11684)
		(layer "F.Cu")
		(net "PWRGD_P1V2_AUX_R2")
	)
	(segment
		(start 81.03362 -55.20436)
		(end 87.372698 -55.20436)
		(width 0.11684)
		(layer "F.Cu")
		(net "PWRGD_P1V2_AUX_R2")
	)
	(segment
		(start 79.85506 -55.90032)
		(end 79.85506 -55.29072)
		(width 0.11684)
		(layer "F.Cu")
		(net "PWRGD_P1V2_AUX_R2")
	)
	(segment
		(start 80.81518 -54.98592)
		(end 81.03362 -55.20436)
		(width 0.11684)
		(layer "F.Cu")
		(net "PWRGD_P1V2_AUX_R2")
	)
	(segment
		(start 88.373458 -54.2036)
		(end 88.373458 -28.957778)
		(width 0.11684)
		(layer "F.Cu")
		(net "PWRGD_P1V2_AUX_R2")
	)
	(via
		(at 74.09688 -24.28494)
		(size 0.762)
		(drill 0.381)
		(layers "F.Cu" "B.Cu")
		(net "PWRGD_P1V2_AUX_R2")
	)
	(via
		(at 15.22603 -30.64002)
		(size 0.508)
		(drill 0.254)
		(layers "F.Cu" "B.Cu")
		(net "PWRGD_P1V2_AUX_R2")
	)
	(via
		(at 71.35114 -26.13152)
		(size 0.508)
		(drill 0.254)
		(layers "F.Cu" "B.Cu")
		(net "PWRGD_P1V2_AUX_R2")
	)
	(segment
		(start 71.35114 -25.53462)
		(end 70.263766 -24.447246)
		(width 0.08382)
		(layer "In2.Cu")
		(net "PWRGD_P1V2_AUX_R2")
	)
	(segment
		(start 66.53784 -21.5138)
		(end 63.98768 -21.5138)
		(width 0.08382)
		(layer "In2.Cu")
		(net "PWRGD_P1V2_AUX_R2")
	)
	(segment
		(start 15.80896 -30.43682)
		(end 15.60576 -30.64002)
		(width 0.08382)
		(layer "In2.Cu")
		(net "PWRGD_P1V2_AUX_R2")
	)
	(segment
		(start 40.575992 -25.82164)
		(end 39.26078 -24.506428)
		(width 0.08382)
		(layer "In2.Cu")
		(net "PWRGD_P1V2_AUX_R2")
	)
	(segment
		(start 37.860732 -21.077936)
		(end 36.208716 -20.39366)
		(width 0.08382)
		(layer "In2.Cu")
		(net "PWRGD_P1V2_AUX_R2")
	)
	(segment
		(start 24.421084 -20.21332)
		(end 18.01368 -20.21332)
		(width 0.08382)
		(layer "In2.Cu")
		(net "PWRGD_P1V2_AUX_R2")
	)
	(segment
		(start 30.20441 -21.63953)
		(end 25.847294 -21.63953)
		(width 0.08382)
		(layer "In2.Cu")
		(net "PWRGD_P1V2_AUX_R2")
	)
	(segment
		(start 70.263766 -24.447246)
		(end 69.001386 -24.447246)
		(width 0.08382)
		(layer "In2.Cu")
		(net "PWRGD_P1V2_AUX_R2")
	)
	(segment
		(start 63.98768 -21.5138)
		(end 62.60592 -22.89556)
		(width 0.08382)
		(layer "In2.Cu")
		(net "PWRGD_P1V2_AUX_R2")
	)
	(segment
		(start 18.01368 -20.21332)
		(end 15.14602 -23.08098)
		(width 0.08382)
		(layer "In2.Cu")
		(net "PWRGD_P1V2_AUX_R2")
	)
	(segment
		(start 48.077882 -26.72842)
		(end 42.802556 -26.72842)
		(width 0.08382)
		(layer "In2.Cu")
		(net "PWRGD_P1V2_AUX_R2")
	)
	(segment
		(start 42.802556 -26.72842)
		(end 41.895776 -25.82164)
		(width 0.08382)
		(layer "In2.Cu")
		(net "PWRGD_P1V2_AUX_R2")
	)
	(segment
		(start 36.208716 -20.39366)
		(end 35.287204 -20.39366)
		(width 0.08382)
		(layer "In2.Cu")
		(net "PWRGD_P1V2_AUX_R2")
	)
	(segment
		(start 33.854644 -21.82622)
		(end 31.985204 -21.82622)
		(width 0.08382)
		(layer "In2.Cu")
		(net "PWRGD_P1V2_AUX_R2")
	)
	(segment
		(start 31.985204 -21.82622)
		(end 31.795974 -22.01545)
		(width 0.08382)
		(layer "In2.Cu")
		(net "PWRGD_P1V2_AUX_R2")
	)
	(segment
		(start 59.64428 -22.89556)
		(end 59.49569 -22.74697)
		(width 0.08382)
		(layer "In2.Cu")
		(net "PWRGD_P1V2_AUX_R2")
	)
	(segment
		(start 35.287204 -20.39366)
		(end 33.854644 -21.82622)
		(width 0.08382)
		(layer "In2.Cu")
		(net "PWRGD_P1V2_AUX_R2")
	)
	(segment
		(start 15.14602 -26.917904)
		(end 15.80896 -28.518612)
		(width 0.08382)
		(layer "In2.Cu")
		(net "PWRGD_P1V2_AUX_R2")
	)
	(segment
		(start 71.35114 -26.13152)
		(end 71.35114 -25.53462)
		(width 0.08382)
		(layer "In2.Cu")
		(net "PWRGD_P1V2_AUX_R2")
	)
	(segment
		(start 59.49569 -22.74697)
		(end 52.059332 -22.74697)
		(width 0.08382)
		(layer "In2.Cu")
		(net "PWRGD_P1V2_AUX_R2")
	)
	(segment
		(start 15.14602 -23.08098)
		(end 15.14602 -26.917904)
		(width 0.08382)
		(layer "In2.Cu")
		(net "PWRGD_P1V2_AUX_R2")
	)
	(segment
		(start 62.60592 -22.89556)
		(end 59.64428 -22.89556)
		(width 0.08382)
		(layer "In2.Cu")
		(net "PWRGD_P1V2_AUX_R2")
	)
	(segment
		(start 15.60576 -30.64002)
		(end 15.22603 -30.64002)
		(width 0.08382)
		(layer "In2.Cu")
		(net "PWRGD_P1V2_AUX_R2")
	)
	(segment
		(start 69.001386 -24.447246)
		(end 68.34124 -23.7871)
		(width 0.08382)
		(layer "In2.Cu")
		(net "PWRGD_P1V2_AUX_R2")
	)
	(segment
		(start 39.26078 -24.506428)
		(end 39.26078 -22.477984)
		(width 0.08382)
		(layer "In2.Cu")
		(net "PWRGD_P1V2_AUX_R2")
	)
	(segment
		(start 68.34124 -23.7871)
		(end 68.34124 -23.3172)
		(width 0.08382)
		(layer "In2.Cu")
		(net "PWRGD_P1V2_AUX_R2")
	)
	(segment
		(start 30.58033 -22.01545)
		(end 30.20441 -21.63953)
		(width 0.08382)
		(layer "In2.Cu")
		(net "PWRGD_P1V2_AUX_R2")
	)
	(segment
		(start 52.059332 -22.74697)
		(end 48.077882 -26.72842)
		(width 0.08382)
		(layer "In2.Cu")
		(net "PWRGD_P1V2_AUX_R2")
	)
	(segment
		(start 31.795974 -22.01545)
		(end 30.58033 -22.01545)
		(width 0.08382)
		(layer "In2.Cu")
		(net "PWRGD_P1V2_AUX_R2")
	)
	(segment
		(start 39.26078 -22.477984)
		(end 37.860732 -21.077936)
		(width 0.08382)
		(layer "In2.Cu")
		(net "PWRGD_P1V2_AUX_R2")
	)
	(segment
		(start 68.34124 -23.3172)
		(end 66.53784 -21.5138)
		(width 0.08382)
		(layer "In2.Cu")
		(net "PWRGD_P1V2_AUX_R2")
	)
	(segment
		(start 25.847294 -21.63953)
		(end 24.421084 -20.21332)
		(width 0.08382)
		(layer "In2.Cu")
		(net "PWRGD_P1V2_AUX_R2")
	)
	(segment
		(start 41.895776 -25.82164)
		(end 40.575992 -25.82164)
		(width 0.08382)
		(layer "In2.Cu")
		(net "PWRGD_P1V2_AUX_R2")
	)
	(segment
		(start 15.80896 -28.518612)
		(end 15.80896 -30.43682)
		(width 0.08382)
		(layer "In2.Cu")
		(net "PWRGD_P1V2_AUX_R2")
	)
	(segment
		(start 11.85545 -62.2046)
		(end 12.1158 -62.2046)
		(width 0.11684)
		(layer "F.Cu")
		(net "EN_P3V3_R1")
	)
	(segment
		(start 8.56615 -54.87035)
		(end 9.0678 -55.372)
		(width 0.11684)
		(layer "F.Cu")
		(net "EN_P3V3_R1")
	)
	(segment
		(start 12.1158 -62.2046)
		(end 12.6238 -61.6966)
		(width 0.11684)
		(layer "F.Cu")
		(net "EN_P3V3_R1")
	)
	(segment
		(start 8.56615 -54.5338)
		(end 8.56615 -54.87035)
		(width 0.11684)
		(layer "F.Cu")
		(net "EN_P3V3_R1")
	)
	(via
		(at 12.6238 -61.6966)
		(size 0.508)
		(drill 0.254)
		(layers "F.Cu" "B.Cu")
		(net "EN_P3V3_R1")
	)
	(via
		(at 12.1412 -61.174122)
		(size 0.6604)
		(drill 0.3302)
		(layers "F.Cu" "B.Cu")
		(net "EN_P3V3_R1")
	)
	(via
		(at 9.0678 -55.372)
		(size 0.508)
		(drill 0.254)
		(layers "F.Cu" "B.Cu")
		(net "EN_P3V3_R1")
	)
	(segment
		(start 9.0678 -57.3278)
		(end 9.0678 -55.372)
		(width 0.11684)
		(layer "B.Cu")
		(net "EN_P3V3_R1")
	)
	(segment
		(start 12.1412 -61.174122)
		(end 12.1412 -60.4012)
		(width 0.11684)
		(layer "B.Cu")
		(net "EN_P3V3_R1")
	)
	(segment
		(start 12.1412 -60.4012)
		(end 9.0678 -57.3278)
		(width 0.11684)
		(layer "B.Cu")
		(net "EN_P3V3_R1")
	)
	(segment
		(start 12.6238 -61.6966)
		(end 12.1412 -61.214)
		(width 0.11684)
		(layer "B.Cu")
		(net "EN_P3V3_R1")
	)
	(segment
		(start 12.1412 -61.214)
		(end 12.1412 -61.174122)
		(width 0.11684)
		(layer "B.Cu")
		(net "EN_P3V3_R1")
	)
	(segment
		(start 27.750008 -73.360534)
		(end 27.7368 -73.347326)
		(width 0.11684)
		(layer "F.Cu")
		(net "SMB_BMC_MM16_R1_SDA")
	)
	(segment
		(start 27.7368 -69.344794)
		(end 28.228544 -68.85305)
		(width 0.11684)
		(layer "F.Cu")
		(net "SMB_BMC_MM16_R1_SDA")
	)
	(segment
		(start 28.228544 -68.85305)
		(end 28.321 -68.85305)
		(width 0.11684)
		(layer "F.Cu")
		(net "SMB_BMC_MM16_R1_SDA")
	)
	(segment
		(start 27.7368 -73.347326)
		(end 27.7368 -69.344794)
		(width 0.11684)
		(layer "F.Cu")
		(net "SMB_BMC_MM16_R1_SDA")
	)
	(segment
		(start 25.8572 -70.0786)
		(end 25.8572 -71.545704)
		(width 0.11684)
		(layer "F.Cu")
		(net "SMB_BMC_MM16_R1_SCL")
	)
	(segment
		(start 26.665936 -72.35444)
		(end 27.122882 -72.35444)
		(width 0.11684)
		(layer "F.Cu")
		(net "SMB_BMC_MM16_R1_SCL")
	)
	(segment
		(start 27.2796 -69.46265)
		(end 26.99385 -69.7484)
		(width 0.11684)
		(layer "F.Cu")
		(net "SMB_BMC_MM16_R1_SCL")
	)
	(segment
		(start 26.1874 -69.7484)
		(end 25.8572 -70.0786)
		(width 0.11684)
		(layer "F.Cu")
		(net "SMB_BMC_MM16_R1_SCL")
	)
	(segment
		(start 25.8572 -71.545704)
		(end 26.665936 -72.35444)
		(width 0.11684)
		(layer "F.Cu")
		(net "SMB_BMC_MM16_R1_SCL")
	)
	(segment
		(start 27.122882 -72.35444)
		(end 27.249882 -72.48144)
		(width 0.11684)
		(layer "F.Cu")
		(net "SMB_BMC_MM16_R1_SCL")
	)
	(segment
		(start 27.249882 -72.48144)
		(end 27.249882 -73.360534)
		(width 0.11684)
		(layer "F.Cu")
		(net "SMB_BMC_MM16_R1_SCL")
	)
	(segment
		(start 26.99385 -69.7484)
		(end 26.1874 -69.7484)
		(width 0.11684)
		(layer "F.Cu")
		(net "SMB_BMC_MM16_R1_SCL")
	)
	(segment
		(start 68.468494 -115.835176)
		(end 68.954396 -116.321078)
		(width 0.11684)
		(layer "F.Cu")
		(net "H_CPU_CATERR_LVC2_R2_N")
	)
	(segment
		(start 68.460112 -117.352318)
		(end 68.460112 -118.460012)
		(width 0.11684)
		(layer "F.Cu")
		(net "H_CPU_CATERR_LVC2_R2_N")
	)
	(segment
		(start 68.954396 -116.321078)
		(end 68.954396 -116.858034)
		(width 0.11684)
		(layer "F.Cu")
		(net "H_CPU_CATERR_LVC2_R2_N")
	)
	(segment
		(start 48.0949 -43.371262)
		(end 47.699676 -42.976038)
		(width 0.11684)
		(layer "F.Cu")
		(net "H_CPU_CATERR_LVC2_R2_N")
	)
	(segment
		(start 68.954396 -116.858034)
		(end 68.460112 -117.352318)
		(width 0.11684)
		(layer "F.Cu")
		(net "H_CPU_CATERR_LVC2_R2_N")
	)
	(via
		(at 47.699676 -42.976038)
		(size 0.4572)
		(drill 0.254)
		(layers "F.Cu" "B.Cu")
		(net "H_CPU_CATERR_LVC2_R2_N")
	)
	(via
		(at 68.468494 -115.835176)
		(size 0.508)
		(drill 0.254)
		(layers "F.Cu" "B.Cu")
		(net "H_CPU_CATERR_LVC2_R2_N")
	)
	(via
		(at 78.467204 -102.0826)
		(size 0.508)
		(drill 0.254)
		(layers "F.Cu" "B.Cu")
		(net "H_CPU_CATERR_LVC2_R2_N")
	)
	(segment
		(start 74.3712 -111.4806)
		(end 74.3712 -110.6678)
		(width 0.08382)
		(layer "In2.Cu")
		(net "H_CPU_CATERR_LVC2_R2_N")
	)
	(segment
		(start 73.2282 -106.120692)
		(end 77.266292 -102.0826)
		(width 0.08382)
		(layer "In2.Cu")
		(net "H_CPU_CATERR_LVC2_R2_N")
	)
	(segment
		(start 72.339708 -111.9378)
		(end 73.914 -111.9378)
		(width 0.08382)
		(layer "In2.Cu")
		(net "H_CPU_CATERR_LVC2_R2_N")
	)
	(segment
		(start 73.2282 -109.5248)
		(end 73.2282 -106.120692)
		(width 0.08382)
		(layer "In2.Cu")
		(net "H_CPU_CATERR_LVC2_R2_N")
	)
	(segment
		(start 77.266292 -102.0826)
		(end 78.467204 -102.0826)
		(width 0.08382)
		(layer "In2.Cu")
		(net "H_CPU_CATERR_LVC2_R2_N")
	)
	(segment
		(start 70.7136 -114.7318)
		(end 70.7136 -113.562638)
		(width 0.08382)
		(layer "In2.Cu")
		(net "H_CPU_CATERR_LVC2_R2_N")
	)
	(segment
		(start 68.468494 -115.835176)
		(end 69.610224 -115.835176)
		(width 0.08382)
		(layer "In2.Cu")
		(net "H_CPU_CATERR_LVC2_R2_N")
	)
	(segment
		(start 74.3712 -110.6678)
		(end 73.2282 -109.5248)
		(width 0.08382)
		(layer "In2.Cu")
		(net "H_CPU_CATERR_LVC2_R2_N")
	)
	(segment
		(start 69.610224 -115.835176)
		(end 70.7136 -114.7318)
		(width 0.08382)
		(layer "In2.Cu")
		(net "H_CPU_CATERR_LVC2_R2_N")
	)
	(segment
		(start 73.914 -111.9378)
		(end 74.3712 -111.4806)
		(width 0.08382)
		(layer "In2.Cu")
		(net "H_CPU_CATERR_LVC2_R2_N")
	)
	(segment
		(start 70.7136 -113.562638)
		(end 72.339708 -111.9378)
		(width 0.08382)
		(layer "In2.Cu")
		(net "H_CPU_CATERR_LVC2_R2_N")
	)
	(segment
		(start 51.316128 -42.817034)
		(end 51.573684 -42.559478)
		(width 0.10668)
		(layer "In7.Cu")
		(net "H_CPU_CATERR_LVC2_R2_N")
	)
	(segment
		(start 52.116228 -42.016934)
		(end 52.340764 -41.792398)
		(width 0.10668)
		(layer "In7.Cu")
		(net "H_CPU_CATERR_LVC2_R2_N")
	)
	(segment
		(start 88.6714 -25.4762)
		(end 88.6714 -79.8576)
		(width 0.10668)
		(layer "In7.Cu")
		(net "H_CPU_CATERR_LVC2_R2_N")
	)
	(segment
		(start 60.921392 -39.495984)
		(end 63.71463 -36.702746)
		(width 0.10668)
		(layer "In7.Cu")
		(net "H_CPU_CATERR_LVC2_R2_N")
	)
	(segment
		(start 81.696306 -100.011992)
		(end 81.46288 -99.778566)
		(width 0.10668)
		(layer "In7.Cu")
		(net "H_CPU_CATERR_LVC2_R2_N")
	)
	(segment
		(start 86.7156 -90.932)
		(end 86.7156 -96.93529)
		(width 0.10668)
		(layer "In7.Cu")
		(net "H_CPU_CATERR_LVC2_R2_N")
	)
	(segment
		(start 60.073794 -40.320722)
		(end 60.21705 -40.177466)
		(width 0.10668)
		(layer "In7.Cu")
		(net "H_CPU_CATERR_LVC2_R2_N")
	)
	(segment
		(start 86.8934 -24.8412)
		(end 88.0364 -24.8412)
		(width 0.10668)
		(layer "In7.Cu")
		(net "H_CPU_CATERR_LVC2_R2_N")
	)
	(segment
		(start 79.34706 -23.07082)
		(end 80.3148 -24.03856)
		(width 0.10668)
		(layer "In7.Cu")
		(net "H_CPU_CATERR_LVC2_R2_N")
	)
	(segment
		(start 71.185786 -28.19908)
		(end 74.95286 -24.432006)
		(width 0.10668)
		(layer "In7.Cu")
		(net "H_CPU_CATERR_LVC2_R2_N")
	)
	(segment
		(start 83.01355 -100.011992)
		(end 81.696306 -100.011992)
		(width 0.10668)
		(layer "In7.Cu")
		(net "H_CPU_CATERR_LVC2_R2_N")
	)
	(segment
		(start 85.62848 -81.543398)
		(end 85.62848 -89.84488)
		(width 0.10668)
		(layer "In7.Cu")
		(net "H_CPU_CATERR_LVC2_R2_N")
	)
	(segment
		(start 84.745322 -98.28022)
		(end 83.01355 -100.011992)
		(width 0.10668)
		(layer "In7.Cu")
		(net "H_CPU_CATERR_LVC2_R2_N")
	)
	(segment
		(start 51.858672 -42.559478)
		(end 52.116228 -42.301922)
		(width 0.10668)
		(layer "In7.Cu")
		(net "H_CPU_CATERR_LVC2_R2_N")
	)
	(segment
		(start 65.134744 -35.171634)
		(end 65.945004 -35.171634)
		(width 0.10668)
		(layer "In7.Cu")
		(net "H_CPU_CATERR_LVC2_R2_N")
	)
	(segment
		(start 52.340764 -41.792398)
		(end 59.816492 -41.792398)
		(width 0.10668)
		(layer "In7.Cu")
		(net "H_CPU_CATERR_LVC2_R2_N")
	)
	(segment
		(start 83.65744 -27.1018)
		(end 84.6328 -27.1018)
		(width 0.10668)
		(layer "In7.Cu")
		(net "H_CPU_CATERR_LVC2_R2_N")
	)
	(segment
		(start 74.95286 -24.432006)
		(end 74.95286 -23.6855)
		(width 0.10668)
		(layer "In7.Cu")
		(net "H_CPU_CATERR_LVC2_R2_N")
	)
	(segment
		(start 66.86296 -34.253678)
		(end 66.86296 -32.950658)
		(width 0.10668)
		(layer "In7.Cu")
		(net "H_CPU_CATERR_LVC2_R2_N")
	)
	(segment
		(start 70.188074 -28.19908)
		(end 71.185786 -28.19908)
		(width 0.10668)
		(layer "In7.Cu")
		(net "H_CPU_CATERR_LVC2_R2_N")
	)
	(segment
		(start 51.316128 -43.171872)
		(end 51.316128 -42.817034)
		(width 0.10668)
		(layer "In7.Cu")
		(net "H_CPU_CATERR_LVC2_R2_N")
	)
	(segment
		(start 85.62848 -89.84488)
		(end 86.7156 -90.932)
		(width 0.10668)
		(layer "In7.Cu")
		(net "H_CPU_CATERR_LVC2_R2_N")
	)
	(segment
		(start 63.71463 -36.702746)
		(end 63.71463 -36.591748)
		(width 0.10668)
		(layer "In7.Cu")
		(net "H_CPU_CATERR_LVC2_R2_N")
	)
	(segment
		(start 67.72275 -30.664404)
		(end 70.188074 -28.19908)
		(width 0.10668)
		(layer "In7.Cu")
		(net "H_CPU_CATERR_LVC2_R2_N")
	)
	(segment
		(start 85.37067 -98.28022)
		(end 84.745322 -98.28022)
		(width 0.10668)
		(layer "In7.Cu")
		(net "H_CPU_CATERR_LVC2_R2_N")
	)
	(segment
		(start 78.467204 -101.126798)
		(end 78.467204 -102.0826)
		(width 0.10668)
		(layer "In7.Cu")
		(net "H_CPU_CATERR_LVC2_R2_N")
	)
	(segment
		(start 80.9498 -25.019)
		(end 81.57464 -25.019)
		(width 0.10668)
		(layer "In7.Cu")
		(net "H_CPU_CATERR_LVC2_R2_N")
	)
	(segment
		(start 75.56754 -23.07082)
		(end 79.34706 -23.07082)
		(width 0.10668)
		(layer "In7.Cu")
		(net "H_CPU_CATERR_LVC2_R2_N")
	)
	(segment
		(start 60.761372 -40.177466)
		(end 60.921392 -40.017446)
		(width 0.10668)
		(layer "In7.Cu")
		(net "H_CPU_CATERR_LVC2_R2_N")
	)
	(segment
		(start 60.073794 -41.535096)
		(end 60.073794 -40.320722)
		(width 0.10668)
		(layer "In7.Cu")
		(net "H_CPU_CATERR_LVC2_R2_N")
	)
	(segment
		(start 52.116228 -42.301922)
		(end 52.116228 -42.016934)
		(width 0.10668)
		(layer "In7.Cu")
		(net "H_CPU_CATERR_LVC2_R2_N")
	)
	(segment
		(start 88.351868 -80.177132)
		(end 86.994746 -80.177132)
		(width 0.10668)
		(layer "In7.Cu")
		(net "H_CPU_CATERR_LVC2_R2_N")
	)
	(segment
		(start 86.994746 -80.177132)
		(end 85.62848 -81.543398)
		(width 0.10668)
		(layer "In7.Cu")
		(net "H_CPU_CATERR_LVC2_R2_N")
	)
	(segment
		(start 67.72275 -32.090868)
		(end 67.72275 -30.664404)
		(width 0.10668)
		(layer "In7.Cu")
		(net "H_CPU_CATERR_LVC2_R2_N")
	)
	(segment
		(start 81.57464 -25.019)
		(end 83.65744 -27.1018)
		(width 0.10668)
		(layer "In7.Cu")
		(net "H_CPU_CATERR_LVC2_R2_N")
	)
	(segment
		(start 59.816492 -41.792398)
		(end 60.073794 -41.535096)
		(width 0.10668)
		(layer "In7.Cu")
		(net "H_CPU_CATERR_LVC2_R2_N")
	)
	(segment
		(start 60.921392 -40.017446)
		(end 60.921392 -39.495984)
		(width 0.10668)
		(layer "In7.Cu")
		(net "H_CPU_CATERR_LVC2_R2_N")
	)
	(segment
		(start 47.699676 -42.976038)
		(end 48.106838 -43.3832)
		(width 0.10668)
		(layer "In7.Cu")
		(net "H_CPU_CATERR_LVC2_R2_N")
	)
	(segment
		(start 88.6714 -79.8576)
		(end 88.351868 -80.177132)
		(width 0.10668)
		(layer "In7.Cu")
		(net "H_CPU_CATERR_LVC2_R2_N")
	)
	(segment
		(start 80.3148 -24.03856)
		(end 80.3148 -24.384)
		(width 0.10668)
		(layer "In7.Cu")
		(net "H_CPU_CATERR_LVC2_R2_N")
	)
	(segment
		(start 84.6328 -27.1018)
		(end 86.8934 -24.8412)
		(width 0.10668)
		(layer "In7.Cu")
		(net "H_CPU_CATERR_LVC2_R2_N")
	)
	(segment
		(start 66.86296 -32.950658)
		(end 67.72275 -32.090868)
		(width 0.10668)
		(layer "In7.Cu")
		(net "H_CPU_CATERR_LVC2_R2_N")
	)
	(segment
		(start 86.7156 -96.93529)
		(end 85.37067 -98.28022)
		(width 0.10668)
		(layer "In7.Cu")
		(net "H_CPU_CATERR_LVC2_R2_N")
	)
	(segment
		(start 81.46288 -99.778566)
		(end 79.815436 -99.778566)
		(width 0.10668)
		(layer "In7.Cu")
		(net "H_CPU_CATERR_LVC2_R2_N")
	)
	(segment
		(start 60.21705 -40.177466)
		(end 60.761372 -40.177466)
		(width 0.10668)
		(layer "In7.Cu")
		(net "H_CPU_CATERR_LVC2_R2_N")
	)
	(segment
		(start 88.0364 -24.8412)
		(end 88.6714 -25.4762)
		(width 0.10668)
		(layer "In7.Cu")
		(net "H_CPU_CATERR_LVC2_R2_N")
	)
	(segment
		(start 65.945004 -35.171634)
		(end 66.86296 -34.253678)
		(width 0.10668)
		(layer "In7.Cu")
		(net "H_CPU_CATERR_LVC2_R2_N")
	)
	(segment
		(start 51.573684 -42.559478)
		(end 51.858672 -42.559478)
		(width 0.10668)
		(layer "In7.Cu")
		(net "H_CPU_CATERR_LVC2_R2_N")
	)
	(segment
		(start 79.815436 -99.778566)
		(end 78.467204 -101.126798)
		(width 0.10668)
		(layer "In7.Cu")
		(net "H_CPU_CATERR_LVC2_R2_N")
	)
	(segment
		(start 48.106838 -43.3832)
		(end 51.1048 -43.3832)
		(width 0.10668)
		(layer "In7.Cu")
		(net "H_CPU_CATERR_LVC2_R2_N")
	)
	(segment
		(start 51.1048 -43.3832)
		(end 51.316128 -43.171872)
		(width 0.10668)
		(layer "In7.Cu")
		(net "H_CPU_CATERR_LVC2_R2_N")
	)
	(segment
		(start 80.3148 -24.384)
		(end 80.9498 -25.019)
		(width 0.10668)
		(layer "In7.Cu")
		(net "H_CPU_CATERR_LVC2_R2_N")
	)
	(segment
		(start 74.95286 -23.6855)
		(end 75.56754 -23.07082)
		(width 0.10668)
		(layer "In7.Cu")
		(net "H_CPU_CATERR_LVC2_R2_N")
	)
	(segment
		(start 63.71463 -36.591748)
		(end 65.134744 -35.171634)
		(width 0.10668)
		(layer "In7.Cu")
		(net "H_CPU_CATERR_LVC2_R2_N")
	)
	(segment
		(start 40.767 -52.24145)
		(end 41.134284 -52.24145)
		(width 0.11684)
		(layer "F.Cu")
		(net "FM_INTRUDER_N")
	)
	(segment
		(start 41.9354 -53.9242)
		(end 42.2402 -53.9242)
		(width 0.11684)
		(layer "F.Cu")
		(net "FM_INTRUDER_N")
	)
	(segment
		(start 41.790874 -53.779674)
		(end 41.9354 -53.9242)
		(width 0.11684)
		(layer "F.Cu")
		(net "FM_INTRUDER_N")
	)
	(segment
		(start 41.790874 -52.89804)
		(end 41.790874 -53.779674)
		(width 0.11684)
		(layer "F.Cu")
		(net "FM_INTRUDER_N")
	)
	(segment
		(start 41.134284 -52.24145)
		(end 41.790874 -52.89804)
		(width 0.11684)
		(layer "F.Cu")
		(net "FM_INTRUDER_N")
	)
	(via
		(at 20.714208 -104.05364)
		(size 0.508)
		(drill 0.254)
		(layers "F.Cu" "B.Cu")
		(net "FM_INTRUDER_N")
	)
	(via
		(at 30.232604 -99.906328)
		(size 0.508)
		(drill 0.254)
		(layers "F.Cu" "B.Cu")
		(net "FM_INTRUDER_N")
	)
	(via
		(at 24.39162 -103.9876)
		(size 0.508)
		(drill 0.254)
		(layers "F.Cu" "B.Cu")
		(net "FM_INTRUDER_N")
	)
	(via
		(at 42.2402 -53.9242)
		(size 0.4572)
		(drill 0.254)
		(layers "F.Cu" "B.Cu")
		(net "FM_INTRUDER_N")
	)
	(via
		(at 59.38266 -97.66046)
		(size 0.508)
		(drill 0.254)
		(layers "F.Cu" "B.Cu")
		(net "FM_INTRUDER_N")
	)
	(via
		(at 59.7916 -77.1652)
		(size 0.508)
		(drill 0.254)
		(layers "F.Cu" "B.Cu")
		(net "FM_INTRUDER_N")
	)
	(via
		(at 21.336 -108.077)
		(size 0.6604)
		(drill 0.3302)
		(layers "F.Cu" "B.Cu")
		(net "FM_INTRUDER_N")
	)
	(segment
		(start 20.714208 -105.658158)
		(end 21.082 -106.02595)
		(width 0.11684)
		(layer "B.Cu")
		(net "FM_INTRUDER_N")
	)
	(segment
		(start 20.714208 -104.05364)
		(end 20.714208 -105.658158)
		(width 0.11684)
		(layer "B.Cu")
		(net "FM_INTRUDER_N")
	)
	(segment
		(start 23.622 -115.697)
		(end 22.912832 -115.697)
		(width 0.11684)
		(layer "B.Cu")
		(net "FM_INTRUDER_N")
	)
	(segment
		(start 20.701 -108.966)
		(end 21.336 -108.331)
		(width 0.11684)
		(layer "B.Cu")
		(net "FM_INTRUDER_N")
	)
	(segment
		(start 21.082 -107.188)
		(end 21.336 -107.442)
		(width 0.11684)
		(layer "B.Cu")
		(net "FM_INTRUDER_N")
	)
	(segment
		(start 22.44852 -112.468406)
		(end 20.701 -110.720886)
		(width 0.11684)
		(layer "B.Cu")
		(net "FM_INTRUDER_N")
	)
	(segment
		(start 21.082 -106.02595)
		(end 21.082 -107.188)
		(width 0.11684)
		(layer "B.Cu")
		(net "FM_INTRUDER_N")
	)
	(segment
		(start 22.912832 -115.697)
		(end 22.44852 -115.232688)
		(width 0.11684)
		(layer "B.Cu")
		(net "FM_INTRUDER_N")
	)
	(segment
		(start 23.945088 -116.020088)
		(end 23.622 -115.697)
		(width 0.11684)
		(layer "B.Cu")
		(net "FM_INTRUDER_N")
	)
	(segment
		(start 23.945088 -118.25986)
		(end 23.945088 -116.020088)
		(width 0.11684)
		(layer "B.Cu")
		(net "FM_INTRUDER_N")
	)
	(segment
		(start 20.701 -110.720886)
		(end 20.701 -108.966)
		(width 0.11684)
		(layer "B.Cu")
		(net "FM_INTRUDER_N")
	)
	(segment
		(start 21.336 -107.442)
		(end 21.336 -108.077)
		(width 0.11684)
		(layer "B.Cu")
		(net "FM_INTRUDER_N")
	)
	(segment
		(start 22.44852 -115.232688)
		(end 22.44852 -112.468406)
		(width 0.11684)
		(layer "B.Cu")
		(net "FM_INTRUDER_N")
	)
	(segment
		(start 21.336 -108.331)
		(end 21.336 -108.077)
		(width 0.11684)
		(layer "B.Cu")
		(net "FM_INTRUDER_N")
	)
	(segment
		(start 32.867346 -99.257612)
		(end 33.513268 -98.61169)
		(width 0.08382)
		(layer "In2.Cu")
		(net "FM_INTRUDER_N")
	)
	(segment
		(start 23.2918 -104.8258)
		(end 21.4122 -104.8258)
		(width 0.08382)
		(layer "In2.Cu")
		(net "FM_INTRUDER_N")
	)
	(segment
		(start 30.954472 -99.78009)
		(end 31.411672 -99.78009)
		(width 0.08382)
		(layer "In2.Cu")
		(net "FM_INTRUDER_N")
	)
	(segment
		(start 31.72714 -99.464622)
		(end 32.227266 -99.257612)
		(width 0.08382)
		(layer "In2.Cu")
		(net "FM_INTRUDER_N")
	)
	(segment
		(start 33.513268 -98.61169)
		(end 36.863528 -98.61169)
		(width 0.08382)
		(layer "In2.Cu")
		(net "FM_INTRUDER_N")
	)
	(segment
		(start 31.411672 -99.78009)
		(end 31.72714 -99.464622)
		(width 0.08382)
		(layer "In2.Cu")
		(net "FM_INTRUDER_N")
	)
	(segment
		(start 45.941488 -95.91929)
		(end 48.33747 -95.91929)
		(width 0.08382)
		(layer "In2.Cu")
		(net "FM_INTRUDER_N")
	)
	(segment
		(start 56.74106 -97.66046)
		(end 59.38266 -97.66046)
		(width 0.08382)
		(layer "In2.Cu")
		(net "FM_INTRUDER_N")
	)
	(segment
		(start 48.63338 -96.2152)
		(end 55.2958 -96.2152)
		(width 0.08382)
		(layer "In2.Cu")
		(net "FM_INTRUDER_N")
	)
	(segment
		(start 32.227266 -99.257612)
		(end 32.867346 -99.257612)
		(width 0.08382)
		(layer "In2.Cu")
		(net "FM_INTRUDER_N")
	)
	(segment
		(start 42.26814 -99.592638)
		(end 45.941488 -95.91929)
		(width 0.08382)
		(layer "In2.Cu")
		(net "FM_INTRUDER_N")
	)
	(segment
		(start 21.4122 -104.8258)
		(end 20.714208 -104.127808)
		(width 0.08382)
		(layer "In2.Cu")
		(net "FM_INTRUDER_N")
	)
	(segment
		(start 30.828234 -99.906328)
		(end 30.954472 -99.78009)
		(width 0.08382)
		(layer "In2.Cu")
		(net "FM_INTRUDER_N")
	)
	(segment
		(start 37.844476 -99.592638)
		(end 42.26814 -99.592638)
		(width 0.08382)
		(layer "In2.Cu")
		(net "FM_INTRUDER_N")
	)
	(segment
		(start 55.2958 -96.2152)
		(end 56.74106 -97.66046)
		(width 0.08382)
		(layer "In2.Cu")
		(net "FM_INTRUDER_N")
	)
	(segment
		(start 20.714208 -104.127808)
		(end 20.714208 -104.05364)
		(width 0.08382)
		(layer "In2.Cu")
		(net "FM_INTRUDER_N")
	)
	(segment
		(start 24.39162 -103.9876)
		(end 24.13 -103.9876)
		(width 0.08382)
		(layer "In2.Cu")
		(net "FM_INTRUDER_N")
	)
	(segment
		(start 48.33747 -95.91929)
		(end 48.63338 -96.2152)
		(width 0.08382)
		(layer "In2.Cu")
		(net "FM_INTRUDER_N")
	)
	(segment
		(start 30.232604 -99.906328)
		(end 30.828234 -99.906328)
		(width 0.08382)
		(layer "In2.Cu")
		(net "FM_INTRUDER_N")
	)
	(segment
		(start 36.863528 -98.61169)
		(end 37.844476 -99.592638)
		(width 0.08382)
		(layer "In2.Cu")
		(net "FM_INTRUDER_N")
	)
	(segment
		(start 24.13 -103.9876)
		(end 23.2918 -104.8258)
		(width 0.08382)
		(layer "In2.Cu")
		(net "FM_INTRUDER_N")
	)
	(segment
		(start 60.25642 -97.04832)
		(end 59.64428 -97.66046)
		(width 0.10668)
		(layer "In4.Cu")
		(net "FM_INTRUDER_N")
	)
	(segment
		(start 59.7916 -78.460346)
		(end 59.309 -78.942946)
		(width 0.10668)
		(layer "In4.Cu")
		(net "FM_INTRUDER_N")
	)
	(segment
		(start 59.8424 -85.6488)
		(end 60.74664 -86.55304)
		(width 0.10668)
		(layer "In4.Cu")
		(net "FM_INTRUDER_N")
	)
	(segment
		(start 57.4294 -84.5058)
		(end 58.5724 -85.6488)
		(width 0.10668)
		(layer "In4.Cu")
		(net "FM_INTRUDER_N")
	)
	(segment
		(start 60.74664 -92.590112)
		(end 60.46724 -93.26499)
		(width 0.10668)
		(layer "In4.Cu")
		(net "FM_INTRUDER_N")
	)
	(segment
		(start 60.25642 -96.244664)
		(end 60.25642 -97.04832)
		(width 0.10668)
		(layer "In4.Cu")
		(net "FM_INTRUDER_N")
	)
	(segment
		(start 60.74664 -86.55304)
		(end 60.74664 -92.590112)
		(width 0.10668)
		(layer "In4.Cu")
		(net "FM_INTRUDER_N")
	)
	(segment
		(start 59.309 -78.942946)
		(end 59.309 -79.3496)
		(width 0.10668)
		(layer "In4.Cu")
		(net "FM_INTRUDER_N")
	)
	(segment
		(start 57.4294 -84.270596)
		(end 57.4294 -84.5058)
		(width 0.10668)
		(layer "In4.Cu")
		(net "FM_INTRUDER_N")
	)
	(segment
		(start 58.5724 -85.6488)
		(end 59.8424 -85.6488)
		(width 0.10668)
		(layer "In4.Cu")
		(net "FM_INTRUDER_N")
	)
	(segment
		(start 59.7916 -77.1652)
		(end 59.7916 -78.460346)
		(width 0.10668)
		(layer "In4.Cu")
		(net "FM_INTRUDER_N")
	)
	(segment
		(start 56.91124 -83.752436)
		(end 57.4294 -84.270596)
		(width 0.10668)
		(layer "In4.Cu")
		(net "FM_INTRUDER_N")
	)
	(segment
		(start 59.64428 -97.66046)
		(end 59.38266 -97.66046)
		(width 0.10668)
		(layer "In4.Cu")
		(net "FM_INTRUDER_N")
	)
	(segment
		(start 60.46724 -96.033844)
		(end 60.25642 -96.244664)
		(width 0.10668)
		(layer "In4.Cu")
		(net "FM_INTRUDER_N")
	)
	(segment
		(start 60.46724 -93.26499)
		(end 60.46724 -96.033844)
		(width 0.10668)
		(layer "In4.Cu")
		(net "FM_INTRUDER_N")
	)
	(segment
		(start 56.91124 -81.74736)
		(end 56.91124 -83.752436)
		(width 0.10668)
		(layer "In4.Cu")
		(net "FM_INTRUDER_N")
	)
	(segment
		(start 59.309 -79.3496)
		(end 56.91124 -81.74736)
		(width 0.10668)
		(layer "In4.Cu")
		(net "FM_INTRUDER_N")
	)
	(segment
		(start 47.377604 -66.7004)
		(end 46.490636 -66.7004)
		(width 0.10668)
		(layer "In7.Cu")
		(net "FM_INTRUDER_N")
	)
	(segment
		(start 54.61 -72.534018)
		(end 52.276502 -70.20052)
		(width 0.10668)
		(layer "In7.Cu")
		(net "FM_INTRUDER_N")
	)
	(segment
		(start 50.07356 -68.946014)
		(end 50.07356 -68.125086)
		(width 0.10668)
		(layer "In7.Cu")
		(net "FM_INTRUDER_N")
	)
	(segment
		(start 42.75836 -57.850786)
		(end 42.99458 -57.614566)
		(width 0.10668)
		(layer "In7.Cu")
		(net "FM_INTRUDER_N")
	)
	(segment
		(start 59.7916 -75.9714)
		(end 57.61863 -73.79843)
		(width 0.10668)
		(layer "In7.Cu")
		(net "FM_INTRUDER_N")
	)
	(segment
		(start 52.276502 -70.20052)
		(end 51.328066 -70.20052)
		(width 0.10668)
		(layer "In7.Cu")
		(net "FM_INTRUDER_N")
	)
	(segment
		(start 55.757826 -73.623932)
		(end 55.757572 -73.624186)
		(width 0.10668)
		(layer "In7.Cu")
		(net "FM_INTRUDER_N")
	)
	(segment
		(start 42.41292 -65.492884)
		(end 42.41292 -63.826898)
		(width 0.10668)
		(layer "In7.Cu")
		(net "FM_INTRUDER_N")
	)
	(segment
		(start 42.2402 -54.5084)
		(end 42.2402 -53.9242)
		(width 0.10668)
		(layer "In7.Cu")
		(net "FM_INTRUDER_N")
	)
	(segment
		(start 42.8244 -65.904364)
		(end 42.41292 -65.492884)
		(width 0.10668)
		(layer "In7.Cu")
		(net "FM_INTRUDER_N")
	)
	(segment
		(start 54.61 -72.974454)
		(end 54.61 -72.534018)
		(width 0.10668)
		(layer "In7.Cu")
		(net "FM_INTRUDER_N")
	)
	(segment
		(start 42.41292 -63.826898)
		(end 42.75836 -63.481458)
		(width 0.10668)
		(layer "In7.Cu")
		(net "FM_INTRUDER_N")
	)
	(segment
		(start 56.707278 -73.24852)
		(end 56.331866 -73.623932)
		(width 0.10668)
		(layer "In7.Cu")
		(net "FM_INTRUDER_N")
	)
	(segment
		(start 46.075346 -66.87185)
		(end 45.256196 -66.87185)
		(width 0.10668)
		(layer "In7.Cu")
		(net "FM_INTRUDER_N")
	)
	(segment
		(start 57.61863 -73.79843)
		(end 57.61863 -73.661524)
		(width 0.10668)
		(layer "In7.Cu")
		(net "FM_INTRUDER_N")
	)
	(segment
		(start 56.331866 -73.623932)
		(end 55.757826 -73.623932)
		(width 0.10668)
		(layer "In7.Cu")
		(net "FM_INTRUDER_N")
	)
	(segment
		(start 44.612306 -66.22796)
		(end 43.12666 -66.22796)
		(width 0.10668)
		(layer "In7.Cu")
		(net "FM_INTRUDER_N")
	)
	(segment
		(start 47.858426 -67.181222)
		(end 47.377604 -66.7004)
		(width 0.10668)
		(layer "In7.Cu")
		(net "FM_INTRUDER_N")
	)
	(segment
		(start 55.757572 -73.624186)
		(end 55.259732 -73.624186)
		(width 0.10668)
		(layer "In7.Cu")
		(net "FM_INTRUDER_N")
	)
	(segment
		(start 59.7916 -77.1652)
		(end 59.7916 -75.9714)
		(width 0.10668)
		(layer "In7.Cu")
		(net "FM_INTRUDER_N")
	)
	(segment
		(start 43.12666 -66.22796)
		(end 42.8244 -65.9257)
		(width 0.10668)
		(layer "In7.Cu")
		(net "FM_INTRUDER_N")
	)
	(segment
		(start 49.129696 -67.181222)
		(end 47.858426 -67.181222)
		(width 0.10668)
		(layer "In7.Cu")
		(net "FM_INTRUDER_N")
	)
	(segment
		(start 57.205626 -73.24852)
		(end 56.707278 -73.24852)
		(width 0.10668)
		(layer "In7.Cu")
		(net "FM_INTRUDER_N")
	)
	(segment
		(start 42.75836 -63.481458)
		(end 42.75836 -57.850786)
		(width 0.10668)
		(layer "In7.Cu")
		(net "FM_INTRUDER_N")
	)
	(segment
		(start 57.61863 -73.661524)
		(end 57.205626 -73.24852)
		(width 0.10668)
		(layer "In7.Cu")
		(net "FM_INTRUDER_N")
	)
	(segment
		(start 45.256196 -66.87185)
		(end 44.612306 -66.22796)
		(width 0.10668)
		(layer "In7.Cu")
		(net "FM_INTRUDER_N")
	)
	(segment
		(start 55.259732 -73.624186)
		(end 54.61 -72.974454)
		(width 0.10668)
		(layer "In7.Cu")
		(net "FM_INTRUDER_N")
	)
	(segment
		(start 46.490636 -66.7004)
		(end 46.075346 -66.87185)
		(width 0.10668)
		(layer "In7.Cu")
		(net "FM_INTRUDER_N")
	)
	(segment
		(start 50.07356 -68.125086)
		(end 49.129696 -67.181222)
		(width 0.10668)
		(layer "In7.Cu")
		(net "FM_INTRUDER_N")
	)
	(segment
		(start 42.8244 -65.9257)
		(end 42.8244 -65.904364)
		(width 0.10668)
		(layer "In7.Cu")
		(net "FM_INTRUDER_N")
	)
	(segment
		(start 42.99458 -55.26278)
		(end 42.2402 -54.5084)
		(width 0.10668)
		(layer "In7.Cu")
		(net "FM_INTRUDER_N")
	)
	(segment
		(start 42.99458 -57.614566)
		(end 42.99458 -55.26278)
		(width 0.10668)
		(layer "In7.Cu")
		(net "FM_INTRUDER_N")
	)
	(segment
		(start 51.328066 -70.20052)
		(end 50.07356 -68.946014)
		(width 0.10668)
		(layer "In7.Cu")
		(net "FM_INTRUDER_N")
	)
	(segment
		(start 24.39162 -103.251)
		(end 24.89962 -102.743)
		(width 0.08382)
		(layer "In9.Cu")
		(net "FM_INTRUDER_N")
	)
	(segment
		(start 29.328872 -99.906328)
		(end 30.232604 -99.906328)
		(width 0.08382)
		(layer "In9.Cu")
		(net "FM_INTRUDER_N")
	)
	(segment
		(start 28.07462 -101.16058)
		(end 29.328872 -99.906328)
		(width 0.08382)
		(layer "In9.Cu")
		(net "FM_INTRUDER_N")
	)
	(segment
		(start 24.39162 -103.9876)
		(end 24.39162 -103.251)
		(width 0.08382)
		(layer "In9.Cu")
		(net "FM_INTRUDER_N")
	)
	(segment
		(start 27.55646 -101.16058)
		(end 28.07462 -101.16058)
		(width 0.08382)
		(layer "In9.Cu")
		(net "FM_INTRUDER_N")
	)
	(segment
		(start 25.97404 -102.743)
		(end 27.55646 -101.16058)
		(width 0.08382)
		(layer "In9.Cu")
		(net "FM_INTRUDER_N")
	)
	(segment
		(start 24.89962 -102.743)
		(end 25.97404 -102.743)
		(width 0.08382)
		(layer "In9.Cu")
		(net "FM_INTRUDER_N")
	)
	(segment
		(start 61.695076 -43.371262)
		(end 62.0903 -42.976038)
		(width 0.11684)
		(layer "F.Cu")
		(net "FM_BOARD_BMC_REV_ID2")
	)
	(segment
		(start 71.80707 -21.20773)
		(end 71.76897 -21.20773)
		(width 0.11684)
		(layer "F.Cu")
		(net "FM_BOARD_BMC_REV_ID2")
	)
	(segment
		(start 72.39 -20.08505)
		(end 72.39 -20.6248)
		(width 0.11684)
		(layer "F.Cu")
		(net "FM_BOARD_BMC_REV_ID2")
	)
	(segment
		(start 71.76897 -21.20773)
		(end 71.75627 -21.22043)
		(width 0.11684)
		(layer "F.Cu")
		(net "FM_BOARD_BMC_REV_ID2")
	)
	(segment
		(start 72.39 -20.6248)
		(end 71.80707 -21.20773)
		(width 0.11684)
		(layer "F.Cu")
		(net "FM_BOARD_BMC_REV_ID2")
	)
	(via
		(at 71.75627 -21.22043)
		(size 0.508)
		(drill 0.254)
		(layers "F.Cu" "B.Cu")
		(net "FM_BOARD_BMC_REV_ID2")
	)
	(via
		(at 62.0903 -42.976038)
		(size 0.4572)
		(drill 0.254)
		(layers "F.Cu" "B.Cu")
		(net "FM_BOARD_BMC_REV_ID2")
	)
	(segment
		(start 71.80707 -21.20773)
		(end 71.76897 -21.20773)
		(width 0.11684)
		(layer "B.Cu")
		(net "FM_BOARD_BMC_REV_ID2")
	)
	(segment
		(start 72.39 -20.08505)
		(end 72.39 -20.6248)
		(width 0.11684)
		(layer "B.Cu")
		(net "FM_BOARD_BMC_REV_ID2")
	)
	(segment
		(start 71.76897 -21.20773)
		(end 71.75627 -21.22043)
		(width 0.11684)
		(layer "B.Cu")
		(net "FM_BOARD_BMC_REV_ID2")
	)
	(segment
		(start 72.39 -20.6248)
		(end 71.80707 -21.20773)
		(width 0.11684)
		(layer "B.Cu")
		(net "FM_BOARD_BMC_REV_ID2")
	)
	(segment
		(start 63.27394 -42.68724)
		(end 63.27394 -43.96994)
		(width 0.10668)
		(layer "In4.Cu")
		(net "FM_BOARD_BMC_REV_ID2")
	)
	(segment
		(start 63.1571 -42.5704)
		(end 63.27394 -42.68724)
		(width 0.10668)
		(layer "In4.Cu")
		(net "FM_BOARD_BMC_REV_ID2")
	)
	(segment
		(start 65.93586 -43.7007)
		(end 65.93586 -37.925756)
		(width 0.10668)
		(layer "In4.Cu")
		(net "FM_BOARD_BMC_REV_ID2")
	)
	(segment
		(start 66.47942 -34.73958)
		(end 67.12585 -34.09315)
		(width 0.10668)
		(layer "In4.Cu")
		(net "FM_BOARD_BMC_REV_ID2")
	)
	(segment
		(start 65.44564 -44.19092)
		(end 65.93586 -43.7007)
		(width 0.10668)
		(layer "In4.Cu")
		(net "FM_BOARD_BMC_REV_ID2")
	)
	(segment
		(start 69.864224 -21.92782)
		(end 70.53072 -21.92782)
		(width 0.10668)
		(layer "In4.Cu")
		(net "FM_BOARD_BMC_REV_ID2")
	)
	(segment
		(start 63.27394 -43.96994)
		(end 63.49492 -44.19092)
		(width 0.10668)
		(layer "In4.Cu")
		(net "FM_BOARD_BMC_REV_ID2")
	)
	(segment
		(start 70.53072 -21.92782)
		(end 71.25081 -21.20773)
		(width 0.10668)
		(layer "In4.Cu")
		(net "FM_BOARD_BMC_REV_ID2")
	)
	(segment
		(start 66.47942 -37.382196)
		(end 66.47942 -34.73958)
		(width 0.10668)
		(layer "In4.Cu")
		(net "FM_BOARD_BMC_REV_ID2")
	)
	(segment
		(start 65.93586 -37.925756)
		(end 66.47942 -37.382196)
		(width 0.10668)
		(layer "In4.Cu")
		(net "FM_BOARD_BMC_REV_ID2")
	)
	(segment
		(start 67.02044 -30.396942)
		(end 68.966588 -28.450794)
		(width 0.10668)
		(layer "In4.Cu")
		(net "FM_BOARD_BMC_REV_ID2")
	)
	(segment
		(start 71.74357 -21.20773)
		(end 71.75627 -21.22043)
		(width 0.10668)
		(layer "In4.Cu")
		(net "FM_BOARD_BMC_REV_ID2")
	)
	(segment
		(start 68.966588 -28.450794)
		(end 68.966588 -22.825456)
		(width 0.10668)
		(layer "In4.Cu")
		(net "FM_BOARD_BMC_REV_ID2")
	)
	(segment
		(start 62.0903 -42.976038)
		(end 62.495938 -42.5704)
		(width 0.10668)
		(layer "In4.Cu")
		(net "FM_BOARD_BMC_REV_ID2")
	)
	(segment
		(start 67.12585 -34.09315)
		(end 67.12585 -32.337756)
		(width 0.10668)
		(layer "In4.Cu")
		(net "FM_BOARD_BMC_REV_ID2")
	)
	(segment
		(start 67.02044 -32.232346)
		(end 67.02044 -30.396942)
		(width 0.10668)
		(layer "In4.Cu")
		(net "FM_BOARD_BMC_REV_ID2")
	)
	(segment
		(start 71.25081 -21.20773)
		(end 71.74357 -21.20773)
		(width 0.10668)
		(layer "In4.Cu")
		(net "FM_BOARD_BMC_REV_ID2")
	)
	(segment
		(start 62.495938 -42.5704)
		(end 63.1571 -42.5704)
		(width 0.10668)
		(layer "In4.Cu")
		(net "FM_BOARD_BMC_REV_ID2")
	)
	(segment
		(start 63.49492 -44.19092)
		(end 65.44564 -44.19092)
		(width 0.10668)
		(layer "In4.Cu")
		(net "FM_BOARD_BMC_REV_ID2")
	)
	(segment
		(start 67.12585 -32.337756)
		(end 67.02044 -32.232346)
		(width 0.10668)
		(layer "In4.Cu")
		(net "FM_BOARD_BMC_REV_ID2")
	)
	(segment
		(start 68.966588 -22.825456)
		(end 69.864224 -21.92782)
		(width 0.10668)
		(layer "In4.Cu")
		(net "FM_BOARD_BMC_REV_ID2")
	)
	(segment
		(start 71.374 -20.3327)
		(end 70.48627 -21.22043)
		(width 0.11684)
		(layer "F.Cu")
		(net "FM_BOARD_BMC_REV_ID1")
	)
	(segment
		(start 62.494922 -42.571162)
		(end 62.890146 -42.175938)
		(width 0.11684)
		(layer "F.Cu")
		(net "FM_BOARD_BMC_REV_ID1")
	)
	(segment
		(start 71.374 -20.08505)
		(end 71.374 -20.3327)
		(width 0.11684)
		(layer "F.Cu")
		(net "FM_BOARD_BMC_REV_ID1")
	)
	(via
		(at 70.48627 -21.22043)
		(size 0.508)
		(drill 0.254)
		(layers "F.Cu" "B.Cu")
		(net "FM_BOARD_BMC_REV_ID1")
	)
	(via
		(at 62.890146 -42.175938)
		(size 0.4572)
		(drill 0.254)
		(layers "F.Cu" "B.Cu")
		(net "FM_BOARD_BMC_REV_ID1")
	)
	(segment
		(start 71.374 -20.3327)
		(end 70.48627 -21.22043)
		(width 0.11684)
		(layer "B.Cu")
		(net "FM_BOARD_BMC_REV_ID1")
	)
	(segment
		(start 71.374 -20.08505)
		(end 71.374 -20.3327)
		(width 0.11684)
		(layer "B.Cu")
		(net "FM_BOARD_BMC_REV_ID1")
	)
	(segment
		(start 66.22034 -34.617914)
		(end 66.86677 -33.971484)
		(width 0.10668)
		(layer "In4.Cu")
		(net "FM_BOARD_BMC_REV_ID1")
	)
	(segment
		(start 64.6684 -43.3705)
		(end 65.67678 -42.36212)
		(width 0.10668)
		(layer "In4.Cu")
		(net "FM_BOARD_BMC_REV_ID1")
	)
	(segment
		(start 63.47206 -42.59072)
		(end 63.87592 -42.59072)
		(width 0.10668)
		(layer "In4.Cu")
		(net "FM_BOARD_BMC_REV_ID1")
	)
	(segment
		(start 65.67678 -42.36212)
		(end 65.67678 -37.818314)
		(width 0.10668)
		(layer "In4.Cu")
		(net "FM_BOARD_BMC_REV_ID1")
	)
	(segment
		(start 66.86677 -33.971484)
		(end 66.86677 -33.17367)
		(width 0.10668)
		(layer "In4.Cu")
		(net "FM_BOARD_BMC_REV_ID1")
	)
	(segment
		(start 62.890146 -42.175938)
		(end 63.057278 -42.175938)
		(width 0.10668)
		(layer "In4.Cu")
		(net "FM_BOARD_BMC_REV_ID1")
	)
	(segment
		(start 68.707508 -22.718014)
		(end 69.756782 -21.66874)
		(width 0.10668)
		(layer "In4.Cu")
		(net "FM_BOARD_BMC_REV_ID1")
	)
	(segment
		(start 66.22034 -37.274754)
		(end 66.22034 -34.617914)
		(width 0.10668)
		(layer "In4.Cu")
		(net "FM_BOARD_BMC_REV_ID1")
	)
	(segment
		(start 65.67678 -37.818314)
		(end 66.22034 -37.274754)
		(width 0.10668)
		(layer "In4.Cu")
		(net "FM_BOARD_BMC_REV_ID1")
	)
	(segment
		(start 63.057278 -42.175938)
		(end 63.47206 -42.59072)
		(width 0.10668)
		(layer "In4.Cu")
		(net "FM_BOARD_BMC_REV_ID1")
	)
	(segment
		(start 66.735198 -30.282134)
		(end 68.707508 -28.309824)
		(width 0.10668)
		(layer "In4.Cu")
		(net "FM_BOARD_BMC_REV_ID1")
	)
	(segment
		(start 69.756782 -21.66874)
		(end 70.03796 -21.66874)
		(width 0.10668)
		(layer "In4.Cu")
		(net "FM_BOARD_BMC_REV_ID1")
	)
	(segment
		(start 66.735198 -33.042098)
		(end 66.735198 -30.282134)
		(width 0.10668)
		(layer "In4.Cu")
		(net "FM_BOARD_BMC_REV_ID1")
	)
	(segment
		(start 63.87592 -42.59072)
		(end 64.10198 -42.81678)
		(width 0.10668)
		(layer "In4.Cu")
		(net "FM_BOARD_BMC_REV_ID1")
	)
	(segment
		(start 64.2493 -43.3705)
		(end 64.6684 -43.3705)
		(width 0.10668)
		(layer "In4.Cu")
		(net "FM_BOARD_BMC_REV_ID1")
	)
	(segment
		(start 68.707508 -28.309824)
		(end 68.707508 -22.718014)
		(width 0.10668)
		(layer "In4.Cu")
		(net "FM_BOARD_BMC_REV_ID1")
	)
	(segment
		(start 66.86677 -33.17367)
		(end 66.735198 -33.042098)
		(width 0.10668)
		(layer "In4.Cu")
		(net "FM_BOARD_BMC_REV_ID1")
	)
	(segment
		(start 64.10198 -42.81678)
		(end 64.10198 -43.22318)
		(width 0.10668)
		(layer "In4.Cu")
		(net "FM_BOARD_BMC_REV_ID1")
	)
	(segment
		(start 64.10198 -43.22318)
		(end 64.2493 -43.3705)
		(width 0.10668)
		(layer "In4.Cu")
		(net "FM_BOARD_BMC_REV_ID1")
	)
	(segment
		(start 70.03796 -21.66874)
		(end 70.48627 -21.22043)
		(width 0.10668)
		(layer "In4.Cu")
		(net "FM_BOARD_BMC_REV_ID1")
	)
	(segment
		(start 63.295022 -41.771316)
		(end 62.899798 -41.376092)
		(width 0.11684)
		(layer "F.Cu")
		(net "FM_BOARD_BMC_REV_ID0")
	)
	(segment
		(start 69.23532 -21.20773)
		(end 69.22897 -21.20773)
		(width 0.11684)
		(layer "F.Cu")
		(net "FM_BOARD_BMC_REV_ID0")
	)
	(segment
		(start 69.22897 -21.20773)
		(end 69.21627 -21.22043)
		(width 0.11684)
		(layer "F.Cu")
		(net "FM_BOARD_BMC_REV_ID0")
	)
	(segment
		(start 70.358 -20.08505)
		(end 69.23532 -21.20773)
		(width 0.11684)
		(layer "F.Cu")
		(net "FM_BOARD_BMC_REV_ID0")
	)
	(via
		(at 69.21627 -21.22043)
		(size 0.508)
		(drill 0.254)
		(layers "F.Cu" "B.Cu")
		(net "FM_BOARD_BMC_REV_ID0")
	)
	(via
		(at 62.899798 -41.376092)
		(size 0.4572)
		(drill 0.254)
		(layers "F.Cu" "B.Cu")
		(net "FM_BOARD_BMC_REV_ID0")
	)
	(segment
		(start 69.23532 -21.20773)
		(end 69.22897 -21.20773)
		(width 0.11684)
		(layer "B.Cu")
		(net "FM_BOARD_BMC_REV_ID0")
	)
	(segment
		(start 70.358 -20.08505)
		(end 69.23532 -21.20773)
		(width 0.11684)
		(layer "B.Cu")
		(net "FM_BOARD_BMC_REV_ID0")
	)
	(segment
		(start 69.22897 -21.20773)
		(end 69.21627 -21.22043)
		(width 0.11684)
		(layer "B.Cu")
		(net "FM_BOARD_BMC_REV_ID0")
	)
	(segment
		(start 65.151 -37.5412)
		(end 65.4177 -37.8079)
		(width 0.10668)
		(layer "In4.Cu")
		(net "FM_BOARD_BMC_REV_ID0")
	)
	(segment
		(start 66.472308 -33.14573)
		(end 66.60769 -33.281112)
		(width 0.10668)
		(layer "In4.Cu")
		(net "FM_BOARD_BMC_REV_ID0")
	)
	(segment
		(start 69.29374 -21.76526)
		(end 68.448428 -22.610572)
		(width 0.10668)
		(layer "In4.Cu")
		(net "FM_BOARD_BMC_REV_ID0")
	)
	(segment
		(start 66.402204 -30.202886)
		(end 66.402204 -30.824932)
		(width 0.10668)
		(layer "In4.Cu")
		(net "FM_BOARD_BMC_REV_ID0")
	)
	(segment
		(start 64.72936 -42.57802)
		(end 64.29756 -42.57802)
		(width 0.10668)
		(layer "In4.Cu")
		(net "FM_BOARD_BMC_REV_ID0")
	)
	(segment
		(start 66.402204 -30.824932)
		(end 65.673478 -31.553658)
		(width 0.10668)
		(layer "In4.Cu")
		(net "FM_BOARD_BMC_REV_ID0")
	)
	(segment
		(start 69.29374 -21.336)
		(end 69.29374 -21.76526)
		(width 0.10668)
		(layer "In4.Cu")
		(net "FM_BOARD_BMC_REV_ID0")
	)
	(segment
		(start 65.673478 -31.553658)
		(end 65.673478 -31.935928)
		(width 0.10668)
		(layer "In4.Cu")
		(net "FM_BOARD_BMC_REV_ID0")
	)
	(segment
		(start 65.151 -36.765992)
		(end 65.151 -37.5412)
		(width 0.10668)
		(layer "In4.Cu")
		(net "FM_BOARD_BMC_REV_ID0")
	)
	(segment
		(start 68.448428 -28.156662)
		(end 66.402204 -30.202886)
		(width 0.10668)
		(layer "In4.Cu")
		(net "FM_BOARD_BMC_REV_ID0")
	)
	(segment
		(start 66.60769 -33.77311)
		(end 65.79108 -34.58972)
		(width 0.10668)
		(layer "In4.Cu")
		(net "FM_BOARD_BMC_REV_ID0")
	)
	(segment
		(start 68.448428 -22.610572)
		(end 68.448428 -28.156662)
		(width 0.10668)
		(layer "In4.Cu")
		(net "FM_BOARD_BMC_REV_ID0")
	)
	(segment
		(start 66.472308 -32.734758)
		(end 66.472308 -33.14573)
		(width 0.10668)
		(layer "In4.Cu")
		(net "FM_BOARD_BMC_REV_ID0")
	)
	(segment
		(start 64.29756 -42.57802)
		(end 64.0969 -42.37736)
		(width 0.10668)
		(layer "In4.Cu")
		(net "FM_BOARD_BMC_REV_ID0")
	)
	(segment
		(start 64.0969 -42.37736)
		(end 64.0969 -41.97096)
		(width 0.10668)
		(layer "In4.Cu")
		(net "FM_BOARD_BMC_REV_ID0")
	)
	(segment
		(start 65.4177 -37.8079)
		(end 65.4177 -41.88968)
		(width 0.10668)
		(layer "In4.Cu")
		(net "FM_BOARD_BMC_REV_ID0")
	)
	(segment
		(start 66.60769 -33.281112)
		(end 66.60769 -33.77311)
		(width 0.10668)
		(layer "In4.Cu")
		(net "FM_BOARD_BMC_REV_ID0")
	)
	(segment
		(start 63.91656 -41.79062)
		(end 63.314326 -41.79062)
		(width 0.10668)
		(layer "In4.Cu")
		(net "FM_BOARD_BMC_REV_ID0")
	)
	(segment
		(start 69.21627 -21.25853)
		(end 69.29374 -21.336)
		(width 0.10668)
		(layer "In4.Cu")
		(net "FM_BOARD_BMC_REV_ID0")
	)
	(segment
		(start 65.79108 -36.125912)
		(end 65.151 -36.765992)
		(width 0.10668)
		(layer "In4.Cu")
		(net "FM_BOARD_BMC_REV_ID0")
	)
	(segment
		(start 65.79108 -34.58972)
		(end 65.79108 -36.125912)
		(width 0.10668)
		(layer "In4.Cu")
		(net "FM_BOARD_BMC_REV_ID0")
	)
	(segment
		(start 63.314326 -41.79062)
		(end 62.899798 -41.376092)
		(width 0.10668)
		(layer "In4.Cu")
		(net "FM_BOARD_BMC_REV_ID0")
	)
	(segment
		(start 69.21627 -21.22043)
		(end 69.21627 -21.25853)
		(width 0.10668)
		(layer "In4.Cu")
		(net "FM_BOARD_BMC_REV_ID0")
	)
	(segment
		(start 64.0969 -41.97096)
		(end 63.91656 -41.79062)
		(width 0.10668)
		(layer "In4.Cu")
		(net "FM_BOARD_BMC_REV_ID0")
	)
	(segment
		(start 65.673478 -31.935928)
		(end 66.472308 -32.734758)
		(width 0.10668)
		(layer "In4.Cu")
		(net "FM_BOARD_BMC_REV_ID0")
	)
	(segment
		(start 65.4177 -41.88968)
		(end 64.72936 -42.57802)
		(width 0.10668)
		(layer "In4.Cu")
		(net "FM_BOARD_BMC_REV_ID0")
	)
	(segment
		(start 28.46451 -70.93585)
		(end 28.87726 -71.3486)
		(width 0.11684)
		(layer "F.Cu")
		(net "EMMC_WP")
	)
	(segment
		(start 28.87726 -71.3486)
		(end 28.87726 -72.27062)
		(width 0.11684)
		(layer "F.Cu")
		(net "EMMC_WP")
	)
	(segment
		(start 28.2194 -70.93585)
		(end 28.46451 -70.93585)
		(width 0.11684)
		(layer "F.Cu")
		(net "EMMC_WP")
	)
	(segment
		(start 28.87726 -72.27062)
		(end 28.750006 -72.397874)
		(width 0.11684)
		(layer "F.Cu")
		(net "EMMC_WP")
	)
	(segment
		(start 28.750006 -72.397874)
		(end 28.750006 -73.360534)
		(width 0.11684)
		(layer "F.Cu")
		(net "EMMC_WP")
	)
	(via
		(at 29.33065 -64.7446)
		(size 0.6604)
		(drill 0.3302)
		(layers "F.Cu" "B.Cu")
		(net "UART_SYS_DBG_TX_R")
	)
	(segment
		(start 30.338014 -66.437002)
		(end 30.338014 -66.076068)
		(width 0.11684)
		(layer "B.Cu")
		(net "UART_SYS_DBG_TX_R")
	)
	(segment
		(start 29.33065 -65.068704)
		(end 29.33065 -64.7446)
		(width 0.11684)
		(layer "B.Cu")
		(net "UART_SYS_DBG_TX_R")
	)
	(segment
		(start 30.338014 -66.076068)
		(end 29.33065 -65.068704)
		(width 0.11684)
		(layer "B.Cu")
		(net "UART_SYS_DBG_TX_R")
	)
	(segment
		(start 29.33065 -64.7446)
		(end 29.33065 -63.4746)
		(width 0.11684)
		(layer "B.Cu")
		(net "UART_SYS_DBG_TX_R")
	)
	(segment
		(start 72.1868 -109.9566)
		(end 72.1868 -111.8108)
		(width 0.11684)
		(layer "F.Cu")
		(net "UART_SYS_DBG_TX")
	)
	(segment
		(start 72.5932 -115.3668)
		(end 71.5518 -116.4082)
		(width 0.11684)
		(layer "F.Cu")
		(net "UART_SYS_DBG_TX")
	)
	(segment
		(start 71.5518 -116.4082)
		(end 71.5518 -117.170454)
		(width 0.11684)
		(layer "F.Cu")
		(net "UART_SYS_DBG_TX")
	)
	(segment
		(start 71.4248 -107.83062)
		(end 71.4248 -108.6358)
		(width 0.11684)
		(layer "F.Cu")
		(net "UART_SYS_DBG_TX")
	)
	(segment
		(start 69.91985 -107.88015)
		(end 70.08622 -107.71378)
		(width 0.11684)
		(layer "F.Cu")
		(net "UART_SYS_DBG_TX")
	)
	(segment
		(start 71.30796 -107.71378)
		(end 71.4248 -107.83062)
		(width 0.11684)
		(layer "F.Cu")
		(net "UART_SYS_DBG_TX")
	)
	(segment
		(start 72.1868 -109.3978)
		(end 72.1868 -109.9566)
		(width 0.11684)
		(layer "F.Cu")
		(net "UART_SYS_DBG_TX")
	)
	(segment
		(start 71.4248 -108.6358)
		(end 72.1868 -109.3978)
		(width 0.11684)
		(layer "F.Cu")
		(net "UART_SYS_DBG_TX")
	)
	(segment
		(start 71.460106 -117.262148)
		(end 71.460106 -118.460012)
		(width 0.11684)
		(layer "F.Cu")
		(net "UART_SYS_DBG_TX")
	)
	(segment
		(start 70.08622 -107.71378)
		(end 71.30796 -107.71378)
		(width 0.11684)
		(layer "F.Cu")
		(net "UART_SYS_DBG_TX")
	)
	(segment
		(start 69.753226 -107.88015)
		(end 69.91985 -107.88015)
		(width 0.11684)
		(layer "F.Cu")
		(net "UART_SYS_DBG_TX")
	)
	(segment
		(start 71.5518 -117.170454)
		(end 71.460106 -117.262148)
		(width 0.11684)
		(layer "F.Cu")
		(net "UART_SYS_DBG_TX")
	)
	(segment
		(start 72.1868 -111.8108)
		(end 72.5932 -112.2172)
		(width 0.11684)
		(layer "F.Cu")
		(net "UART_SYS_DBG_TX")
	)
	(segment
		(start 72.5932 -112.2172)
		(end 72.5932 -115.3668)
		(width 0.11684)
		(layer "F.Cu")
		(net "UART_SYS_DBG_TX")
	)
	(via
		(at 42.838624 -69.889624)
		(size 0.508)
		(drill 0.254)
		(layers "F.Cu" "B.Cu")
		(net "UART_SYS_DBG_TX")
	)
	(via
		(at 72.1868 -109.9566)
		(size 0.762)
		(drill 0.381)
		(layers "F.Cu" "B.Cu")
		(net "UART_SYS_DBG_TX")
	)
	(via
		(at 69.753226 -107.88015)
		(size 0.508)
		(drill 0.254)
		(layers "F.Cu" "B.Cu")
		(net "UART_SYS_DBG_TX")
	)
	(segment
		(start 29.963618 -72.6694)
		(end 34.6964 -72.6694)
		(width 0.11684)
		(layer "B.Cu")
		(net "UART_SYS_DBG_TX")
	)
	(segment
		(start 25.3492 -62.3824)
		(end 25.3492 -67.744848)
		(width 0.11684)
		(layer "B.Cu")
		(net "UART_SYS_DBG_TX")
	)
	(segment
		(start 35.783266 -71.582534)
		(end 38.821106 -71.582534)
		(width 0.11684)
		(layer "B.Cu")
		(net "UART_SYS_DBG_TX")
	)
	(segment
		(start 27.95016 -63.574422)
		(end 27.161236 -62.785498)
		(width 0.11684)
		(layer "B.Cu")
		(net "UART_SYS_DBG_TX")
	)
	(segment
		(start 28.430728 -63.574422)
		(end 27.95016 -63.574422)
		(width 0.11684)
		(layer "B.Cu")
		(net "UART_SYS_DBG_TX")
	)
	(segment
		(start 38.821106 -71.582534)
		(end 40.82034 -69.5833)
		(width 0.11684)
		(layer "B.Cu")
		(net "UART_SYS_DBG_TX")
	)
	(segment
		(start 42.051224 -69.889624)
		(end 42.838624 -69.889624)
		(width 0.11684)
		(layer "B.Cu")
		(net "UART_SYS_DBG_TX")
	)
	(segment
		(start 34.6964 -72.6694)
		(end 35.783266 -71.582534)
		(width 0.11684)
		(layer "B.Cu")
		(net "UART_SYS_DBG_TX")
	)
	(segment
		(start 40.82034 -69.5833)
		(end 41.7449 -69.5833)
		(width 0.11684)
		(layer "B.Cu")
		(net "UART_SYS_DBG_TX")
	)
	(segment
		(start 27.2542 -70.4342)
		(end 27.728418 -70.4342)
		(width 0.11684)
		(layer "B.Cu")
		(net "UART_SYS_DBG_TX")
	)
	(segment
		(start 27.161236 -59.800236)
		(end 26.9748 -59.6138)
		(width 0.11684)
		(layer "B.Cu")
		(net "UART_SYS_DBG_TX")
	)
	(segment
		(start 25.7556 -61.976)
		(end 25.3492 -62.3824)
		(width 0.11684)
		(layer "B.Cu")
		(net "UART_SYS_DBG_TX")
	)
	(segment
		(start 27.161236 -62.785498)
		(end 27.161236 -59.800236)
		(width 0.11684)
		(layer "B.Cu")
		(net "UART_SYS_DBG_TX")
	)
	(segment
		(start 27.728418 -70.4342)
		(end 29.963618 -72.6694)
		(width 0.11684)
		(layer "B.Cu")
		(net "UART_SYS_DBG_TX")
	)
	(segment
		(start 26.9748 -59.6138)
		(end 26.0858 -59.6138)
		(width 0.11684)
		(layer "B.Cu")
		(net "UART_SYS_DBG_TX")
	)
	(segment
		(start 25.903682 -69.083682)
		(end 27.2542 -70.4342)
		(width 0.11684)
		(layer "B.Cu")
		(net "UART_SYS_DBG_TX")
	)
	(segment
		(start 41.7449 -69.5833)
		(end 42.051224 -69.889624)
		(width 0.11684)
		(layer "B.Cu")
		(net "UART_SYS_DBG_TX")
	)
	(segment
		(start 25.7556 -59.944)
		(end 25.7556 -61.976)
		(width 0.11684)
		(layer "B.Cu")
		(net "UART_SYS_DBG_TX")
	)
	(segment
		(start 25.3492 -67.744848)
		(end 25.903682 -69.083682)
		(width 0.11684)
		(layer "B.Cu")
		(net "UART_SYS_DBG_TX")
	)
	(segment
		(start 28.53055 -63.4746)
		(end 28.430728 -63.574422)
		(width 0.11684)
		(layer "B.Cu")
		(net "UART_SYS_DBG_TX")
	)
	(segment
		(start 26.0858 -59.6138)
		(end 25.7556 -59.944)
		(width 0.11684)
		(layer "B.Cu")
		(net "UART_SYS_DBG_TX")
	)
	(segment
		(start 67.35064 -105.529634)
		(end 67.35064 -103.240332)
		(width 0.10668)
		(layer "In7.Cu")
		(net "UART_SYS_DBG_TX")
	)
	(segment
		(start 57.511442 -83.333082)
		(end 56.8452 -82.66684)
		(width 0.10668)
		(layer "In7.Cu")
		(net "UART_SYS_DBG_TX")
	)
	(segment
		(start 56.8452 -82.66684)
		(end 56.8452 -81.0514)
		(width 0.10668)
		(layer "In7.Cu")
		(net "UART_SYS_DBG_TX")
	)
	(segment
		(start 69.753226 -107.88015)
		(end 69.701156 -107.88015)
		(width 0.10668)
		(layer "In7.Cu")
		(net "UART_SYS_DBG_TX")
	)
	(segment
		(start 51.801776 -74.416412)
		(end 50.55616 -73.170796)
		(width 0.10668)
		(layer "In7.Cu")
		(net "UART_SYS_DBG_TX")
	)
	(segment
		(start 42.1132 -69.1642)
		(end 42.838624 -69.889624)
		(width 0.10668)
		(layer "In7.Cu")
		(net "UART_SYS_DBG_TX")
	)
	(segment
		(start 56.8452 -81.0514)
		(end 55.753 -79.9592)
		(width 0.10668)
		(layer "In7.Cu")
		(net "UART_SYS_DBG_TX")
	)
	(segment
		(start 67.35064 -103.240332)
		(end 65.09766 -100.987352)
		(width 0.10668)
		(layer "In7.Cu")
		(net "UART_SYS_DBG_TX")
	)
	(segment
		(start 53.5178 -75.751944)
		(end 52.182268 -74.416412)
		(width 0.10668)
		(layer "In7.Cu")
		(net "UART_SYS_DBG_TX")
	)
	(segment
		(start 61.115956 -90.800174)
		(end 61.115956 -87.280242)
		(width 0.10668)
		(layer "In7.Cu")
		(net "UART_SYS_DBG_TX")
	)
	(segment
		(start 58.57875 -85.805264)
		(end 57.511442 -84.737956)
		(width 0.10668)
		(layer "In7.Cu")
		(net "UART_SYS_DBG_TX")
	)
	(segment
		(start 45.402246 -69.977)
		(end 44.4246 -69.977)
		(width 0.10668)
		(layer "In7.Cu")
		(net "UART_SYS_DBG_TX")
	)
	(segment
		(start 69.701156 -107.88015)
		(end 67.35064 -105.529634)
		(width 0.10668)
		(layer "In7.Cu")
		(net "UART_SYS_DBG_TX")
	)
	(segment
		(start 42.845228 -68.397628)
		(end 42.574972 -68.397628)
		(width 0.10668)
		(layer "In7.Cu")
		(net "UART_SYS_DBG_TX")
	)
	(segment
		(start 47.243492 -71.626476)
		(end 47.243492 -71.096378)
		(width 0.10668)
		(layer "In7.Cu")
		(net "UART_SYS_DBG_TX")
	)
	(segment
		(start 44.4246 -69.977)
		(end 42.845228 -68.397628)
		(width 0.10668)
		(layer "In7.Cu")
		(net "UART_SYS_DBG_TX")
	)
	(segment
		(start 47.80407 -72.10679)
		(end 47.66691 -72.049894)
		(width 0.10668)
		(layer "In7.Cu")
		(net "UART_SYS_DBG_TX")
	)
	(segment
		(start 55.753 -79.9592)
		(end 55.753 -78.81112)
		(width 0.10668)
		(layer "In7.Cu")
		(net "UART_SYS_DBG_TX")
	)
	(segment
		(start 54.66588 -77.724)
		(end 53.8988 -77.724)
		(width 0.10668)
		(layer "In7.Cu")
		(net "UART_SYS_DBG_TX")
	)
	(segment
		(start 53.5178 -77.343)
		(end 53.5178 -75.751944)
		(width 0.10668)
		(layer "In7.Cu")
		(net "UART_SYS_DBG_TX")
	)
	(segment
		(start 59.640978 -85.805264)
		(end 58.57875 -85.805264)
		(width 0.10668)
		(layer "In7.Cu")
		(net "UART_SYS_DBG_TX")
	)
	(segment
		(start 53.8988 -77.724)
		(end 53.5178 -77.343)
		(width 0.10668)
		(layer "In7.Cu")
		(net "UART_SYS_DBG_TX")
	)
	(segment
		(start 61.115956 -87.280242)
		(end 59.640978 -85.805264)
		(width 0.10668)
		(layer "In7.Cu")
		(net "UART_SYS_DBG_TX")
	)
	(segment
		(start 52.182268 -74.416412)
		(end 51.801776 -74.416412)
		(width 0.10668)
		(layer "In7.Cu")
		(net "UART_SYS_DBG_TX")
	)
	(segment
		(start 50.55616 -73.170796)
		(end 47.987458 -72.10679)
		(width 0.10668)
		(layer "In7.Cu")
		(net "UART_SYS_DBG_TX")
	)
	(segment
		(start 55.753 -78.81112)
		(end 54.66588 -77.724)
		(width 0.10668)
		(layer "In7.Cu")
		(net "UART_SYS_DBG_TX")
	)
	(segment
		(start 47.66691 -72.049894)
		(end 47.243492 -71.626476)
		(width 0.10668)
		(layer "In7.Cu")
		(net "UART_SYS_DBG_TX")
	)
	(segment
		(start 47.243492 -71.096378)
		(end 46.011338 -70.586092)
		(width 0.10668)
		(layer "In7.Cu")
		(net "UART_SYS_DBG_TX")
	)
	(segment
		(start 42.574972 -68.397628)
		(end 42.1132 -68.8594)
		(width 0.10668)
		(layer "In7.Cu")
		(net "UART_SYS_DBG_TX")
	)
	(segment
		(start 65.09766 -100.987352)
		(end 65.09766 -94.781878)
		(width 0.10668)
		(layer "In7.Cu")
		(net "UART_SYS_DBG_TX")
	)
	(segment
		(start 47.987458 -72.10679)
		(end 47.80407 -72.10679)
		(width 0.10668)
		(layer "In7.Cu")
		(net "UART_SYS_DBG_TX")
	)
	(segment
		(start 65.09766 -94.781878)
		(end 61.115956 -90.800174)
		(width 0.10668)
		(layer "In7.Cu")
		(net "UART_SYS_DBG_TX")
	)
	(segment
		(start 57.511442 -84.737956)
		(end 57.511442 -83.333082)
		(width 0.10668)
		(layer "In7.Cu")
		(net "UART_SYS_DBG_TX")
	)
	(segment
		(start 46.011338 -70.586092)
		(end 45.402246 -69.977)
		(width 0.10668)
		(layer "In7.Cu")
		(net "UART_SYS_DBG_TX")
	)
	(segment
		(start 42.1132 -68.8594)
		(end 42.1132 -69.1642)
		(width 0.10668)
		(layer "In7.Cu")
		(net "UART_SYS_DBG_TX")
	)
	(via
		(at 34.812986 -64.914272)
		(size 0.6604)
		(drill 0.3302)
		(layers "F.Cu" "B.Cu")
		(net "UART_SYS_DBG_RX_R")
	)
	(segment
		(start 34.44875 -64.040004)
		(end 34.812986 -64.40424)
		(width 0.11684)
		(layer "B.Cu")
		(net "UART_SYS_DBG_RX_R")
	)
	(segment
		(start 33.513014 -66.029332)
		(end 34.628074 -64.914272)
		(width 0.11684)
		(layer "B.Cu")
		(net "UART_SYS_DBG_RX_R")
	)
	(segment
		(start 34.44875 -63.6778)
		(end 34.44875 -64.040004)
		(width 0.11684)
		(layer "B.Cu")
		(net "UART_SYS_DBG_RX_R")
	)
	(segment
		(start 33.513014 -66.437002)
		(end 33.513014 -66.029332)
		(width 0.11684)
		(layer "B.Cu")
		(net "UART_SYS_DBG_RX_R")
	)
	(segment
		(start 34.812986 -64.40424)
		(end 34.812986 -64.914272)
		(width 0.11684)
		(layer "B.Cu")
		(net "UART_SYS_DBG_RX_R")
	)
	(segment
		(start 34.628074 -64.914272)
		(end 34.812986 -64.914272)
		(width 0.11684)
		(layer "B.Cu")
		(net "UART_SYS_DBG_RX_R")
	)
	(segment
		(start 70.7136 -108.419392)
		(end 71.5518 -109.257592)
		(width 0.11684)
		(layer "F.Cu")
		(net "UART_SYS_DBG_RX")
	)
	(segment
		(start 69.8754 -108.631228)
		(end 70.201028 -108.3056)
		(width 0.11684)
		(layer "F.Cu")
		(net "UART_SYS_DBG_RX")
	)
	(segment
		(start 71.5518 -109.257592)
		(end 71.5518 -115.8748)
		(width 0.11684)
		(layer "F.Cu")
		(net "UART_SYS_DBG_RX")
	)
	(segment
		(start 71.1962 -116.2304)
		(end 71.1962 -117.025928)
		(width 0.11684)
		(layer "F.Cu")
		(net "UART_SYS_DBG_RX")
	)
	(segment
		(start 70.7136 -108.3056)
		(end 70.7136 -108.419392)
		(width 0.11684)
		(layer "F.Cu")
		(net "UART_SYS_DBG_RX")
	)
	(segment
		(start 70.201028 -108.3056)
		(end 70.7136 -108.3056)
		(width 0.11684)
		(layer "F.Cu")
		(net "UART_SYS_DBG_RX")
	)
	(segment
		(start 71.5518 -115.8748)
		(end 71.1962 -116.2304)
		(width 0.11684)
		(layer "F.Cu")
		(net "UART_SYS_DBG_RX")
	)
	(segment
		(start 71.1962 -117.025928)
		(end 70.859904 -117.362224)
		(width 0.11684)
		(layer "F.Cu")
		(net "UART_SYS_DBG_RX")
	)
	(segment
		(start 70.859904 -117.362224)
		(end 70.859904 -118.460012)
		(width 0.11684)
		(layer "F.Cu")
		(net "UART_SYS_DBG_RX")
	)
	(via
		(at 70.7136 -108.3056)
		(size 0.762)
		(drill 0.381)
		(layers "F.Cu" "B.Cu")
		(net "UART_SYS_DBG_RX")
	)
	(via
		(at 69.8754 -108.631228)
		(size 0.508)
		(drill 0.254)
		(layers "F.Cu" "B.Cu")
		(net "UART_SYS_DBG_RX")
	)
	(via
		(at 42.85234 -69.153024)
		(size 0.508)
		(drill 0.254)
		(layers "F.Cu" "B.Cu")
		(net "UART_SYS_DBG_RX")
	)
	(segment
		(start 36.35248 -65.66408)
		(end 36.35248 -64.78143)
		(width 0.11684)
		(layer "B.Cu")
		(net "UART_SYS_DBG_RX")
	)
	(segment
		(start 37.0586 -67.6402)
		(end 37.0586 -66.3702)
		(width 0.11684)
		(layer "B.Cu")
		(net "UART_SYS_DBG_RX")
	)
	(segment
		(start 36.35248 -64.78143)
		(end 35.24885 -63.6778)
		(width 0.11684)
		(layer "B.Cu")
		(net "UART_SYS_DBG_RX")
	)
	(segment
		(start 36.48964 -68.20916)
		(end 37.0586 -67.6402)
		(width 0.11684)
		(layer "B.Cu")
		(net "UART_SYS_DBG_RX")
	)
	(segment
		(start 36.89858 -71.09968)
		(end 36.48964 -70.69074)
		(width 0.11684)
		(layer "B.Cu")
		(net "UART_SYS_DBG_RX")
	)
	(segment
		(start 40.635682 -69.070982)
		(end 38.606984 -71.09968)
		(width 0.11684)
		(layer "B.Cu")
		(net "UART_SYS_DBG_RX")
	)
	(segment
		(start 38.606984 -71.09968)
		(end 36.89858 -71.09968)
		(width 0.11684)
		(layer "B.Cu")
		(net "UART_SYS_DBG_RX")
	)
	(segment
		(start 42.85234 -69.153024)
		(end 42.770298 -69.070982)
		(width 0.11684)
		(layer "B.Cu")
		(net "UART_SYS_DBG_RX")
	)
	(segment
		(start 37.0586 -66.3702)
		(end 36.35248 -65.66408)
		(width 0.11684)
		(layer "B.Cu")
		(net "UART_SYS_DBG_RX")
	)
	(segment
		(start 36.48964 -70.69074)
		(end 36.48964 -68.20916)
		(width 0.11684)
		(layer "B.Cu")
		(net "UART_SYS_DBG_RX")
	)
	(segment
		(start 42.770298 -69.070982)
		(end 40.635682 -69.070982)
		(width 0.11684)
		(layer "B.Cu")
		(net "UART_SYS_DBG_RX")
	)
	(segment
		(start 56.48452 -82.816446)
		(end 57.150762 -83.482688)
		(width 0.10668)
		(layer "In7.Cu")
		(net "UART_SYS_DBG_RX")
	)
	(segment
		(start 43.307 -69.4944)
		(end 43.307 -70.523354)
		(width 0.10668)
		(layer "In7.Cu")
		(net "UART_SYS_DBG_RX")
	)
	(segment
		(start 58.429144 -86.165944)
		(end 59.491372 -86.165944)
		(width 0.10668)
		(layer "In7.Cu")
		(net "UART_SYS_DBG_RX")
	)
	(segment
		(start 69.165978 -108.631228)
		(end 69.8754 -108.631228)
		(width 0.10668)
		(layer "In7.Cu")
		(net "UART_SYS_DBG_RX")
	)
	(segment
		(start 47.90821 -72.46747)
		(end 50.356516 -73.481438)
		(width 0.10668)
		(layer "In7.Cu")
		(net "UART_SYS_DBG_RX")
	)
	(segment
		(start 57.150762 -84.887562)
		(end 58.429144 -86.165944)
		(width 0.10668)
		(layer "In7.Cu")
		(net "UART_SYS_DBG_RX")
	)
	(segment
		(start 69.059298 -107.748578)
		(end 69.059298 -108.524548)
		(width 0.10668)
		(layer "In7.Cu")
		(net "UART_SYS_DBG_RX")
	)
	(segment
		(start 53.15712 -78.328774)
		(end 54.660546 -79.8322)
		(width 0.10668)
		(layer "In7.Cu")
		(net "UART_SYS_DBG_RX")
	)
	(segment
		(start 66.98996 -103.389938)
		(end 66.98996 -105.67924)
		(width 0.10668)
		(layer "In7.Cu")
		(net "UART_SYS_DBG_RX")
	)
	(segment
		(start 60.755276 -87.429848)
		(end 60.755276 -91.057476)
		(width 0.10668)
		(layer "In7.Cu")
		(net "UART_SYS_DBG_RX")
	)
	(segment
		(start 47.5107 -72.40397)
		(end 47.663862 -72.46747)
		(width 0.10668)
		(layer "In7.Cu")
		(net "UART_SYS_DBG_RX")
	)
	(segment
		(start 60.755276 -91.057476)
		(end 64.73698 -95.03918)
		(width 0.10668)
		(layer "In7.Cu")
		(net "UART_SYS_DBG_RX")
	)
	(segment
		(start 45.67174 -72.03694)
		(end 47.14367 -72.03694)
		(width 0.10668)
		(layer "In7.Cu")
		(net "UART_SYS_DBG_RX")
	)
	(segment
		(start 47.14367 -72.03694)
		(end 47.5107 -72.40397)
		(width 0.10668)
		(layer "In7.Cu")
		(net "UART_SYS_DBG_RX")
	)
	(segment
		(start 53.15712 -75.90155)
		(end 53.15712 -78.328774)
		(width 0.10668)
		(layer "In7.Cu")
		(net "UART_SYS_DBG_RX")
	)
	(segment
		(start 42.85234 -69.153024)
		(end 42.947844 -69.248528)
		(width 0.10668)
		(layer "In7.Cu")
		(net "UART_SYS_DBG_RX")
	)
	(segment
		(start 55.115714 -79.8322)
		(end 56.48452 -81.201006)
		(width 0.10668)
		(layer "In7.Cu")
		(net "UART_SYS_DBG_RX")
	)
	(segment
		(start 50.356516 -73.481438)
		(end 51.65217 -74.777092)
		(width 0.10668)
		(layer "In7.Cu")
		(net "UART_SYS_DBG_RX")
	)
	(segment
		(start 43.061128 -69.248528)
		(end 43.307 -69.4944)
		(width 0.10668)
		(layer "In7.Cu")
		(net "UART_SYS_DBG_RX")
	)
	(segment
		(start 66.98996 -105.67924)
		(end 69.059298 -107.748578)
		(width 0.10668)
		(layer "In7.Cu")
		(net "UART_SYS_DBG_RX")
	)
	(segment
		(start 51.65217 -74.777092)
		(end 52.032662 -74.777092)
		(width 0.10668)
		(layer "In7.Cu")
		(net "UART_SYS_DBG_RX")
	)
	(segment
		(start 47.663862 -72.46747)
		(end 47.90821 -72.46747)
		(width 0.10668)
		(layer "In7.Cu")
		(net "UART_SYS_DBG_RX")
	)
	(segment
		(start 43.817032 -71.033386)
		(end 44.668186 -71.033386)
		(width 0.10668)
		(layer "In7.Cu")
		(net "UART_SYS_DBG_RX")
	)
	(segment
		(start 64.73698 -95.03918)
		(end 64.73698 -101.136958)
		(width 0.10668)
		(layer "In7.Cu")
		(net "UART_SYS_DBG_RX")
	)
	(segment
		(start 59.491372 -86.165944)
		(end 60.755276 -87.429848)
		(width 0.10668)
		(layer "In7.Cu")
		(net "UART_SYS_DBG_RX")
	)
	(segment
		(start 43.307 -70.523354)
		(end 43.817032 -71.033386)
		(width 0.10668)
		(layer "In7.Cu")
		(net "UART_SYS_DBG_RX")
	)
	(segment
		(start 52.032662 -74.777092)
		(end 53.15712 -75.90155)
		(width 0.10668)
		(layer "In7.Cu")
		(net "UART_SYS_DBG_RX")
	)
	(segment
		(start 54.660546 -79.8322)
		(end 55.115714 -79.8322)
		(width 0.10668)
		(layer "In7.Cu")
		(net "UART_SYS_DBG_RX")
	)
	(segment
		(start 64.73698 -101.136958)
		(end 66.98996 -103.389938)
		(width 0.10668)
		(layer "In7.Cu")
		(net "UART_SYS_DBG_RX")
	)
	(segment
		(start 42.947844 -69.248528)
		(end 43.061128 -69.248528)
		(width 0.10668)
		(layer "In7.Cu")
		(net "UART_SYS_DBG_RX")
	)
	(segment
		(start 57.150762 -83.482688)
		(end 57.150762 -84.887562)
		(width 0.10668)
		(layer "In7.Cu")
		(net "UART_SYS_DBG_RX")
	)
	(segment
		(start 69.059298 -108.524548)
		(end 69.165978 -108.631228)
		(width 0.10668)
		(layer "In7.Cu")
		(net "UART_SYS_DBG_RX")
	)
	(segment
		(start 56.48452 -81.201006)
		(end 56.48452 -82.816446)
		(width 0.10668)
		(layer "In7.Cu")
		(net "UART_SYS_DBG_RX")
	)
	(segment
		(start 44.668186 -71.033386)
		(end 45.67174 -72.03694)
		(width 0.10668)
		(layer "In7.Cu")
		(net "UART_SYS_DBG_RX")
	)
	(segment
		(start 18.545048 -114.948716)
		(end 17.304258 -111.95304)
		(width 0.11684)
		(layer "F.Cu")
		(net "TP_GF_B63")
	)
	(segment
		(start 17.304258 -109.534198)
		(end 16.24203 -108.47197)
		(width 0.11684)
		(layer "F.Cu")
		(net "TP_GF_B63")
	)
	(segment
		(start 17.304258 -111.95304)
		(end 17.304258 -109.534198)
		(width 0.11684)
		(layer "F.Cu")
		(net "TP_GF_B63")
	)
	(segment
		(start 18.545048 -118.25986)
		(end 18.545048 -114.948716)
		(width 0.11684)
		(layer "F.Cu")
		(net "TP_GF_B63")
	)
	(via
		(at 16.24203 -108.47197)
		(size 0.762)
		(drill 0.381)
		(layers "F.Cu" "B.Cu")
		(net "TP_GF_B63")
	)
	(segment
		(start 18.814288 -114.81562)
		(end 17.573498 -111.820198)
		(width 0.11684)
		(layer "F.Cu")
		(net "TP_GF_B62")
	)
	(segment
		(start 19.144996 -117.315996)
		(end 18.814288 -116.985288)
		(width 0.11684)
		(layer "F.Cu")
		(net "TP_GF_B62")
	)
	(segment
		(start 18.814288 -116.985288)
		(end 18.814288 -114.81562)
		(width 0.11684)
		(layer "F.Cu")
		(net "TP_GF_B62")
	)
	(segment
		(start 17.573498 -111.820198)
		(end 17.573498 -108.966)
		(width 0.11684)
		(layer "F.Cu")
		(net "TP_GF_B62")
	)
	(segment
		(start 19.144996 -118.25986)
		(end 19.144996 -117.315996)
		(width 0.11684)
		(layer "F.Cu")
		(net "TP_GF_B62")
	)
	(via
		(at 17.573498 -108.966)
		(size 0.762)
		(drill 0.381)
		(layers "F.Cu" "B.Cu")
		(net "TP_GF_B62")
	)
	(segment
		(start 55.295038 -57.771284)
		(end 55.690262 -58.166508)
		(width 0.11684)
		(layer "F.Cu")
		(net "TP_BMC_SPICS0_N")
	)
	(via
		(at 55.690262 -58.166508)
		(size 0.4572)
		(drill 0.254)
		(layers "F.Cu" "B.Cu")
		(net "TP_BMC_SPICS0_N")
	)
	(segment
		(start 46.504606 -53.771292)
		(end 46.494954 -53.771292)
		(width 0.11684)
		(layer "F.Cu")
		(net "SYS_BMC_PWRBTN_R1_N")
	)
	(segment
		(start 46.89983 -54.166516)
		(end 46.504606 -53.771292)
		(width 0.11684)
		(layer "F.Cu")
		(net "SYS_BMC_PWRBTN_R1_N")
	)
	(via
		(at 39.9288 -60.96)
		(size 0.508)
		(drill 0.254)
		(layers "F.Cu" "B.Cu")
		(net "SYS_BMC_PWRBTN_R1_N")
	)
	(via
		(at 46.89983 -54.166516)
		(size 0.4572)
		(drill 0.254)
		(layers "F.Cu" "B.Cu")
		(net "SYS_BMC_PWRBTN_R1_N")
	)
	(via
		(at 44.5262 -60.96)
		(size 0.508)
		(drill 0.254)
		(layers "F.Cu" "B.Cu")
		(net "SYS_BMC_PWRBTN_R1_N")
	)
	(segment
		(start 40.13581 -60.75299)
		(end 39.9288 -60.96)
		(width 0.11684)
		(layer "B.Cu")
		(net "SYS_BMC_PWRBTN_R1_N")
	)
	(segment
		(start 40.047164 -61.627766)
		(end 40.047164 -61.078364)
		(width 0.11684)
		(layer "B.Cu")
		(net "SYS_BMC_PWRBTN_R1_N")
	)
	(segment
		(start 40.047164 -61.078364)
		(end 39.9288 -60.96)
		(width 0.11684)
		(layer "B.Cu")
		(net "SYS_BMC_PWRBTN_R1_N")
	)
	(segment
		(start 40.62222 -60.75299)
		(end 40.13581 -60.75299)
		(width 0.11684)
		(layer "B.Cu")
		(net "SYS_BMC_PWRBTN_R1_N")
	)
	(segment
		(start 40.793162 -61.824362)
		(end 39.9288 -60.96)
		(width 0.08382)
		(layer "In2.Cu")
		(net "SYS_BMC_PWRBTN_R1_N")
	)
	(segment
		(start 42.904918 -61.824362)
		(end 40.793162 -61.824362)
		(width 0.08382)
		(layer "In2.Cu")
		(net "SYS_BMC_PWRBTN_R1_N")
	)
	(segment
		(start 44.5262 -60.96)
		(end 43.76928 -60.96)
		(width 0.08382)
		(layer "In2.Cu")
		(net "SYS_BMC_PWRBTN_R1_N")
	)
	(segment
		(start 43.76928 -60.96)
		(end 42.904918 -61.824362)
		(width 0.08382)
		(layer "In2.Cu")
		(net "SYS_BMC_PWRBTN_R1_N")
	)
	(segment
		(start 45.37456 -58.93562)
		(end 44.8945 -58.45556)
		(width 0.10668)
		(layer "In4.Cu")
		(net "SYS_BMC_PWRBTN_R1_N")
	)
	(segment
		(start 46.89983 -55.131716)
		(end 46.89983 -54.166516)
		(width 0.10668)
		(layer "In4.Cu")
		(net "SYS_BMC_PWRBTN_R1_N")
	)
	(segment
		(start 45.37456 -60.11164)
		(end 45.37456 -58.93562)
		(width 0.10668)
		(layer "In4.Cu")
		(net "SYS_BMC_PWRBTN_R1_N")
	)
	(segment
		(start 45.14342 -57.77738)
		(end 46.331378 -57.77738)
		(width 0.10668)
		(layer "In4.Cu")
		(net "SYS_BMC_PWRBTN_R1_N")
	)
	(segment
		(start 44.8945 -58.0263)
		(end 45.14342 -57.77738)
		(width 0.10668)
		(layer "In4.Cu")
		(net "SYS_BMC_PWRBTN_R1_N")
	)
	(segment
		(start 46.331378 -57.77738)
		(end 46.501558 -57.6072)
		(width 0.10668)
		(layer "In4.Cu")
		(net "SYS_BMC_PWRBTN_R1_N")
	)
	(segment
		(start 46.501558 -57.6072)
		(end 46.501558 -55.529988)
		(width 0.10668)
		(layer "In4.Cu")
		(net "SYS_BMC_PWRBTN_R1_N")
	)
	(segment
		(start 44.8945 -58.45556)
		(end 44.8945 -58.0263)
		(width 0.10668)
		(layer "In4.Cu")
		(net "SYS_BMC_PWRBTN_R1_N")
	)
	(segment
		(start 46.501558 -55.529988)
		(end 46.89983 -55.131716)
		(width 0.10668)
		(layer "In4.Cu")
		(net "SYS_BMC_PWRBTN_R1_N")
	)
	(segment
		(start 44.5262 -60.96)
		(end 45.37456 -60.11164)
		(width 0.10668)
		(layer "In4.Cu")
		(net "SYS_BMC_PWRBTN_R1_N")
	)
	(via
		(at 31.637986 -64.897)
		(size 0.6604)
		(drill 0.3302)
		(layers "F.Cu" "B.Cu")
		(net "SPA_SOUT_SW_DBG_R")
	)
	(segment
		(start 31.637986 -64.647064)
		(end 31.637986 -64.897)
		(width 0.11684)
		(layer "B.Cu")
		(net "SPA_SOUT_SW_DBG_R")
	)
	(segment
		(start 31.637986 -66.437002)
		(end 31.637986 -64.897)
		(width 0.11684)
		(layer "B.Cu")
		(net "SPA_SOUT_SW_DBG_R")
	)
	(segment
		(start 32.86125 -63.4238)
		(end 31.637986 -64.647064)
		(width 0.11684)
		(layer "B.Cu")
		(net "SPA_SOUT_SW_DBG_R")
	)
	(segment
		(start 26.23185 -66.31305)
		(end 26.486104 -66.567304)
		(width 0.11684)
		(layer "F.Cu")
		(net "SPA_SOUT_SW_BUF_R")
	)
	(segment
		(start 26.486104 -66.567304)
		(end 27.1272 -66.567304)
		(width 0.11684)
		(layer "F.Cu")
		(net "SPA_SOUT_SW_BUF_R")
	)
	(segment
		(start 25.781 -66.31305)
		(end 26.23185 -66.31305)
		(width 0.11684)
		(layer "F.Cu")
		(net "SPA_SOUT_SW_BUF_R")
	)
	(via
		(at 28.741878 -68.815966)
		(size 0.6604)
		(drill 0.3302)
		(layers "F.Cu" "B.Cu")
		(net "SPA_SOUT_SW_BUF_R")
	)
	(via
		(at 27.1272 -66.567304)
		(size 0.508)
		(drill 0.254)
		(layers "F.Cu" "B.Cu")
		(net "SPA_SOUT_SW_BUF_R")
	)
	(segment
		(start 30.089602 -68.961762)
		(end 30.338014 -68.71335)
		(width 0.11684)
		(layer "B.Cu")
		(net "SPA_SOUT_SW_BUF_R")
	)
	(segment
		(start 30.338014 -67.422014)
		(end 30.099 -67.183)
		(width 0.11684)
		(layer "B.Cu")
		(net "SPA_SOUT_SW_BUF_R")
	)
	(segment
		(start 30.338014 -68.71335)
		(end 30.338014 -68.436998)
		(width 0.11684)
		(layer "B.Cu")
		(net "SPA_SOUT_SW_BUF_R")
	)
	(segment
		(start 28.741878 -68.815966)
		(end 28.887674 -68.961762)
		(width 0.11684)
		(layer "B.Cu")
		(net "SPA_SOUT_SW_BUF_R")
	)
	(segment
		(start 29.6164 -67.183)
		(end 28.6258 -66.1924)
		(width 0.11684)
		(layer "B.Cu")
		(net "SPA_SOUT_SW_BUF_R")
	)
	(segment
		(start 28.6258 -66.1924)
		(end 27.502104 -66.1924)
		(width 0.11684)
		(layer "B.Cu")
		(net "SPA_SOUT_SW_BUF_R")
	)
	(segment
		(start 28.887674 -68.961762)
		(end 30.089602 -68.961762)
		(width 0.11684)
		(layer "B.Cu")
		(net "SPA_SOUT_SW_BUF_R")
	)
	(segment
		(start 30.099 -67.183)
		(end 29.6164 -67.183)
		(width 0.11684)
		(layer "B.Cu")
		(net "SPA_SOUT_SW_BUF_R")
	)
	(segment
		(start 30.338014 -68.436998)
		(end 30.338014 -67.422014)
		(width 0.11684)
		(layer "B.Cu")
		(net "SPA_SOUT_SW_BUF_R")
	)
	(segment
		(start 27.502104 -66.1924)
		(end 27.1272 -66.567304)
		(width 0.11684)
		(layer "B.Cu")
		(net "SPA_SOUT_SW_BUF_R")
	)
	(via
		(at 34.236152 -71.882)
		(size 0.6604)
		(drill 0.3302)
		(layers "F.Cu" "B.Cu")
		(net "SPA_SIN_SW_DBG_R")
	)
	(segment
		(start 33.06445 -71.882)
		(end 34.236152 -71.882)
		(width 0.11684)
		(layer "B.Cu")
		(net "SPA_SIN_SW_DBG_R")
	)
	(segment
		(start 35.3568 -71.322946)
		(end 34.797746 -71.882)
		(width 0.11684)
		(layer "B.Cu")
		(net "SPA_SIN_SW_DBG_R")
	)
	(segment
		(start 34.812986 -67.137026)
		(end 35.3568 -67.68084)
		(width 0.11684)
		(layer "B.Cu")
		(net "SPA_SIN_SW_DBG_R")
	)
	(segment
		(start 34.797746 -71.882)
		(end 34.236152 -71.882)
		(width 0.11684)
		(layer "B.Cu")
		(net "SPA_SIN_SW_DBG_R")
	)
	(segment
		(start 35.3568 -67.68084)
		(end 35.3568 -71.322946)
		(width 0.11684)
		(layer "B.Cu")
		(net "SPA_SIN_SW_DBG_R")
	)
	(segment
		(start 34.812986 -66.437002)
		(end 34.812986 -67.137026)
		(width 0.11684)
		(layer "B.Cu")
		(net "SPA_SIN_SW_DBG_R")
	)
	(via
		(at 21.340064 -65.59042)
		(size 0.508)
		(drill 0.254)
		(layers "F.Cu" "B.Cu")
		(net "SPA_SIN_SW_BUF_R")
	)
	(via
		(at 30.25267 -63.883794)
		(size 0.508)
		(drill 0.254)
		(layers "F.Cu" "B.Cu")
		(net "SPA_SIN_SW_BUF_R")
	)
	(via
		(at 33.63468 -69.547994)
		(size 0.508)
		(drill 0.254)
		(layers "F.Cu" "B.Cu")
		(net "SPA_SIN_SW_BUF_R")
	)
	(segment
		(start 21.340064 -65.59042)
		(end 20.53717 -65.59042)
		(width 0.11684)
		(layer "B.Cu")
		(net "SPA_SIN_SW_BUF_R")
	)
	(segment
		(start 20.53717 -65.59042)
		(end 20.4724 -65.52565)
		(width 0.11684)
		(layer "B.Cu")
		(net "SPA_SIN_SW_BUF_R")
	)
	(segment
		(start 33.63468 -69.54266)
		(end 33.513014 -69.420994)
		(width 0.11684)
		(layer "B.Cu")
		(net "SPA_SIN_SW_BUF_R")
	)
	(segment
		(start 33.63468 -69.547994)
		(end 33.63468 -69.54266)
		(width 0.11684)
		(layer "B.Cu")
		(net "SPA_SIN_SW_BUF_R")
	)
	(segment
		(start 33.513014 -69.420994)
		(end 33.513014 -68.436998)
		(width 0.11684)
		(layer "B.Cu")
		(net "SPA_SIN_SW_BUF_R")
	)
	(segment
		(start 25.604724 -63.676276)
		(end 23.82393 -65.45707)
		(width 0.08382)
		(layer "In2.Cu")
		(net "SPA_SIN_SW_BUF_R")
	)
	(segment
		(start 28.212034 -63.92799)
		(end 27.96032 -63.676276)
		(width 0.08382)
		(layer "In2.Cu")
		(net "SPA_SIN_SW_BUF_R")
	)
	(segment
		(start 23.82393 -65.45707)
		(end 23.82393 -65.904618)
		(width 0.08382)
		(layer "In2.Cu")
		(net "SPA_SIN_SW_BUF_R")
	)
	(segment
		(start 23.82393 -65.904618)
		(end 23.378668 -66.34988)
		(width 0.08382)
		(layer "In2.Cu")
		(net "SPA_SIN_SW_BUF_R")
	)
	(segment
		(start 23.378668 -66.34988)
		(end 22.099524 -66.34988)
		(width 0.08382)
		(layer "In2.Cu")
		(net "SPA_SIN_SW_BUF_R")
	)
	(segment
		(start 27.96032 -63.676276)
		(end 25.604724 -63.676276)
		(width 0.08382)
		(layer "In2.Cu")
		(net "SPA_SIN_SW_BUF_R")
	)
	(segment
		(start 30.208474 -63.92799)
		(end 28.212034 -63.92799)
		(width 0.08382)
		(layer "In2.Cu")
		(net "SPA_SIN_SW_BUF_R")
	)
	(segment
		(start 30.25267 -63.883794)
		(end 30.208474 -63.92799)
		(width 0.08382)
		(layer "In2.Cu")
		(net "SPA_SIN_SW_BUF_R")
	)
	(segment
		(start 22.099524 -66.34988)
		(end 21.340064 -65.59042)
		(width 0.08382)
		(layer "In2.Cu")
		(net "SPA_SIN_SW_BUF_R")
	)
	(segment
		(start 30.25267 -63.883794)
		(end 30.381194 -63.883794)
		(width 0.10668)
		(layer "In4.Cu")
		(net "SPA_SIN_SW_BUF_R")
	)
	(segment
		(start 32.168592 -68.076572)
		(end 33.63468 -69.54266)
		(width 0.10668)
		(layer "In4.Cu")
		(net "SPA_SIN_SW_BUF_R")
	)
	(segment
		(start 30.381194 -63.883794)
		(end 30.48 -63.9826)
		(width 0.10668)
		(layer "In4.Cu")
		(net "SPA_SIN_SW_BUF_R")
	)
	(segment
		(start 30.48 -63.9826)
		(end 31.3436 -63.9826)
		(width 0.10668)
		(layer "In4.Cu")
		(net "SPA_SIN_SW_BUF_R")
	)
	(segment
		(start 31.80334 -64.44234)
		(end 31.80334 -66.04508)
		(width 0.10668)
		(layer "In4.Cu")
		(net "SPA_SIN_SW_BUF_R")
	)
	(segment
		(start 33.63468 -69.54266)
		(end 33.63468 -69.547994)
		(width 0.10668)
		(layer "In4.Cu")
		(net "SPA_SIN_SW_BUF_R")
	)
	(segment
		(start 31.3436 -63.9826)
		(end 31.80334 -64.44234)
		(width 0.10668)
		(layer "In4.Cu")
		(net "SPA_SIN_SW_BUF_R")
	)
	(segment
		(start 31.80334 -66.04508)
		(end 32.168592 -66.410332)
		(width 0.10668)
		(layer "In4.Cu")
		(net "SPA_SIN_SW_BUF_R")
	)
	(segment
		(start 32.168592 -66.410332)
		(end 32.168592 -68.076572)
		(width 0.10668)
		(layer "In4.Cu")
		(net "SPA_SIN_SW_BUF_R")
	)
	(segment
		(start 45.695108 -48.171354)
		(end 45.299884 -47.77613)
		(width 0.11684)
		(layer "F.Cu")
		(net "RST_PFR_OVR_RTC_R")
	)
	(segment
		(start 22.65934 -100.12045)
		(end 22.65934 -99.58705)
		(width 0.11684)
		(layer "F.Cu")
		(net "RST_PFR_OVR_RTC_R")
	)
	(via
		(at 45.299884 -47.77613)
		(size 0.4572)
		(drill 0.254)
		(layers "F.Cu" "B.Cu")
		(net "RST_PFR_OVR_RTC_R")
	)
	(via
		(at 22.65934 -100.12045)
		(size 0.4572)
		(drill 0.254)
		(layers "F.Cu" "B.Cu")
		(net "RST_PFR_OVR_RTC_R")
	)
	(via
		(at 38.30828 -98.38055)
		(size 0.508)
		(drill 0.254)
		(layers "F.Cu" "B.Cu")
		(net "RST_PFR_OVR_RTC_R")
	)
	(segment
		(start 30.023054 -98.5774)
		(end 30.80004 -98.5774)
		(width 0.08382)
		(layer "In2.Cu")
		(net "RST_PFR_OVR_RTC_R")
	)
	(segment
		(start 31.420816 -98.320352)
		(end 32.478726 -98.320352)
		(width 0.08382)
		(layer "In2.Cu")
		(net "RST_PFR_OVR_RTC_R")
	)
	(segment
		(start 28.676854 -99.9236)
		(end 30.023054 -98.5774)
		(width 0.08382)
		(layer "In2.Cu")
		(net "RST_PFR_OVR_RTC_R")
	)
	(segment
		(start 37.252148 -97.67443)
		(end 37.958268 -98.38055)
		(width 0.08382)
		(layer "In2.Cu")
		(net "RST_PFR_OVR_RTC_R")
	)
	(segment
		(start 22.65934 -100.12045)
		(end 23.03145 -100.49256)
		(width 0.08382)
		(layer "In2.Cu")
		(net "RST_PFR_OVR_RTC_R")
	)
	(segment
		(start 37.958268 -98.38055)
		(end 38.30828 -98.38055)
		(width 0.08382)
		(layer "In2.Cu")
		(net "RST_PFR_OVR_RTC_R")
	)
	(segment
		(start 23.662386 -100.49256)
		(end 24.231346 -99.9236)
		(width 0.08382)
		(layer "In2.Cu")
		(net "RST_PFR_OVR_RTC_R")
	)
	(segment
		(start 30.80004 -98.5774)
		(end 31.420816 -98.320352)
		(width 0.08382)
		(layer "In2.Cu")
		(net "RST_PFR_OVR_RTC_R")
	)
	(segment
		(start 33.124648 -97.67443)
		(end 37.252148 -97.67443)
		(width 0.08382)
		(layer "In2.Cu")
		(net "RST_PFR_OVR_RTC_R")
	)
	(segment
		(start 24.231346 -99.9236)
		(end 28.676854 -99.9236)
		(width 0.08382)
		(layer "In2.Cu")
		(net "RST_PFR_OVR_RTC_R")
	)
	(segment
		(start 32.478726 -98.320352)
		(end 33.124648 -97.67443)
		(width 0.08382)
		(layer "In2.Cu")
		(net "RST_PFR_OVR_RTC_R")
	)
	(segment
		(start 23.03145 -100.49256)
		(end 23.662386 -100.49256)
		(width 0.08382)
		(layer "In2.Cu")
		(net "RST_PFR_OVR_RTC_R")
	)
	(segment
		(start 40.2844 -73.575418)
		(end 41.11752 -72.742298)
		(width 0.10668)
		(layer "In4.Cu")
		(net "RST_PFR_OVR_RTC_R")
	)
	(segment
		(start 39.67226 -70.490842)
		(end 39.67226 -67.793362)
		(width 0.10668)
		(layer "In4.Cu")
		(net "RST_PFR_OVR_RTC_R")
	)
	(segment
		(start 34.778696 -98.38055)
		(end 34.37128 -97.973134)
		(width 0.10668)
		(layer "In4.Cu")
		(net "RST_PFR_OVR_RTC_R")
	)
	(segment
		(start 35.941 -91.7702)
		(end 36.068 -91.7702)
		(width 0.10668)
		(layer "In4.Cu")
		(net "RST_PFR_OVR_RTC_R")
	)
	(segment
		(start 39.82974 -81.7499)
		(end 39.82974 -81.3689)
		(width 0.10668)
		(layer "In4.Cu")
		(net "RST_PFR_OVR_RTC_R")
	)
	(segment
		(start 40.19296 -55.685436)
		(end 40.19296 -55.055516)
		(width 0.10668)
		(layer "In4.Cu")
		(net "RST_PFR_OVR_RTC_R")
	)
	(segment
		(start 38.53942 -85.749638)
		(end 38.53942 -83.04022)
		(width 0.10668)
		(layer "In4.Cu")
		(net "RST_PFR_OVR_RTC_R")
	)
	(segment
		(start 37.35705 -86.932008)
		(end 38.53942 -85.749638)
		(width 0.10668)
		(layer "In4.Cu")
		(net "RST_PFR_OVR_RTC_R")
	)
	(segment
		(start 38.30828 -98.38055)
		(end 34.778696 -98.38055)
		(width 0.10668)
		(layer "In4.Cu")
		(net "RST_PFR_OVR_RTC_R")
	)
	(segment
		(start 39.304722 -76.067666)
		(end 40.2844 -75.087988)
		(width 0.10668)
		(layer "In4.Cu")
		(net "RST_PFR_OVR_RTC_R")
	)
	(segment
		(start 40.1955 -55.052976)
		(end 40.1955 -54.116224)
		(width 0.10668)
		(layer "In4.Cu")
		(net "RST_PFR_OVR_RTC_R")
	)
	(segment
		(start 41.11752 -71.936102)
		(end 39.67226 -70.490842)
		(width 0.10668)
		(layer "In4.Cu")
		(net "RST_PFR_OVR_RTC_R")
	)
	(segment
		(start 41.11752 -72.742298)
		(end 41.11752 -71.936102)
		(width 0.10668)
		(layer "In4.Cu")
		(net "RST_PFR_OVR_RTC_R")
	)
	(segment
		(start 36.068 -91.7702)
		(end 37.35705 -90.48115)
		(width 0.10668)
		(layer "In4.Cu")
		(net "RST_PFR_OVR_RTC_R")
	)
	(segment
		(start 39.690802 -63.798958)
		(end 39.690802 -62.322456)
		(width 0.10668)
		(layer "In4.Cu")
		(net "RST_PFR_OVR_RTC_R")
	)
	(segment
		(start 38.53942 -83.04022)
		(end 39.82974 -81.7499)
		(width 0.10668)
		(layer "In4.Cu")
		(net "RST_PFR_OVR_RTC_R")
	)
	(segment
		(start 34.58718 -96.32442)
		(end 34.58718 -93.12402)
		(width 0.10668)
		(layer "In4.Cu")
		(net "RST_PFR_OVR_RTC_R")
	)
	(segment
		(start 39.304722 -80.603598)
		(end 39.304722 -76.067666)
		(width 0.10668)
		(layer "In4.Cu")
		(net "RST_PFR_OVR_RTC_R")
	)
	(segment
		(start 34.37128 -96.54032)
		(end 34.58718 -96.32442)
		(width 0.10668)
		(layer "In4.Cu")
		(net "RST_PFR_OVR_RTC_R")
	)
	(segment
		(start 40.19296 -53.087016)
		(end 41.529 -51.750976)
		(width 0.10668)
		(layer "In4.Cu")
		(net "RST_PFR_OVR_RTC_R")
	)
	(segment
		(start 39.67226 -67.793362)
		(end 39.15156 -67.272662)
		(width 0.10668)
		(layer "In4.Cu")
		(net "RST_PFR_OVR_RTC_R")
	)
	(segment
		(start 39.49192 -56.386476)
		(end 40.19296 -55.685436)
		(width 0.10668)
		(layer "In4.Cu")
		(net "RST_PFR_OVR_RTC_R")
	)
	(segment
		(start 39.30396 -80.84312)
		(end 39.30396 -80.60436)
		(width 0.10668)
		(layer "In4.Cu")
		(net "RST_PFR_OVR_RTC_R")
	)
	(segment
		(start 39.15156 -64.3382)
		(end 39.690802 -63.798958)
		(width 0.10668)
		(layer "In4.Cu")
		(net "RST_PFR_OVR_RTC_R")
	)
	(segment
		(start 39.690802 -62.322456)
		(end 40.72382 -61.289438)
		(width 0.10668)
		(layer "In4.Cu")
		(net "RST_PFR_OVR_RTC_R")
	)
	(segment
		(start 37.35705 -90.48115)
		(end 37.35705 -86.932008)
		(width 0.10668)
		(layer "In4.Cu")
		(net "RST_PFR_OVR_RTC_R")
	)
	(segment
		(start 39.30396 -80.60436)
		(end 39.304722 -80.603598)
		(width 0.10668)
		(layer "In4.Cu")
		(net "RST_PFR_OVR_RTC_R")
	)
	(segment
		(start 43.1038 -48.514)
		(end 44.562014 -48.514)
		(width 0.10668)
		(layer "In4.Cu")
		(net "RST_PFR_OVR_RTC_R")
	)
	(segment
		(start 44.562014 -48.514)
		(end 45.299884 -47.77613)
		(width 0.10668)
		(layer "In4.Cu")
		(net "RST_PFR_OVR_RTC_R")
	)
	(segment
		(start 41.529 -51.750976)
		(end 41.529 -50.0888)
		(width 0.10668)
		(layer "In4.Cu")
		(net "RST_PFR_OVR_RTC_R")
	)
	(segment
		(start 40.72382 -60.518802)
		(end 40.36822 -60.163202)
		(width 0.10668)
		(layer "In4.Cu")
		(net "RST_PFR_OVR_RTC_R")
	)
	(segment
		(start 40.19296 -54.113684)
		(end 40.19296 -53.087016)
		(width 0.10668)
		(layer "In4.Cu")
		(net "RST_PFR_OVR_RTC_R")
	)
	(segment
		(start 40.19296 -55.055516)
		(end 40.1955 -55.052976)
		(width 0.10668)
		(layer "In4.Cu")
		(net "RST_PFR_OVR_RTC_R")
	)
	(segment
		(start 34.37128 -97.973134)
		(end 34.37128 -96.54032)
		(width 0.10668)
		(layer "In4.Cu")
		(net "RST_PFR_OVR_RTC_R")
	)
	(segment
		(start 41.529 -50.0888)
		(end 43.1038 -48.514)
		(width 0.10668)
		(layer "In4.Cu")
		(net "RST_PFR_OVR_RTC_R")
	)
	(segment
		(start 39.82974 -81.3689)
		(end 39.30396 -80.84312)
		(width 0.10668)
		(layer "In4.Cu")
		(net "RST_PFR_OVR_RTC_R")
	)
	(segment
		(start 34.58718 -93.12402)
		(end 35.941 -91.7702)
		(width 0.10668)
		(layer "In4.Cu")
		(net "RST_PFR_OVR_RTC_R")
	)
	(segment
		(start 40.72382 -61.289438)
		(end 40.72382 -60.518802)
		(width 0.10668)
		(layer "In4.Cu")
		(net "RST_PFR_OVR_RTC_R")
	)
	(segment
		(start 40.2844 -75.087988)
		(end 40.2844 -73.575418)
		(width 0.10668)
		(layer "In4.Cu")
		(net "RST_PFR_OVR_RTC_R")
	)
	(segment
		(start 40.36822 -59.284362)
		(end 39.49192 -58.408062)
		(width 0.10668)
		(layer "In4.Cu")
		(net "RST_PFR_OVR_RTC_R")
	)
	(segment
		(start 39.15156 -67.272662)
		(end 39.15156 -64.3382)
		(width 0.10668)
		(layer "In4.Cu")
		(net "RST_PFR_OVR_RTC_R")
	)
	(segment
		(start 39.49192 -58.408062)
		(end 39.49192 -56.386476)
		(width 0.10668)
		(layer "In4.Cu")
		(net "RST_PFR_OVR_RTC_R")
	)
	(segment
		(start 40.36822 -60.163202)
		(end 40.36822 -59.284362)
		(width 0.10668)
		(layer "In4.Cu")
		(net "RST_PFR_OVR_RTC_R")
	)
	(segment
		(start 40.1955 -54.116224)
		(end 40.19296 -54.113684)
		(width 0.10668)
		(layer "In4.Cu")
		(net "RST_PFR_OVR_RTC_R")
	)
	(segment
		(start 65.024 -14.732)
		(end 65.024 -14.224)
		(width 0.11684)
		(layer "F.Cu")
		(net "PU_J13_P1")
	)
	(segment
		(start 67.287902 -15.113)
		(end 65.405 -15.113)
		(width 0.11684)
		(layer "F.Cu")
		(net "PU_J13_P1")
	)
	(segment
		(start 65.405 -15.113)
		(end 65.024 -14.732)
		(width 0.11684)
		(layer "F.Cu")
		(net "PU_J13_P1")
	)
	(via
		(at 65.024 -14.224)
		(size 0.508)
		(drill 0.254)
		(layers "F.Cu" "B.Cu")
		(net "PU_J13_P1")
	)
	(segment
		(start 65.04305 -14.20495)
		(end 65.024 -14.224)
		(width 0.11684)
		(layer "B.Cu")
		(net "PU_J13_P1")
	)
	(segment
		(start 65.04305 -13.081)
		(end 65.04305 -14.20495)
		(width 0.11684)
		(layer "B.Cu")
		(net "PU_J13_P1")
	)
	(segment
		(start 14.8336 -114.039396)
		(end 14.484604 -113.6904)
		(width 0.11684)
		(layer "F.Cu")
		(net "PCH_BEEP_R_LED")
	)
	(segment
		(start 14.963648 -118.241318)
		(end 14.963648 -114.633502)
		(width 0.11684)
		(layer "F.Cu")
		(net "PCH_BEEP_R_LED")
	)
	(segment
		(start 14.8336 -114.503454)
		(end 14.8336 -114.039396)
		(width 0.11684)
		(layer "F.Cu")
		(net "PCH_BEEP_R_LED")
	)
	(segment
		(start 14.963648 -114.633502)
		(end 14.8336 -114.503454)
		(width 0.11684)
		(layer "F.Cu")
		(net "PCH_BEEP_R_LED")
	)
	(segment
		(start 14.484604 -113.6904)
		(end 14.351 -113.6904)
		(width 0.11684)
		(layer "F.Cu")
		(net "PCH_BEEP_R_LED")
	)
	(segment
		(start 14.945106 -118.25986)
		(end 14.963648 -118.241318)
		(width 0.11684)
		(layer "F.Cu")
		(net "PCH_BEEP_R_LED")
	)
	(via
		(at 11.5062 -108.3056)
		(size 0.6604)
		(drill 0.3302)
		(layers "F.Cu" "B.Cu")
		(net "PCH_BEEP_R_LED")
	)
	(via
		(at 14.351 -113.6904)
		(size 0.508)
		(drill 0.254)
		(layers "F.Cu" "B.Cu")
		(net "PCH_BEEP_R_LED")
	)
	(segment
		(start 10.2616 -107.4166)
		(end 11.1506 -108.3056)
		(width 0.11684)
		(layer "B.Cu")
		(net "PCH_BEEP_R_LED")
	)
	(segment
		(start 10.2616 -106.77525)
		(end 10.2616 -107.4166)
		(width 0.11684)
		(layer "B.Cu")
		(net "PCH_BEEP_R_LED")
	)
	(segment
		(start 11.5062 -108.3056)
		(end 11.5062 -108.6612)
		(width 0.11684)
		(layer "B.Cu")
		(net "PCH_BEEP_R_LED")
	)
	(segment
		(start 11.5062 -108.6612)
		(end 14.351 -111.506)
		(width 0.11684)
		(layer "B.Cu")
		(net "PCH_BEEP_R_LED")
	)
	(segment
		(start 11.1506 -108.3056)
		(end 11.5062 -108.3056)
		(width 0.11684)
		(layer "B.Cu")
		(net "PCH_BEEP_R_LED")
	)
	(segment
		(start 14.351 -111.506)
		(end 14.351 -113.6904)
		(width 0.11684)
		(layer "B.Cu")
		(net "PCH_BEEP_R_LED")
	)
	(segment
		(start 23.054564 -97.582228)
		(end 22.65934 -97.187004)
		(width 0.11684)
		(layer "F.Cu")
		(net "IRQ_SML0_ALERT_R_N")
	)
	(segment
		(start 46.494954 -43.371262)
		(end 46.09973 -42.976038)
		(width 0.11684)
		(layer "F.Cu")
		(net "IRQ_SML0_ALERT_R_N")
	)
	(via
		(at 23.054564 -97.582228)
		(size 0.4572)
		(drill 0.254)
		(layers "F.Cu" "B.Cu")
		(net "IRQ_SML0_ALERT_R_N")
	)
	(via
		(at 44.2976 -63.991744)
		(size 0.508)
		(drill 0.254)
		(layers "F.Cu" "B.Cu")
		(net "IRQ_SML0_ALERT_R_N")
	)
	(via
		(at 46.09973 -42.976038)
		(size 0.4572)
		(drill 0.254)
		(layers "F.Cu" "B.Cu")
		(net "IRQ_SML0_ALERT_R_N")
	)
	(segment
		(start 42.91076 -49.88687)
		(end 42.91076 -48.47844)
		(width 0.10668)
		(layer "In7.Cu")
		(net "IRQ_SML0_ALERT_R_N")
	)
	(segment
		(start 44.7548 -55.11038)
		(end 44.07662 -54.4322)
		(width 0.10668)
		(layer "In7.Cu")
		(net "IRQ_SML0_ALERT_R_N")
	)
	(segment
		(start 44.7548 -55.8546)
		(end 44.7548 -55.11038)
		(width 0.10668)
		(layer "In7.Cu")
		(net "IRQ_SML0_ALERT_R_N")
	)
	(segment
		(start 45.6946 -45.1358)
		(end 45.6946 -43.381168)
		(width 0.10668)
		(layer "In7.Cu")
		(net "IRQ_SML0_ALERT_R_N")
	)
	(segment
		(start 43.7642 -63.458344)
		(end 43.7642 -58.2676)
		(width 0.10668)
		(layer "In7.Cu")
		(net "IRQ_SML0_ALERT_R_N")
	)
	(segment
		(start 44.6024 -56.007)
		(end 44.7548 -55.8546)
		(width 0.10668)
		(layer "In7.Cu")
		(net "IRQ_SML0_ALERT_R_N")
	)
	(segment
		(start 43.212004 -51.574954)
		(end 43.212004 -50.188114)
		(width 0.10668)
		(layer "In7.Cu")
		(net "IRQ_SML0_ALERT_R_N")
	)
	(segment
		(start 42.91076 -48.47844)
		(end 43.4848 -47.9044)
		(width 0.10668)
		(layer "In7.Cu")
		(net "IRQ_SML0_ALERT_R_N")
	)
	(segment
		(start 43.7642 -58.2676)
		(end 44.6024 -57.4294)
		(width 0.10668)
		(layer "In7.Cu")
		(net "IRQ_SML0_ALERT_R_N")
	)
	(segment
		(start 43.225212 -51.606958)
		(end 43.212004 -51.574954)
		(width 0.10668)
		(layer "In7.Cu")
		(net "IRQ_SML0_ALERT_R_N")
	)
	(segment
		(start 43.4848 -47.3456)
		(end 45.6946 -45.1358)
		(width 0.10668)
		(layer "In7.Cu")
		(net "IRQ_SML0_ALERT_R_N")
	)
	(segment
		(start 44.07662 -54.4322)
		(end 44.07662 -54.204362)
		(width 0.10668)
		(layer "In7.Cu")
		(net "IRQ_SML0_ALERT_R_N")
	)
	(segment
		(start 44.2976 -63.991744)
		(end 43.7642 -63.458344)
		(width 0.10668)
		(layer "In7.Cu")
		(net "IRQ_SML0_ALERT_R_N")
	)
	(segment
		(start 44.6024 -57.4294)
		(end 44.6024 -56.007)
		(width 0.10668)
		(layer "In7.Cu")
		(net "IRQ_SML0_ALERT_R_N")
	)
	(segment
		(start 43.212004 -50.188114)
		(end 42.91076 -49.88687)
		(width 0.10668)
		(layer "In7.Cu")
		(net "IRQ_SML0_ALERT_R_N")
	)
	(segment
		(start 45.6946 -43.381168)
		(end 46.09973 -42.976038)
		(width 0.10668)
		(layer "In7.Cu")
		(net "IRQ_SML0_ALERT_R_N")
	)
	(segment
		(start 43.4848 -47.9044)
		(end 43.4848 -47.3456)
		(width 0.10668)
		(layer "In7.Cu")
		(net "IRQ_SML0_ALERT_R_N")
	)
	(segment
		(start 44.07662 -54.204362)
		(end 43.225212 -53.352954)
		(width 0.10668)
		(layer "In7.Cu")
		(net "IRQ_SML0_ALERT_R_N")
	)
	(segment
		(start 43.225212 -53.352954)
		(end 43.225212 -51.606958)
		(width 0.10668)
		(layer "In7.Cu")
		(net "IRQ_SML0_ALERT_R_N")
	)
	(segment
		(start 33.16859 -88.62441)
		(end 33.655 -88.138)
		(width 0.08382)
		(layer "In9.Cu")
		(net "IRQ_SML0_ALERT_R_N")
	)
	(segment
		(start 44.128182 -68.0212)
		(end 44.128182 -68.020946)
		(width 0.08382)
		(layer "In9.Cu")
		(net "IRQ_SML0_ALERT_R_N")
	)
	(segment
		(start 29.792676 -98.1456)
		(end 30.551628 -97.386648)
		(width 0.08382)
		(layer "In9.Cu")
		(net "IRQ_SML0_ALERT_R_N")
	)
	(segment
		(start 33.02127 -90.793824)
		(end 33.16859 -90.646504)
		(width 0.08382)
		(layer "In9.Cu")
		(net "IRQ_SML0_ALERT_R_N")
	)
	(segment
		(start 33.01111 -96.731582)
		(end 32.324548 -96.04502)
		(width 0.08382)
		(layer "In9.Cu")
		(net "IRQ_SML0_ALERT_R_N")
	)
	(segment
		(start 44.958 -67.191128)
		(end 44.958 -64.652144)
		(width 0.08382)
		(layer "In9.Cu")
		(net "IRQ_SML0_ALERT_R_N")
	)
	(segment
		(start 44.128182 -68.020946)
		(end 44.958 -67.191128)
		(width 0.08382)
		(layer "In9.Cu")
		(net "IRQ_SML0_ALERT_R_N")
	)
	(segment
		(start 33.25749 -92.812616)
		(end 33.02127 -92.576396)
		(width 0.08382)
		(layer "In9.Cu")
		(net "IRQ_SML0_ALERT_R_N")
	)
	(segment
		(start 35.01771 -85.30209)
		(end 35.01771 -82.99577)
		(width 0.08382)
		(layer "In9.Cu")
		(net "IRQ_SML0_ALERT_R_N")
	)
	(segment
		(start 35.2044 -78.641956)
		(end 35.792156 -78.0542)
		(width 0.08382)
		(layer "In9.Cu")
		(net "IRQ_SML0_ALERT_R_N")
	)
	(segment
		(start 27.711146 -98.1456)
		(end 29.792676 -98.1456)
		(width 0.08382)
		(layer "In9.Cu")
		(net "IRQ_SML0_ALERT_R_N")
	)
	(segment
		(start 26.771346 -97.2058)
		(end 27.711146 -98.1456)
		(width 0.08382)
		(layer "In9.Cu")
		(net "IRQ_SML0_ALERT_R_N")
	)
	(segment
		(start 32.60217 -98.1456)
		(end 33.01111 -97.73666)
		(width 0.08382)
		(layer "In9.Cu")
		(net "IRQ_SML0_ALERT_R_N")
	)
	(segment
		(start 43.907964 -69.24548)
		(end 43.907964 -68.241418)
		(width 0.08382)
		(layer "In9.Cu")
		(net "IRQ_SML0_ALERT_R_N")
	)
	(segment
		(start 40.46982 -73.986644)
		(end 43.43273 -71.023734)
		(width 0.08382)
		(layer "In9.Cu")
		(net "IRQ_SML0_ALERT_R_N")
	)
	(segment
		(start 43.43273 -70.392544)
		(end 43.907964 -69.24548)
		(width 0.08382)
		(layer "In9.Cu")
		(net "IRQ_SML0_ALERT_R_N")
	)
	(segment
		(start 43.43273 -71.023734)
		(end 43.43273 -70.392544)
		(width 0.08382)
		(layer "In9.Cu")
		(net "IRQ_SML0_ALERT_R_N")
	)
	(segment
		(start 32.324548 -95.127318)
		(end 33.25749 -94.194376)
		(width 0.08382)
		(layer "In9.Cu")
		(net "IRQ_SML0_ALERT_R_N")
	)
	(segment
		(start 33.02127 -92.576396)
		(end 33.02127 -90.793824)
		(width 0.08382)
		(layer "In9.Cu")
		(net "IRQ_SML0_ALERT_R_N")
	)
	(segment
		(start 44.958 -64.652144)
		(end 44.2976 -63.991744)
		(width 0.08382)
		(layer "In9.Cu")
		(net "IRQ_SML0_ALERT_R_N")
	)
	(segment
		(start 34.6456 -85.6742)
		(end 35.01771 -85.30209)
		(width 0.08382)
		(layer "In9.Cu")
		(net "IRQ_SML0_ALERT_R_N")
	)
	(segment
		(start 31.66999 -98.1456)
		(end 32.60217 -98.1456)
		(width 0.08382)
		(layer "In9.Cu")
		(net "IRQ_SML0_ALERT_R_N")
	)
	(segment
		(start 34.22904 -85.6742)
		(end 34.6456 -85.6742)
		(width 0.08382)
		(layer "In9.Cu")
		(net "IRQ_SML0_ALERT_R_N")
	)
	(segment
		(start 39.51097 -76.89723)
		(end 39.51097 -76.17587)
		(width 0.08382)
		(layer "In9.Cu")
		(net "IRQ_SML0_ALERT_R_N")
	)
	(segment
		(start 30.911038 -97.386648)
		(end 31.66999 -98.1456)
		(width 0.08382)
		(layer "In9.Cu")
		(net "IRQ_SML0_ALERT_R_N")
	)
	(segment
		(start 33.655 -86.24824)
		(end 34.22904 -85.6742)
		(width 0.08382)
		(layer "In9.Cu")
		(net "IRQ_SML0_ALERT_R_N")
	)
	(segment
		(start 33.655 -88.138)
		(end 33.655 -86.24824)
		(width 0.08382)
		(layer "In9.Cu")
		(net "IRQ_SML0_ALERT_R_N")
	)
	(segment
		(start 43.907964 -68.241418)
		(end 44.128182 -68.0212)
		(width 0.08382)
		(layer "In9.Cu")
		(net "IRQ_SML0_ALERT_R_N")
	)
	(segment
		(start 40.46982 -75.21702)
		(end 40.46982 -73.986644)
		(width 0.08382)
		(layer "In9.Cu")
		(net "IRQ_SML0_ALERT_R_N")
	)
	(segment
		(start 30.551628 -97.386648)
		(end 30.911038 -97.386648)
		(width 0.08382)
		(layer "In9.Cu")
		(net "IRQ_SML0_ALERT_R_N")
	)
	(segment
		(start 35.2044 -82.80908)
		(end 35.2044 -78.641956)
		(width 0.08382)
		(layer "In9.Cu")
		(net "IRQ_SML0_ALERT_R_N")
	)
	(segment
		(start 38.354 -78.0542)
		(end 39.51097 -76.89723)
		(width 0.08382)
		(layer "In9.Cu")
		(net "IRQ_SML0_ALERT_R_N")
	)
	(segment
		(start 35.792156 -78.0542)
		(end 38.354 -78.0542)
		(width 0.08382)
		(layer "In9.Cu")
		(net "IRQ_SML0_ALERT_R_N")
	)
	(segment
		(start 39.51097 -76.17587)
		(end 40.46982 -75.21702)
		(width 0.08382)
		(layer "In9.Cu")
		(net "IRQ_SML0_ALERT_R_N")
	)
	(segment
		(start 23.430992 -97.2058)
		(end 26.771346 -97.2058)
		(width 0.08382)
		(layer "In9.Cu")
		(net "IRQ_SML0_ALERT_R_N")
	)
	(segment
		(start 33.01111 -97.73666)
		(end 33.01111 -96.731582)
		(width 0.08382)
		(layer "In9.Cu")
		(net "IRQ_SML0_ALERT_R_N")
	)
	(segment
		(start 33.16859 -90.646504)
		(end 33.16859 -88.62441)
		(width 0.08382)
		(layer "In9.Cu")
		(net "IRQ_SML0_ALERT_R_N")
	)
	(segment
		(start 33.25749 -94.194376)
		(end 33.25749 -92.812616)
		(width 0.08382)
		(layer "In9.Cu")
		(net "IRQ_SML0_ALERT_R_N")
	)
	(segment
		(start 23.054564 -97.582228)
		(end 23.430992 -97.2058)
		(width 0.08382)
		(layer "In9.Cu")
		(net "IRQ_SML0_ALERT_R_N")
	)
	(segment
		(start 32.324548 -96.04502)
		(end 32.324548 -95.127318)
		(width 0.08382)
		(layer "In9.Cu")
		(net "IRQ_SML0_ALERT_R_N")
	)
	(segment
		(start 35.01771 -82.99577)
		(end 35.2044 -82.80908)
		(width 0.08382)
		(layer "In9.Cu")
		(net "IRQ_SML0_ALERT_R_N")
	)
	(segment
		(start 12.7508 -110.567724)
		(end 12.3444 -110.161324)
		(width 0.11684)
		(layer "F.Cu")
		(net "HDD_LED_R_N")
	)
	(segment
		(start 12.8778 -111.5314)
		(end 12.7508 -111.4044)
		(width 0.11684)
		(layer "F.Cu")
		(net "HDD_LED_R_N")
	)
	(segment
		(start 12.7508 -111.4044)
		(end 12.7508 -110.567724)
		(width 0.11684)
		(layer "F.Cu")
		(net "HDD_LED_R_N")
	)
	(segment
		(start 15.545054 -118.25986)
		(end 15.545054 -114.782854)
		(width 0.11684)
		(layer "F.Cu")
		(net "HDD_LED_R_N")
	)
	(segment
		(start 15.545054 -114.782854)
		(end 15.2654 -114.5032)
		(width 0.11684)
		(layer "F.Cu")
		(net "HDD_LED_R_N")
	)
	(segment
		(start 12.3444 -110.161324)
		(end 12.3444 -109.74705)
		(width 0.11684)
		(layer "F.Cu")
		(net "HDD_LED_R_N")
	)
	(segment
		(start 15.2654 -113.919)
		(end 12.8778 -111.5314)
		(width 0.11684)
		(layer "F.Cu")
		(net "HDD_LED_R_N")
	)
	(segment
		(start 15.2654 -114.5032)
		(end 15.2654 -113.919)
		(width 0.11684)
		(layer "F.Cu")
		(net "HDD_LED_R_N")
	)
	(via
		(at 12.8778 -111.5314)
		(size 0.762)
		(drill 0.381)
		(layers "F.Cu" "B.Cu")
		(net "HDD_LED_R_N")
	)
	(segment
		(start 43.903138 -56.171338)
		(end 43.7896 -56.0578)
		(width 0.11684)
		(layer "F.Cu")
		(net "GPU_WP_HW_CTRL_R_N")
	)
	(segment
		(start 23.054564 -98.382328)
		(end 22.65934 -97.987104)
		(width 0.11684)
		(layer "F.Cu")
		(net "GPU_WP_HW_CTRL_R_N")
	)
	(segment
		(start 44.895008 -56.171338)
		(end 43.903138 -56.171338)
		(width 0.11684)
		(layer "F.Cu")
		(net "GPU_WP_HW_CTRL_R_N")
	)
	(via
		(at 40.1828 -96.8756)
		(size 0.508)
		(drill 0.254)
		(layers "F.Cu" "B.Cu")
		(net "GPU_WP_HW_CTRL_R_N")
	)
	(via
		(at 23.054564 -98.382328)
		(size 0.4572)
		(drill 0.254)
		(layers "F.Cu" "B.Cu")
		(net "GPU_WP_HW_CTRL_R_N")
	)
	(via
		(at 43.7896 -56.0578)
		(size 0.508)
		(drill 0.254)
		(layers "F.Cu" "B.Cu")
		(net "GPU_WP_HW_CTRL_R_N")
	)
	(segment
		(start 23.058374 -98.382328)
		(end 23.435056 -98.75901)
		(width 0.08382)
		(layer "In2.Cu")
		(net "GPU_WP_HW_CTRL_R_N")
	)
	(segment
		(start 30.067504 -95.95358)
		(end 31.237936 -95.95358)
		(width 0.08382)
		(layer "In2.Cu")
		(net "GPU_WP_HW_CTRL_R_N")
	)
	(segment
		(start 39.08171 -95.36938)
		(end 39.3192 -95.13189)
		(width 0.08382)
		(layer "In2.Cu")
		(net "GPU_WP_HW_CTRL_R_N")
	)
	(segment
		(start 40.1828 -95.391478)
		(end 40.1828 -96.8756)
		(width 0.08382)
		(layer "In2.Cu")
		(net "GPU_WP_HW_CTRL_R_N")
	)
	(segment
		(start 23.435056 -98.75901)
		(end 27.262074 -98.75901)
		(width 0.08382)
		(layer "In2.Cu")
		(net "GPU_WP_HW_CTRL_R_N")
	)
	(segment
		(start 27.262074 -98.75901)
		(end 30.067504 -95.95358)
		(width 0.08382)
		(layer "In2.Cu")
		(net "GPU_WP_HW_CTRL_R_N")
	)
	(segment
		(start 31.237936 -95.95358)
		(end 32.743648 -96.57715)
		(width 0.08382)
		(layer "In2.Cu")
		(net "GPU_WP_HW_CTRL_R_N")
	)
	(segment
		(start 23.054564 -98.382328)
		(end 23.058374 -98.382328)
		(width 0.08382)
		(layer "In2.Cu")
		(net "GPU_WP_HW_CTRL_R_N")
	)
	(segment
		(start 39.3192 -95.13189)
		(end 39.923212 -95.13189)
		(width 0.08382)
		(layer "In2.Cu")
		(net "GPU_WP_HW_CTRL_R_N")
	)
	(segment
		(start 39.08171 -96.299528)
		(end 39.08171 -95.36938)
		(width 0.08382)
		(layer "In2.Cu")
		(net "GPU_WP_HW_CTRL_R_N")
	)
	(segment
		(start 39.923212 -95.13189)
		(end 40.1828 -95.391478)
		(width 0.08382)
		(layer "In2.Cu")
		(net "GPU_WP_HW_CTRL_R_N")
	)
	(segment
		(start 38.819328 -96.56191)
		(end 39.08171 -96.299528)
		(width 0.08382)
		(layer "In2.Cu")
		(net "GPU_WP_HW_CTRL_R_N")
	)
	(segment
		(start 36.925504 -96.57715)
		(end 36.940744 -96.56191)
		(width 0.08382)
		(layer "In2.Cu")
		(net "GPU_WP_HW_CTRL_R_N")
	)
	(segment
		(start 36.940744 -96.56191)
		(end 38.819328 -96.56191)
		(width 0.08382)
		(layer "In2.Cu")
		(net "GPU_WP_HW_CTRL_R_N")
	)
	(segment
		(start 32.743648 -96.57715)
		(end 36.925504 -96.57715)
		(width 0.08382)
		(layer "In2.Cu")
		(net "GPU_WP_HW_CTRL_R_N")
	)
	(segment
		(start 42.23004 -75.70851)
		(end 42.23004 -77.44587)
		(width 0.10668)
		(layer "In4.Cu")
		(net "GPU_WP_HW_CTRL_R_N")
	)
	(segment
		(start 40.4876 -96.8756)
		(end 40.1828 -96.8756)
		(width 0.10668)
		(layer "In4.Cu")
		(net "GPU_WP_HW_CTRL_R_N")
	)
	(segment
		(start 42.6212 -89.7128)
		(end 42.6212 -94.742)
		(width 0.10668)
		(layer "In4.Cu")
		(net "GPU_WP_HW_CTRL_R_N")
	)
	(segment
		(start 42.18178 -79.163926)
		(end 42.545 -79.527146)
		(width 0.10668)
		(layer "In4.Cu")
		(net "GPU_WP_HW_CTRL_R_N")
	)
	(segment
		(start 43.42638 -56.953658)
		(end 43.42638 -57.193434)
		(width 0.10668)
		(layer "In4.Cu")
		(net "GPU_WP_HW_CTRL_R_N")
	)
	(segment
		(start 43.1419 -66.230754)
		(end 43.124628 -66.248026)
		(width 0.10668)
		(layer "In4.Cu")
		(net "GPU_WP_HW_CTRL_R_N")
	)
	(segment
		(start 42.18178 -77.49413)
		(end 42.18178 -79.163926)
		(width 0.10668)
		(layer "In4.Cu")
		(net "GPU_WP_HW_CTRL_R_N")
	)
	(segment
		(start 43.03268 -74.402442)
		(end 43.027854 -74.407268)
		(width 0.10668)
		(layer "In4.Cu")
		(net "GPU_WP_HW_CTRL_R_N")
	)
	(segment
		(start 43.7896 -56.590438)
		(end 43.42638 -56.953658)
		(width 0.10668)
		(layer "In4.Cu")
		(net "GPU_WP_HW_CTRL_R_N")
	)
	(segment
		(start 43.3324 -70.959218)
		(end 43.03268 -71.258938)
		(width 0.10668)
		(layer "In4.Cu")
		(net "GPU_WP_HW_CTRL_R_N")
	)
	(segment
		(start 42.6212 -94.742)
		(end 40.4876 -96.8756)
		(width 0.10668)
		(layer "In4.Cu")
		(net "GPU_WP_HW_CTRL_R_N")
	)
	(segment
		(start 43.7896 -56.0578)
		(end 43.7896 -56.590438)
		(width 0.10668)
		(layer "In4.Cu")
		(net "GPU_WP_HW_CTRL_R_N")
	)
	(segment
		(start 42.3164 -80.659224)
		(end 42.3164 -89.408)
		(width 0.10668)
		(layer "In4.Cu")
		(net "GPU_WP_HW_CTRL_R_N")
	)
	(segment
		(start 42.545 -79.527146)
		(end 42.545 -80.430624)
		(width 0.10668)
		(layer "In4.Cu")
		(net "GPU_WP_HW_CTRL_R_N")
	)
	(segment
		(start 43.124628 -67.249802)
		(end 43.3324 -67.457574)
		(width 0.10668)
		(layer "In4.Cu")
		(net "GPU_WP_HW_CTRL_R_N")
	)
	(segment
		(start 43.03268 -71.258938)
		(end 43.03268 -74.402442)
		(width 0.10668)
		(layer "In4.Cu")
		(net "GPU_WP_HW_CTRL_R_N")
	)
	(segment
		(start 42.23004 -77.44587)
		(end 42.18178 -77.49413)
		(width 0.10668)
		(layer "In4.Cu")
		(net "GPU_WP_HW_CTRL_R_N")
	)
	(segment
		(start 43.42638 -57.193434)
		(end 43.1419 -57.882536)
		(width 0.10668)
		(layer "In4.Cu")
		(net "GPU_WP_HW_CTRL_R_N")
	)
	(segment
		(start 43.027854 -74.407268)
		(end 43.027854 -74.910696)
		(width 0.10668)
		(layer "In4.Cu")
		(net "GPU_WP_HW_CTRL_R_N")
	)
	(segment
		(start 43.027854 -74.910696)
		(end 42.23004 -75.70851)
		(width 0.10668)
		(layer "In4.Cu")
		(net "GPU_WP_HW_CTRL_R_N")
	)
	(segment
		(start 42.545 -80.430624)
		(end 42.3164 -80.659224)
		(width 0.10668)
		(layer "In4.Cu")
		(net "GPU_WP_HW_CTRL_R_N")
	)
	(segment
		(start 43.3324 -67.457574)
		(end 43.3324 -70.959218)
		(width 0.10668)
		(layer "In4.Cu")
		(net "GPU_WP_HW_CTRL_R_N")
	)
	(segment
		(start 43.124628 -66.248026)
		(end 43.124628 -67.249802)
		(width 0.10668)
		(layer "In4.Cu")
		(net "GPU_WP_HW_CTRL_R_N")
	)
	(segment
		(start 42.3164 -89.408)
		(end 42.6212 -89.7128)
		(width 0.10668)
		(layer "In4.Cu")
		(net "GPU_WP_HW_CTRL_R_N")
	)
	(segment
		(start 43.1419 -57.882536)
		(end 43.1419 -66.230754)
		(width 0.10668)
		(layer "In4.Cu")
		(net "GPU_WP_HW_CTRL_R_N")
	)
	(segment
		(start 23.054564 -99.182174)
		(end 22.65934 -98.78695)
		(width 0.11684)
		(layer "F.Cu")
		(net "GPU_NVS_PWR_BRAKE_R_N")
	)
	(segment
		(start 46.494954 -54.571138)
		(end 46.09973 -54.966362)
		(width 0.11684)
		(layer "F.Cu")
		(net "GPU_NVS_PWR_BRAKE_R_N")
	)
	(via
		(at 42.037 -59.9694)
		(size 0.508)
		(drill 0.254)
		(layers "F.Cu" "B.Cu")
		(net "GPU_NVS_PWR_BRAKE_R_N")
	)
	(via
		(at 38.735 -97.1804)
		(size 0.508)
		(drill 0.254)
		(layers "F.Cu" "B.Cu")
		(net "GPU_NVS_PWR_BRAKE_R_N")
	)
	(via
		(at 23.054564 -99.182174)
		(size 0.4572)
		(drill 0.254)
		(layers "F.Cu" "B.Cu")
		(net "GPU_NVS_PWR_BRAKE_R_N")
	)
	(via
		(at 46.09973 -54.966362)
		(size 0.4572)
		(drill 0.254)
		(layers "F.Cu" "B.Cu")
		(net "GPU_NVS_PWR_BRAKE_R_N")
	)
	(segment
		(start 30.3276 -96.4946)
		(end 30.6324 -96.1898)
		(width 0.08382)
		(layer "In2.Cu")
		(net "GPU_NVS_PWR_BRAKE_R_N")
	)
	(segment
		(start 30.3276 -97.0026)
		(end 30.3276 -96.4946)
		(width 0.08382)
		(layer "In2.Cu")
		(net "GPU_NVS_PWR_BRAKE_R_N")
	)
	(segment
		(start 31.190946 -96.1898)
		(end 32.696404 -96.81337)
		(width 0.08382)
		(layer "In2.Cu")
		(net "GPU_NVS_PWR_BRAKE_R_N")
	)
	(segment
		(start 38.36797 -96.81337)
		(end 38.735 -97.1804)
		(width 0.08382)
		(layer "In2.Cu")
		(net "GPU_NVS_PWR_BRAKE_R_N")
	)
	(segment
		(start 30.6324 -96.1898)
		(end 31.190946 -96.1898)
		(width 0.08382)
		(layer "In2.Cu")
		(net "GPU_NVS_PWR_BRAKE_R_N")
	)
	(segment
		(start 23.054564 -99.182174)
		(end 23.252938 -98.9838)
		(width 0.08382)
		(layer "In2.Cu")
		(net "GPU_NVS_PWR_BRAKE_R_N")
	)
	(segment
		(start 23.252938 -98.9838)
		(end 28.3464 -98.9838)
		(width 0.08382)
		(layer "In2.Cu")
		(net "GPU_NVS_PWR_BRAKE_R_N")
	)
	(segment
		(start 28.3464 -98.9838)
		(end 30.3276 -97.0026)
		(width 0.08382)
		(layer "In2.Cu")
		(net "GPU_NVS_PWR_BRAKE_R_N")
	)
	(segment
		(start 32.696404 -96.81337)
		(end 38.36797 -96.81337)
		(width 0.08382)
		(layer "In2.Cu")
		(net "GPU_NVS_PWR_BRAKE_R_N")
	)
	(segment
		(start 41.11752 -69.34708)
		(end 42.347134 -68.117466)
		(width 0.10668)
		(layer "In4.Cu")
		(net "GPU_NVS_PWR_BRAKE_R_N")
	)
	(segment
		(start 41.99128 -71.683626)
		(end 41.11752 -70.809866)
		(width 0.10668)
		(layer "In4.Cu")
		(net "GPU_NVS_PWR_BRAKE_R_N")
	)
	(segment
		(start 39.1414 -92.441522)
		(end 39.687246 -91.895676)
		(width 0.10668)
		(layer "In4.Cu")
		(net "GPU_NVS_PWR_BRAKE_R_N")
	)
	(segment
		(start 38.735 -97.1804)
		(end 39.1414 -96.774)
		(width 0.10668)
		(layer "In4.Cu")
		(net "GPU_NVS_PWR_BRAKE_R_N")
	)
	(segment
		(start 39.1414 -96.774)
		(end 39.1414 -92.441522)
		(width 0.10668)
		(layer "In4.Cu")
		(net "GPU_NVS_PWR_BRAKE_R_N")
	)
	(segment
		(start 41.4528 -65.1256)
		(end 41.4528 -61.9506)
		(width 0.10668)
		(layer "In4.Cu")
		(net "GPU_NVS_PWR_BRAKE_R_N")
	)
	(segment
		(start 40.60698 -81.046574)
		(end 40.081962 -80.521556)
		(width 0.10668)
		(layer "In4.Cu")
		(net "GPU_NVS_PWR_BRAKE_R_N")
	)
	(segment
		(start 41.11752 -70.809866)
		(end 41.11752 -69.34708)
		(width 0.10668)
		(layer "In4.Cu")
		(net "GPU_NVS_PWR_BRAKE_R_N")
	)
	(segment
		(start 40.081962 -76.3905)
		(end 41.99128 -74.481182)
		(width 0.10668)
		(layer "In4.Cu")
		(net "GPU_NVS_PWR_BRAKE_R_N")
	)
	(segment
		(start 41.4528 -61.9506)
		(end 42.037 -61.3664)
		(width 0.10668)
		(layer "In4.Cu")
		(net "GPU_NVS_PWR_BRAKE_R_N")
	)
	(segment
		(start 41.99128 -74.481182)
		(end 41.99128 -71.683626)
		(width 0.10668)
		(layer "In4.Cu")
		(net "GPU_NVS_PWR_BRAKE_R_N")
	)
	(segment
		(start 39.687246 -91.895676)
		(end 39.687246 -82.99196)
		(width 0.10668)
		(layer "In4.Cu")
		(net "GPU_NVS_PWR_BRAKE_R_N")
	)
	(segment
		(start 42.347134 -66.019934)
		(end 41.4528 -65.1256)
		(width 0.10668)
		(layer "In4.Cu")
		(net "GPU_NVS_PWR_BRAKE_R_N")
	)
	(segment
		(start 40.60698 -82.072226)
		(end 40.60698 -81.046574)
		(width 0.10668)
		(layer "In4.Cu")
		(net "GPU_NVS_PWR_BRAKE_R_N")
	)
	(segment
		(start 40.081962 -80.521556)
		(end 40.081962 -76.3905)
		(width 0.10668)
		(layer "In4.Cu")
		(net "GPU_NVS_PWR_BRAKE_R_N")
	)
	(segment
		(start 39.687246 -82.99196)
		(end 40.60698 -82.072226)
		(width 0.10668)
		(layer "In4.Cu")
		(net "GPU_NVS_PWR_BRAKE_R_N")
	)
	(segment
		(start 42.347134 -68.117466)
		(end 42.347134 -66.019934)
		(width 0.10668)
		(layer "In4.Cu")
		(net "GPU_NVS_PWR_BRAKE_R_N")
	)
	(segment
		(start 42.037 -61.3664)
		(end 42.037 -59.9694)
		(width 0.10668)
		(layer "In4.Cu")
		(net "GPU_NVS_PWR_BRAKE_R_N")
	)
	(segment
		(start 43.697652 -56.581294)
		(end 43.917616 -56.49087)
		(width 0.08382)
		(layer "In9.Cu")
		(net "GPU_NVS_PWR_BRAKE_R_N")
	)
	(segment
		(start 43.519344 -56.759602)
		(end 43.697652 -56.581294)
		(width 0.08382)
		(layer "In9.Cu")
		(net "GPU_NVS_PWR_BRAKE_R_N")
	)
	(segment
		(start 43.436032 -56.88457)
		(end 43.519344 -56.759602)
		(width 0.08382)
		(layer "In9.Cu")
		(net "GPU_NVS_PWR_BRAKE_R_N")
	)
	(segment
		(start 45.781976 -54.966362)
		(end 46.09973 -54.966362)
		(width 0.08382)
		(layer "In9.Cu")
		(net "GPU_NVS_PWR_BRAKE_R_N")
	)
	(segment
		(start 43.239182 -57.35955)
		(end 43.436032 -56.88457)
		(width 0.08382)
		(layer "In9.Cu")
		(net "GPU_NVS_PWR_BRAKE_R_N")
	)
	(segment
		(start 43.917616 -56.49087)
		(end 44.257468 -56.49087)
		(width 0.08382)
		(layer "In9.Cu")
		(net "GPU_NVS_PWR_BRAKE_R_N")
	)
	(segment
		(start 42.58818 -59.05246)
		(end 43.239182 -58.401458)
		(width 0.08382)
		(layer "In9.Cu")
		(net "GPU_NVS_PWR_BRAKE_R_N")
	)
	(segment
		(start 42.291 -59.9694)
		(end 42.58818 -59.67222)
		(width 0.08382)
		(layer "In9.Cu")
		(net "GPU_NVS_PWR_BRAKE_R_N")
	)
	(segment
		(start 44.257468 -56.49087)
		(end 45.781976 -54.966362)
		(width 0.08382)
		(layer "In9.Cu")
		(net "GPU_NVS_PWR_BRAKE_R_N")
	)
	(segment
		(start 42.58818 -59.67222)
		(end 42.58818 -59.05246)
		(width 0.08382)
		(layer "In9.Cu")
		(net "GPU_NVS_PWR_BRAKE_R_N")
	)
	(segment
		(start 42.037 -59.9694)
		(end 42.291 -59.9694)
		(width 0.08382)
		(layer "In9.Cu")
		(net "GPU_NVS_PWR_BRAKE_R_N")
	)
	(segment
		(start 43.239182 -58.401458)
		(end 43.239182 -57.35955)
		(width 0.08382)
		(layer "In9.Cu")
		(net "GPU_NVS_PWR_BRAKE_R_N")
	)
	(segment
		(start 46.494954 -48.171354)
		(end 46.09973 -47.77613)
		(width 0.11684)
		(layer "F.Cu")
		(net "FM_PFR_DSW_PWROK_N")
	)
	(segment
		(start 22.254718 -95.982282)
		(end 21.859494 -95.587058)
		(width 0.11684)
		(layer "F.Cu")
		(net "FM_PFR_DSW_PWROK_N")
	)
	(via
		(at 22.254718 -95.982282)
		(size 0.4572)
		(drill 0.254)
		(layers "F.Cu" "B.Cu")
		(net "FM_PFR_DSW_PWROK_N")
	)
	(via
		(at 42.037254 -97.2312)
		(size 0.508)
		(drill 0.254)
		(layers "F.Cu" "B.Cu")
		(net "FM_PFR_DSW_PWROK_N")
	)
	(via
		(at 46.09973 -47.77613)
		(size 0.4572)
		(drill 0.254)
		(layers "F.Cu" "B.Cu")
		(net "FM_PFR_DSW_PWROK_N")
	)
	(segment
		(start 35.459416 -95.149162)
		(end 34.111184 -95.149162)
		(width 0.08382)
		(layer "In2.Cu")
		(net "FM_PFR_DSW_PWROK_N")
	)
	(segment
		(start 28.332176 -96.63938)
		(end 26.535126 -96.63938)
		(width 0.08382)
		(layer "In2.Cu")
		(net "FM_PFR_DSW_PWROK_N")
	)
	(segment
		(start 37.60978 -94.63278)
		(end 37.3126 -94.92996)
		(width 0.08382)
		(layer "In2.Cu")
		(net "FM_PFR_DSW_PWROK_N")
	)
	(segment
		(start 32.933386 -95.63227)
		(end 31.427674 -95.0087)
		(width 0.08382)
		(layer "In2.Cu")
		(net "FM_PFR_DSW_PWROK_N")
	)
	(segment
		(start 33.628076 -95.63227)
		(end 32.933386 -95.63227)
		(width 0.08382)
		(layer "In2.Cu")
		(net "FM_PFR_DSW_PWROK_N")
	)
	(segment
		(start 35.678618 -94.92996)
		(end 35.459416 -95.149162)
		(width 0.08382)
		(layer "In2.Cu")
		(net "FM_PFR_DSW_PWROK_N")
	)
	(segment
		(start 25.505918 -95.610172)
		(end 22.626828 -95.610172)
		(width 0.08382)
		(layer "In2.Cu")
		(net "FM_PFR_DSW_PWROK_N")
	)
	(segment
		(start 22.626828 -95.610172)
		(end 22.254718 -95.982282)
		(width 0.08382)
		(layer "In2.Cu")
		(net "FM_PFR_DSW_PWROK_N")
	)
	(segment
		(start 40.98798 -94.63278)
		(end 37.60978 -94.63278)
		(width 0.08382)
		(layer "In2.Cu")
		(net "FM_PFR_DSW_PWROK_N")
	)
	(segment
		(start 29.962856 -95.0087)
		(end 28.332176 -96.63938)
		(width 0.08382)
		(layer "In2.Cu")
		(net "FM_PFR_DSW_PWROK_N")
	)
	(segment
		(start 42.037254 -95.682054)
		(end 40.98798 -94.63278)
		(width 0.08382)
		(layer "In2.Cu")
		(net "FM_PFR_DSW_PWROK_N")
	)
	(segment
		(start 26.535126 -96.63938)
		(end 25.505918 -95.610172)
		(width 0.08382)
		(layer "In2.Cu")
		(net "FM_PFR_DSW_PWROK_N")
	)
	(segment
		(start 37.3126 -94.92996)
		(end 35.678618 -94.92996)
		(width 0.08382)
		(layer "In2.Cu")
		(net "FM_PFR_DSW_PWROK_N")
	)
	(segment
		(start 34.111184 -95.149162)
		(end 33.628076 -95.63227)
		(width 0.08382)
		(layer "In2.Cu")
		(net "FM_PFR_DSW_PWROK_N")
	)
	(segment
		(start 42.037254 -97.2312)
		(end 42.037254 -95.682054)
		(width 0.08382)
		(layer "In2.Cu")
		(net "FM_PFR_DSW_PWROK_N")
	)
	(segment
		(start 31.427674 -95.0087)
		(end 29.962856 -95.0087)
		(width 0.08382)
		(layer "In2.Cu")
		(net "FM_PFR_DSW_PWROK_N")
	)
	(segment
		(start 45.212 -54.796944)
		(end 45.974 -54.034944)
		(width 0.10668)
		(layer "In4.Cu")
		(net "FM_PFR_DSW_PWROK_N")
	)
	(segment
		(start 42.4307 -96.837754)
		(end 42.4307 -96.8375)
		(width 0.10668)
		(layer "In4.Cu")
		(net "FM_PFR_DSW_PWROK_N")
	)
	(segment
		(start 43.16984 -76.71816)
		(end 43.20032 -76.71816)
		(width 0.10668)
		(layer "In4.Cu")
		(net "FM_PFR_DSW_PWROK_N")
	)
	(segment
		(start 44.395898 -71.610982)
		(end 44.395898 -69.92239)
		(width 0.10668)
		(layer "In4.Cu")
		(net "FM_PFR_DSW_PWROK_N")
	)
	(segment
		(start 47.11192 -50.55108)
		(end 47.3202 -50.3428)
		(width 0.10668)
		(layer "In4.Cu")
		(net "FM_PFR_DSW_PWROK_N")
	)
	(segment
		(start 47.3202 -48.4124)
		(end 47.0916 -48.1838)
		(width 0.10668)
		(layer "In4.Cu")
		(net "FM_PFR_DSW_PWROK_N")
	)
	(segment
		(start 43.918632 -86.480396)
		(end 43.9166 -86.478364)
		(width 0.10668)
		(layer "In4.Cu")
		(net "FM_PFR_DSW_PWROK_N")
	)
	(segment
		(start 43.20032 -76.71816)
		(end 43.307 -76.61148)
		(width 0.10668)
		(layer "In4.Cu")
		(net "FM_PFR_DSW_PWROK_N")
	)
	(segment
		(start 42.8244 -77.0636)
		(end 43.16984 -76.71816)
		(width 0.10668)
		(layer "In4.Cu")
		(net "FM_PFR_DSW_PWROK_N")
	)
	(segment
		(start 45.974 -54.034944)
		(end 45.974 -53.6448)
		(width 0.10668)
		(layer "In4.Cu")
		(net "FM_PFR_DSW_PWROK_N")
	)
	(segment
		(start 44.395898 -69.92239)
		(end 43.67657 -69.203062)
		(width 0.10668)
		(layer "In4.Cu")
		(net "FM_PFR_DSW_PWROK_N")
	)
	(segment
		(start 43.307 -72.69988)
		(end 44.395898 -71.610982)
		(width 0.10668)
		(layer "In4.Cu")
		(net "FM_PFR_DSW_PWROK_N")
	)
	(segment
		(start 44.74972 -67.120516)
		(end 44.74972 -66.613024)
		(width 0.10668)
		(layer "In4.Cu")
		(net "FM_PFR_DSW_PWROK_N")
	)
	(segment
		(start 42.8244 -77.343)
		(end 42.8244 -77.0636)
		(width 0.10668)
		(layer "In4.Cu")
		(net "FM_PFR_DSW_PWROK_N")
	)
	(segment
		(start 43.9166 -85.5726)
		(end 42.82186 -84.47786)
		(width 0.10668)
		(layer "In4.Cu")
		(net "FM_PFR_DSW_PWROK_N")
	)
	(segment
		(start 43.918632 -86.861396)
		(end 43.918632 -86.480396)
		(width 0.10668)
		(layer "In4.Cu")
		(net "FM_PFR_DSW_PWROK_N")
	)
	(segment
		(start 42.44086 -77.72654)
		(end 42.8244 -77.343)
		(width 0.10668)
		(layer "In4.Cu")
		(net "FM_PFR_DSW_PWROK_N")
	)
	(segment
		(start 43.40098 -65.264284)
		(end 43.40098 -57.934098)
		(width 0.10668)
		(layer "In4.Cu")
		(net "FM_PFR_DSW_PWROK_N")
	)
	(segment
		(start 43.9547 -56.79186)
		(end 44.55414 -56.79186)
		(width 0.10668)
		(layer "In4.Cu")
		(net "FM_PFR_DSW_PWROK_N")
	)
	(segment
		(start 46.73092 -50.55108)
		(end 47.11192 -50.55108)
		(width 0.10668)
		(layer "In4.Cu")
		(net "FM_PFR_DSW_PWROK_N")
	)
	(segment
		(start 43.67657 -69.203062)
		(end 43.67657 -67.76847)
		(width 0.10668)
		(layer "In4.Cu")
		(net "FM_PFR_DSW_PWROK_N")
	)
	(segment
		(start 42.82186 -84.47786)
		(end 42.82186 -79.346806)
		(width 0.10668)
		(layer "In4.Cu")
		(net "FM_PFR_DSW_PWROK_N")
	)
	(segment
		(start 47.316136 -50.00752)
		(end 47.3202 -50.003456)
		(width 0.10668)
		(layer "In4.Cu")
		(net "FM_PFR_DSW_PWROK_N")
	)
	(segment
		(start 42.4307 -96.8375)
		(end 43.9166 -95.3516)
		(width 0.10668)
		(layer "In4.Cu")
		(net "FM_PFR_DSW_PWROK_N")
	)
	(segment
		(start 42.037254 -97.2312)
		(end 42.4307 -96.837754)
		(width 0.10668)
		(layer "In4.Cu")
		(net "FM_PFR_DSW_PWROK_N")
	)
	(segment
		(start 44.00804 -67.437)
		(end 44.433236 -67.437)
		(width 0.10668)
		(layer "In4.Cu")
		(net "FM_PFR_DSW_PWROK_N")
	)
	(segment
		(start 46.5074 -48.1838)
		(end 46.09973 -47.77613)
		(width 0.10668)
		(layer "In4.Cu")
		(net "FM_PFR_DSW_PWROK_N")
	)
	(segment
		(start 47.3202 -50.3428)
		(end 47.3202 -50.329592)
		(width 0.10668)
		(layer "In4.Cu")
		(net "FM_PFR_DSW_PWROK_N")
	)
	(segment
		(start 43.307 -76.61148)
		(end 43.307 -72.69988)
		(width 0.10668)
		(layer "In4.Cu")
		(net "FM_PFR_DSW_PWROK_N")
	)
	(segment
		(start 44.74972 -66.613024)
		(end 43.40098 -65.264284)
		(width 0.10668)
		(layer "In4.Cu")
		(net "FM_PFR_DSW_PWROK_N")
	)
	(segment
		(start 43.9166 -95.3516)
		(end 43.9166 -86.863428)
		(width 0.10668)
		(layer "In4.Cu")
		(net "FM_PFR_DSW_PWROK_N")
	)
	(segment
		(start 44.433236 -67.437)
		(end 44.74972 -67.120516)
		(width 0.10668)
		(layer "In4.Cu")
		(net "FM_PFR_DSW_PWROK_N")
	)
	(segment
		(start 45.212 -56.134)
		(end 45.212 -54.796944)
		(width 0.10668)
		(layer "In4.Cu")
		(net "FM_PFR_DSW_PWROK_N")
	)
	(segment
		(start 43.40098 -57.934098)
		(end 43.68546 -57.247536)
		(width 0.10668)
		(layer "In4.Cu")
		(net "FM_PFR_DSW_PWROK_N")
	)
	(segment
		(start 43.67657 -67.76847)
		(end 44.00804 -67.437)
		(width 0.10668)
		(layer "In4.Cu")
		(net "FM_PFR_DSW_PWROK_N")
	)
	(segment
		(start 44.55414 -56.79186)
		(end 45.212 -56.134)
		(width 0.10668)
		(layer "In4.Cu")
		(net "FM_PFR_DSW_PWROK_N")
	)
	(segment
		(start 46.5074 -53.1114)
		(end 46.5074 -50.7746)
		(width 0.10668)
		(layer "In4.Cu")
		(net "FM_PFR_DSW_PWROK_N")
	)
	(segment
		(start 43.68546 -57.0611)
		(end 43.9547 -56.79186)
		(width 0.10668)
		(layer "In4.Cu")
		(net "FM_PFR_DSW_PWROK_N")
	)
	(segment
		(start 47.316136 -50.325528)
		(end 47.316136 -50.00752)
		(width 0.10668)
		(layer "In4.Cu")
		(net "FM_PFR_DSW_PWROK_N")
	)
	(segment
		(start 47.3202 -50.003456)
		(end 47.3202 -48.4124)
		(width 0.10668)
		(layer "In4.Cu")
		(net "FM_PFR_DSW_PWROK_N")
	)
	(segment
		(start 43.68546 -57.247536)
		(end 43.68546 -57.0611)
		(width 0.10668)
		(layer "In4.Cu")
		(net "FM_PFR_DSW_PWROK_N")
	)
	(segment
		(start 43.9166 -86.478364)
		(end 43.9166 -85.5726)
		(width 0.10668)
		(layer "In4.Cu")
		(net "FM_PFR_DSW_PWROK_N")
	)
	(segment
		(start 46.5074 -50.7746)
		(end 46.73092 -50.55108)
		(width 0.10668)
		(layer "In4.Cu")
		(net "FM_PFR_DSW_PWROK_N")
	)
	(segment
		(start 42.44086 -78.965806)
		(end 42.44086 -77.72654)
		(width 0.10668)
		(layer "In4.Cu")
		(net "FM_PFR_DSW_PWROK_N")
	)
	(segment
		(start 45.974 -53.6448)
		(end 46.5074 -53.1114)
		(width 0.10668)
		(layer "In4.Cu")
		(net "FM_PFR_DSW_PWROK_N")
	)
	(segment
		(start 47.3202 -50.329592)
		(end 47.316136 -50.325528)
		(width 0.10668)
		(layer "In4.Cu")
		(net "FM_PFR_DSW_PWROK_N")
	)
	(segment
		(start 42.82186 -79.346806)
		(end 42.44086 -78.965806)
		(width 0.10668)
		(layer "In4.Cu")
		(net "FM_PFR_DSW_PWROK_N")
	)
	(segment
		(start 43.9166 -86.863428)
		(end 43.918632 -86.861396)
		(width 0.10668)
		(layer "In4.Cu")
		(net "FM_PFR_DSW_PWROK_N")
	)
	(segment
		(start 47.0916 -48.1838)
		(end 46.5074 -48.1838)
		(width 0.10668)
		(layer "In4.Cu")
		(net "FM_PFR_DSW_PWROK_N")
	)
	(segment
		(start 42.83456 -53.32476)
		(end 43.602402 -54.092602)
		(width 0.11684)
		(layer "F.Cu")
		(net "FM_PCH_BEEP_LED")
	)
	(segment
		(start 44.152566 -54.860698)
		(end 44.679362 -54.9656)
		(width 0.11684)
		(layer "F.Cu")
		(net "FM_PCH_BEEP_LED")
	)
	(segment
		(start 43.2054 -50.3682)
		(end 42.83456 -50.73904)
		(width 0.11684)
		(layer "F.Cu")
		(net "FM_PCH_BEEP_LED")
	)
	(segment
		(start 43.837606 -54.660038)
		(end 43.909742 -54.732174)
		(width 0.11684)
		(layer "F.Cu")
		(net "FM_PCH_BEEP_LED")
	)
	(segment
		(start 45.300646 -54.9656)
		(end 45.695108 -54.571138)
		(width 0.11684)
		(layer "F.Cu")
		(net "FM_PCH_BEEP_LED")
	)
	(segment
		(start 23.45944 -100.12045)
		(end 23.45944 -99.58705)
		(width 0.11684)
		(layer "F.Cu")
		(net "FM_PCH_BEEP_LED")
	)
	(segment
		(start 43.909742 -54.732174)
		(end 44.018962 -54.805326)
		(width 0.11684)
		(layer "F.Cu")
		(net "FM_PCH_BEEP_LED")
	)
	(segment
		(start 43.602402 -54.092602)
		(end 43.837606 -54.660038)
		(width 0.11684)
		(layer "F.Cu")
		(net "FM_PCH_BEEP_LED")
	)
	(segment
		(start 44.679362 -54.9656)
		(end 45.300646 -54.9656)
		(width 0.11684)
		(layer "F.Cu")
		(net "FM_PCH_BEEP_LED")
	)
	(segment
		(start 42.83456 -50.73904)
		(end 42.83456 -53.32476)
		(width 0.11684)
		(layer "F.Cu")
		(net "FM_PCH_BEEP_LED")
	)
	(segment
		(start 44.018962 -54.805326)
		(end 44.152566 -54.860698)
		(width 0.11684)
		(layer "F.Cu")
		(net "FM_PCH_BEEP_LED")
	)
	(segment
		(start 43.646344 -50.3682)
		(end 43.2054 -50.3682)
		(width 0.11684)
		(layer "F.Cu")
		(net "FM_PCH_BEEP_LED")
	)
	(via
		(at 43.646344 -50.3682)
		(size 0.4572)
		(drill 0.254)
		(layers "F.Cu" "B.Cu")
		(net "FM_PCH_BEEP_LED")
	)
	(via
		(at 11.7094 -107.3912)
		(size 0.508)
		(drill 0.254)
		(layers "F.Cu" "B.Cu")
		(net "FM_PCH_BEEP_LED")
	)
	(via
		(at 39.7002 -95.5802)
		(size 0.508)
		(drill 0.254)
		(layers "F.Cu" "B.Cu")
		(net "FM_PCH_BEEP_LED")
	)
	(via
		(at 23.45944 -100.12045)
		(size 0.4572)
		(drill 0.254)
		(layers "F.Cu" "B.Cu")
		(net "FM_PCH_BEEP_LED")
	)
	(segment
		(start 11.59256 -106.77525)
		(end 11.7094 -106.89209)
		(width 0.11684)
		(layer "B.Cu")
		(net "FM_PCH_BEEP_LED")
	)
	(segment
		(start 11.7094 -106.89209)
		(end 11.7094 -107.3912)
		(width 0.11684)
		(layer "B.Cu")
		(net "FM_PCH_BEEP_LED")
	)
	(segment
		(start 11.2776 -106.77525)
		(end 11.59256 -106.77525)
		(width 0.11684)
		(layer "B.Cu")
		(net "FM_PCH_BEEP_LED")
	)
	(segment
		(start 39.4208 -97.3074)
		(end 39.4208 -95.8596)
		(width 0.08382)
		(layer "In2.Cu")
		(net "FM_PCH_BEEP_LED")
	)
	(segment
		(start 23.98649 -99.5934)
		(end 28.5242 -99.5934)
		(width 0.08382)
		(layer "In2.Cu")
		(net "FM_PCH_BEEP_LED")
	)
	(segment
		(start 38.98011 -97.74809)
		(end 39.4208 -97.3074)
		(width 0.08382)
		(layer "In2.Cu")
		(net "FM_PCH_BEEP_LED")
	)
	(segment
		(start 31.604204 -97.988374)
		(end 32.476186 -97.988374)
		(width 0.08382)
		(layer "In2.Cu")
		(net "FM_PCH_BEEP_LED")
	)
	(segment
		(start 30.75305 -98.34118)
		(end 31.604204 -97.988374)
		(width 0.08382)
		(layer "In2.Cu")
		(net "FM_PCH_BEEP_LED")
	)
	(segment
		(start 29.77642 -98.34118)
		(end 30.75305 -98.34118)
		(width 0.08382)
		(layer "In2.Cu")
		(net "FM_PCH_BEEP_LED")
	)
	(segment
		(start 37.350192 -97.43821)
		(end 37.660072 -97.74809)
		(width 0.08382)
		(layer "In2.Cu")
		(net "FM_PCH_BEEP_LED")
	)
	(segment
		(start 33.02635 -97.43821)
		(end 37.350192 -97.43821)
		(width 0.08382)
		(layer "In2.Cu")
		(net "FM_PCH_BEEP_LED")
	)
	(segment
		(start 39.4208 -95.8596)
		(end 39.7002 -95.5802)
		(width 0.08382)
		(layer "In2.Cu")
		(net "FM_PCH_BEEP_LED")
	)
	(segment
		(start 23.45944 -100.12045)
		(end 23.98649 -99.5934)
		(width 0.08382)
		(layer "In2.Cu")
		(net "FM_PCH_BEEP_LED")
	)
	(segment
		(start 32.476186 -97.988374)
		(end 33.02635 -97.43821)
		(width 0.08382)
		(layer "In2.Cu")
		(net "FM_PCH_BEEP_LED")
	)
	(segment
		(start 28.5242 -99.5934)
		(end 29.77642 -98.34118)
		(width 0.08382)
		(layer "In2.Cu")
		(net "FM_PCH_BEEP_LED")
	)
	(segment
		(start 37.660072 -97.74809)
		(end 38.98011 -97.74809)
		(width 0.08382)
		(layer "In2.Cu")
		(net "FM_PCH_BEEP_LED")
	)
	(segment
		(start 41.4528 -77.123544)
		(end 41.214548 -77.361796)
		(width 0.10668)
		(layer "In4.Cu")
		(net "FM_PCH_BEEP_LED")
	)
	(segment
		(start 43.2562 -52.5018)
		(end 43.2562 -53.90896)
		(width 0.10668)
		(layer "In4.Cu")
		(net "FM_PCH_BEEP_LED")
	)
	(segment
		(start 44.080684 -50.659284)
		(end 44.080684 -51.677316)
		(width 0.10668)
		(layer "In4.Cu")
		(net "FM_PCH_BEEP_LED")
	)
	(segment
		(start 42.25036 -74.588624)
		(end 41.4528 -75.386184)
		(width 0.10668)
		(layer "In4.Cu")
		(net "FM_PCH_BEEP_LED")
	)
	(segment
		(start 40.0558 -89.0778)
		(end 40.0558 -91.9226)
		(width 0.10668)
		(layer "In4.Cu")
		(net "FM_PCH_BEEP_LED")
	)
	(segment
		(start 40.341042 -77.743558)
		(end 40.341042 -80.414114)
		(width 0.10668)
		(layer "In4.Cu")
		(net "FM_PCH_BEEP_LED")
	)
	(segment
		(start 42.82186 -54.7243)
		(end 42.9514 -54.85384)
		(width 0.10668)
		(layer "In4.Cu")
		(net "FM_PCH_BEEP_LED")
	)
	(segment
		(start 44.080684 -51.677316)
		(end 43.2562 -52.5018)
		(width 0.10668)
		(layer "In4.Cu")
		(net "FM_PCH_BEEP_LED")
	)
	(segment
		(start 41.214548 -77.361796)
		(end 40.722804 -77.361796)
		(width 0.10668)
		(layer "In4.Cu")
		(net "FM_PCH_BEEP_LED")
	)
	(segment
		(start 42.119804 -71.445628)
		(end 42.25036 -71.576184)
		(width 0.10668)
		(layer "In4.Cu")
		(net "FM_PCH_BEEP_LED")
	)
	(segment
		(start 40.85844 -82.187288)
		(end 40.85844 -88.27516)
		(width 0.10668)
		(layer "In4.Cu")
		(net "FM_PCH_BEEP_LED")
	)
	(segment
		(start 41.4528 -75.386184)
		(end 41.4528 -77.123544)
		(width 0.10668)
		(layer "In4.Cu")
		(net "FM_PCH_BEEP_LED")
	)
	(segment
		(start 40.722804 -77.361796)
		(end 40.341042 -77.743558)
		(width 0.10668)
		(layer "In4.Cu")
		(net "FM_PCH_BEEP_LED")
	)
	(segment
		(start 40.0558 -91.9226)
		(end 39.7002 -92.2782)
		(width 0.10668)
		(layer "In4.Cu")
		(net "FM_PCH_BEEP_LED")
	)
	(segment
		(start 42.119804 -68.746116)
		(end 42.119804 -71.445628)
		(width 0.10668)
		(layer "In4.Cu")
		(net "FM_PCH_BEEP_LED")
	)
	(segment
		(start 43.646344 -50.3682)
		(end 43.7896 -50.3682)
		(width 0.10668)
		(layer "In4.Cu")
		(net "FM_PCH_BEEP_LED")
	)
	(segment
		(start 43.2562 -53.90896)
		(end 42.82186 -54.3433)
		(width 0.10668)
		(layer "In4.Cu")
		(net "FM_PCH_BEEP_LED")
	)
	(segment
		(start 42.9514 -56.745886)
		(end 42.606214 -57.580784)
		(width 0.10668)
		(layer "In4.Cu")
		(net "FM_PCH_BEEP_LED")
	)
	(segment
		(start 40.341042 -80.414114)
		(end 40.86606 -80.939132)
		(width 0.10668)
		(layer "In4.Cu")
		(net "FM_PCH_BEEP_LED")
	)
	(segment
		(start 42.25036 -71.576184)
		(end 42.25036 -74.588624)
		(width 0.10668)
		(layer "In4.Cu")
		(net "FM_PCH_BEEP_LED")
	)
	(segment
		(start 42.9514 -54.85384)
		(end 42.9514 -56.745886)
		(width 0.10668)
		(layer "In4.Cu")
		(net "FM_PCH_BEEP_LED")
	)
	(segment
		(start 42.82186 -54.3433)
		(end 42.82186 -54.7243)
		(width 0.10668)
		(layer "In4.Cu")
		(net "FM_PCH_BEEP_LED")
	)
	(segment
		(start 40.85844 -88.27516)
		(end 40.0558 -89.0778)
		(width 0.10668)
		(layer "In4.Cu")
		(net "FM_PCH_BEEP_LED")
	)
	(segment
		(start 40.86606 -80.939132)
		(end 40.86606 -82.179668)
		(width 0.10668)
		(layer "In4.Cu")
		(net "FM_PCH_BEEP_LED")
	)
	(segment
		(start 43.7896 -50.3682)
		(end 44.080684 -50.659284)
		(width 0.10668)
		(layer "In4.Cu")
		(net "FM_PCH_BEEP_LED")
	)
	(segment
		(start 42.606214 -68.259706)
		(end 42.119804 -68.746116)
		(width 0.10668)
		(layer "In4.Cu")
		(net "FM_PCH_BEEP_LED")
	)
	(segment
		(start 40.86606 -82.179668)
		(end 40.85844 -82.187288)
		(width 0.10668)
		(layer "In4.Cu")
		(net "FM_PCH_BEEP_LED")
	)
	(segment
		(start 39.7002 -92.2782)
		(end 39.7002 -95.5802)
		(width 0.10668)
		(layer "In4.Cu")
		(net "FM_PCH_BEEP_LED")
	)
	(segment
		(start 42.606214 -57.580784)
		(end 42.606214 -68.259706)
		(width 0.10668)
		(layer "In4.Cu")
		(net "FM_PCH_BEEP_LED")
	)
	(segment
		(start 12.7254 -106.3752)
		(end 11.7094 -107.3912)
		(width 0.08382)
		(layer "In9.Cu")
		(net "FM_PCH_BEEP_LED")
	)
	(segment
		(start 22.98319 -99.6442)
		(end 17.288002 -99.6442)
		(width 0.08382)
		(layer "In9.Cu")
		(net "FM_PCH_BEEP_LED")
	)
	(segment
		(start 23.45944 -100.12045)
		(end 22.98319 -99.6442)
		(width 0.08382)
		(layer "In9.Cu")
		(net "FM_PCH_BEEP_LED")
	)
	(segment
		(start 15.5956 -104.539796)
		(end 13.760196 -106.3752)
		(width 0.08382)
		(layer "In9.Cu")
		(net "FM_PCH_BEEP_LED")
	)
	(segment
		(start 17.288002 -99.6442)
		(end 16.75384 -100.178362)
		(width 0.08382)
		(layer "In9.Cu")
		(net "FM_PCH_BEEP_LED")
	)
	(segment
		(start 16.75384 -100.178362)
		(end 16.75384 -100.907088)
		(width 0.08382)
		(layer "In9.Cu")
		(net "FM_PCH_BEEP_LED")
	)
	(segment
		(start 13.760196 -106.3752)
		(end 12.7254 -106.3752)
		(width 0.08382)
		(layer "In9.Cu")
		(net "FM_PCH_BEEP_LED")
	)
	(segment
		(start 15.5956 -102.065328)
		(end 15.5956 -104.539796)
		(width 0.08382)
		(layer "In9.Cu")
		(net "FM_PCH_BEEP_LED")
	)
	(segment
		(start 16.75384 -100.907088)
		(end 15.5956 -102.065328)
		(width 0.08382)
		(layer "In9.Cu")
		(net "FM_PCH_BEEP_LED")
	)
	(segment
		(start 11.4554 -110.2868)
		(end 11.4554 -110.6932)
		(width 0.11684)
		(layer "F.Cu")
		(net "FM_HDD_LED_N")
	)
	(segment
		(start 44.26204 -54.497986)
		(end 44.43857 -54.571138)
		(width 0.11684)
		(layer "F.Cu")
		(net "FM_HDD_LED_N")
	)
	(segment
		(start 11.3538 -110.1852)
		(end 11.4554 -110.2868)
		(width 0.11684)
		(layer "F.Cu")
		(net "FM_HDD_LED_N")
	)
	(segment
		(start 44.08678 -54.225444)
		(end 44.155614 -54.39156)
		(width 0.11684)
		(layer "F.Cu")
		(net "FM_HDD_LED_N")
	)
	(segment
		(start 43.646344 -50.96637)
		(end 43.3324 -51.280314)
		(width 0.11684)
		(layer "F.Cu")
		(net "FM_HDD_LED_N")
	)
	(segment
		(start 11.3538 -109.74705)
		(end 11.3538 -110.1852)
		(width 0.11684)
		(layer "F.Cu")
		(net "FM_HDD_LED_N")
	)
	(segment
		(start 43.3324 -53.262022)
		(end 44.08678 -54.016402)
		(width 0.11684)
		(layer "F.Cu")
		(net "FM_HDD_LED_N")
	)
	(segment
		(start 43.3324 -51.280314)
		(end 43.3324 -53.262022)
		(width 0.11684)
		(layer "F.Cu")
		(net "FM_HDD_LED_N")
	)
	(segment
		(start 44.43857 -54.571138)
		(end 44.895008 -54.571138)
		(width 0.11684)
		(layer "F.Cu")
		(net "FM_HDD_LED_N")
	)
	(segment
		(start 44.08678 -54.016402)
		(end 44.08678 -54.225444)
		(width 0.11684)
		(layer "F.Cu")
		(net "FM_HDD_LED_N")
	)
	(segment
		(start 23.854664 -98.382328)
		(end 23.45944 -97.987104)
		(width 0.11684)
		(layer "F.Cu")
		(net "FM_HDD_LED_N")
	)
	(segment
		(start 44.155614 -54.39156)
		(end 44.26204 -54.497986)
		(width 0.11684)
		(layer "F.Cu")
		(net "FM_HDD_LED_N")
	)
	(via
		(at 43.646344 -50.96637)
		(size 0.4572)
		(drill 0.254)
		(layers "F.Cu" "B.Cu")
		(net "FM_HDD_LED_N")
	)
	(via
		(at 23.854664 -98.382328)
		(size 0.4572)
		(drill 0.254)
		(layers "F.Cu" "B.Cu")
		(net "FM_HDD_LED_N")
	)
	(via
		(at 38.6334 -96.1136)
		(size 0.508)
		(drill 0.254)
		(layers "F.Cu" "B.Cu")
		(net "FM_HDD_LED_N")
	)
	(via
		(at 11.4554 -110.6932)
		(size 0.508)
		(drill 0.254)
		(layers "F.Cu" "B.Cu")
		(net "FM_HDD_LED_N")
	)
	(segment
		(start 30.041342 -95.71736)
		(end 27.765502 -97.9932)
		(width 0.08382)
		(layer "In2.Cu")
		(net "FM_HDD_LED_N")
	)
	(segment
		(start 38.6334 -96.1136)
		(end 37.011864 -96.1136)
		(width 0.08382)
		(layer "In2.Cu")
		(net "FM_HDD_LED_N")
	)
	(segment
		(start 32.791146 -96.34093)
		(end 31.285688 -95.71736)
		(width 0.08382)
		(layer "In2.Cu")
		(net "FM_HDD_LED_N")
	)
	(segment
		(start 31.285688 -95.71736)
		(end 30.041342 -95.71736)
		(width 0.08382)
		(layer "In2.Cu")
		(net "FM_HDD_LED_N")
	)
	(segment
		(start 27.765502 -97.9932)
		(end 24.243792 -97.9932)
		(width 0.08382)
		(layer "In2.Cu")
		(net "FM_HDD_LED_N")
	)
	(segment
		(start 36.784534 -96.34093)
		(end 32.791146 -96.34093)
		(width 0.08382)
		(layer "In2.Cu")
		(net "FM_HDD_LED_N")
	)
	(segment
		(start 37.011864 -96.1136)
		(end 36.784534 -96.34093)
		(width 0.08382)
		(layer "In2.Cu")
		(net "FM_HDD_LED_N")
	)
	(segment
		(start 24.243792 -97.9932)
		(end 23.854664 -98.382328)
		(width 0.08382)
		(layer "In2.Cu")
		(net "FM_HDD_LED_N")
	)
	(segment
		(start 41.2369 -58.59272)
		(end 41.66362 -59.01944)
		(width 0.10668)
		(layer "In4.Cu")
		(net "FM_HDD_LED_N")
	)
	(segment
		(start 41.7322 -71.791068)
		(end 41.7322 -74.37374)
		(width 0.10668)
		(layer "In4.Cu")
		(net "FM_HDD_LED_N")
	)
	(segment
		(start 40.85844 -70.917308)
		(end 41.7322 -71.791068)
		(width 0.10668)
		(layer "In4.Cu")
		(net "FM_HDD_LED_N")
	)
	(segment
		(start 39.428166 -82.884518)
		(end 39.428166 -91.788234)
		(width 0.10668)
		(layer "In4.Cu")
		(net "FM_HDD_LED_N")
	)
	(segment
		(start 40.01008 -56.60136)
		(end 40.01008 -58.109358)
		(width 0.10668)
		(layer "In4.Cu")
		(net "FM_HDD_LED_N")
	)
	(segment
		(start 40.85844 -67.45986)
		(end 40.85844 -70.917308)
		(width 0.10668)
		(layer "In4.Cu")
		(net "FM_HDD_LED_N")
	)
	(segment
		(start 41.25722 -67.06108)
		(end 40.85844 -67.45986)
		(width 0.10668)
		(layer "In4.Cu")
		(net "FM_HDD_LED_N")
	)
	(segment
		(start 41.25722 -66.00952)
		(end 41.25722 -67.06108)
		(width 0.10668)
		(layer "In4.Cu")
		(net "FM_HDD_LED_N")
	)
	(segment
		(start 40.33012 -65.08242)
		(end 41.25722 -66.00952)
		(width 0.10668)
		(layer "In4.Cu")
		(net "FM_HDD_LED_N")
	)
	(segment
		(start 43.646344 -50.96637)
		(end 43.646344 -51.745134)
		(width 0.10668)
		(layer "In4.Cu")
		(net "FM_HDD_LED_N")
	)
	(segment
		(start 38.4683 -92.7481)
		(end 38.4683 -95.9485)
		(width 0.10668)
		(layer "In4.Cu")
		(net "FM_HDD_LED_N")
	)
	(segment
		(start 40.01008 -58.109358)
		(end 40.493442 -58.59272)
		(width 0.10668)
		(layer "In4.Cu")
		(net "FM_HDD_LED_N")
	)
	(segment
		(start 41.7322 -74.37374)
		(end 39.822882 -76.283058)
		(width 0.10668)
		(layer "In4.Cu")
		(net "FM_HDD_LED_N")
	)
	(segment
		(start 41.117266 -54.460394)
		(end 40.71366 -54.864)
		(width 0.10668)
		(layer "In4.Cu")
		(net "FM_HDD_LED_N")
	)
	(segment
		(start 42.318432 -54.460394)
		(end 41.117266 -54.460394)
		(width 0.10668)
		(layer "In4.Cu")
		(net "FM_HDD_LED_N")
	)
	(segment
		(start 42.99712 -52.394358)
		(end 42.99712 -53.781706)
		(width 0.10668)
		(layer "In4.Cu")
		(net "FM_HDD_LED_N")
	)
	(segment
		(start 40.33012 -62.416182)
		(end 40.33012 -65.08242)
		(width 0.10668)
		(layer "In4.Cu")
		(net "FM_HDD_LED_N")
	)
	(segment
		(start 40.3479 -81.154016)
		(end 40.3479 -81.964784)
		(width 0.10668)
		(layer "In4.Cu")
		(net "FM_HDD_LED_N")
	)
	(segment
		(start 43.646344 -51.745134)
		(end 42.99712 -52.394358)
		(width 0.10668)
		(layer "In4.Cu")
		(net "FM_HDD_LED_N")
	)
	(segment
		(start 41.24198 -60.054236)
		(end 41.24198 -61.504322)
		(width 0.10668)
		(layer "In4.Cu")
		(net "FM_HDD_LED_N")
	)
	(segment
		(start 38.4683 -95.9485)
		(end 38.6334 -96.1136)
		(width 0.10668)
		(layer "In4.Cu")
		(net "FM_HDD_LED_N")
	)
	(segment
		(start 40.71366 -55.89778)
		(end 40.01008 -56.60136)
		(width 0.10668)
		(layer "In4.Cu")
		(net "FM_HDD_LED_N")
	)
	(segment
		(start 40.493442 -58.59272)
		(end 41.2369 -58.59272)
		(width 0.10668)
		(layer "In4.Cu")
		(net "FM_HDD_LED_N")
	)
	(segment
		(start 41.24198 -61.504322)
		(end 40.33012 -62.416182)
		(width 0.10668)
		(layer "In4.Cu")
		(net "FM_HDD_LED_N")
	)
	(segment
		(start 39.822882 -76.283058)
		(end 39.822882 -80.628998)
		(width 0.10668)
		(layer "In4.Cu")
		(net "FM_HDD_LED_N")
	)
	(segment
		(start 39.822882 -80.628998)
		(end 40.3479 -81.154016)
		(width 0.10668)
		(layer "In4.Cu")
		(net "FM_HDD_LED_N")
	)
	(segment
		(start 39.428166 -91.788234)
		(end 38.4683 -92.7481)
		(width 0.10668)
		(layer "In4.Cu")
		(net "FM_HDD_LED_N")
	)
	(segment
		(start 42.99712 -53.781706)
		(end 42.318432 -54.460394)
		(width 0.10668)
		(layer "In4.Cu")
		(net "FM_HDD_LED_N")
	)
	(segment
		(start 40.3479 -81.964784)
		(end 39.428166 -82.884518)
		(width 0.10668)
		(layer "In4.Cu")
		(net "FM_HDD_LED_N")
	)
	(segment
		(start 41.66362 -59.01944)
		(end 41.66362 -59.632596)
		(width 0.10668)
		(layer "In4.Cu")
		(net "FM_HDD_LED_N")
	)
	(segment
		(start 40.71366 -54.864)
		(end 40.71366 -55.89778)
		(width 0.10668)
		(layer "In4.Cu")
		(net "FM_HDD_LED_N")
	)
	(segment
		(start 41.66362 -59.632596)
		(end 41.24198 -60.054236)
		(width 0.10668)
		(layer "In4.Cu")
		(net "FM_HDD_LED_N")
	)
	(segment
		(start 11.44524 -106.13898)
		(end 10.49782 -107.0864)
		(width 0.08382)
		(layer "In9.Cu")
		(net "FM_HDD_LED_N")
	)
	(segment
		(start 23.456392 -98.7806)
		(end 17.88922 -98.7806)
		(width 0.08382)
		(layer "In9.Cu")
		(net "FM_HDD_LED_N")
	)
	(segment
		(start 17.88922 -98.7806)
		(end 16.51762 -100.1522)
		(width 0.08382)
		(layer "In9.Cu")
		(net "FM_HDD_LED_N")
	)
	(segment
		(start 16.51762 -100.1522)
		(end 16.51762 -100.809044)
		(width 0.08382)
		(layer "In9.Cu")
		(net "FM_HDD_LED_N")
	)
	(segment
		(start 11.31062 -108.697776)
		(end 11.31062 -110.54842)
		(width 0.08382)
		(layer "In9.Cu")
		(net "FM_HDD_LED_N")
	)
	(segment
		(start 13.662152 -106.13898)
		(end 11.44524 -106.13898)
		(width 0.08382)
		(layer "In9.Cu")
		(net "FM_HDD_LED_N")
	)
	(segment
		(start 16.51762 -100.809044)
		(end 15.33779 -101.988874)
		(width 0.08382)
		(layer "In9.Cu")
		(net "FM_HDD_LED_N")
	)
	(segment
		(start 23.854664 -98.382328)
		(end 23.456392 -98.7806)
		(width 0.08382)
		(layer "In9.Cu")
		(net "FM_HDD_LED_N")
	)
	(segment
		(start 11.31062 -110.54842)
		(end 11.4554 -110.6932)
		(width 0.08382)
		(layer "In9.Cu")
		(net "FM_HDD_LED_N")
	)
	(segment
		(start 10.49782 -107.884976)
		(end 11.31062 -108.697776)
		(width 0.08382)
		(layer "In9.Cu")
		(net "FM_HDD_LED_N")
	)
	(segment
		(start 15.33779 -101.988874)
		(end 15.33779 -104.463342)
		(width 0.08382)
		(layer "In9.Cu")
		(net "FM_HDD_LED_N")
	)
	(segment
		(start 10.49782 -107.0864)
		(end 10.49782 -107.884976)
		(width 0.08382)
		(layer "In9.Cu")
		(net "FM_HDD_LED_N")
	)
	(segment
		(start 15.33779 -104.463342)
		(end 13.662152 -106.13898)
		(width 0.08382)
		(layer "In9.Cu")
		(net "FM_HDD_LED_N")
	)
	(segment
		(start 62.865 -17.78)
		(end 62.865 -18.415)
		(width 0.11684)
		(layer "F.Cu")
		(net "FM_DBG_SW_N")
	)
	(segment
		(start 62.865 -18.415)
		(end 62.992 -18.542)
		(width 0.11684)
		(layer "F.Cu")
		(net "FM_DBG_SW_N")
	)
	(segment
		(start 64.538098 -17.653)
		(end 62.992 -17.653)
		(width 0.11684)
		(layer "F.Cu")
		(net "FM_DBG_SW_N")
	)
	(segment
		(start 62.992 -18.542)
		(end 63.5 -18.542)
		(width 0.11684)
		(layer "F.Cu")
		(net "FM_DBG_SW_N")
	)
	(segment
		(start 62.992 -17.653)
		(end 62.865 -17.78)
		(width 0.11684)
		(layer "F.Cu")
		(net "FM_DBG_SW_N")
	)
	(via
		(at 63.5 -18.542)
		(size 0.508)
		(drill 0.254)
		(layers "F.Cu" "B.Cu")
		(net "FM_DBG_SW_N")
	)
	(via
		(at 62.028832 -24.714708)
		(size 0.508)
		(drill 0.254)
		(layers "F.Cu" "B.Cu")
		(net "FM_DBG_SW_N")
	)
	(via
		(at 34.847784 -69.720714)
		(size 0.508)
		(drill 0.254)
		(layers "F.Cu" "B.Cu")
		(net "FM_DBG_SW_N")
	)
	(via
		(at 64.2366 -20.4216)
		(size 0.6604)
		(drill 0.3302)
		(layers "F.Cu" "B.Cu")
		(net "FM_DBG_SW_N")
	)
	(via
		(at 54.032658 -33.567116)
		(size 0.508)
		(drill 0.254)
		(layers "F.Cu" "B.Cu")
		(net "FM_DBG_SW_N")
	)
	(segment
		(start 31.637986 -68.848986)
		(end 31.637986 -68.436998)
		(width 0.11684)
		(layer "B.Cu")
		(net "FM_DBG_SW_N")
	)
	(segment
		(start 34.4678 -67.691)
		(end 33.2486 -67.691)
		(width 0.11684)
		(layer "B.Cu")
		(net "FM_DBG_SW_N")
	)
	(segment
		(start 63.51524 -18.542)
		(end 63.7032 -18.72996)
		(width 0.11684)
		(layer "B.Cu")
		(net "FM_DBG_SW_N")
	)
	(segment
		(start 62.028832 -21.824188)
		(end 62.028832 -24.714708)
		(width 0.11684)
		(layer "B.Cu")
		(net "FM_DBG_SW_N")
	)
	(segment
		(start 34.847784 -69.631306)
		(end 34.87928 -69.59981)
		(width 0.11684)
		(layer "B.Cu")
		(net "FM_DBG_SW_N")
	)
	(segment
		(start 31.947104 -68.992496)
		(end 31.781496 -68.992496)
		(width 0.11684)
		(layer "B.Cu")
		(net "FM_DBG_SW_N")
	)
	(segment
		(start 63.5 -18.542)
		(end 63.51524 -18.542)
		(width 0.11684)
		(layer "B.Cu")
		(net "FM_DBG_SW_N")
	)
	(segment
		(start 63.7032 -18.72996)
		(end 63.7032 -19.8882)
		(width 0.11684)
		(layer "B.Cu")
		(net "FM_DBG_SW_N")
	)
	(segment
		(start 64.262 -18.26895)
		(end 63.77305 -18.26895)
		(width 0.11684)
		(layer "B.Cu")
		(net "FM_DBG_SW_N")
	)
	(segment
		(start 34.87928 -69.59981)
		(end 34.87928 -68.503292)
		(width 0.11684)
		(layer "B.Cu")
		(net "FM_DBG_SW_N")
	)
	(segment
		(start 34.847784 -69.720714)
		(end 34.847784 -69.631306)
		(width 0.11684)
		(layer "B.Cu")
		(net "FM_DBG_SW_N")
	)
	(segment
		(start 34.87928 -68.503292)
		(end 34.812986 -68.436998)
		(width 0.11684)
		(layer "B.Cu")
		(net "FM_DBG_SW_N")
	)
	(segment
		(start 63.7032 -19.8882)
		(end 64.2366 -20.4216)
		(width 0.11684)
		(layer "B.Cu")
		(net "FM_DBG_SW_N")
	)
	(segment
		(start 63.72606 -20.93214)
		(end 62.92088 -20.93214)
		(width 0.11684)
		(layer "B.Cu")
		(net "FM_DBG_SW_N")
	)
	(segment
		(start 31.781496 -68.992496)
		(end 31.637986 -68.848986)
		(width 0.11684)
		(layer "B.Cu")
		(net "FM_DBG_SW_N")
	)
	(segment
		(start 33.2486 -67.691)
		(end 31.947104 -68.992496)
		(width 0.11684)
		(layer "B.Cu")
		(net "FM_DBG_SW_N")
	)
	(segment
		(start 34.812986 -68.436998)
		(end 34.812986 -68.036186)
		(width 0.11684)
		(layer "B.Cu")
		(net "FM_DBG_SW_N")
	)
	(segment
		(start 62.92088 -20.93214)
		(end 62.028832 -21.824188)
		(width 0.11684)
		(layer "B.Cu")
		(net "FM_DBG_SW_N")
	)
	(segment
		(start 34.812986 -68.036186)
		(end 34.4678 -67.691)
		(width 0.11684)
		(layer "B.Cu")
		(net "FM_DBG_SW_N")
	)
	(segment
		(start 63.77305 -18.26895)
		(end 63.5 -18.542)
		(width 0.11684)
		(layer "B.Cu")
		(net "FM_DBG_SW_N")
	)
	(segment
		(start 64.2366 -20.4216)
		(end 63.72606 -20.93214)
		(width 0.11684)
		(layer "B.Cu")
		(net "FM_DBG_SW_N")
	)
	(segment
		(start 52.47132 -30.86608)
		(end 53.4924 -31.88716)
		(width 0.08382)
		(layer "In2.Cu")
		(net "FM_DBG_SW_N")
	)
	(segment
		(start 53.4924 -33.30956)
		(end 53.749956 -33.567116)
		(width 0.08382)
		(layer "In2.Cu")
		(net "FM_DBG_SW_N")
	)
	(segment
		(start 55.60695 -25.164288)
		(end 54.876192 -25.895046)
		(width 0.08382)
		(layer "In2.Cu")
		(net "FM_DBG_SW_N")
	)
	(segment
		(start 59.897772 -25.164288)
		(end 55.60695 -25.164288)
		(width 0.08382)
		(layer "In2.Cu")
		(net "FM_DBG_SW_N")
	)
	(segment
		(start 53.278786 -25.895046)
		(end 52.12207 -27.051762)
		(width 0.08382)
		(layer "In2.Cu")
		(net "FM_DBG_SW_N")
	)
	(segment
		(start 54.876192 -25.895046)
		(end 53.278786 -25.895046)
		(width 0.08382)
		(layer "In2.Cu")
		(net "FM_DBG_SW_N")
	)
	(segment
		(start 52.12207 -28.66771)
		(end 51.2572 -29.53258)
		(width 0.08382)
		(layer "In2.Cu")
		(net "FM_DBG_SW_N")
	)
	(segment
		(start 60.281312 -24.780748)
		(end 59.897772 -25.164288)
		(width 0.08382)
		(layer "In2.Cu")
		(net "FM_DBG_SW_N")
	)
	(segment
		(start 61.962792 -24.780748)
		(end 60.281312 -24.780748)
		(width 0.08382)
		(layer "In2.Cu")
		(net "FM_DBG_SW_N")
	)
	(segment
		(start 52.12207 -27.051762)
		(end 52.12207 -28.66771)
		(width 0.08382)
		(layer "In2.Cu")
		(net "FM_DBG_SW_N")
	)
	(segment
		(start 62.028832 -24.714708)
		(end 61.962792 -24.780748)
		(width 0.08382)
		(layer "In2.Cu")
		(net "FM_DBG_SW_N")
	)
	(segment
		(start 53.4924 -31.88716)
		(end 53.4924 -33.30956)
		(width 0.08382)
		(layer "In2.Cu")
		(net "FM_DBG_SW_N")
	)
	(segment
		(start 51.2572 -29.53258)
		(end 51.2572 -30.65526)
		(width 0.08382)
		(layer "In2.Cu")
		(net "FM_DBG_SW_N")
	)
	(segment
		(start 53.749956 -33.567116)
		(end 54.032658 -33.567116)
		(width 0.08382)
		(layer "In2.Cu")
		(net "FM_DBG_SW_N")
	)
	(segment
		(start 51.2572 -30.65526)
		(end 51.46802 -30.86608)
		(width 0.08382)
		(layer "In2.Cu")
		(net "FM_DBG_SW_N")
	)
	(segment
		(start 51.46802 -30.86608)
		(end 52.47132 -30.86608)
		(width 0.08382)
		(layer "In2.Cu")
		(net "FM_DBG_SW_N")
	)
	(segment
		(start 52.79644 -34.94532)
		(end 52.79644 -34.803334)
		(width 0.10668)
		(layer "In4.Cu")
		(net "FM_DBG_SW_N")
	)
	(segment
		(start 43.428158 -36.32073)
		(end 52.233322 -36.32073)
		(width 0.10668)
		(layer "In4.Cu")
		(net "FM_DBG_SW_N")
	)
	(segment
		(start 36.21532 -43.85564)
		(end 36.21532 -42.76852)
		(width 0.10668)
		(layer "In4.Cu")
		(net "FM_DBG_SW_N")
	)
	(segment
		(start 33.60674 -68.39331)
		(end 33.60674 -66.067686)
		(width 0.10668)
		(layer "In4.Cu")
		(net "FM_DBG_SW_N")
	)
	(segment
		(start 30.861 -58.8772)
		(end 30.861 -57.668922)
		(width 0.10668)
		(layer "In4.Cu")
		(net "FM_DBG_SW_N")
	)
	(segment
		(start 32.4104 -65.4812)
		(end 32.20974 -65.28054)
		(width 0.10668)
		(layer "In4.Cu")
		(net "FM_DBG_SW_N")
	)
	(segment
		(start 31.3309 -61.0235)
		(end 31.3309 -59.3471)
		(width 0.10668)
		(layer "In4.Cu")
		(net "FM_DBG_SW_N")
	)
	(segment
		(start 34.847784 -69.634354)
		(end 33.60674 -68.39331)
		(width 0.10668)
		(layer "In4.Cu")
		(net "FM_DBG_SW_N")
	)
	(segment
		(start 31.9024 -61.595)
		(end 31.3309 -61.0235)
		(width 0.10668)
		(layer "In4.Cu")
		(net "FM_DBG_SW_N")
	)
	(segment
		(start 34.64306 -43.94454)
		(end 34.9631 -44.26458)
		(width 0.10668)
		(layer "In4.Cu")
		(net "FM_DBG_SW_N")
	)
	(segment
		(start 33.60674 -66.067686)
		(end 33.020254 -65.4812)
		(width 0.10668)
		(layer "In4.Cu")
		(net "FM_DBG_SW_N")
	)
	(segment
		(start 36.21532 -42.76852)
		(end 36.63696 -42.34688)
		(width 0.10668)
		(layer "In4.Cu")
		(net "FM_DBG_SW_N")
	)
	(segment
		(start 30.861 -57.668922)
		(end 32.512 -53.682392)
		(width 0.10668)
		(layer "In4.Cu")
		(net "FM_DBG_SW_N")
	)
	(segment
		(start 32.512 -53.682392)
		(end 32.512 -48.40224)
		(width 0.10668)
		(layer "In4.Cu")
		(net "FM_DBG_SW_N")
	)
	(segment
		(start 34.847784 -69.720714)
		(end 34.847784 -69.634354)
		(width 0.10668)
		(layer "In4.Cu")
		(net "FM_DBG_SW_N")
	)
	(segment
		(start 52.79644 -34.803334)
		(end 54.032658 -33.567116)
		(width 0.10668)
		(layer "In4.Cu")
		(net "FM_DBG_SW_N")
	)
	(segment
		(start 33.020254 -65.4812)
		(end 32.4104 -65.4812)
		(width 0.10668)
		(layer "In4.Cu")
		(net "FM_DBG_SW_N")
	)
	(segment
		(start 33.2105 -47.70374)
		(end 33.2105 -44.6659)
		(width 0.10668)
		(layer "In4.Cu")
		(net "FM_DBG_SW_N")
	)
	(segment
		(start 42.0878 -38.651688)
		(end 42.846244 -37.893244)
		(width 0.10668)
		(layer "In4.Cu")
		(net "FM_DBG_SW_N")
	)
	(segment
		(start 36.63696 -42.34688)
		(end 39.68496 -42.34688)
		(width 0.10668)
		(layer "In4.Cu")
		(net "FM_DBG_SW_N")
	)
	(segment
		(start 32.20974 -65.28054)
		(end 32.20974 -63.78194)
		(width 0.10668)
		(layer "In4.Cu")
		(net "FM_DBG_SW_N")
	)
	(segment
		(start 52.233322 -36.32073)
		(end 52.68976 -35.864292)
		(width 0.10668)
		(layer "In4.Cu")
		(net "FM_DBG_SW_N")
	)
	(segment
		(start 52.68976 -35.864292)
		(end 52.68976 -35.052)
		(width 0.10668)
		(layer "In4.Cu")
		(net "FM_DBG_SW_N")
	)
	(segment
		(start 32.512 -48.40224)
		(end 33.2105 -47.70374)
		(width 0.10668)
		(layer "In4.Cu")
		(net "FM_DBG_SW_N")
	)
	(segment
		(start 32.20974 -63.78194)
		(end 31.9024 -63.4746)
		(width 0.10668)
		(layer "In4.Cu")
		(net "FM_DBG_SW_N")
	)
	(segment
		(start 39.68496 -42.34688)
		(end 42.0878 -39.94404)
		(width 0.10668)
		(layer "In4.Cu")
		(net "FM_DBG_SW_N")
	)
	(segment
		(start 34.9631 -44.26458)
		(end 35.80638 -44.26458)
		(width 0.10668)
		(layer "In4.Cu")
		(net "FM_DBG_SW_N")
	)
	(segment
		(start 52.68976 -35.052)
		(end 52.79644 -34.94532)
		(width 0.10668)
		(layer "In4.Cu")
		(net "FM_DBG_SW_N")
	)
	(segment
		(start 31.9024 -63.4746)
		(end 31.9024 -61.595)
		(width 0.10668)
		(layer "In4.Cu")
		(net "FM_DBG_SW_N")
	)
	(segment
		(start 35.80638 -44.26458)
		(end 36.21532 -43.85564)
		(width 0.10668)
		(layer "In4.Cu")
		(net "FM_DBG_SW_N")
	)
	(segment
		(start 31.3309 -59.3471)
		(end 30.861 -58.8772)
		(width 0.10668)
		(layer "In4.Cu")
		(net "FM_DBG_SW_N")
	)
	(segment
		(start 42.846244 -36.902644)
		(end 43.428158 -36.32073)
		(width 0.10668)
		(layer "In4.Cu")
		(net "FM_DBG_SW_N")
	)
	(segment
		(start 42.846244 -37.893244)
		(end 42.846244 -36.902644)
		(width 0.10668)
		(layer "In4.Cu")
		(net "FM_DBG_SW_N")
	)
	(segment
		(start 42.0878 -39.94404)
		(end 42.0878 -38.651688)
		(width 0.10668)
		(layer "In4.Cu")
		(net "FM_DBG_SW_N")
	)
	(segment
		(start 33.2105 -44.6659)
		(end 33.93186 -43.94454)
		(width 0.10668)
		(layer "In4.Cu")
		(net "FM_DBG_SW_N")
	)
	(segment
		(start 33.93186 -43.94454)
		(end 34.64306 -43.94454)
		(width 0.10668)
		(layer "In4.Cu")
		(net "FM_DBG_SW_N")
	)
	(segment
		(start 23.054564 -96.782382)
		(end 22.65934 -96.387158)
		(width 0.11684)
		(layer "F.Cu")
		(net "CLK_GEN2_BMC_RC_OE_N")
	)
	(segment
		(start 57.695084 -61.597286)
		(end 57.695084 -59.37123)
		(width 0.11684)
		(layer "F.Cu")
		(net "CLK_GEN2_BMC_RC_OE_N")
	)
	(segment
		(start 57.21985 -62.484)
		(end 57.21985 -62.07252)
		(width 0.11684)
		(layer "F.Cu")
		(net "CLK_GEN2_BMC_RC_OE_N")
	)
	(segment
		(start 57.21985 -62.07252)
		(end 57.695084 -61.597286)
		(width 0.11684)
		(layer "F.Cu")
		(net "CLK_GEN2_BMC_RC_OE_N")
	)
	(via
		(at 50.8762 -83.5152)
		(size 0.508)
		(drill 0.254)
		(layers "F.Cu" "B.Cu")
		(net "CLK_GEN2_BMC_RC_OE_N")
	)
	(via
		(at 58.53303 -82.79003)
		(size 0.508)
		(drill 0.254)
		(layers "F.Cu" "B.Cu")
		(net "CLK_GEN2_BMC_RC_OE_N")
	)
	(via
		(at 23.054564 -96.782382)
		(size 0.4572)
		(drill 0.254)
		(layers "F.Cu" "B.Cu")
		(net "CLK_GEN2_BMC_RC_OE_N")
	)
	(via
		(at 57.21985 -62.484)
		(size 0.508)
		(drill 0.254)
		(layers "F.Cu" "B.Cu")
		(net "CLK_GEN2_BMC_RC_OE_N")
	)
	(via
		(at 40.933116 -95.682816)
		(size 0.508)
		(drill 0.254)
		(layers "F.Cu" "B.Cu")
		(net "CLK_GEN2_BMC_RC_OE_N")
	)
	(segment
		(start 30.01518 -95.48114)
		(end 28.34132 -97.155)
		(width 0.08382)
		(layer "In2.Cu")
		(net "CLK_GEN2_BMC_RC_OE_N")
	)
	(segment
		(start 40.933116 -95.682816)
		(end 40.933116 -95.41637)
		(width 0.08382)
		(layer "In2.Cu")
		(net "CLK_GEN2_BMC_RC_OE_N")
	)
	(segment
		(start 58.337958 -82.79003)
		(end 57.785254 -83.342734)
		(width 0.08382)
		(layer "In2.Cu")
		(net "CLK_GEN2_BMC_RC_OE_N")
	)
	(segment
		(start 28.34132 -97.155)
		(end 23.427182 -97.155)
		(width 0.08382)
		(layer "In2.Cu")
		(net "CLK_GEN2_BMC_RC_OE_N")
	)
	(segment
		(start 23.427182 -97.155)
		(end 23.054564 -96.782382)
		(width 0.08382)
		(layer "In2.Cu")
		(net "CLK_GEN2_BMC_RC_OE_N")
	)
	(segment
		(start 40.385746 -94.869)
		(end 37.707824 -94.869)
		(width 0.08382)
		(layer "In2.Cu")
		(net "CLK_GEN2_BMC_RC_OE_N")
	)
	(segment
		(start 40.933116 -95.41637)
		(end 40.385746 -94.869)
		(width 0.08382)
		(layer "In2.Cu")
		(net "CLK_GEN2_BMC_RC_OE_N")
	)
	(segment
		(start 32.838644 -96.10471)
		(end 31.332932 -95.48114)
		(width 0.08382)
		(layer "In2.Cu")
		(net "CLK_GEN2_BMC_RC_OE_N")
	)
	(segment
		(start 51.048666 -83.342734)
		(end 50.8762 -83.5152)
		(width 0.08382)
		(layer "In2.Cu")
		(net "CLK_GEN2_BMC_RC_OE_N")
	)
	(segment
		(start 31.332932 -95.48114)
		(end 30.01518 -95.48114)
		(width 0.08382)
		(layer "In2.Cu")
		(net "CLK_GEN2_BMC_RC_OE_N")
	)
	(segment
		(start 36.472114 -96.10471)
		(end 32.838644 -96.10471)
		(width 0.08382)
		(layer "In2.Cu")
		(net "CLK_GEN2_BMC_RC_OE_N")
	)
	(segment
		(start 58.53303 -82.79003)
		(end 58.337958 -82.79003)
		(width 0.08382)
		(layer "In2.Cu")
		(net "CLK_GEN2_BMC_RC_OE_N")
	)
	(segment
		(start 37.707824 -94.869)
		(end 36.472114 -96.10471)
		(width 0.08382)
		(layer "In2.Cu")
		(net "CLK_GEN2_BMC_RC_OE_N")
	)
	(segment
		(start 57.785254 -83.342734)
		(end 51.048666 -83.342734)
		(width 0.08382)
		(layer "In2.Cu")
		(net "CLK_GEN2_BMC_RC_OE_N")
	)
	(segment
		(start 57.21985 -62.484)
		(end 57.21985 -64.457834)
		(width 0.08382)
		(layer "In9.Cu")
		(net "CLK_GEN2_BMC_RC_OE_N")
	)
	(segment
		(start 50.8762 -84.6836)
		(end 49.022 -86.5378)
		(width 0.08382)
		(layer "In9.Cu")
		(net "CLK_GEN2_BMC_RC_OE_N")
	)
	(segment
		(start 56.5658 -67.40906)
		(end 56.5658 -73.075546)
		(width 0.08382)
		(layer "In9.Cu")
		(net "CLK_GEN2_BMC_RC_OE_N")
	)
	(segment
		(start 55.88508 -78.012544)
		(end 57.211214 -81.214214)
		(width 0.08382)
		(layer "In9.Cu")
		(net "CLK_GEN2_BMC_RC_OE_N")
	)
	(segment
		(start 49.022 -86.5378)
		(end 49.022 -89.281)
		(width 0.08382)
		(layer "In9.Cu")
		(net "CLK_GEN2_BMC_RC_OE_N")
	)
	(segment
		(start 57.1119 -65.088516)
		(end 57.1119 -66.86296)
		(width 0.08382)
		(layer "In9.Cu")
		(net "CLK_GEN2_BMC_RC_OE_N")
	)
	(segment
		(start 55.88508 -73.756266)
		(end 55.88508 -78.012544)
		(width 0.08382)
		(layer "In9.Cu")
		(net "CLK_GEN2_BMC_RC_OE_N")
	)
	(segment
		(start 49.3014 -89.5604)
		(end 49.3014 -91.4908)
		(width 0.08382)
		(layer "In9.Cu")
		(net "CLK_GEN2_BMC_RC_OE_N")
	)
	(segment
		(start 57.29478 -64.532764)
		(end 57.29478 -64.905636)
		(width 0.08382)
		(layer "In9.Cu")
		(net "CLK_GEN2_BMC_RC_OE_N")
	)
	(segment
		(start 50.011584 -95.682816)
		(end 40.933116 -95.682816)
		(width 0.08382)
		(layer "In9.Cu")
		(net "CLK_GEN2_BMC_RC_OE_N")
	)
	(segment
		(start 49.022 -89.281)
		(end 49.3014 -89.5604)
		(width 0.08382)
		(layer "In9.Cu")
		(net "CLK_GEN2_BMC_RC_OE_N")
	)
	(segment
		(start 56.5658 -73.075546)
		(end 55.88508 -73.756266)
		(width 0.08382)
		(layer "In9.Cu")
		(net "CLK_GEN2_BMC_RC_OE_N")
	)
	(segment
		(start 50.8254 -93.0148)
		(end 50.8254 -94.869)
		(width 0.08382)
		(layer "In9.Cu")
		(net "CLK_GEN2_BMC_RC_OE_N")
	)
	(segment
		(start 49.3014 -91.4908)
		(end 50.8254 -93.0148)
		(width 0.08382)
		(layer "In9.Cu")
		(net "CLK_GEN2_BMC_RC_OE_N")
	)
	(segment
		(start 58.53303 -82.53603)
		(end 58.53303 -82.79003)
		(width 0.08382)
		(layer "In9.Cu")
		(net "CLK_GEN2_BMC_RC_OE_N")
	)
	(segment
		(start 57.1119 -66.86296)
		(end 56.5658 -67.40906)
		(width 0.08382)
		(layer "In9.Cu")
		(net "CLK_GEN2_BMC_RC_OE_N")
	)
	(segment
		(start 57.21985 -64.457834)
		(end 57.29478 -64.532764)
		(width 0.08382)
		(layer "In9.Cu")
		(net "CLK_GEN2_BMC_RC_OE_N")
	)
	(segment
		(start 57.29478 -64.905636)
		(end 57.1119 -65.088516)
		(width 0.08382)
		(layer "In9.Cu")
		(net "CLK_GEN2_BMC_RC_OE_N")
	)
	(segment
		(start 50.8254 -94.869)
		(end 50.011584 -95.682816)
		(width 0.08382)
		(layer "In9.Cu")
		(net "CLK_GEN2_BMC_RC_OE_N")
	)
	(segment
		(start 50.8762 -83.5152)
		(end 50.8762 -84.6836)
		(width 0.08382)
		(layer "In9.Cu")
		(net "CLK_GEN2_BMC_RC_OE_N")
	)
	(segment
		(start 57.211214 -81.214214)
		(end 58.53303 -82.53603)
		(width 0.08382)
		(layer "In9.Cu")
		(net "CLK_GEN2_BMC_RC_OE_N")
	)
	(segment
		(start 23.854664 -96.782382)
		(end 23.45944 -96.387158)
		(width 0.11684)
		(layer "F.Cu")
		(net "BMC_MONITER")
	)
	(segment
		(start 45.695108 -51.371246)
		(end 45.299884 -51.76647)
		(width 0.11684)
		(layer "F.Cu")
		(net "BMC_MONITER")
	)
	(via
		(at 35.2298 -95.6564)
		(size 0.508)
		(drill 0.254)
		(layers "F.Cu" "B.Cu")
		(net "BMC_MONITER")
	)
	(via
		(at 23.854664 -96.782382)
		(size 0.4572)
		(drill 0.254)
		(layers "F.Cu" "B.Cu")
		(net "BMC_MONITER")
	)
	(via
		(at 45.299884 -51.76647)
		(size 0.4572)
		(drill 0.254)
		(layers "F.Cu" "B.Cu")
		(net "BMC_MONITER")
	)
	(segment
		(start 25.823672 -96.410272)
		(end 24.226774 -96.410272)
		(width 0.08382)
		(layer "In2.Cu")
		(net "BMC_MONITER")
	)
	(segment
		(start 29.989018 -95.24492)
		(end 28.409138 -96.8248)
		(width 0.08382)
		(layer "In2.Cu")
		(net "BMC_MONITER")
	)
	(segment
		(start 35.2298 -95.6564)
		(end 35.01771 -95.86849)
		(width 0.08382)
		(layer "In2.Cu")
		(net "BMC_MONITER")
	)
	(segment
		(start 31.379922 -95.24492)
		(end 29.989018 -95.24492)
		(width 0.08382)
		(layer "In2.Cu")
		(net "BMC_MONITER")
	)
	(segment
		(start 26.2382 -96.8248)
		(end 25.823672 -96.410272)
		(width 0.08382)
		(layer "In2.Cu")
		(net "BMC_MONITER")
	)
	(segment
		(start 32.886396 -95.86849)
		(end 31.379922 -95.24492)
		(width 0.08382)
		(layer "In2.Cu")
		(net "BMC_MONITER")
	)
	(segment
		(start 35.01771 -95.86849)
		(end 32.886396 -95.86849)
		(width 0.08382)
		(layer "In2.Cu")
		(net "BMC_MONITER")
	)
	(segment
		(start 28.409138 -96.8248)
		(end 26.2382 -96.8248)
		(width 0.08382)
		(layer "In2.Cu")
		(net "BMC_MONITER")
	)
	(segment
		(start 24.226774 -96.410272)
		(end 23.854664 -96.782382)
		(width 0.08382)
		(layer "In2.Cu")
		(net "BMC_MONITER")
	)
	(segment
		(start 40.08882 -81.261458)
		(end 39.56304 -80.735678)
		(width 0.10668)
		(layer "In4.Cu")
		(net "BMC_MONITER")
	)
	(segment
		(start 37.5666 -95.6564)
		(end 38.20922 -95.01378)
		(width 0.10668)
		(layer "In4.Cu")
		(net "BMC_MONITER")
	)
	(segment
		(start 39.56304 -80.711802)
		(end 39.563802 -80.71104)
		(width 0.10668)
		(layer "In4.Cu")
		(net "BMC_MONITER")
	)
	(segment
		(start 40.45458 -55.790338)
		(end 40.45458 -53.50002)
		(width 0.10668)
		(layer "In4.Cu")
		(net "BMC_MONITER")
	)
	(segment
		(start 39.41064 -64.5414)
		(end 40.02659 -63.92545)
		(width 0.10668)
		(layer "In4.Cu")
		(net "BMC_MONITER")
	)
	(segment
		(start 41.5671 -52.3875)
		(end 41.5671 -52.2605)
		(width 0.10668)
		(layer "In4.Cu")
		(net "BMC_MONITER")
	)
	(segment
		(start 41.40454 -59.525154)
		(end 41.40454 -59.126882)
		(width 0.10668)
		(layer "In4.Cu")
		(net "BMC_MONITER")
	)
	(segment
		(start 44.558204 -49.6824)
		(end 44.883324 -50.00752)
		(width 0.10668)
		(layer "In4.Cu")
		(net "BMC_MONITER")
	)
	(segment
		(start 40.59936 -67.92976)
		(end 40.33012 -67.66052)
		(width 0.10668)
		(layer "In4.Cu")
		(net "BMC_MONITER")
	)
	(segment
		(start 39.563802 -76.175362)
		(end 40.54348 -75.195684)
		(width 0.10668)
		(layer "In4.Cu")
		(net "BMC_MONITER")
	)
	(segment
		(start 39.751 -58.2168)
		(end 39.751 -56.493918)
		(width 0.10668)
		(layer "In4.Cu")
		(net "BMC_MONITER")
	)
	(segment
		(start 39.563802 -80.71104)
		(end 39.563802 -76.175362)
		(width 0.10668)
		(layer "In4.Cu")
		(net "BMC_MONITER")
	)
	(segment
		(start 40.33012 -67.66052)
		(end 40.33012 -65.98666)
		(width 0.10668)
		(layer "In4.Cu")
		(net "BMC_MONITER")
	)
	(segment
		(start 41.3766 -71.82866)
		(end 40.59936 -71.05142)
		(width 0.10668)
		(layer "In4.Cu")
		(net "BMC_MONITER")
	)
	(segment
		(start 40.386 -58.8518)
		(end 39.751 -58.2168)
		(width 0.10668)
		(layer "In4.Cu")
		(net "BMC_MONITER")
	)
	(segment
		(start 38.31336 -86.34222)
		(end 38.7985 -85.85708)
		(width 0.10668)
		(layer "In4.Cu")
		(net "BMC_MONITER")
	)
	(segment
		(start 40.59936 -71.05142)
		(end 40.59936 -67.92976)
		(width 0.10668)
		(layer "In4.Cu")
		(net "BMC_MONITER")
	)
	(segment
		(start 38.31336 -88.73236)
		(end 38.31336 -86.34222)
		(width 0.10668)
		(layer "In4.Cu")
		(net "BMC_MONITER")
	)
	(segment
		(start 40.45458 -53.50002)
		(end 41.5671 -52.3875)
		(width 0.10668)
		(layer "In4.Cu")
		(net "BMC_MONITER")
	)
	(segment
		(start 39.56304 -80.735678)
		(end 39.56304 -80.711802)
		(width 0.10668)
		(layer "In4.Cu")
		(net "BMC_MONITER")
	)
	(segment
		(start 39.41064 -65.06718)
		(end 39.41064 -64.5414)
		(width 0.10668)
		(layer "In4.Cu")
		(net "BMC_MONITER")
	)
	(segment
		(start 44.883324 -51.34991)
		(end 45.299884 -51.76647)
		(width 0.10668)
		(layer "In4.Cu")
		(net "BMC_MONITER")
	)
	(segment
		(start 38.20922 -92.640658)
		(end 39.0652 -91.784678)
		(width 0.10668)
		(layer "In4.Cu")
		(net "BMC_MONITER")
	)
	(segment
		(start 40.54348 -75.195684)
		(end 40.54348 -73.68286)
		(width 0.10668)
		(layer "In4.Cu")
		(net "BMC_MONITER")
	)
	(segment
		(start 38.7985 -85.85708)
		(end 38.7985 -83.147662)
		(width 0.10668)
		(layer "In4.Cu")
		(net "BMC_MONITER")
	)
	(segment
		(start 40.33012 -65.98666)
		(end 39.41064 -65.06718)
		(width 0.10668)
		(layer "In4.Cu")
		(net "BMC_MONITER")
	)
	(segment
		(start 40.02659 -63.92545)
		(end 40.02659 -62.35319)
		(width 0.10668)
		(layer "In4.Cu")
		(net "BMC_MONITER")
	)
	(segment
		(start 40.02659 -62.35319)
		(end 40.9829 -61.39688)
		(width 0.10668)
		(layer "In4.Cu")
		(net "BMC_MONITER")
	)
	(segment
		(start 42.5196 -51.308)
		(end 42.5196 -50.4952)
		(width 0.10668)
		(layer "In4.Cu")
		(net "BMC_MONITER")
	)
	(segment
		(start 43.3324 -49.6824)
		(end 44.558204 -49.6824)
		(width 0.10668)
		(layer "In4.Cu")
		(net "BMC_MONITER")
	)
	(segment
		(start 41.3766 -72.84974)
		(end 41.3766 -71.82866)
		(width 0.10668)
		(layer "In4.Cu")
		(net "BMC_MONITER")
	)
	(segment
		(start 38.20922 -95.01378)
		(end 38.20922 -92.640658)
		(width 0.10668)
		(layer "In4.Cu")
		(net "BMC_MONITER")
	)
	(segment
		(start 41.40454 -59.126882)
		(end 41.129458 -58.8518)
		(width 0.10668)
		(layer "In4.Cu")
		(net "BMC_MONITER")
	)
	(segment
		(start 40.9829 -59.946794)
		(end 41.40454 -59.525154)
		(width 0.10668)
		(layer "In4.Cu")
		(net "BMC_MONITER")
	)
	(segment
		(start 42.5196 -50.4952)
		(end 43.3324 -49.6824)
		(width 0.10668)
		(layer "In4.Cu")
		(net "BMC_MONITER")
	)
	(segment
		(start 35.2298 -95.6564)
		(end 37.5666 -95.6564)
		(width 0.10668)
		(layer "In4.Cu")
		(net "BMC_MONITER")
	)
	(segment
		(start 40.54348 -73.68286)
		(end 41.3766 -72.84974)
		(width 0.10668)
		(layer "In4.Cu")
		(net "BMC_MONITER")
	)
	(segment
		(start 40.08882 -81.857342)
		(end 40.08882 -81.261458)
		(width 0.10668)
		(layer "In4.Cu")
		(net "BMC_MONITER")
	)
	(segment
		(start 40.9829 -61.39688)
		(end 40.9829 -59.946794)
		(width 0.10668)
		(layer "In4.Cu")
		(net "BMC_MONITER")
	)
	(segment
		(start 38.7985 -83.147662)
		(end 40.08882 -81.857342)
		(width 0.10668)
		(layer "In4.Cu")
		(net "BMC_MONITER")
	)
	(segment
		(start 39.751 -56.493918)
		(end 40.45458 -55.790338)
		(width 0.10668)
		(layer "In4.Cu")
		(net "BMC_MONITER")
	)
	(segment
		(start 41.129458 -58.8518)
		(end 40.386 -58.8518)
		(width 0.10668)
		(layer "In4.Cu")
		(net "BMC_MONITER")
	)
	(segment
		(start 39.0652 -89.4842)
		(end 38.31336 -88.73236)
		(width 0.10668)
		(layer "In4.Cu")
		(net "BMC_MONITER")
	)
	(segment
		(start 39.0652 -91.784678)
		(end 39.0652 -89.4842)
		(width 0.10668)
		(layer "In4.Cu")
		(net "BMC_MONITER")
	)
	(segment
		(start 41.5671 -52.2605)
		(end 42.5196 -51.308)
		(width 0.10668)
		(layer "In4.Cu")
		(net "BMC_MONITER")
	)
	(segment
		(start 44.883324 -50.00752)
		(end 44.883324 -51.34991)
		(width 0.10668)
		(layer "In4.Cu")
		(net "BMC_MONITER")
	)
	(segment
		(start 23.9268 -71.8312)
		(end 23.9268 -70.58025)
		(width 0.11684)
		(layer "F.Cu")
		(net "SPI_BMC_HOLD1_N")
	)
	(segment
		(start 23.9268 -70.58025)
		(end 25.273 -69.23405)
		(width 0.11684)
		(layer "F.Cu")
		(net "SPI_BMC_HOLD1_N")
	)
	(segment
		(start 23.750016 -72.007984)
		(end 23.9268 -71.8312)
		(width 0.11684)
		(layer "F.Cu")
		(net "SPI_BMC_HOLD1_N")
	)
	(segment
		(start 23.750016 -73.360534)
		(end 23.750016 -72.007984)
		(width 0.11684)
		(layer "F.Cu")
		(net "SPI_BMC_HOLD1_N")
	)
	(segment
		(start 29.425646 -75.850242)
		(end 29.425646 -77.106018)
		(width 0.11684)
		(layer "F.Cu")
		(net "SPI_BMC_IO1_FLASH_R")
	)
	(segment
		(start 28.798266 -77.106018)
		(end 28.798266 -75.850242)
		(width 0.11684)
		(layer "F.Cu")
		(net "SPI_BMC_IO1_FLASH_R")
	)
	(segment
		(start 32.916622 -76.053442)
		(end 32.73298 -75.8698)
		(width 0.11684)
		(layer "F.Cu")
		(net "SPI_BMC_IO1_FLASH_R")
	)
	(segment
		(start 26.916126 -75.850242)
		(end 26.916126 -77.106018)
		(width 0.11684)
		(layer "F.Cu")
		(net "SPI_BMC_IO1_FLASH_R")
	)
	(segment
		(start 25.845008 -75.6666)
		(end 25.661366 -75.850242)
		(width 0.11684)
		(layer "F.Cu")
		(net "SPI_BMC_IO1_FLASH_R")
	)
	(segment
		(start 27.543506 -77.106018)
		(end 27.543506 -75.850242)
		(width 0.11684)
		(layer "F.Cu")
		(net "SPI_BMC_IO1_FLASH_R")
	)
	(segment
		(start 39.012876 -76.70927)
		(end 38.432486 -77.28966)
		(width 0.11684)
		(layer "F.Cu")
		(net "SPI_BMC_IO1_FLASH_R")
	)
	(segment
		(start 27.727148 -77.28966)
		(end 27.543506 -77.106018)
		(width 0.11684)
		(layer "F.Cu")
		(net "SPI_BMC_IO1_FLASH_R")
	)
	(segment
		(start 23.814532 -79.567532)
		(end 23.50008 -79.881984)
		(width 0.11684)
		(layer "F.Cu")
		(net "SPI_BMC_IO1_FLASH_R")
	)
	(segment
		(start 26.288746 -75.850242)
		(end 26.105104 -75.6666)
		(width 0.11684)
		(layer "F.Cu")
		(net "SPI_BMC_IO1_FLASH_R")
	)
	(segment
		(start 32.73298 -75.8698)
		(end 32.472884 -75.8698)
		(width 0.11684)
		(layer "F.Cu")
		(net "SPI_BMC_IO1_FLASH_R")
	)
	(segment
		(start 32.289242 -76.053442)
		(end 32.289242 -77.106018)
		(width 0.11684)
		(layer "F.Cu")
		(net "SPI_BMC_IO1_FLASH_R")
	)
	(segment
		(start 24.4856 -77.6732)
		(end 24.4856 -79.300324)
		(width 0.11684)
		(layer "F.Cu")
		(net "SPI_BMC_IO1_FLASH_R")
	)
	(segment
		(start 26.105104 -75.6666)
		(end 25.845008 -75.6666)
		(width 0.11684)
		(layer "F.Cu")
		(net "SPI_BMC_IO1_FLASH_R")
	)
	(segment
		(start 29.609288 -75.6666)
		(end 29.425646 -75.850242)
		(width 0.11684)
		(layer "F.Cu")
		(net "SPI_BMC_IO1_FLASH_R")
	)
	(segment
		(start 33.100264 -77.28966)
		(end 32.916622 -77.106018)
		(width 0.11684)
		(layer "F.Cu")
		(net "SPI_BMC_IO1_FLASH_R")
	)
	(segment
		(start 39.012876 -75.852274)
		(end 39.012876 -76.70927)
		(width 0.11684)
		(layer "F.Cu")
		(net "SPI_BMC_IO1_FLASH_R")
	)
	(segment
		(start 32.916622 -77.106018)
		(end 32.916622 -76.053442)
		(width 0.11684)
		(layer "F.Cu")
		(net "SPI_BMC_IO1_FLASH_R")
	)
	(segment
		(start 29.242004 -77.28966)
		(end 28.981908 -77.28966)
		(width 0.11684)
		(layer "F.Cu")
		(net "SPI_BMC_IO1_FLASH_R")
	)
	(segment
		(start 29.869384 -75.6666)
		(end 29.609288 -75.6666)
		(width 0.11684)
		(layer "F.Cu")
		(net "SPI_BMC_IO1_FLASH_R")
	)
	(segment
		(start 24.86914 -77.28966)
		(end 24.4856 -77.6732)
		(width 0.11684)
		(layer "F.Cu")
		(net "SPI_BMC_IO1_FLASH_R")
	)
	(segment
		(start 25.661366 -77.106018)
		(end 25.477724 -77.28966)
		(width 0.11684)
		(layer "F.Cu")
		(net "SPI_BMC_IO1_FLASH_R")
	)
	(segment
		(start 28.170886 -77.106018)
		(end 27.987244 -77.28966)
		(width 0.11684)
		(layer "F.Cu")
		(net "SPI_BMC_IO1_FLASH_R")
	)
	(segment
		(start 24.4856 -79.300324)
		(end 24.218392 -79.567532)
		(width 0.11684)
		(layer "F.Cu")
		(net "SPI_BMC_IO1_FLASH_R")
	)
	(segment
		(start 26.916126 -77.106018)
		(end 26.732484 -77.28966)
		(width 0.11684)
		(layer "F.Cu")
		(net "SPI_BMC_IO1_FLASH_R")
	)
	(segment
		(start 24.218392 -79.567532)
		(end 23.814532 -79.567532)
		(width 0.11684)
		(layer "F.Cu")
		(net "SPI_BMC_IO1_FLASH_R")
	)
	(segment
		(start 25.477724 -77.28966)
		(end 24.86914 -77.28966)
		(width 0.11684)
		(layer "F.Cu")
		(net "SPI_BMC_IO1_FLASH_R")
	)
	(segment
		(start 28.614624 -75.6666)
		(end 28.354528 -75.6666)
		(width 0.11684)
		(layer "F.Cu")
		(net "SPI_BMC_IO1_FLASH_R")
	)
	(segment
		(start 28.170886 -75.850242)
		(end 28.170886 -77.106018)
		(width 0.11684)
		(layer "F.Cu")
		(net "SPI_BMC_IO1_FLASH_R")
	)
	(segment
		(start 32.289242 -77.106018)
		(end 32.1056 -77.28966)
		(width 0.11684)
		(layer "F.Cu")
		(net "SPI_BMC_IO1_FLASH_R")
	)
	(segment
		(start 29.425646 -77.106018)
		(end 29.242004 -77.28966)
		(width 0.11684)
		(layer "F.Cu")
		(net "SPI_BMC_IO1_FLASH_R")
	)
	(segment
		(start 28.798266 -75.850242)
		(end 28.614624 -75.6666)
		(width 0.11684)
		(layer "F.Cu")
		(net "SPI_BMC_IO1_FLASH_R")
	)
	(segment
		(start 39.42715 -75.438)
		(end 39.012876 -75.852274)
		(width 0.11684)
		(layer "F.Cu")
		(net "SPI_BMC_IO1_FLASH_R")
	)
	(segment
		(start 26.732484 -77.28966)
		(end 26.472388 -77.28966)
		(width 0.11684)
		(layer "F.Cu")
		(net "SPI_BMC_IO1_FLASH_R")
	)
	(segment
		(start 26.472388 -77.28966)
		(end 26.288746 -77.106018)
		(width 0.11684)
		(layer "F.Cu")
		(net "SPI_BMC_IO1_FLASH_R")
	)
	(segment
		(start 27.359864 -75.6666)
		(end 27.099768 -75.6666)
		(width 0.11684)
		(layer "F.Cu")
		(net "SPI_BMC_IO1_FLASH_R")
	)
	(segment
		(start 27.987244 -77.28966)
		(end 27.727148 -77.28966)
		(width 0.11684)
		(layer "F.Cu")
		(net "SPI_BMC_IO1_FLASH_R")
	)
	(segment
		(start 30.236668 -77.28966)
		(end 30.053026 -77.106018)
		(width 0.11684)
		(layer "F.Cu")
		(net "SPI_BMC_IO1_FLASH_R")
	)
	(segment
		(start 26.288746 -77.106018)
		(end 26.288746 -75.850242)
		(width 0.11684)
		(layer "F.Cu")
		(net "SPI_BMC_IO1_FLASH_R")
	)
	(segment
		(start 30.053026 -77.106018)
		(end 30.053026 -75.850242)
		(width 0.11684)
		(layer "F.Cu")
		(net "SPI_BMC_IO1_FLASH_R")
	)
	(segment
		(start 25.661366 -75.850242)
		(end 25.661366 -77.106018)
		(width 0.11684)
		(layer "F.Cu")
		(net "SPI_BMC_IO1_FLASH_R")
	)
	(segment
		(start 38.432486 -77.28966)
		(end 33.100264 -77.28966)
		(width 0.11684)
		(layer "F.Cu")
		(net "SPI_BMC_IO1_FLASH_R")
	)
	(segment
		(start 32.1056 -77.28966)
		(end 30.236668 -77.28966)
		(width 0.11684)
		(layer "F.Cu")
		(net "SPI_BMC_IO1_FLASH_R")
	)
	(segment
		(start 32.472884 -75.8698)
		(end 32.289242 -76.053442)
		(width 0.11684)
		(layer "F.Cu")
		(net "SPI_BMC_IO1_FLASH_R")
	)
	(segment
		(start 27.099768 -75.6666)
		(end 26.916126 -75.850242)
		(width 0.11684)
		(layer "F.Cu")
		(net "SPI_BMC_IO1_FLASH_R")
	)
	(segment
		(start 27.543506 -75.850242)
		(end 27.359864 -75.6666)
		(width 0.11684)
		(layer "F.Cu")
		(net "SPI_BMC_IO1_FLASH_R")
	)
	(segment
		(start 23.50008 -79.881984)
		(end 23.50008 -80.910176)
		(width 0.11684)
		(layer "F.Cu")
		(net "SPI_BMC_IO1_FLASH_R")
	)
	(segment
		(start 30.053026 -75.850242)
		(end 29.869384 -75.6666)
		(width 0.11684)
		(layer "F.Cu")
		(net "SPI_BMC_IO1_FLASH_R")
	)
	(segment
		(start 28.981908 -77.28966)
		(end 28.798266 -77.106018)
		(width 0.11684)
		(layer "F.Cu")
		(net "SPI_BMC_IO1_FLASH_R")
	)
	(segment
		(start 28.354528 -75.6666)
		(end 28.170886 -75.850242)
		(width 0.11684)
		(layer "F.Cu")
		(net "SPI_BMC_IO1_FLASH_R")
	)
	(segment
		(start 24.8158 -78.1304)
		(end 24.8158 -79.5274)
		(width 0.11684)
		(layer "F.Cu")
		(net "SPI_BMC_IO0_FLASH_R")
	)
	(segment
		(start 24.4602 -79.883)
		(end 24.2062 -79.883)
		(width 0.11684)
		(layer "F.Cu")
		(net "SPI_BMC_IO0_FLASH_R")
	)
	(segment
		(start 39.42715 -76.454)
		(end 39.42715 -76.754228)
		(width 0.11684)
		(layer "F.Cu")
		(net "SPI_BMC_IO0_FLASH_R")
	)
	(segment
		(start 39.42715 -76.754228)
		(end 38.622478 -77.5589)
		(width 0.11684)
		(layer "F.Cu")
		(net "SPI_BMC_IO0_FLASH_R")
	)
	(segment
		(start 24.2062 -79.883)
		(end 23.999952 -80.089248)
		(width 0.11684)
		(layer "F.Cu")
		(net "SPI_BMC_IO0_FLASH_R")
	)
	(segment
		(start 25.3873 -77.5589)
		(end 24.8158 -78.1304)
		(width 0.11684)
		(layer "F.Cu")
		(net "SPI_BMC_IO0_FLASH_R")
	)
	(segment
		(start 23.999952 -80.089248)
		(end 23.999952 -80.910176)
		(width 0.11684)
		(layer "F.Cu")
		(net "SPI_BMC_IO0_FLASH_R")
	)
	(segment
		(start 24.8158 -79.5274)
		(end 24.4602 -79.883)
		(width 0.11684)
		(layer "F.Cu")
		(net "SPI_BMC_IO0_FLASH_R")
	)
	(segment
		(start 38.622478 -77.5589)
		(end 25.3873 -77.5589)
		(width 0.11684)
		(layer "F.Cu")
		(net "SPI_BMC_IO0_FLASH_R")
	)
	(segment
		(start 26.502614 -78.09738)
		(end 38.881812 -78.09738)
		(width 0.11684)
		(layer "F.Cu")
		(net "SPI_BMC_CS1_FLASH_R_N")
	)
	(segment
		(start 42.1386 -77.6224)
		(end 42.164 -77.597)
		(width 0.11684)
		(layer "F.Cu")
		(net "SPI_BMC_CS1_FLASH_R_N")
	)
	(segment
		(start 38.881812 -78.09738)
		(end 39.42715 -78.642718)
		(width 0.11684)
		(layer "F.Cu")
		(net "SPI_BMC_CS1_FLASH_R_N")
	)
	(segment
		(start 42.164 -75.057)
		(end 42.164 -77.597)
		(width 0.11684)
		(layer "F.Cu")
		(net "SPI_BMC_CS1_FLASH_R_N")
	)
	(segment
		(start 39.42715 -78.642718)
		(end 39.42715 -78.6638)
		(width 0.11684)
		(layer "F.Cu")
		(net "SPI_BMC_CS1_FLASH_R_N")
	)
	(segment
		(start 40.36441 -78.10119)
		(end 40.8432 -77.6224)
		(width 0.11684)
		(layer "F.Cu")
		(net "SPI_BMC_CS1_FLASH_R_N")
	)
	(segment
		(start 40.8432 -77.6224)
		(end 42.1386 -77.6224)
		(width 0.11684)
		(layer "F.Cu")
		(net "SPI_BMC_CS1_FLASH_R_N")
	)
	(segment
		(start 40.014906 -78.10119)
		(end 40.36441 -78.10119)
		(width 0.11684)
		(layer "F.Cu")
		(net "SPI_BMC_CS1_FLASH_R_N")
	)
	(segment
		(start 39.452296 -78.6638)
		(end 40.014906 -78.10119)
		(width 0.11684)
		(layer "F.Cu")
		(net "SPI_BMC_CS1_FLASH_R_N")
	)
	(segment
		(start 25.999948 -79.994252)
		(end 26.19756 -79.79664)
		(width 0.11684)
		(layer "F.Cu")
		(net "SPI_BMC_CS1_FLASH_R_N")
	)
	(segment
		(start 39.42715 -78.6638)
		(end 39.452296 -78.6638)
		(width 0.11684)
		(layer "F.Cu")
		(net "SPI_BMC_CS1_FLASH_R_N")
	)
	(segment
		(start 26.19756 -78.39964)
		(end 26.4668 -78.1304)
		(width 0.11684)
		(layer "F.Cu")
		(net "SPI_BMC_CS1_FLASH_R_N")
	)
	(segment
		(start 26.4668 -78.1304)
		(end 26.469594 -78.1304)
		(width 0.11684)
		(layer "F.Cu")
		(net "SPI_BMC_CS1_FLASH_R_N")
	)
	(segment
		(start 26.19756 -79.79664)
		(end 26.19756 -78.39964)
		(width 0.11684)
		(layer "F.Cu")
		(net "SPI_BMC_CS1_FLASH_R_N")
	)
	(segment
		(start 26.469594 -78.1304)
		(end 26.502614 -78.09738)
		(width 0.11684)
		(layer "F.Cu")
		(net "SPI_BMC_CS1_FLASH_R_N")
	)
	(segment
		(start 41.1734 -74.0664)
		(end 42.164 -75.057)
		(width 0.11684)
		(layer "F.Cu")
		(net "SPI_BMC_CS1_FLASH_R_N")
	)
	(segment
		(start 25.999948 -80.910176)
		(end 25.999948 -79.994252)
		(width 0.11684)
		(layer "F.Cu")
		(net "SPI_BMC_CS1_FLASH_R_N")
	)
	(via
		(at 58.1152 -77.597)
		(size 0.508)
		(drill 0.254)
		(layers "F.Cu" "B.Cu")
		(net "SPI_BMC_CS1_FLASH_R_N")
	)
	(via
		(at 41.1734 -74.0664)
		(size 0.508)
		(drill 0.254)
		(layers "F.Cu" "B.Cu")
		(net "SPI_BMC_CS1_FLASH_R_N")
	)
	(via
		(at 42.164 -77.597)
		(size 0.762)
		(drill 0.381)
		(layers "F.Cu" "B.Cu")
		(net "SPI_BMC_CS1_FLASH_R_N")
	)
	(segment
		(start 59.78525 -77.9526)
		(end 59.25185 -77.4192)
		(width 0.11684)
		(layer "B.Cu")
		(net "SPI_BMC_CS1_FLASH_R_N")
	)
	(segment
		(start 58.293 -77.4192)
		(end 58.1152 -77.597)
		(width 0.11684)
		(layer "B.Cu")
		(net "SPI_BMC_CS1_FLASH_R_N")
	)
	(segment
		(start 59.25185 -77.4192)
		(end 58.293 -77.4192)
		(width 0.11684)
		(layer "B.Cu")
		(net "SPI_BMC_CS1_FLASH_R_N")
	)
	(segment
		(start 56.08193 -76.43749)
		(end 55.03164 -75.3872)
		(width 0.08382)
		(layer "In2.Cu")
		(net "SPI_BMC_CS1_FLASH_R_N")
	)
	(segment
		(start 42.186606 -73.05294)
		(end 42.186606 -73.053194)
		(width 0.08382)
		(layer "In2.Cu")
		(net "SPI_BMC_CS1_FLASH_R_N")
	)
	(segment
		(start 50.345086 -73.05294)
		(end 42.186606 -73.05294)
		(width 0.08382)
		(layer "In2.Cu")
		(net "SPI_BMC_CS1_FLASH_R_N")
	)
	(segment
		(start 56.95569 -76.43749)
		(end 56.08193 -76.43749)
		(width 0.08382)
		(layer "In2.Cu")
		(net "SPI_BMC_CS1_FLASH_R_N")
	)
	(segment
		(start 42.186606 -73.053194)
		(end 41.1734 -74.0664)
		(width 0.08382)
		(layer "In2.Cu")
		(net "SPI_BMC_CS1_FLASH_R_N")
	)
	(segment
		(start 52.679346 -75.3872)
		(end 50.345086 -73.05294)
		(width 0.08382)
		(layer "In2.Cu")
		(net "SPI_BMC_CS1_FLASH_R_N")
	)
	(segment
		(start 55.03164 -75.3872)
		(end 52.679346 -75.3872)
		(width 0.08382)
		(layer "In2.Cu")
		(net "SPI_BMC_CS1_FLASH_R_N")
	)
	(segment
		(start 58.1152 -77.597)
		(end 56.95569 -76.43749)
		(width 0.08382)
		(layer "In2.Cu")
		(net "SPI_BMC_CS1_FLASH_R_N")
	)
	(segment
		(start 39.426896 -80.02016)
		(end 39.543736 -80.137)
		(width 0.11684)
		(layer "F.Cu")
		(net "SPI_BMC_CS0_FLASH_R_N")
	)
	(segment
		(start 34.426906 -78.593442)
		(end 34.426906 -78.810358)
		(width 0.11684)
		(layer "F.Cu")
		(net "SPI_BMC_CS0_FLASH_R_N")
	)
	(segment
		(start 33.983168 -78.4098)
		(end 34.243264 -78.4098)
		(width 0.11684)
		(layer "F.Cu")
		(net "SPI_BMC_CS0_FLASH_R_N")
	)
	(segment
		(start 41.9608 -80.62595)
		(end 41.04005 -80.62595)
		(width 0.11684)
		(layer "F.Cu")
		(net "SPI_BMC_CS0_FLASH_R_N")
	)
	(segment
		(start 34.243264 -78.4098)
		(end 34.426906 -78.593442)
		(width 0.11684)
		(layer "F.Cu")
		(net "SPI_BMC_CS0_FLASH_R_N")
	)
	(segment
		(start 26.500074 -79.875126)
		(end 26.67 -79.7052)
		(width 0.11684)
		(layer "F.Cu")
		(net "SPI_BMC_CS0_FLASH_R_N")
	)
	(segment
		(start 33.172146 -78.593442)
		(end 33.172146 -78.810358)
		(width 0.11684)
		(layer "F.Cu")
		(net "SPI_BMC_CS0_FLASH_R_N")
	)
	(segment
		(start 33.355788 -78.994)
		(end 33.615884 -78.994)
		(width 0.11684)
		(layer "F.Cu")
		(net "SPI_BMC_CS0_FLASH_R_N")
	)
	(segment
		(start 31.260542 -78.4098)
		(end 32.988504 -78.4098)
		(width 0.11684)
		(layer "F.Cu")
		(net "SPI_BMC_CS0_FLASH_R_N")
	)
	(segment
		(start 33.172146 -78.810358)
		(end 33.355788 -78.994)
		(width 0.11684)
		(layer "F.Cu")
		(net "SPI_BMC_CS0_FLASH_R_N")
	)
	(segment
		(start 30.44952 -78.593442)
		(end 30.44952 -78.810358)
		(width 0.11684)
		(layer "F.Cu")
		(net "SPI_BMC_CS0_FLASH_R_N")
	)
	(segment
		(start 26.500074 -80.910176)
		(end 26.500074 -79.875126)
		(width 0.11684)
		(layer "F.Cu")
		(net "SPI_BMC_CS0_FLASH_R_N")
	)
	(segment
		(start 32.988504 -78.4098)
		(end 33.172146 -78.593442)
		(width 0.11684)
		(layer "F.Cu")
		(net "SPI_BMC_CS0_FLASH_R_N")
	)
	(segment
		(start 34.426906 -78.810358)
		(end 34.610548 -78.994)
		(width 0.11684)
		(layer "F.Cu")
		(net "SPI_BMC_CS0_FLASH_R_N")
	)
	(segment
		(start 39.426896 -79.64424)
		(end 39.426896 -80.02016)
		(width 0.11684)
		(layer "F.Cu")
		(net "SPI_BMC_CS0_FLASH_R_N")
	)
	(segment
		(start 33.615884 -78.994)
		(end 33.799526 -78.810358)
		(width 0.11684)
		(layer "F.Cu")
		(net "SPI_BMC_CS0_FLASH_R_N")
	)
	(segment
		(start 41.04005 -80.62595)
		(end 40.767 -80.899)
		(width 0.11684)
		(layer "F.Cu")
		(net "SPI_BMC_CS0_FLASH_R_N")
	)
	(segment
		(start 35.237928 -78.4098)
		(end 37.719 -78.4098)
		(width 0.11684)
		(layer "F.Cu")
		(net "SPI_BMC_CS0_FLASH_R_N")
	)
	(segment
		(start 38.95344 -79.64424)
		(end 39.426896 -79.64424)
		(width 0.11684)
		(layer "F.Cu")
		(net "SPI_BMC_CS0_FLASH_R_N")
	)
	(segment
		(start 30.265878 -78.4098)
		(end 30.44952 -78.593442)
		(width 0.11684)
		(layer "F.Cu")
		(net "SPI_BMC_CS0_FLASH_R_N")
	)
	(segment
		(start 40.005 -80.137)
		(end 40.767 -80.899)
		(width 0.11684)
		(layer "F.Cu")
		(net "SPI_BMC_CS0_FLASH_R_N")
	)
	(segment
		(start 30.633162 -78.994)
		(end 30.893258 -78.994)
		(width 0.11684)
		(layer "F.Cu")
		(net "SPI_BMC_CS0_FLASH_R_N")
	)
	(segment
		(start 30.44952 -78.810358)
		(end 30.633162 -78.994)
		(width 0.11684)
		(layer "F.Cu")
		(net "SPI_BMC_CS0_FLASH_R_N")
	)
	(segment
		(start 26.67 -79.7052)
		(end 26.903426 -79.7052)
		(width 0.11684)
		(layer "F.Cu")
		(net "SPI_BMC_CS0_FLASH_R_N")
	)
	(segment
		(start 30.893258 -78.994)
		(end 31.0769 -78.810358)
		(width 0.11684)
		(layer "F.Cu")
		(net "SPI_BMC_CS0_FLASH_R_N")
	)
	(segment
		(start 31.0769 -78.810358)
		(end 31.0769 -78.593442)
		(width 0.11684)
		(layer "F.Cu")
		(net "SPI_BMC_CS0_FLASH_R_N")
	)
	(segment
		(start 37.719 -78.4098)
		(end 38.95344 -79.64424)
		(width 0.11684)
		(layer "F.Cu")
		(net "SPI_BMC_CS0_FLASH_R_N")
	)
	(segment
		(start 31.0769 -78.593442)
		(end 31.260542 -78.4098)
		(width 0.11684)
		(layer "F.Cu")
		(net "SPI_BMC_CS0_FLASH_R_N")
	)
	(segment
		(start 33.799526 -78.593442)
		(end 33.983168 -78.4098)
		(width 0.11684)
		(layer "F.Cu")
		(net "SPI_BMC_CS0_FLASH_R_N")
	)
	(segment
		(start 34.870644 -78.994)
		(end 35.054286 -78.810358)
		(width 0.11684)
		(layer "F.Cu")
		(net "SPI_BMC_CS0_FLASH_R_N")
	)
	(segment
		(start 39.543736 -80.137)
		(end 40.005 -80.137)
		(width 0.11684)
		(layer "F.Cu")
		(net "SPI_BMC_CS0_FLASH_R_N")
	)
	(segment
		(start 34.610548 -78.994)
		(end 34.870644 -78.994)
		(width 0.11684)
		(layer "F.Cu")
		(net "SPI_BMC_CS0_FLASH_R_N")
	)
	(segment
		(start 33.799526 -78.810358)
		(end 33.799526 -78.593442)
		(width 0.11684)
		(layer "F.Cu")
		(net "SPI_BMC_CS0_FLASH_R_N")
	)
	(segment
		(start 35.054286 -78.810358)
		(end 35.054286 -78.593442)
		(width 0.11684)
		(layer "F.Cu")
		(net "SPI_BMC_CS0_FLASH_R_N")
	)
	(segment
		(start 35.054286 -78.593442)
		(end 35.237928 -78.4098)
		(width 0.11684)
		(layer "F.Cu")
		(net "SPI_BMC_CS0_FLASH_R_N")
	)
	(segment
		(start 27.134566 -79.47406)
		(end 27.83332 -79.47406)
		(width 0.11684)
		(layer "F.Cu")
		(net "SPI_BMC_CS0_FLASH_R_N")
	)
	(segment
		(start 26.903426 -79.7052)
		(end 27.134566 -79.47406)
		(width 0.11684)
		(layer "F.Cu")
		(net "SPI_BMC_CS0_FLASH_R_N")
	)
	(segment
		(start 28.89758 -78.4098)
		(end 30.265878 -78.4098)
		(width 0.11684)
		(layer "F.Cu")
		(net "SPI_BMC_CS0_FLASH_R_N")
	)
	(segment
		(start 27.83332 -79.47406)
		(end 28.89758 -78.4098)
		(width 0.11684)
		(layer "F.Cu")
		(net "SPI_BMC_CS0_FLASH_R_N")
	)
	(via
		(at 40.767 -80.899)
		(size 0.762)
		(drill 0.381)
		(layers "F.Cu" "B.Cu")
		(net "SPI_BMC_CS0_FLASH_R_N")
	)
	(segment
		(start 39.09441 -77.82814)
		(end 26.390854 -77.82814)
		(width 0.11684)
		(layer "F.Cu")
		(net "SPI_BMC_CLK_FLASH_R")
	)
	(segment
		(start 24.99995 -80.003904)
		(end 24.99995 -80.910176)
		(width 0.11684)
		(layer "F.Cu")
		(net "SPI_BMC_CLK_FLASH_R")
	)
	(segment
		(start 25.68702 -79.72298)
		(end 25.280874 -79.72298)
		(width 0.11684)
		(layer "F.Cu")
		(net "SPI_BMC_CLK_FLASH_R")
	)
	(segment
		(start 39.42715 -77.4954)
		(end 39.09441 -77.82814)
		(width 0.11684)
		(layer "F.Cu")
		(net "SPI_BMC_CLK_FLASH_R")
	)
	(segment
		(start 25.92832 -79.48168)
		(end 25.68702 -79.72298)
		(width 0.11684)
		(layer "F.Cu")
		(net "SPI_BMC_CLK_FLASH_R")
	)
	(segment
		(start 25.92832 -78.28788)
		(end 25.92832 -79.48168)
		(width 0.11684)
		(layer "F.Cu")
		(net "SPI_BMC_CLK_FLASH_R")
	)
	(segment
		(start 26.390854 -77.82814)
		(end 26.332434 -77.88656)
		(width 0.11684)
		(layer "F.Cu")
		(net "SPI_BMC_CLK_FLASH_R")
	)
	(segment
		(start 26.32964 -77.88656)
		(end 25.92832 -78.28788)
		(width 0.11684)
		(layer "F.Cu")
		(net "SPI_BMC_CLK_FLASH_R")
	)
	(segment
		(start 25.280874 -79.72298)
		(end 24.99995 -80.003904)
		(width 0.11684)
		(layer "F.Cu")
		(net "SPI_BMC_CLK_FLASH_R")
	)
	(segment
		(start 26.332434 -77.88656)
		(end 26.32964 -77.88656)
		(width 0.11684)
		(layer "F.Cu")
		(net "SPI_BMC_CLK_FLASH_R")
	)
	(segment
		(start 48.7172 -82.5246)
		(end 48.7172 -82.471768)
		(width 0.11684)
		(layer "F.Cu")
		(net "PU_J1_P1")
	)
	(segment
		(start 48.7172 -82.471768)
		(end 47.773082 -81.52765)
		(width 0.11684)
		(layer "F.Cu")
		(net "PU_J1_P1")
	)
	(segment
		(start 52.624482 -83.05038)
		(end 49.24298 -83.05038)
		(width 0.11684)
		(layer "F.Cu")
		(net "PU_J1_P1")
	)
	(segment
		(start 47.773082 -81.52765)
		(end 47.752 -81.52765)
		(width 0.11684)
		(layer "F.Cu")
		(net "PU_J1_P1")
	)
	(segment
		(start 49.24298 -83.05038)
		(end 48.7172 -82.5246)
		(width 0.11684)
		(layer "F.Cu")
		(net "PU_J1_P1")
	)
	(segment
		(start 52.936902 -83.3628)
		(end 52.624482 -83.05038)
		(width 0.11684)
		(layer "F.Cu")
		(net "PU_J1_P1")
	)
	(segment
		(start 57.19572 -78.81239)
		(end 56.20004 -78.81239)
		(width 0.11684)
		(layer "F.Cu")
		(net "FLASH_LATCH_Q_N_R1")
	)
	(segment
		(start 57.42305 -78.58506)
		(end 57.19572 -78.81239)
		(width 0.11684)
		(layer "F.Cu")
		(net "FLASH_LATCH_Q_N_R1")
	)
	(segment
		(start 57.42305 -77.3684)
		(end 57.42305 -78.58506)
		(width 0.11684)
		(layer "F.Cu")
		(net "FLASH_LATCH_Q_N_R1")
	)
	(via
		(at 57.42305 -78.58506)
		(size 0.762)
		(drill 0.381)
		(layers "F.Cu" "B.Cu")
		(net "FLASH_LATCH_Q_N_R1")
	)
	(segment
		(start 54.70652 -76.67752)
		(end 53.590952 -76.67752)
		(width 0.11684)
		(layer "F.Cu")
		(net "FLASH_LATCH_Q_N_R")
	)
	(segment
		(start 55.3974 -77.6224)
		(end 55.3974 -77.3684)
		(width 0.11684)
		(layer "F.Cu")
		(net "FLASH_LATCH_Q_N_R")
	)
	(segment
		(start 55.3974 -77.3684)
		(end 54.70652 -76.67752)
		(width 0.11684)
		(layer "F.Cu")
		(net "FLASH_LATCH_Q_N_R")
	)
	(segment
		(start 56.62295 -77.3684)
		(end 56.36895 -77.6224)
		(width 0.11684)
		(layer "F.Cu")
		(net "FLASH_LATCH_Q_N_R")
	)
	(segment
		(start 56.36895 -77.6224)
		(end 55.3974 -77.6224)
		(width 0.11684)
		(layer "F.Cu")
		(net "FLASH_LATCH_Q_N_R")
	)
	(via
		(at 55.3974 -77.6224)
		(size 0.762)
		(drill 0.381)
		(layers "F.Cu" "B.Cu")
		(net "FLASH_LATCH_Q_N_R")
	)
	(segment
		(start 44.0944 -82.01025)
		(end 44.0944 -79.943706)
		(width 0.11684)
		(layer "F.Cu")
		(net "SPI_BMC_BT_WP1_N_R")
	)
	(segment
		(start 17.8816 -79.121)
		(end 17.8816 -80.1116)
		(width 0.11684)
		(layer "F.Cu")
		(net "SPI_BMC_BT_WP1_N_R")
	)
	(segment
		(start 43.7007 -79.550006)
		(end 43.7007 -78.26248)
		(width 0.11684)
		(layer "F.Cu")
		(net "SPI_BMC_BT_WP1_N_R")
	)
	(segment
		(start 16.9164 -74.549)
		(end 17.2466 -74.549)
		(width 0.11684)
		(layer "F.Cu")
		(net "SPI_BMC_BT_WP1_N_R")
	)
	(segment
		(start 43.7007 -78.26248)
		(end 43.322494 -77.884274)
		(width 0.11684)
		(layer "F.Cu")
		(net "SPI_BMC_BT_WP1_N_R")
	)
	(segment
		(start 16.383 -74.0156)
		(end 16.9164 -74.549)
		(width 0.11684)
		(layer "F.Cu")
		(net "SPI_BMC_BT_WP1_N_R")
	)
	(segment
		(start 18.2118 -78.105)
		(end 18.2118 -78.7908)
		(width 0.11684)
		(layer "F.Cu")
		(net "SPI_BMC_BT_WP1_N_R")
	)
	(segment
		(start 17.9324 -75.2348)
		(end 17.9324 -77.8256)
		(width 0.11684)
		(layer "F.Cu")
		(net "SPI_BMC_BT_WP1_N_R")
	)
	(segment
		(start 15.5448 -71.11365)
		(end 15.5448 -71.7804)
		(width 0.11684)
		(layer "F.Cu")
		(net "SPI_BMC_BT_WP1_N_R")
	)
	(segment
		(start 17.9324 -77.8256)
		(end 18.2118 -78.105)
		(width 0.11684)
		(layer "F.Cu")
		(net "SPI_BMC_BT_WP1_N_R")
	)
	(segment
		(start 44.0944 -79.943706)
		(end 43.7007 -79.550006)
		(width 0.11684)
		(layer "F.Cu")
		(net "SPI_BMC_BT_WP1_N_R")
	)
	(segment
		(start 17.8816 -80.1116)
		(end 17.999964 -80.229964)
		(width 0.11684)
		(layer "F.Cu")
		(net "SPI_BMC_BT_WP1_N_R")
	)
	(segment
		(start 44.68495 -82.6008)
		(end 44.0944 -82.01025)
		(width 0.11684)
		(layer "F.Cu")
		(net "SPI_BMC_BT_WP1_N_R")
	)
	(segment
		(start 17.2466 -74.549)
		(end 17.9324 -75.2348)
		(width 0.11684)
		(layer "F.Cu")
		(net "SPI_BMC_BT_WP1_N_R")
	)
	(segment
		(start 18.2118 -78.7908)
		(end 17.8816 -79.121)
		(width 0.11684)
		(layer "F.Cu")
		(net "SPI_BMC_BT_WP1_N_R")
	)
	(segment
		(start 15.5448 -71.7804)
		(end 16.383 -72.6186)
		(width 0.11684)
		(layer "F.Cu")
		(net "SPI_BMC_BT_WP1_N_R")
	)
	(segment
		(start 17.999964 -80.229964)
		(end 17.999964 -80.910176)
		(width 0.11684)
		(layer "F.Cu")
		(net "SPI_BMC_BT_WP1_N_R")
	)
	(segment
		(start 16.383 -72.6186)
		(end 16.383 -74.0156)
		(width 0.11684)
		(layer "F.Cu")
		(net "SPI_BMC_BT_WP1_N_R")
	)
	(via
		(at 43.322494 -77.884274)
		(size 0.508)
		(drill 0.254)
		(layers "F.Cu" "B.Cu")
		(net "SPI_BMC_BT_WP1_N_R")
	)
	(via
		(at 15.5448 -71.7804)
		(size 0.508)
		(drill 0.254)
		(layers "F.Cu" "B.Cu")
		(net "SPI_BMC_BT_WP1_N_R")
	)
	(segment
		(start 32.173164 -77.70114)
		(end 27.929078 -77.70114)
		(width 0.08382)
		(layer "In2.Cu")
		(net "SPI_BMC_BT_WP1_N_R")
	)
	(segment
		(start 18.0848 -70.79107)
		(end 17.9578 -70.66407)
		(width 0.08382)
		(layer "In2.Cu")
		(net "SPI_BMC_BT_WP1_N_R")
	)
	(segment
		(start 16.66113 -70.66407)
		(end 15.5448 -71.7804)
		(width 0.08382)
		(layer "In2.Cu")
		(net "SPI_BMC_BT_WP1_N_R")
	)
	(segment
		(start 21.612606 -70.79107)
		(end 18.0848 -70.79107)
		(width 0.08382)
		(layer "In2.Cu")
		(net "SPI_BMC_BT_WP1_N_R")
	)
	(segment
		(start 27.929078 -77.70114)
		(end 25.1206 -74.892662)
		(width 0.08382)
		(layer "In2.Cu")
		(net "SPI_BMC_BT_WP1_N_R")
	)
	(segment
		(start 32.493204 -78.02118)
		(end 32.173164 -77.70114)
		(width 0.08382)
		(layer "In2.Cu")
		(net "SPI_BMC_BT_WP1_N_R")
	)
	(segment
		(start 40.052498 -78.61173)
		(end 39.461948 -78.02118)
		(width 0.08382)
		(layer "In2.Cu")
		(net "SPI_BMC_BT_WP1_N_R")
	)
	(segment
		(start 25.1206 -74.892662)
		(end 25.1206 -74.299064)
		(width 0.08382)
		(layer "In2.Cu")
		(net "SPI_BMC_BT_WP1_N_R")
	)
	(segment
		(start 17.9578 -70.66407)
		(end 16.66113 -70.66407)
		(width 0.08382)
		(layer "In2.Cu")
		(net "SPI_BMC_BT_WP1_N_R")
	)
	(segment
		(start 42.308526 -77.884274)
		(end 41.58107 -78.61173)
		(width 0.08382)
		(layer "In2.Cu")
		(net "SPI_BMC_BT_WP1_N_R")
	)
	(segment
		(start 43.322494 -77.884274)
		(end 42.308526 -77.884274)
		(width 0.08382)
		(layer "In2.Cu")
		(net "SPI_BMC_BT_WP1_N_R")
	)
	(segment
		(start 25.1206 -74.299064)
		(end 21.612606 -70.79107)
		(width 0.08382)
		(layer "In2.Cu")
		(net "SPI_BMC_BT_WP1_N_R")
	)
	(segment
		(start 39.461948 -78.02118)
		(end 32.493204 -78.02118)
		(width 0.08382)
		(layer "In2.Cu")
		(net "SPI_BMC_BT_WP1_N_R")
	)
	(segment
		(start 41.58107 -78.61173)
		(end 40.052498 -78.61173)
		(width 0.08382)
		(layer "In2.Cu")
		(net "SPI_BMC_BT_WP1_N_R")
	)
	(segment
		(start 17.0942 -74.2442)
		(end 16.764 -73.914)
		(width 0.11684)
		(layer "F.Cu")
		(net "SPI_BMC_BT_WP0_N_R")
	)
	(segment
		(start 18.50009 -77.30871)
		(end 18.9738 -76.835)
		(width 0.11684)
		(layer "F.Cu")
		(net "SPI_BMC_BT_WP0_N_R")
	)
	(segment
		(start 44.68495 -83.6168)
		(end 44.068746 -83.6168)
		(width 0.11684)
		(layer "F.Cu")
		(net "SPI_BMC_BT_WP0_N_R")
	)
	(segment
		(start 16.5354 -71.13905)
		(end 16.5354 -71.74865)
		(width 0.11684)
		(layer "F.Cu")
		(net "SPI_BMC_BT_WP0_N_R")
	)
	(segment
		(start 18.9738 -75.8444)
		(end 17.3736 -74.2442)
		(width 0.11684)
		(layer "F.Cu")
		(net "SPI_BMC_BT_WP0_N_R")
	)
	(segment
		(start 18.50009 -80.910176)
		(end 18.50009 -80.196944)
		(width 0.11684)
		(layer "F.Cu")
		(net "SPI_BMC_BT_WP0_N_R")
	)
	(segment
		(start 42.545 -82.093054)
		(end 42.545 -79.375)
		(width 0.11684)
		(layer "F.Cu")
		(net "SPI_BMC_BT_WP0_N_R")
	)
	(segment
		(start 16.764 -71.97725)
		(end 16.5354 -71.74865)
		(width 0.11684)
		(layer "F.Cu")
		(net "SPI_BMC_BT_WP0_N_R")
	)
	(segment
		(start 18.9738 -76.835)
		(end 18.9738 -75.8444)
		(width 0.11684)
		(layer "F.Cu")
		(net "SPI_BMC_BT_WP0_N_R")
	)
	(segment
		(start 18.176494 -79.873348)
		(end 18.176494 -79.232252)
		(width 0.11684)
		(layer "F.Cu")
		(net "SPI_BMC_BT_WP0_N_R")
	)
	(segment
		(start 42.545 -79.375)
		(end 42.545 -78.8162)
		(width 0.11684)
		(layer "F.Cu")
		(net "SPI_BMC_BT_WP0_N_R")
	)
	(segment
		(start 18.50009 -80.196944)
		(end 18.176494 -79.873348)
		(width 0.11684)
		(layer "F.Cu")
		(net "SPI_BMC_BT_WP0_N_R")
	)
	(segment
		(start 16.764 -73.914)
		(end 16.764 -71.97725)
		(width 0.11684)
		(layer "F.Cu")
		(net "SPI_BMC_BT_WP0_N_R")
	)
	(segment
		(start 44.068746 -83.6168)
		(end 42.545 -82.093054)
		(width 0.11684)
		(layer "F.Cu")
		(net "SPI_BMC_BT_WP0_N_R")
	)
	(segment
		(start 42.545 -78.8162)
		(end 42.9514 -78.4098)
		(width 0.11684)
		(layer "F.Cu")
		(net "SPI_BMC_BT_WP0_N_R")
	)
	(segment
		(start 42.9514 -78.403958)
		(end 42.945558 -78.403958)
		(width 0.11684)
		(layer "F.Cu")
		(net "SPI_BMC_BT_WP0_N_R")
	)
	(segment
		(start 17.3736 -74.2442)
		(end 17.0942 -74.2442)
		(width 0.11684)
		(layer "F.Cu")
		(net "SPI_BMC_BT_WP0_N_R")
	)
	(segment
		(start 42.9514 -78.4098)
		(end 42.9514 -78.403958)
		(width 0.11684)
		(layer "F.Cu")
		(net "SPI_BMC_BT_WP0_N_R")
	)
	(segment
		(start 18.176494 -79.232252)
		(end 18.50009 -78.908656)
		(width 0.11684)
		(layer "F.Cu")
		(net "SPI_BMC_BT_WP0_N_R")
	)
	(segment
		(start 18.50009 -78.908656)
		(end 18.50009 -77.30871)
		(width 0.11684)
		(layer "F.Cu")
		(net "SPI_BMC_BT_WP0_N_R")
	)
	(via
		(at 42.545 -79.375)
		(size 0.762)
		(drill 0.381)
		(layers "F.Cu" "B.Cu")
		(net "SPI_BMC_BT_WP0_N_R")
	)
	(via
		(at 16.5354 -71.74865)
		(size 0.508)
		(drill 0.254)
		(layers "F.Cu" "B.Cu")
		(net "SPI_BMC_BT_WP0_N_R")
	)
	(via
		(at 42.945558 -78.403958)
		(size 0.508)
		(drill 0.254)
		(layers "F.Cu" "B.Cu")
		(net "SPI_BMC_BT_WP0_N_R")
	)
	(segment
		(start 42.483786 -78.86573)
		(end 39.972234 -78.86573)
		(width 0.08382)
		(layer "In2.Cu")
		(net "SPI_BMC_BT_WP0_N_R")
	)
	(segment
		(start 32.07512 -77.93736)
		(end 27.831034 -77.93736)
		(width 0.08382)
		(layer "In2.Cu")
		(net "SPI_BMC_BT_WP0_N_R")
	)
	(segment
		(start 21.7932 -71.4502)
		(end 19.799554 -71.4502)
		(width 0.08382)
		(layer "In2.Cu")
		(net "SPI_BMC_BT_WP0_N_R")
	)
	(segment
		(start 19.799554 -71.4502)
		(end 19.562064 -71.68769)
		(width 0.08382)
		(layer "In2.Cu")
		(net "SPI_BMC_BT_WP0_N_R")
	)
	(segment
		(start 24.88438 -74.990706)
		(end 24.88438 -74.54138)
		(width 0.08382)
		(layer "In2.Cu")
		(net "SPI_BMC_BT_WP0_N_R")
	)
	(segment
		(start 16.59636 -71.68769)
		(end 16.5354 -71.74865)
		(width 0.08382)
		(layer "In2.Cu")
		(net "SPI_BMC_BT_WP0_N_R")
	)
	(segment
		(start 24.88438 -74.54138)
		(end 21.7932 -71.4502)
		(width 0.08382)
		(layer "In2.Cu")
		(net "SPI_BMC_BT_WP0_N_R")
	)
	(segment
		(start 19.562064 -71.68769)
		(end 16.59636 -71.68769)
		(width 0.08382)
		(layer "In2.Cu")
		(net "SPI_BMC_BT_WP0_N_R")
	)
	(segment
		(start 32.39516 -78.2574)
		(end 32.07512 -77.93736)
		(width 0.08382)
		(layer "In2.Cu")
		(net "SPI_BMC_BT_WP0_N_R")
	)
	(segment
		(start 27.831034 -77.93736)
		(end 24.88438 -74.990706)
		(width 0.08382)
		(layer "In2.Cu")
		(net "SPI_BMC_BT_WP0_N_R")
	)
	(segment
		(start 39.363904 -78.2574)
		(end 32.39516 -78.2574)
		(width 0.08382)
		(layer "In2.Cu")
		(net "SPI_BMC_BT_WP0_N_R")
	)
	(segment
		(start 42.945558 -78.403958)
		(end 42.483786 -78.86573)
		(width 0.08382)
		(layer "In2.Cu")
		(net "SPI_BMC_BT_WP0_N_R")
	)
	(segment
		(start 39.972234 -78.86573)
		(end 39.363904 -78.2574)
		(width 0.08382)
		(layer "In2.Cu")
		(net "SPI_BMC_BT_WP0_N_R")
	)
	(segment
		(start 47.72025 -77.597)
		(end 48.57242 -77.597)
		(width 0.11684)
		(layer "F.Cu")
		(net "RD_N")
	)
	(segment
		(start 47.39005 -77.2668)
		(end 47.72025 -77.597)
		(width 0.11684)
		(layer "F.Cu")
		(net "RD_N")
	)
	(segment
		(start 48.57242 -77.597)
		(end 48.816768 -77.597)
		(width 0.11684)
		(layer "F.Cu")
		(net "RD_N")
	)
	(segment
		(start 48.816768 -77.597)
		(end 49.736248 -76.67752)
		(width 0.11684)
		(layer "F.Cu")
		(net "RD_N")
	)
	(segment
		(start 49.736248 -76.67752)
		(end 50.041048 -76.67752)
		(width 0.11684)
		(layer "F.Cu")
		(net "RD_N")
	)
	(segment
		(start 47.36465 -77.2668)
		(end 47.39005 -77.2668)
		(width 0.11684)
		(layer "F.Cu")
		(net "RD_N")
	)
	(via
		(at 48.57242 -77.597)
		(size 0.762)
		(drill 0.381)
		(layers "F.Cu" "B.Cu")
		(net "RD_N")
	)
	(segment
		(start 55.875174 -88.4428)
		(end 56.921654 -89.48928)
		(width 0.11684)
		(layer "F.Cu")
		(net "NC_J1_P3")
	)
	(segment
		(start 52.936902 -88.4428)
		(end 55.875174 -88.4428)
		(width 0.11684)
		(layer "F.Cu")
		(net "NC_J1_P3")
	)
	(via
		(at 56.921654 -89.48928)
		(size 0.762)
		(drill 0.381)
		(layers "F.Cu" "B.Cu")
		(net "NC_J1_P3")
	)
	(segment
		(start 47.36465 -76.2508)
		(end 48.564546 -76.2508)
		(width 0.11684)
		(layer "F.Cu")
		(net "FM_FLASH_LATCH_N")
	)
	(segment
		(start 48.788066 -76.02728)
		(end 48.564546 -76.2508)
		(width 0.11684)
		(layer "F.Cu")
		(net "FM_FLASH_LATCH_N")
	)
	(segment
		(start 50.041048 -76.02728)
		(end 48.788066 -76.02728)
		(width 0.11684)
		(layer "F.Cu")
		(net "FM_FLASH_LATCH_N")
	)
	(segment
		(start 56.39943 -65.76822)
		(end 56.39943 -66.26352)
		(width 0.11684)
		(layer "F.Cu")
		(net "FM_FLASH_LATCH_N")
	)
	(segment
		(start 56.39943 -66.26352)
		(end 56.599582 -66.463672)
		(width 0.11684)
		(layer "F.Cu")
		(net "FM_FLASH_LATCH_N")
	)
	(via
		(at 52.43322 -75.89012)
		(size 0.508)
		(drill 0.254)
		(layers "F.Cu" "B.Cu")
		(net "FM_FLASH_LATCH_N")
	)
	(via
		(at 48.564546 -76.2508)
		(size 0.762)
		(drill 0.254)
		(layers "F.Cu" "B.Cu")
		(net "FM_FLASH_LATCH_N")
	)
	(via
		(at 56.599582 -66.463672)
		(size 0.508)
		(drill 0.254)
		(layers "F.Cu" "B.Cu")
		(net "FM_FLASH_LATCH_N")
	)
	(segment
		(start 48.564546 -76.2508)
		(end 49.082706 -75.73264)
		(width 0.11684)
		(layer "B.Cu")
		(net "FM_FLASH_LATCH_N")
	)
	(segment
		(start 49.082706 -75.73264)
		(end 52.27574 -75.73264)
		(width 0.11684)
		(layer "B.Cu")
		(net "FM_FLASH_LATCH_N")
	)
	(segment
		(start 52.27574 -75.73264)
		(end 52.43322 -75.89012)
		(width 0.11684)
		(layer "B.Cu")
		(net "FM_FLASH_LATCH_N")
	)
	(segment
		(start 52.56784 -76.02474)
		(end 56.60644 -76.02474)
		(width 0.10668)
		(layer "In4.Cu")
		(net "FM_FLASH_LATCH_N")
	)
	(segment
		(start 57.730898 -74.900282)
		(end 57.730898 -70.938898)
		(width 0.10668)
		(layer "In4.Cu")
		(net "FM_FLASH_LATCH_N")
	)
	(segment
		(start 52.43322 -75.89012)
		(end 52.56784 -76.02474)
		(width 0.10668)
		(layer "In4.Cu")
		(net "FM_FLASH_LATCH_N")
	)
	(segment
		(start 57.730898 -70.938898)
		(end 56.9722 -70.1802)
		(width 0.10668)
		(layer "In4.Cu")
		(net "FM_FLASH_LATCH_N")
	)
	(segment
		(start 56.9722 -70.1802)
		(end 56.9722 -66.83629)
		(width 0.10668)
		(layer "In4.Cu")
		(net "FM_FLASH_LATCH_N")
	)
	(segment
		(start 56.9722 -66.83629)
		(end 56.599582 -66.463672)
		(width 0.10668)
		(layer "In4.Cu")
		(net "FM_FLASH_LATCH_N")
	)
	(segment
		(start 56.60644 -76.02474)
		(end 57.730898 -74.900282)
		(width 0.10668)
		(layer "In4.Cu")
		(net "FM_FLASH_LATCH_N")
	)
	(segment
		(start 55.83555 -80.9498)
		(end 54.483 -80.9498)
		(width 0.11684)
		(layer "F.Cu")
		(net "FLASH_WP_STATUS")
	)
	(segment
		(start 56.0324 -80.75295)
		(end 55.83555 -80.9498)
		(width 0.11684)
		(layer "F.Cu")
		(net "FLASH_WP_STATUS")
	)
	(segment
		(start 52.6034 -78.6638)
		(end 52.2732 -78.3336)
		(width 0.11684)
		(layer "F.Cu")
		(net "FLASH_WP_STATUS")
	)
	(segment
		(start 56.4642 -72.8472)
		(end 56.4642 -71.67245)
		(width 0.11684)
		(layer "F.Cu")
		(net "FLASH_WP_STATUS")
	)
	(segment
		(start 51.0032 -77.4954)
		(end 51.0032 -75.7682)
		(width 0.11684)
		(layer "F.Cu")
		(net "FLASH_WP_STATUS")
	)
	(segment
		(start 53.34 -73.4314)
		(end 55.88 -73.4314)
		(width 0.11684)
		(layer "F.Cu")
		(net "FLASH_WP_STATUS")
	)
	(segment
		(start 55.88 -73.4314)
		(end 56.4642 -72.8472)
		(width 0.11684)
		(layer "F.Cu")
		(net "FLASH_WP_STATUS")
	)
	(segment
		(start 52.2732 -78.3336)
		(end 51.8414 -78.3336)
		(width 0.11684)
		(layer "F.Cu")
		(net "FLASH_WP_STATUS")
	)
	(segment
		(start 51.0032 -75.7682)
		(end 53.34 -73.4314)
		(width 0.11684)
		(layer "F.Cu")
		(net "FLASH_WP_STATUS")
	)
	(segment
		(start 52.8828 -80.772)
		(end 52.6034 -80.4926)
		(width 0.11684)
		(layer "F.Cu")
		(net "FLASH_WP_STATUS")
	)
	(segment
		(start 52.6034 -80.4926)
		(end 52.6034 -78.6638)
		(width 0.11684)
		(layer "F.Cu")
		(net "FLASH_WP_STATUS")
	)
	(segment
		(start 51.8414 -78.3336)
		(end 51.0032 -77.4954)
		(width 0.11684)
		(layer "F.Cu")
		(net "FLASH_WP_STATUS")
	)
	(segment
		(start 54.483 -80.9498)
		(end 54.3052 -80.772)
		(width 0.11684)
		(layer "F.Cu")
		(net "FLASH_WP_STATUS")
	)
	(segment
		(start 54.3052 -80.772)
		(end 52.8828 -80.772)
		(width 0.11684)
		(layer "F.Cu")
		(net "FLASH_WP_STATUS")
	)
	(segment
		(start 56.0324 -81.55305)
		(end 55.81015 -81.3308)
		(width 0.11684)
		(layer "F.Cu")
		(net "FLASH_R_WP_STATUS")
	)
	(segment
		(start 54.0004 -81.153)
		(end 52.2986 -81.153)
		(width 0.11684)
		(layer "F.Cu")
		(net "FLASH_R_WP_STATUS")
	)
	(segment
		(start 52.1716 -81.026)
		(end 52.1716 -80.4418)
		(width 0.11684)
		(layer "F.Cu")
		(net "FLASH_R_WP_STATUS")
	)
	(segment
		(start 54.1782 -81.3308)
		(end 54.0004 -81.153)
		(width 0.11684)
		(layer "F.Cu")
		(net "FLASH_R_WP_STATUS")
	)
	(segment
		(start 56.0324 -81.55305)
		(end 56.0324 -82.48015)
		(width 0.11684)
		(layer "F.Cu")
		(net "FLASH_R_WP_STATUS")
	)
	(segment
		(start 52.1716 -80.4418)
		(end 52.034186 -80.304386)
		(width 0.11684)
		(layer "F.Cu")
		(net "FLASH_R_WP_STATUS")
	)
	(segment
		(start 55.81015 -81.3308)
		(end 54.1782 -81.3308)
		(width 0.11684)
		(layer "F.Cu")
		(net "FLASH_R_WP_STATUS")
	)
	(segment
		(start 52.2986 -81.153)
		(end 52.1716 -81.026)
		(width 0.11684)
		(layer "F.Cu")
		(net "FLASH_R_WP_STATUS")
	)
	(segment
		(start 52.034186 -80.304386)
		(end 51.615594 -80.304386)
		(width 0.11684)
		(layer "F.Cu")
		(net "FLASH_R_WP_STATUS")
	)
	(segment
		(start 56.8706 -83.2866)
		(end 56.8706 -80.28305)
		(width 0.11684)
		(layer "F.Cu")
		(net "FLASH_LATCH_Q_N_R2")
	)
	(segment
		(start 45.48505 -82.6008)
		(end 45.48505 -83.6168)
		(width 0.11684)
		(layer "F.Cu")
		(net "FLASH_LATCH_Q_N_R2")
	)
	(segment
		(start 56.007 -84.1502)
		(end 56.8706 -83.2866)
		(width 0.11684)
		(layer "F.Cu")
		(net "FLASH_LATCH_Q_N_R2")
	)
	(segment
		(start 45.78477 -83.91652)
		(end 47.391574 -83.91652)
		(width 0.11684)
		(layer "F.Cu")
		(net "FLASH_LATCH_Q_N_R2")
	)
	(segment
		(start 45.48505 -83.6168)
		(end 45.78477 -83.91652)
		(width 0.11684)
		(layer "F.Cu")
		(net "FLASH_LATCH_Q_N_R2")
	)
	(segment
		(start 55.943246 -79.869284)
		(end 56.20004 -79.61249)
		(width 0.11684)
		(layer "F.Cu")
		(net "FLASH_LATCH_Q_N_R2")
	)
	(segment
		(start 54.0004 -79.6544)
		(end 54.215284 -79.869284)
		(width 0.11684)
		(layer "F.Cu")
		(net "FLASH_LATCH_Q_N_R2")
	)
	(segment
		(start 56.8706 -80.28305)
		(end 56.20004 -79.61249)
		(width 0.11684)
		(layer "F.Cu")
		(net "FLASH_LATCH_Q_N_R2")
	)
	(segment
		(start 54.215284 -79.869284)
		(end 55.943246 -79.869284)
		(width 0.11684)
		(layer "F.Cu")
		(net "FLASH_LATCH_Q_N_R2")
	)
	(segment
		(start 51.8414 -85.9028)
		(end 53.594 -84.1502)
		(width 0.11684)
		(layer "F.Cu")
		(net "FLASH_LATCH_Q_N_R2")
	)
	(segment
		(start 50.187098 -85.9028)
		(end 51.8414 -85.9028)
		(width 0.11684)
		(layer "F.Cu")
		(net "FLASH_LATCH_Q_N_R2")
	)
	(segment
		(start 53.594 -84.1502)
		(end 56.007 -84.1502)
		(width 0.11684)
		(layer "F.Cu")
		(net "FLASH_LATCH_Q_N_R2")
	)
	(segment
		(start 47.391574 -83.91652)
		(end 49.377854 -85.9028)
		(width 0.11684)
		(layer "F.Cu")
		(net "FLASH_LATCH_Q_N_R2")
	)
	(segment
		(start 53.540406 -79.6544)
		(end 54.0004 -79.6544)
		(width 0.11684)
		(layer "F.Cu")
		(net "FLASH_LATCH_Q_N_R2")
	)
	(segment
		(start 49.377854 -85.9028)
		(end 50.187098 -85.9028)
		(width 0.11684)
		(layer "F.Cu")
		(net "FLASH_LATCH_Q_N_R2")
	)
	(segment
		(start 55.288942 -76.3524)
		(end 54.963822 -76.02728)
		(width 0.11684)
		(layer "F.Cu")
		(net "FLASH_LATCH_D")
	)
	(segment
		(start 54.963822 -76.02728)
		(end 53.590952 -76.02728)
		(width 0.11684)
		(layer "F.Cu")
		(net "FLASH_LATCH_D")
	)
	(segment
		(start 56.62295 -76.3524)
		(end 55.288942 -76.3524)
		(width 0.11684)
		(layer "F.Cu")
		(net "FLASH_LATCH_D")
	)
	(via
		(at 55.288942 -76.3524)
		(size 0.762)
		(drill 0.381)
		(layers "F.Cu" "B.Cu")
		(net "FLASH_LATCH_D")
	)
	(segment
		(start 54.87289 -75.32751)
		(end 55.2196 -74.9808)
		(width 0.11684)
		(layer "F.Cu")
		(net "FLASH_LATCH_CP")
	)
	(segment
		(start 55.2196 -74.9808)
		(end 56.26735 -74.9808)
		(width 0.11684)
		(layer "F.Cu")
		(net "FLASH_LATCH_CP")
	)
	(segment
		(start 56.26735 -74.9808)
		(end 56.62295 -75.3364)
		(width 0.11684)
		(layer "F.Cu")
		(net "FLASH_LATCH_CP")
	)
	(segment
		(start 53.590952 -75.32751)
		(end 54.87289 -75.32751)
		(width 0.11684)
		(layer "F.Cu")
		(net "FLASH_LATCH_CP")
	)
	(via
		(at 55.2196 -74.9808)
		(size 0.762)
		(drill 0.381)
		(layers "F.Cu" "B.Cu")
		(net "FLASH_LATCH_CP")
	)
	(segment
		(start 57.49798 -24.83104)
		(end 56.61406 -25.71496)
		(width 0.11684)
		(layer "F.Cu")
		(net "BMC_RSTIND_N")
	)
	(segment
		(start 72.20839 -23.68804)
		(end 71.67245 -23.1521)
		(width 0.11684)
		(layer "F.Cu")
		(net "BMC_RSTIND_N")
	)
	(segment
		(start 71.01078 -22.24532)
		(end 68.37172 -22.24532)
		(width 0.11684)
		(layer "F.Cu")
		(net "BMC_RSTIND_N")
	)
	(segment
		(start 60.190634 -24.83104)
		(end 57.49798 -24.83104)
		(width 0.11684)
		(layer "F.Cu")
		(net "BMC_RSTIND_N")
	)
	(segment
		(start 71.18858 -22.47138)
		(end 71.18858 -22.42312)
		(width 0.11684)
		(layer "F.Cu")
		(net "BMC_RSTIND_N")
	)
	(segment
		(start 63.406274 -21.6154)
		(end 60.190634 -24.83104)
		(width 0.11684)
		(layer "F.Cu")
		(net "BMC_RSTIND_N")
	)
	(segment
		(start 44.6786 -76.4794)
		(end 42.7482 -76.4794)
		(width 0.11684)
		(layer "F.Cu")
		(net "BMC_RSTIND_N")
	)
	(segment
		(start 45.466 -77.2668)
		(end 44.6786 -76.4794)
		(width 0.11684)
		(layer "F.Cu")
		(net "BMC_RSTIND_N")
	)
	(segment
		(start 68.37172 -22.24532)
		(end 67.7418 -21.6154)
		(width 0.11684)
		(layer "F.Cu")
		(net "BMC_RSTIND_N")
	)
	(segment
		(start 46.56455 -77.2668)
		(end 45.466 -77.2668)
		(width 0.11684)
		(layer "F.Cu")
		(net "BMC_RSTIND_N")
	)
	(segment
		(start 67.7418 -21.6154)
		(end 63.406274 -21.6154)
		(width 0.11684)
		(layer "F.Cu")
		(net "BMC_RSTIND_N")
	)
	(segment
		(start 71.30542 -23.1521)
		(end 71.18858 -23.03526)
		(width 0.11684)
		(layer "F.Cu")
		(net "BMC_RSTIND_N")
	)
	(segment
		(start 71.18858 -23.03526)
		(end 71.18858 -22.47138)
		(width 0.11684)
		(layer "F.Cu")
		(net "BMC_RSTIND_N")
	)
	(segment
		(start 71.67245 -23.1521)
		(end 71.30542 -23.1521)
		(width 0.11684)
		(layer "F.Cu")
		(net "BMC_RSTIND_N")
	)
	(segment
		(start 71.18858 -22.42312)
		(end 71.01078 -22.24532)
		(width 0.11684)
		(layer "F.Cu")
		(net "BMC_RSTIND_N")
	)
	(via
		(at 42.7482 -76.4794)
		(size 0.508)
		(drill 0.254)
		(layers "F.Cu" "B.Cu")
		(net "BMC_RSTIND_N")
	)
	(via
		(at 26.9494 -71.8566)
		(size 0.508)
		(drill 0.254)
		(layers "F.Cu" "B.Cu")
		(net "BMC_RSTIND_N")
	)
	(via
		(at 71.18858 -22.47138)
		(size 0.762)
		(drill 0.381)
		(layers "F.Cu" "B.Cu")
		(net "BMC_RSTIND_N")
	)
	(via
		(at 56.61406 -25.71496)
		(size 0.508)
		(drill 0.254)
		(layers "F.Cu" "B.Cu")
		(net "BMC_RSTIND_N")
	)
	(segment
		(start 30.675326 -73.440036)
		(end 27.7495 -73.440036)
		(width 0.08382)
		(layer "In2.Cu")
		(net "BMC_RSTIND_N")
	)
	(segment
		(start 42.7482 -76.64958)
		(end 42.1894 -77.20838)
		(width 0.08382)
		(layer "In2.Cu")
		(net "BMC_RSTIND_N")
	)
	(segment
		(start 26.9494 -72.639936)
		(end 26.9494 -71.8566)
		(width 0.08382)
		(layer "In2.Cu")
		(net "BMC_RSTIND_N")
	)
	(segment
		(start 30.40888 -76.99248)
		(end 30.1244 -76.708)
		(width 0.08382)
		(layer "In2.Cu")
		(net "BMC_RSTIND_N")
	)
	(segment
		(start 30.1244 -75.683872)
		(end 31.08071 -74.727562)
		(width 0.08382)
		(layer "In2.Cu")
		(net "BMC_RSTIND_N")
	)
	(segment
		(start 32.683196 -77.20838)
		(end 32.467296 -76.99248)
		(width 0.08382)
		(layer "In2.Cu")
		(net "BMC_RSTIND_N")
	)
	(segment
		(start 42.1894 -77.20838)
		(end 32.683196 -77.20838)
		(width 0.08382)
		(layer "In2.Cu")
		(net "BMC_RSTIND_N")
	)
	(segment
		(start 31.08071 -73.84542)
		(end 30.675326 -73.440036)
		(width 0.08382)
		(layer "In2.Cu")
		(net "BMC_RSTIND_N")
	)
	(segment
		(start 27.7495 -73.440036)
		(end 26.9494 -72.639936)
		(width 0.08382)
		(layer "In2.Cu")
		(net "BMC_RSTIND_N")
	)
	(segment
		(start 30.1244 -76.708)
		(end 30.1244 -75.683872)
		(width 0.08382)
		(layer "In2.Cu")
		(net "BMC_RSTIND_N")
	)
	(segment
		(start 42.7482 -76.4794)
		(end 42.7482 -76.64958)
		(width 0.08382)
		(layer "In2.Cu")
		(net "BMC_RSTIND_N")
	)
	(segment
		(start 31.08071 -74.727562)
		(end 31.08071 -73.84542)
		(width 0.08382)
		(layer "In2.Cu")
		(net "BMC_RSTIND_N")
	)
	(segment
		(start 32.467296 -76.99248)
		(end 30.40888 -76.99248)
		(width 0.08382)
		(layer "In2.Cu")
		(net "BMC_RSTIND_N")
	)
	(segment
		(start 32.41802 -51.615086)
		(end 32.9692 -51.063906)
		(width 0.08382)
		(layer "In9.Cu")
		(net "BMC_RSTIND_N")
	)
	(segment
		(start 32.9692 -51.063906)
		(end 32.9692 -50.000662)
		(width 0.08382)
		(layer "In9.Cu")
		(net "BMC_RSTIND_N")
	)
	(segment
		(start 29.873956 -66.366644)
		(end 30.7086 -65.532)
		(width 0.08382)
		(layer "In9.Cu")
		(net "BMC_RSTIND_N")
	)
	(segment
		(start 26.9494 -71.76008)
		(end 26.543 -71.35368)
		(width 0.08382)
		(layer "In9.Cu")
		(net "BMC_RSTIND_N")
	)
	(segment
		(start 30.478984 -55.553356)
		(end 32.41802 -53.61432)
		(width 0.08382)
		(layer "In9.Cu")
		(net "BMC_RSTIND_N")
	)
	(segment
		(start 32.9692 -50.000662)
		(end 31.97479 -49.006252)
		(width 0.08382)
		(layer "In9.Cu")
		(net "BMC_RSTIND_N")
	)
	(segment
		(start 32.76727 -47.276766)
		(end 32.76727 -42.926)
		(width 0.08382)
		(layer "In9.Cu")
		(net "BMC_RSTIND_N")
	)
	(segment
		(start 31.5722 -39.4462)
		(end 32.0802 -38.9382)
		(width 0.08382)
		(layer "In9.Cu")
		(net "BMC_RSTIND_N")
	)
	(segment
		(start 30.33649 -58.579258)
		(end 30.17647 -58.419238)
		(width 0.08382)
		(layer "In9.Cu")
		(net "BMC_RSTIND_N")
	)
	(segment
		(start 43.467274 -25.20696)
		(end 44.313094 -26.05278)
		(width 0.08382)
		(layer "In9.Cu")
		(net "BMC_RSTIND_N")
	)
	(segment
		(start 32.0802 -32.3596)
		(end 32.522922 -31.916878)
		(width 0.08382)
		(layer "In9.Cu")
		(net "BMC_RSTIND_N")
	)
	(segment
		(start 30.17647 -56.283606)
		(end 30.478984 -55.553356)
		(width 0.08382)
		(layer "In9.Cu")
		(net "BMC_RSTIND_N")
	)
	(segment
		(start 30.93339 -64.439292)
		(end 30.82671 -64.332612)
		(width 0.08382)
		(layer "In9.Cu")
		(net "BMC_RSTIND_N")
	)
	(segment
		(start 44.313094 -26.05278)
		(end 44.73702 -26.05278)
		(width 0.08382)
		(layer "In9.Cu")
		(net "BMC_RSTIND_N")
	)
	(segment
		(start 33.440624 -31.916878)
		(end 33.78962 -31.567882)
		(width 0.08382)
		(layer "In9.Cu")
		(net "BMC_RSTIND_N")
	)
	(segment
		(start 30.7086 -63.678562)
		(end 30.7086 -60.220098)
		(width 0.08382)
		(layer "In9.Cu")
		(net "BMC_RSTIND_N")
	)
	(segment
		(start 28.48864 -68.9864)
		(end 29.179774 -68.295266)
		(width 0.08382)
		(layer "In9.Cu")
		(net "BMC_RSTIND_N")
	)
	(segment
		(start 29.179774 -68.295266)
		(end 29.179774 -68.042536)
		(width 0.08382)
		(layer "In9.Cu")
		(net "BMC_RSTIND_N")
	)
	(segment
		(start 35.043364 -29.125672)
		(end 36.1061 -29.125672)
		(width 0.08382)
		(layer "In9.Cu")
		(net "BMC_RSTIND_N")
	)
	(segment
		(start 26.543 -71.35368)
		(end 26.543 -69.7484)
		(width 0.08382)
		(layer "In9.Cu")
		(net "BMC_RSTIND_N")
	)
	(segment
		(start 31.5722 -41.73093)
		(end 31.5722 -39.4462)
		(width 0.08382)
		(layer "In9.Cu")
		(net "BMC_RSTIND_N")
	)
	(segment
		(start 30.7086 -60.220098)
		(end 30.33649 -59.847988)
		(width 0.08382)
		(layer "In9.Cu")
		(net "BMC_RSTIND_N")
	)
	(segment
		(start 32.522922 -31.916878)
		(end 33.440624 -31.916878)
		(width 0.08382)
		(layer "In9.Cu")
		(net "BMC_RSTIND_N")
	)
	(segment
		(start 33.78962 -30.379416)
		(end 35.043364 -29.125672)
		(width 0.08382)
		(layer "In9.Cu")
		(net "BMC_RSTIND_N")
	)
	(segment
		(start 45.35678 -25.10282)
		(end 45.9486 -24.511)
		(width 0.08382)
		(layer "In9.Cu")
		(net "BMC_RSTIND_N")
	)
	(segment
		(start 30.7086 -65.035938)
		(end 30.93339 -64.811148)
		(width 0.08382)
		(layer "In9.Cu")
		(net "BMC_RSTIND_N")
	)
	(segment
		(start 30.82671 -63.796672)
		(end 30.7086 -63.678562)
		(width 0.08382)
		(layer "In9.Cu")
		(net "BMC_RSTIND_N")
	)
	(segment
		(start 30.33649 -59.847988)
		(end 30.33649 -58.579258)
		(width 0.08382)
		(layer "In9.Cu")
		(net "BMC_RSTIND_N")
	)
	(segment
		(start 32.76727 -42.926)
		(end 31.5722 -41.73093)
		(width 0.08382)
		(layer "In9.Cu")
		(net "BMC_RSTIND_N")
	)
	(segment
		(start 32.41802 -53.61432)
		(end 32.41802 -51.615086)
		(width 0.08382)
		(layer "In9.Cu")
		(net "BMC_RSTIND_N")
	)
	(segment
		(start 36.1061 -29.125672)
		(end 40.024812 -25.20696)
		(width 0.08382)
		(layer "In9.Cu")
		(net "BMC_RSTIND_N")
	)
	(segment
		(start 45.9486 -24.511)
		(end 55.4101 -24.511)
		(width 0.08382)
		(layer "In9.Cu")
		(net "BMC_RSTIND_N")
	)
	(segment
		(start 33.78962 -31.567882)
		(end 33.78962 -30.379416)
		(width 0.08382)
		(layer "In9.Cu")
		(net "BMC_RSTIND_N")
	)
	(segment
		(start 32.0802 -38.9382)
		(end 32.0802 -32.3596)
		(width 0.08382)
		(layer "In9.Cu")
		(net "BMC_RSTIND_N")
	)
	(segment
		(start 27.305 -68.9864)
		(end 28.48864 -68.9864)
		(width 0.08382)
		(layer "In9.Cu")
		(net "BMC_RSTIND_N")
	)
	(segment
		(start 29.179774 -68.042536)
		(end 29.873956 -66.366644)
		(width 0.08382)
		(layer "In9.Cu")
		(net "BMC_RSTIND_N")
	)
	(segment
		(start 26.543 -69.7484)
		(end 27.305 -68.9864)
		(width 0.08382)
		(layer "In9.Cu")
		(net "BMC_RSTIND_N")
	)
	(segment
		(start 26.9494 -71.8566)
		(end 26.9494 -71.76008)
		(width 0.08382)
		(layer "In9.Cu")
		(net "BMC_RSTIND_N")
	)
	(segment
		(start 30.17647 -58.419238)
		(end 30.17647 -56.283606)
		(width 0.08382)
		(layer "In9.Cu")
		(net "BMC_RSTIND_N")
	)
	(segment
		(start 31.97479 -49.006252)
		(end 31.97479 -48.069246)
		(width 0.08382)
		(layer "In9.Cu")
		(net "BMC_RSTIND_N")
	)
	(segment
		(start 44.73702 -26.05278)
		(end 45.35678 -25.43302)
		(width 0.08382)
		(layer "In9.Cu")
		(net "BMC_RSTIND_N")
	)
	(segment
		(start 45.35678 -25.43302)
		(end 45.35678 -25.10282)
		(width 0.08382)
		(layer "In9.Cu")
		(net "BMC_RSTIND_N")
	)
	(segment
		(start 40.024812 -25.20696)
		(end 43.467274 -25.20696)
		(width 0.08382)
		(layer "In9.Cu")
		(net "BMC_RSTIND_N")
	)
	(segment
		(start 30.93339 -64.811148)
		(end 30.93339 -64.439292)
		(width 0.08382)
		(layer "In9.Cu")
		(net "BMC_RSTIND_N")
	)
	(segment
		(start 30.7086 -65.532)
		(end 30.7086 -65.035938)
		(width 0.08382)
		(layer "In9.Cu")
		(net "BMC_RSTIND_N")
	)
	(segment
		(start 31.97479 -48.069246)
		(end 32.76727 -47.276766)
		(width 0.08382)
		(layer "In9.Cu")
		(net "BMC_RSTIND_N")
	)
	(segment
		(start 55.4101 -24.511)
		(end 56.61406 -25.71496)
		(width 0.08382)
		(layer "In9.Cu")
		(net "BMC_RSTIND_N")
	)
	(segment
		(start 30.82671 -64.332612)
		(end 30.82671 -63.796672)
		(width 0.08382)
		(layer "In9.Cu")
		(net "BMC_RSTIND_N")
	)
	(segment
		(start 31.115 -64.42075)
		(end 32.131 -64.42075)
		(width 0.11684)
		(layer "F.Cu")
		(net "PWRGD_P3V3_RGM_R2")
	)
	(segment
		(start 32.9184 -62.09284)
		(end 32.80156 -61.976)
		(width 0.11684)
		(layer "F.Cu")
		(net "PWRGD_P3V3_RGM_R2")
	)
	(segment
		(start 32.9184 -63.63335)
		(end 32.9184 -62.09284)
		(width 0.11684)
		(layer "F.Cu")
		(net "PWRGD_P3V3_RGM_R2")
	)
	(segment
		(start 32.80156 -61.976)
		(end 32.099504 -61.976)
		(width 0.11684)
		(layer "F.Cu")
		(net "PWRGD_P3V3_RGM_R2")
	)
	(segment
		(start 32.131 -64.42075)
		(end 32.9184 -63.63335)
		(width 0.11684)
		(layer "F.Cu")
		(net "PWRGD_P3V3_RGM_R2")
	)
	(segment
		(start 13.90015 -53.6448)
		(end 14.31417 -53.6448)
		(width 0.11684)
		(layer "F.Cu")
		(net "PWRGD_P1V8_AUX_R2")
	)
	(segment
		(start 13.876782 -54.080156)
		(end 13.876782 -53.668168)
		(width 0.11684)
		(layer "F.Cu")
		(net "PWRGD_P1V8_AUX_R2")
	)
	(segment
		(start 13.876782 -53.668168)
		(end 13.90015 -53.6448)
		(width 0.11684)
		(layer "F.Cu")
		(net "PWRGD_P1V8_AUX_R2")
	)
	(segment
		(start 13.96365 -54.167024)
		(end 13.876782 -54.080156)
		(width 0.11684)
		(layer "F.Cu")
		(net "PWRGD_P1V8_AUX_R2")
	)
	(segment
		(start 13.96365 -54.8386)
		(end 13.96365 -54.167024)
		(width 0.11684)
		(layer "F.Cu")
		(net "PWRGD_P1V8_AUX_R2")
	)
	(segment
		(start 13.96365 -56.0324)
		(end 13.96365 -54.8386)
		(width 0.11684)
		(layer "F.Cu")
		(net "PWRGD_P1V8_AUX_R2")
	)
	(segment
		(start 14.36497 -53.6956)
		(end 14.6812 -53.6956)
		(width 0.11684)
		(layer "F.Cu")
		(net "PWRGD_P1V8_AUX_R2")
	)
	(segment
		(start 14.31417 -53.6448)
		(end 14.36497 -53.6956)
		(width 0.11684)
		(layer "F.Cu")
		(net "PWRGD_P1V8_AUX_R2")
	)
	(segment
		(start 15.1638 -53.213)
		(end 15.1638 -52.067206)
		(width 0.11684)
		(layer "F.Cu")
		(net "PWRGD_P1V8_AUX_R2")
	)
	(segment
		(start 14.6812 -53.6956)
		(end 15.1638 -53.213)
		(width 0.11684)
		(layer "F.Cu")
		(net "PWRGD_P1V8_AUX_R2")
	)
	(via
		(at 13.96365 -54.8386)
		(size 0.762)
		(drill 0.381)
		(layers "F.Cu" "B.Cu")
		(net "PWRGD_P1V8_AUX_R2")
	)
	(segment
		(start 67.5386 -27.92095)
		(end 68.17995 -27.2796)
		(width 0.11684)
		(layer "F.Cu")
		(net "EN_P3V3_RGM")
	)
	(segment
		(start 68.9864 -27.2796)
		(end 69.1642 -27.1018)
		(width 0.11684)
		(layer "F.Cu")
		(net "EN_P3V3_RGM")
	)
	(segment
		(start 69.28104 -26.08834)
		(end 69.948044 -26.08834)
		(width 0.11684)
		(layer "F.Cu")
		(net "EN_P3V3_RGM")
	)
	(segment
		(start 14.513814 -49.769014)
		(end 14.513814 -50.142394)
		(width 0.11684)
		(layer "F.Cu")
		(net "EN_P3V3_RGM")
	)
	(segment
		(start 69.1642 -26.20518)
		(end 69.28104 -26.08834)
		(width 0.11684)
		(layer "F.Cu")
		(net "EN_P3V3_RGM")
	)
	(segment
		(start 13.31214 -47.4726)
		(end 14.02842 -48.18888)
		(width 0.11684)
		(layer "F.Cu")
		(net "EN_P3V3_RGM")
	)
	(segment
		(start 14.02842 -48.18888)
		(end 14.02842 -49.28362)
		(width 0.11684)
		(layer "F.Cu")
		(net "EN_P3V3_RGM")
	)
	(segment
		(start 69.1642 -27.1018)
		(end 69.1642 -26.20518)
		(width 0.11684)
		(layer "F.Cu")
		(net "EN_P3V3_RGM")
	)
	(segment
		(start 68.17995 -27.2796)
		(end 68.9864 -27.2796)
		(width 0.11684)
		(layer "F.Cu")
		(net "EN_P3V3_RGM")
	)
	(segment
		(start 14.02842 -49.28362)
		(end 14.513814 -49.769014)
		(width 0.11684)
		(layer "F.Cu")
		(net "EN_P3V3_RGM")
	)
	(via
		(at 13.31214 -47.4726)
		(size 0.508)
		(drill 0.254)
		(layers "F.Cu" "B.Cu")
		(net "EN_P3V3_RGM")
	)
	(via
		(at 69.948044 -26.08834)
		(size 0.508)
		(drill 0.254)
		(layers "F.Cu" "B.Cu")
		(net "EN_P3V3_RGM")
	)
	(segment
		(start 16.163036 -19.4945)
		(end 14.4018 -21.255736)
		(width 0.10668)
		(layer "In7.Cu")
		(net "EN_P3V3_RGM")
	)
	(segment
		(start 34.939986 -14.54404)
		(end 33.900364 -13.504418)
		(width 0.10668)
		(layer "In7.Cu")
		(net "EN_P3V3_RGM")
	)
	(segment
		(start 13.31214 -46.99508)
		(end 13.31214 -47.4726)
		(width 0.10668)
		(layer "In7.Cu")
		(net "EN_P3V3_RGM")
	)
	(segment
		(start 66.586862 -20.50288)
		(end 62.964568 -20.50288)
		(width 0.10668)
		(layer "In7.Cu")
		(net "EN_P3V3_RGM")
	)
	(segment
		(start 36.574222 -14.54404)
		(end 34.939986 -14.54404)
		(width 0.10668)
		(layer "In7.Cu")
		(net "EN_P3V3_RGM")
	)
	(segment
		(start 14.625574 -34.583878)
		(end 14.626082 -34.904426)
		(width 0.10668)
		(layer "In7.Cu")
		(net "EN_P3V3_RGM")
	)
	(segment
		(start 25.402286 -14.332458)
		(end 24.728424 -15.00632)
		(width 0.10668)
		(layer "In7.Cu")
		(net "EN_P3V3_RGM")
	)
	(segment
		(start 38.207442 -16.17726)
		(end 36.574222 -14.54404)
		(width 0.10668)
		(layer "In7.Cu")
		(net "EN_P3V3_RGM")
	)
	(segment
		(start 58.452766 -19.347434)
		(end 56.665114 -19.347434)
		(width 0.10668)
		(layer "In7.Cu")
		(net "EN_P3V3_RGM")
	)
	(segment
		(start 62.964568 -20.50288)
		(end 60.902088 -18.4404)
		(width 0.10668)
		(layer "In7.Cu")
		(net "EN_P3V3_RGM")
	)
	(segment
		(start 60.902088 -18.4404)
		(end 59.3598 -18.4404)
		(width 0.10668)
		(layer "In7.Cu")
		(net "EN_P3V3_RGM")
	)
	(segment
		(start 14.4018 -28.210764)
		(end 14.09192 -28.520644)
		(width 0.10668)
		(layer "In7.Cu")
		(net "EN_P3V3_RGM")
	)
	(segment
		(start 49.09566 -16.17726)
		(end 38.207442 -16.17726)
		(width 0.10668)
		(layer "In7.Cu")
		(net "EN_P3V3_RGM")
	)
	(segment
		(start 14.09192 -28.520644)
		(end 14.09192 -33.29432)
		(width 0.10668)
		(layer "In7.Cu")
		(net "EN_P3V3_RGM")
	)
	(segment
		(start 27.563318 -14.332458)
		(end 25.402286 -14.332458)
		(width 0.10668)
		(layer "In7.Cu")
		(net "EN_P3V3_RGM")
	)
	(segment
		(start 59.3598 -18.4404)
		(end 58.452766 -19.347434)
		(width 0.10668)
		(layer "In7.Cu")
		(net "EN_P3V3_RGM")
	)
	(segment
		(start 55.71744 -18.0848)
		(end 51.0032 -18.0848)
		(width 0.10668)
		(layer "In7.Cu")
		(net "EN_P3V3_RGM")
	)
	(segment
		(start 28.7274 -14.0081)
		(end 27.887676 -14.0081)
		(width 0.10668)
		(layer "In7.Cu")
		(net "EN_P3V3_RGM")
	)
	(segment
		(start 56.43626 -19.11858)
		(end 56.43626 -18.80362)
		(width 0.10668)
		(layer "In7.Cu")
		(net "EN_P3V3_RGM")
	)
	(segment
		(start 56.43626 -18.80362)
		(end 55.71744 -18.0848)
		(width 0.10668)
		(layer "In7.Cu")
		(net "EN_P3V3_RGM")
	)
	(segment
		(start 71.2216 -23.6982)
		(end 69.72808 -22.20468)
		(width 0.10668)
		(layer "In7.Cu")
		(net "EN_P3V3_RGM")
	)
	(segment
		(start 69.72808 -22.20468)
		(end 68.288662 -22.20468)
		(width 0.10668)
		(layer "In7.Cu")
		(net "EN_P3V3_RGM")
	)
	(segment
		(start 16.163036 -18.929604)
		(end 16.163036 -19.4945)
		(width 0.10668)
		(layer "In7.Cu")
		(net "EN_P3V3_RGM")
	)
	(segment
		(start 71.2216 -24.3586)
		(end 71.2216 -23.6982)
		(width 0.10668)
		(layer "In7.Cu")
		(net "EN_P3V3_RGM")
	)
	(segment
		(start 14.09192 -33.29432)
		(end 14.625574 -34.583878)
		(width 0.10668)
		(layer "In7.Cu")
		(net "EN_P3V3_RGM")
	)
	(segment
		(start 69.948044 -26.08834)
		(end 69.948044 -25.632156)
		(width 0.10668)
		(layer "In7.Cu")
		(net "EN_P3V3_RGM")
	)
	(segment
		(start 69.948044 -25.632156)
		(end 71.2216 -24.3586)
		(width 0.10668)
		(layer "In7.Cu")
		(net "EN_P3V3_RGM")
	)
	(segment
		(start 14.86408 -35.478974)
		(end 14.86408 -45.44314)
		(width 0.10668)
		(layer "In7.Cu")
		(net "EN_P3V3_RGM")
	)
	(segment
		(start 14.626082 -34.904426)
		(end 14.86408 -35.478974)
		(width 0.10668)
		(layer "In7.Cu")
		(net "EN_P3V3_RGM")
	)
	(segment
		(start 27.887676 -14.0081)
		(end 27.563318 -14.332458)
		(width 0.10668)
		(layer "In7.Cu")
		(net "EN_P3V3_RGM")
	)
	(segment
		(start 33.900364 -13.504418)
		(end 29.231082 -13.504418)
		(width 0.10668)
		(layer "In7.Cu")
		(net "EN_P3V3_RGM")
	)
	(segment
		(start 68.288662 -22.20468)
		(end 66.586862 -20.50288)
		(width 0.10668)
		(layer "In7.Cu")
		(net "EN_P3V3_RGM")
	)
	(segment
		(start 17.907 -16.07312)
		(end 17.907 -17.18564)
		(width 0.10668)
		(layer "In7.Cu")
		(net "EN_P3V3_RGM")
	)
	(segment
		(start 24.728424 -15.00632)
		(end 18.9738 -15.00632)
		(width 0.10668)
		(layer "In7.Cu")
		(net "EN_P3V3_RGM")
	)
	(segment
		(start 14.86408 -45.44314)
		(end 13.31214 -46.99508)
		(width 0.10668)
		(layer "In7.Cu")
		(net "EN_P3V3_RGM")
	)
	(segment
		(start 18.9738 -15.00632)
		(end 17.907 -16.07312)
		(width 0.10668)
		(layer "In7.Cu")
		(net "EN_P3V3_RGM")
	)
	(segment
		(start 51.0032 -18.0848)
		(end 49.09566 -16.17726)
		(width 0.10668)
		(layer "In7.Cu")
		(net "EN_P3V3_RGM")
	)
	(segment
		(start 17.907 -17.18564)
		(end 16.163036 -18.929604)
		(width 0.10668)
		(layer "In7.Cu")
		(net "EN_P3V3_RGM")
	)
	(segment
		(start 56.665114 -19.347434)
		(end 56.43626 -19.11858)
		(width 0.10668)
		(layer "In7.Cu")
		(net "EN_P3V3_RGM")
	)
	(segment
		(start 14.4018 -21.255736)
		(end 14.4018 -28.210764)
		(width 0.10668)
		(layer "In7.Cu")
		(net "EN_P3V3_RGM")
	)
	(segment
		(start 29.231082 -13.504418)
		(end 28.7274 -14.0081)
		(width 0.10668)
		(layer "In7.Cu")
		(net "EN_P3V3_RGM")
	)
	(segment
		(start 12.626594 -63.1952)
		(end 12.05865 -63.1952)
		(width 0.11684)
		(layer "F.Cu")
		(net "EN_P3V3")
	)
	(segment
		(start 14.03096 -62.70244)
		(end 13.79855 -62.93485)
		(width 0.11684)
		(layer "F.Cu")
		(net "EN_P3V3")
	)
	(segment
		(start 12.886944 -62.93485)
		(end 12.626594 -63.1952)
		(width 0.11684)
		(layer "F.Cu")
		(net "EN_P3V3")
	)
	(segment
		(start 14.03096 -59.823096)
		(end 14.03096 -61.8998)
		(width 0.11684)
		(layer "F.Cu")
		(net "EN_P3V3")
	)
	(segment
		(start 14.03096 -61.8998)
		(end 14.03096 -62.70244)
		(width 0.11684)
		(layer "F.Cu")
		(net "EN_P3V3")
	)
	(segment
		(start 13.79855 -62.93485)
		(end 12.886944 -62.93485)
		(width 0.11684)
		(layer "F.Cu")
		(net "EN_P3V3")
	)
	(via
		(at 14.03096 -61.8998)
		(size 0.762)
		(drill 0.381)
		(layers "F.Cu" "B.Cu")
		(net "EN_P3V3")
	)
	(segment
		(start 34.35604 -61.02604)
		(end 33.629092 -60.299092)
		(width 0.11684)
		(layer "F.Cu")
		(net "EN_P1V8")
	)
	(segment
		(start 33.629092 -60.299092)
		(end 33.629092 -59.0296)
		(width 0.11684)
		(layer "F.Cu")
		(net "EN_P1V8")
	)
	(segment
		(start 33.629092 -59.0296)
		(end 33.629092 -57.852818)
		(width 0.11684)
		(layer "F.Cu")
		(net "EN_P1V8")
	)
	(segment
		(start 34.499296 -61.02604)
		(end 34.35604 -61.02604)
		(width 0.11684)
		(layer "F.Cu")
		(net "EN_P1V8")
	)
	(via
		(at 33.629092 -59.0296)
		(size 0.762)
		(drill 0.381)
		(layers "F.Cu" "B.Cu")
		(net "EN_P1V8")
	)
	(segment
		(start 76.931266 -71.040244)
		(end 77.287374 -71.396352)
		(width 0.11684)
		(layer "F.Cu")
		(net "EN_P1V2_AUX")
	)
	(segment
		(start 77.287374 -71.396352)
		(end 77.547724 -71.396352)
		(width 0.11684)
		(layer "F.Cu")
		(net "EN_P1V2_AUX")
	)
	(via
		(at 80.334104 -64.865504)
		(size 0.6604)
		(drill 0.3302)
		(layers "F.Cu" "B.Cu")
		(net "EN_P1V2_AUX")
	)
	(via
		(at 76.931266 -71.040244)
		(size 0.508)
		(drill 0.254)
		(layers "F.Cu" "B.Cu")
		(net "EN_P1V2_AUX")
	)
	(segment
		(start 80.431386 -64.962786)
		(end 80.334104 -64.865504)
		(width 0.11684)
		(layer "B.Cu")
		(net "EN_P1V2_AUX")
	)
	(segment
		(start 78.039468 -68.641468)
		(end 78.039468 -70.295008)
		(width 0.11684)
		(layer "B.Cu")
		(net "EN_P1V2_AUX")
	)
	(segment
		(start 77.343 -67.945)
		(end 78.039468 -68.641468)
		(width 0.11684)
		(layer "B.Cu")
		(net "EN_P1V2_AUX")
	)
	(segment
		(start 80.431386 -67.693794)
		(end 80.431386 -64.962786)
		(width 0.11684)
		(layer "B.Cu")
		(net "EN_P1V2_AUX")
	)
	(segment
		(start 77.343 -65.024)
		(end 77.343 -67.945)
		(width 0.11684)
		(layer "B.Cu")
		(net "EN_P1V2_AUX")
	)
	(segment
		(start 77.724 -64.643)
		(end 77.343 -65.024)
		(width 0.11684)
		(layer "B.Cu")
		(net "EN_P1V2_AUX")
	)
	(segment
		(start 80.334104 -64.865504)
		(end 80.1116 -64.643)
		(width 0.11684)
		(layer "B.Cu")
		(net "EN_P1V2_AUX")
	)
	(segment
		(start 80.1116 -64.643)
		(end 77.724 -64.643)
		(width 0.11684)
		(layer "B.Cu")
		(net "EN_P1V2_AUX")
	)
	(segment
		(start 77.294232 -71.040244)
		(end 76.931266 -71.040244)
		(width 0.11684)
		(layer "B.Cu")
		(net "EN_P1V2_AUX")
	)
	(segment
		(start 78.039468 -70.295008)
		(end 77.294232 -71.040244)
		(width 0.11684)
		(layer "B.Cu")
		(net "EN_P1V2_AUX")
	)
	(segment
		(start 14.74216 -30.4038)
		(end 14.74216 -30.90799)
		(width 0.11684)
		(layer "F.Cu")
		(net "EN_P1V0_AUX")
	)
	(segment
		(start 16.235172 -30.929072)
		(end 15.22603 -29.91993)
		(width 0.11684)
		(layer "F.Cu")
		(net "EN_P1V0_AUX")
	)
	(segment
		(start 15.4432 -35.0266)
		(end 15.098014 -35.371786)
		(width 0.11684)
		(layer "F.Cu")
		(net "EN_P1V0_AUX")
	)
	(segment
		(start 14.739112 -34.685732)
		(end 15.330932 -34.685732)
		(width 0.11684)
		(layer "F.Cu")
		(net "EN_P1V0_AUX")
	)
	(segment
		(start 16.235172 -31.26232)
		(end 16.235172 -30.929072)
		(width 0.11684)
		(layer "F.Cu")
		(net "EN_P1V0_AUX")
	)
	(segment
		(start 15.22603 -29.91993)
		(end 14.74216 -30.4038)
		(width 0.11684)
		(layer "F.Cu")
		(net "EN_P1V0_AUX")
	)
	(segment
		(start 14.3002 -34.24682)
		(end 14.739112 -34.685732)
		(width 0.11684)
		(layer "F.Cu")
		(net "EN_P1V0_AUX")
	)
	(segment
		(start 15.330932 -34.685732)
		(end 15.4432 -34.798)
		(width 0.11684)
		(layer "F.Cu")
		(net "EN_P1V0_AUX")
	)
	(segment
		(start 15.4432 -34.798)
		(end 15.4432 -35.0266)
		(width 0.11684)
		(layer "F.Cu")
		(net "EN_P1V0_AUX")
	)
	(segment
		(start 14.74216 -30.90799)
		(end 14.3002 -31.34995)
		(width 0.11684)
		(layer "F.Cu")
		(net "EN_P1V0_AUX")
	)
	(segment
		(start 14.3002 -31.34995)
		(end 14.3002 -34.24682)
		(width 0.11684)
		(layer "F.Cu")
		(net "EN_P1V0_AUX")
	)
	(segment
		(start 15.098014 -35.371786)
		(end 15.098014 -35.816794)
		(width 0.11684)
		(layer "F.Cu")
		(net "EN_P1V0_AUX")
	)
	(via
		(at 15.4432 -34.798)
		(size 0.508)
		(drill 0.254)
		(layers "F.Cu" "B.Cu")
		(net "EN_P1V0_AUX")
	)
	(via
		(at 15.22603 -29.91993)
		(size 0.508)
		(drill 0.254)
		(layers "F.Cu" "B.Cu")
		(net "EN_P1V0_AUX")
	)
	(segment
		(start 42.288968 -32.078168)
		(end 42.390568 -32.078168)
		(width 0.11684)
		(layer "F.Cu")
		(net "SMB_BMC_MM2_SCL_R1")
	)
	(segment
		(start 41.7576 -31.5468)
		(end 42.288968 -32.078168)
		(width 0.11684)
		(layer "F.Cu")
		(net "SMB_BMC_MM2_SCL_R1")
	)
	(segment
		(start 42.3926 -32.0802)
		(end 42.568368 -32.0802)
		(width 0.11684)
		(layer "F.Cu")
		(net "SMB_BMC_MM2_SCL_R1")
	)
	(segment
		(start 41.7576 -31.26105)
		(end 41.7576 -31.5468)
		(width 0.11684)
		(layer "F.Cu")
		(net "SMB_BMC_MM2_SCL_R1")
	)
	(segment
		(start 42.390568 -32.078168)
		(end 42.3926 -32.0802)
		(width 0.11684)
		(layer "F.Cu")
		(net "SMB_BMC_MM2_SCL_R1")
	)
	(segment
		(start 42.568368 -32.0802)
		(end 42.8752 -32.2072)
		(width 0.11684)
		(layer "F.Cu")
		(net "SMB_BMC_MM2_SCL_R1")
	)
	(via
		(at 42.8752 -32.2072)
		(size 0.508)
		(drill 0.254)
		(layers "F.Cu" "B.Cu")
		(net "SMB_BMC_MM2_SCL_R1")
	)
	(via
		(at 61.0108 -114.4651)
		(size 0.508)
		(drill 0.254)
		(layers "F.Cu" "B.Cu")
		(net "SMB_BMC_MM2_SCL_R1")
	)
	(via
		(at 52.3621 -104.856534)
		(size 0.508)
		(drill 0.254)
		(layers "F.Cu" "B.Cu")
		(net "SMB_BMC_MM2_SCL_R1")
	)
	(segment
		(start 61.492384 -114.654584)
		(end 61.3029 -114.4651)
		(width 0.11684)
		(layer "B.Cu")
		(net "SMB_BMC_MM2_SCL_R1")
	)
	(segment
		(start 61.3029 -114.4651)
		(end 61.0108 -114.4651)
		(width 0.11684)
		(layer "B.Cu")
		(net "SMB_BMC_MM2_SCL_R1")
	)
	(segment
		(start 61.064902 -116.59743)
		(end 61.47816 -116.184172)
		(width 0.11684)
		(layer "B.Cu")
		(net "SMB_BMC_MM2_SCL_R1")
	)
	(segment
		(start 61.064902 -118.460012)
		(end 61.064902 -116.59743)
		(width 0.11684)
		(layer "B.Cu")
		(net "SMB_BMC_MM2_SCL_R1")
	)
	(segment
		(start 61.47816 -114.669062)
		(end 61.492384 -114.654584)
		(width 0.11684)
		(layer "B.Cu")
		(net "SMB_BMC_MM2_SCL_R1")
	)
	(segment
		(start 61.47816 -116.184172)
		(end 61.47816 -114.669062)
		(width 0.11684)
		(layer "B.Cu")
		(net "SMB_BMC_MM2_SCL_R1")
	)
	(segment
		(start 34.28238 -53.21046)
		(end 34.28238 -55.084726)
		(width 0.10668)
		(layer "In7.Cu")
		(net "SMB_BMC_MM2_SCL_R1")
	)
	(segment
		(start 36.77412 -77.532738)
		(end 41.117266 -77.532738)
		(width 0.10668)
		(layer "In7.Cu")
		(net "SMB_BMC_MM2_SCL_R1")
	)
	(segment
		(start 34.48304 -72.68464)
		(end 34.48304 -74.665078)
		(width 0.10668)
		(layer "In7.Cu")
		(net "SMB_BMC_MM2_SCL_R1")
	)
	(segment
		(start 41.117266 -77.532738)
		(end 41.45534 -77.870812)
		(width 0.10668)
		(layer "In7.Cu")
		(net "SMB_BMC_MM2_SCL_R1")
	)
	(segment
		(start 51.054 -88.092534)
		(end 51.054 -95.394018)
		(width 0.10668)
		(layer "In7.Cu")
		(net "SMB_BMC_MM2_SCL_R1")
	)
	(segment
		(start 51.816 -104.310434)
		(end 52.3621 -104.856534)
		(width 0.10668)
		(layer "In7.Cu")
		(net "SMB_BMC_MM2_SCL_R1")
	)
	(segment
		(start 38.85438 -40.00246)
		(end 37.95522 -40.90162)
		(width 0.10668)
		(layer "In7.Cu")
		(net "SMB_BMC_MM2_SCL_R1")
	)
	(segment
		(start 61.0108 -114.4651)
		(end 60.5917 -114.4651)
		(width 0.10668)
		(layer "In7.Cu")
		(net "SMB_BMC_MM2_SCL_R1")
	)
	(segment
		(start 37.67328 -43.429174)
		(end 36.5125 -44.589954)
		(width 0.10668)
		(layer "In7.Cu")
		(net "SMB_BMC_MM2_SCL_R1")
	)
	(segment
		(start 34.74466 -74.926698)
		(end 34.74466 -76.121006)
		(width 0.10668)
		(layer "In7.Cu")
		(net "SMB_BMC_MM2_SCL_R1")
	)
	(segment
		(start 34.86658 -52.62626)
		(end 34.28238 -53.21046)
		(width 0.10668)
		(layer "In7.Cu")
		(net "SMB_BMC_MM2_SCL_R1")
	)
	(segment
		(start 58.547762 -111.91748)
		(end 57.874408 -111.91748)
		(width 0.10668)
		(layer "In7.Cu")
		(net "SMB_BMC_MM2_SCL_R1")
	)
	(segment
		(start 42.835322 -82.3214)
		(end 44.424854 -82.3214)
		(width 0.10668)
		(layer "In7.Cu")
		(net "SMB_BMC_MM2_SCL_R1")
	)
	(segment
		(start 51.816 -101.69652)
		(end 51.816 -104.310434)
		(width 0.10668)
		(layer "In7.Cu")
		(net "SMB_BMC_MM2_SCL_R1")
	)
	(segment
		(start 40.6146 -79.56804)
		(end 40.6146 -80.100678)
		(width 0.10668)
		(layer "In7.Cu")
		(net "SMB_BMC_MM2_SCL_R1")
	)
	(segment
		(start 32.714438 -61.09462)
		(end 32.714438 -63.907162)
		(width 0.10668)
		(layer "In7.Cu")
		(net "SMB_BMC_MM2_SCL_R1")
	)
	(segment
		(start 57.874408 -111.91748)
		(end 52.078128 -106.1212)
		(width 0.10668)
		(layer "In7.Cu")
		(net "SMB_BMC_MM2_SCL_R1")
	)
	(segment
		(start 60.325 -113.694718)
		(end 58.547762 -111.91748)
		(width 0.10668)
		(layer "In7.Cu")
		(net "SMB_BMC_MM2_SCL_R1")
	)
	(segment
		(start 42.8752 -33.8582)
		(end 41.62171 -35.11169)
		(width 0.10668)
		(layer "In7.Cu")
		(net "SMB_BMC_MM2_SCL_R1")
	)
	(segment
		(start 32.2326 -64.389)
		(end 32.2326 -65.2018)
		(width 0.10668)
		(layer "In7.Cu")
		(net "SMB_BMC_MM2_SCL_R1")
	)
	(segment
		(start 34.09696 -69.735954)
		(end 33.87598 -69.956934)
		(width 0.10668)
		(layer "In7.Cu")
		(net "SMB_BMC_MM2_SCL_R1")
	)
	(segment
		(start 44.424854 -82.3214)
		(end 45.776134 -83.67268)
		(width 0.10668)
		(layer "In7.Cu")
		(net "SMB_BMC_MM2_SCL_R1")
	)
	(segment
		(start 48.96612 -85.10778)
		(end 50.420016 -86.561676)
		(width 0.10668)
		(layer "In7.Cu")
		(net "SMB_BMC_MM2_SCL_R1")
	)
	(segment
		(start 38.85438 -39.28364)
		(end 38.85438 -40.00246)
		(width 0.10668)
		(layer "In7.Cu")
		(net "SMB_BMC_MM2_SCL_R1")
	)
	(segment
		(start 42.8752 -32.2072)
		(end 42.8752 -33.8582)
		(width 0.10668)
		(layer "In7.Cu")
		(net "SMB_BMC_MM2_SCL_R1")
	)
	(segment
		(start 37.67328 -41.507918)
		(end 37.67328 -43.429174)
		(width 0.10668)
		(layer "In7.Cu")
		(net "SMB_BMC_MM2_SCL_R1")
	)
	(segment
		(start 34.0614 -69.088)
		(end 34.09696 -69.12356)
		(width 0.10668)
		(layer "In7.Cu")
		(net "SMB_BMC_MM2_SCL_R1")
	)
	(segment
		(start 60.5917 -114.4651)
		(end 60.325 -114.1984)
		(width 0.10668)
		(layer "In7.Cu")
		(net "SMB_BMC_MM2_SCL_R1")
	)
	(segment
		(start 33.19526 -56.171846)
		(end 33.19526 -58.630312)
		(width 0.10668)
		(layer "In7.Cu")
		(net "SMB_BMC_MM2_SCL_R1")
	)
	(segment
		(start 36.5125 -44.589954)
		(end 36.5125 -46.198282)
		(width 0.10668)
		(layer "In7.Cu")
		(net "SMB_BMC_MM2_SCL_R1")
	)
	(segment
		(start 52.43576 -96.775778)
		(end 52.43576 -101.07676)
		(width 0.10668)
		(layer "In7.Cu")
		(net "SMB_BMC_MM2_SCL_R1")
	)
	(segment
		(start 36.660582 -77.4192)
		(end 36.77412 -77.532738)
		(width 0.10668)
		(layer "In7.Cu")
		(net "SMB_BMC_MM2_SCL_R1")
	)
	(segment
		(start 33.87598 -69.956934)
		(end 33.87598 -72.07758)
		(width 0.10668)
		(layer "In7.Cu")
		(net "SMB_BMC_MM2_SCL_R1")
	)
	(segment
		(start 60.325 -114.1984)
		(end 60.325 -113.694718)
		(width 0.10668)
		(layer "In7.Cu")
		(net "SMB_BMC_MM2_SCL_R1")
	)
	(segment
		(start 33.9217 -59.356752)
		(end 33.9217 -59.887358)
		(width 0.10668)
		(layer "In7.Cu")
		(net "SMB_BMC_MM2_SCL_R1")
	)
	(segment
		(start 52.3621 -104.898698)
		(end 52.3621 -104.856534)
		(width 0.10668)
		(layer "In7.Cu")
		(net "SMB_BMC_MM2_SCL_R1")
	)
	(segment
		(start 45.776134 -83.67268)
		(end 46.284642 -83.67268)
		(width 0.10668)
		(layer "In7.Cu")
		(net "SMB_BMC_MM2_SCL_R1")
	)
	(segment
		(start 34.74466 -76.121006)
		(end 36.042854 -77.4192)
		(width 0.10668)
		(layer "In7.Cu")
		(net "SMB_BMC_MM2_SCL_R1")
	)
	(segment
		(start 41.45534 -77.870812)
		(end 41.45534 -78.7273)
		(width 0.10668)
		(layer "In7.Cu")
		(net "SMB_BMC_MM2_SCL_R1")
	)
	(segment
		(start 41.62171 -36.51631)
		(end 38.85438 -39.28364)
		(width 0.10668)
		(layer "In7.Cu")
		(net "SMB_BMC_MM2_SCL_R1")
	)
	(segment
		(start 32.5374 -65.5066)
		(end 32.8168 -65.5066)
		(width 0.10668)
		(layer "In7.Cu")
		(net "SMB_BMC_MM2_SCL_R1")
	)
	(segment
		(start 41.45534 -78.7273)
		(end 40.6146 -79.56804)
		(width 0.10668)
		(layer "In7.Cu")
		(net "SMB_BMC_MM2_SCL_R1")
	)
	(segment
		(start 34.86658 -52.41798)
		(end 34.86658 -52.62626)
		(width 0.10668)
		(layer "In7.Cu")
		(net "SMB_BMC_MM2_SCL_R1")
	)
	(segment
		(start 52.078128 -106.1212)
		(end 52.078128 -105.18267)
		(width 0.10668)
		(layer "In7.Cu")
		(net "SMB_BMC_MM2_SCL_R1")
	)
	(segment
		(start 34.48304 -74.665078)
		(end 34.74466 -74.926698)
		(width 0.10668)
		(layer "In7.Cu")
		(net "SMB_BMC_MM2_SCL_R1")
	)
	(segment
		(start 33.19526 -58.630312)
		(end 33.9217 -59.356752)
		(width 0.10668)
		(layer "In7.Cu")
		(net "SMB_BMC_MM2_SCL_R1")
	)
	(segment
		(start 33.87598 -72.07758)
		(end 34.48304 -72.68464)
		(width 0.10668)
		(layer "In7.Cu")
		(net "SMB_BMC_MM2_SCL_R1")
	)
	(segment
		(start 37.95522 -41.225978)
		(end 37.67328 -41.507918)
		(width 0.10668)
		(layer "In7.Cu")
		(net "SMB_BMC_MM2_SCL_R1")
	)
	(segment
		(start 52.43576 -101.07676)
		(end 51.816 -101.69652)
		(width 0.10668)
		(layer "In7.Cu")
		(net "SMB_BMC_MM2_SCL_R1")
	)
	(segment
		(start 34.53384 -52.08524)
		(end 34.86658 -52.41798)
		(width 0.10668)
		(layer "In7.Cu")
		(net "SMB_BMC_MM2_SCL_R1")
	)
	(segment
		(start 34.09696 -69.12356)
		(end 34.09696 -69.735954)
		(width 0.10668)
		(layer "In7.Cu")
		(net "SMB_BMC_MM2_SCL_R1")
	)
	(segment
		(start 50.420016 -86.561676)
		(end 51.054 -88.092534)
		(width 0.10668)
		(layer "In7.Cu")
		(net "SMB_BMC_MM2_SCL_R1")
	)
	(segment
		(start 36.5125 -46.198282)
		(end 34.53384 -48.176942)
		(width 0.10668)
		(layer "In7.Cu")
		(net "SMB_BMC_MM2_SCL_R1")
	)
	(segment
		(start 34.28238 -55.084726)
		(end 33.19526 -56.171846)
		(width 0.10668)
		(layer "In7.Cu")
		(net "SMB_BMC_MM2_SCL_R1")
	)
	(segment
		(start 40.6146 -80.100678)
		(end 42.835322 -82.3214)
		(width 0.10668)
		(layer "In7.Cu")
		(net "SMB_BMC_MM2_SCL_R1")
	)
	(segment
		(start 41.62171 -35.11169)
		(end 41.62171 -36.51631)
		(width 0.10668)
		(layer "In7.Cu")
		(net "SMB_BMC_MM2_SCL_R1")
	)
	(segment
		(start 34.53384 -48.176942)
		(end 34.53384 -52.08524)
		(width 0.10668)
		(layer "In7.Cu")
		(net "SMB_BMC_MM2_SCL_R1")
	)
	(segment
		(start 36.042854 -77.4192)
		(end 36.660582 -77.4192)
		(width 0.10668)
		(layer "In7.Cu")
		(net "SMB_BMC_MM2_SCL_R1")
	)
	(segment
		(start 32.8168 -65.5066)
		(end 34.0614 -66.7512)
		(width 0.10668)
		(layer "In7.Cu")
		(net "SMB_BMC_MM2_SCL_R1")
	)
	(segment
		(start 34.0614 -66.7512)
		(end 34.0614 -69.088)
		(width 0.10668)
		(layer "In7.Cu")
		(net "SMB_BMC_MM2_SCL_R1")
	)
	(segment
		(start 46.284642 -83.67268)
		(end 47.719742 -85.10778)
		(width 0.10668)
		(layer "In7.Cu")
		(net "SMB_BMC_MM2_SCL_R1")
	)
	(segment
		(start 51.054 -95.394018)
		(end 52.43576 -96.775778)
		(width 0.10668)
		(layer "In7.Cu")
		(net "SMB_BMC_MM2_SCL_R1")
	)
	(segment
		(start 47.719742 -85.10778)
		(end 48.96612 -85.10778)
		(width 0.10668)
		(layer "In7.Cu")
		(net "SMB_BMC_MM2_SCL_R1")
	)
	(segment
		(start 33.9217 -59.887358)
		(end 32.714438 -61.09462)
		(width 0.10668)
		(layer "In7.Cu")
		(net "SMB_BMC_MM2_SCL_R1")
	)
	(segment
		(start 32.2326 -65.2018)
		(end 32.5374 -65.5066)
		(width 0.10668)
		(layer "In7.Cu")
		(net "SMB_BMC_MM2_SCL_R1")
	)
	(segment
		(start 37.95522 -40.90162)
		(end 37.95522 -41.225978)
		(width 0.10668)
		(layer "In7.Cu")
		(net "SMB_BMC_MM2_SCL_R1")
	)
	(segment
		(start 52.078128 -105.18267)
		(end 52.3621 -104.898698)
		(width 0.10668)
		(layer "In7.Cu")
		(net "SMB_BMC_MM2_SCL_R1")
	)
	(segment
		(start 32.714438 -63.907162)
		(end 32.2326 -64.389)
		(width 0.10668)
		(layer "In7.Cu")
		(net "SMB_BMC_MM2_SCL_R1")
	)
	(segment
		(start 8.00227 -66.675)
		(end 7.79907 -66.4718)
		(width 0.254)
		(layer "F.Cu")
		(net "SW_P3V3_AUX_BST_R")
	)
	(segment
		(start 9.296146 -66.675)
		(end 8.00227 -66.675)
		(width 0.254)
		(layer "F.Cu")
		(net "SW_P3V3_AUX_BST_R")
	)
	(segment
		(start 9.62025 -67.183)
		(end 9.62025 -66.999104)
		(width 0.254)
		(layer "F.Cu")
		(net "SW_P3V3_AUX_BST_R")
	)
	(segment
		(start 7.79907 -66.4718)
		(end 7.79907 -65.636902)
		(width 0.254)
		(layer "F.Cu")
		(net "SW_P3V3_AUX_BST_R")
	)
	(segment
		(start 9.62025 -66.999104)
		(end 9.296146 -66.675)
		(width 0.254)
		(layer "F.Cu")
		(net "SW_P3V3_AUX_BST_R")
	)
	(segment
		(start 38.717982 -56.436514)
		(end 39.32682 -55.827676)
		(width 0.11684)
		(layer "F.Cu")
		(net "U41_ADJ")
	)
	(segment
		(start 39.32682 -55.827676)
		(end 39.631112 -55.827676)
		(width 0.11684)
		(layer "F.Cu")
		(net "U41_ADJ")
	)
	(segment
		(start 40.648128 -55.827676)
		(end 39.631112 -55.827676)
		(width 0.11684)
		(layer "F.Cu")
		(net "U41_ADJ")
	)
	(segment
		(start 38.218618 -56.436514)
		(end 38.717982 -56.436514)
		(width 0.11684)
		(layer "F.Cu")
		(net "U41_ADJ")
	)
	(segment
		(start 82.817208 -37.703506)
		(end 82.817208 -36.683442)
		(width 0.11684)
		(layer "F.Cu")
		(net "U39_ADJ")
	)
	(segment
		(start 82.139536 -35.130486)
		(end 82.139536 -35.68827)
		(width 0.11684)
		(layer "F.Cu")
		(net "U39_ADJ")
	)
	(segment
		(start 82.817208 -36.365942)
		(end 82.817208 -36.683442)
		(width 0.11684)
		(layer "F.Cu")
		(net "U39_ADJ")
	)
	(segment
		(start 82.139536 -35.68827)
		(end 82.817208 -36.365942)
		(width 0.11684)
		(layer "F.Cu")
		(net "U39_ADJ")
	)
	(segment
		(start 56.094884 -56.171338)
		(end 55.69966 -56.566562)
		(width 0.11684)
		(layer "F.Cu")
		(net "PU_FWSPIWP_N_R")
	)
	(via
		(at 57.50687 -67.64909)
		(size 0.762)
		(drill 0.254)
		(layers "F.Cu" "B.Cu")
		(net "PU_FWSPIWP_N_R")
	)
	(via
		(at 55.69966 -56.566562)
		(size 0.4572)
		(drill 0.254)
		(layers "F.Cu" "B.Cu")
		(net "PU_FWSPIWP_N_R")
	)
	(segment
		(start 57.23255 -68.21805)
		(end 57.50687 -67.94373)
		(width 0.11684)
		(layer "B.Cu")
		(net "PU_FWSPIWP_N_R")
	)
	(segment
		(start 56.7436 -68.21805)
		(end 57.23255 -68.21805)
		(width 0.11684)
		(layer "B.Cu")
		(net "PU_FWSPIWP_N_R")
	)
	(segment
		(start 57.50687 -67.94373)
		(end 57.50687 -67.64909)
		(width 0.11684)
		(layer "B.Cu")
		(net "PU_FWSPIWP_N_R")
	)
	(segment
		(start 57.50687 -66.592704)
		(end 57.278524 -66.364358)
		(width 0.10668)
		(layer "In4.Cu")
		(net "PU_FWSPIWP_N_R")
	)
	(segment
		(start 56.719978 -63.527178)
		(end 56.719978 -60.229242)
		(width 0.10668)
		(layer "In4.Cu")
		(net "PU_FWSPIWP_N_R")
	)
	(segment
		(start 57.278524 -64.997076)
		(end 57.5056 -64.77)
		(width 0.10668)
		(layer "In4.Cu")
		(net "PU_FWSPIWP_N_R")
	)
	(segment
		(start 57.5056 -64.3128)
		(end 56.719978 -63.527178)
		(width 0.10668)
		(layer "In4.Cu")
		(net "PU_FWSPIWP_N_R")
	)
	(segment
		(start 57.278524 -66.364358)
		(end 57.278524 -64.997076)
		(width 0.10668)
		(layer "In4.Cu")
		(net "PU_FWSPIWP_N_R")
	)
	(segment
		(start 56.719978 -60.229242)
		(end 56.0832 -59.592464)
		(width 0.10668)
		(layer "In4.Cu")
		(net "PU_FWSPIWP_N_R")
	)
	(segment
		(start 57.5056 -64.77)
		(end 57.5056 -64.3128)
		(width 0.10668)
		(layer "In4.Cu")
		(net "PU_FWSPIWP_N_R")
	)
	(segment
		(start 56.0832 -59.592464)
		(end 56.0832 -57.175654)
		(width 0.10668)
		(layer "In4.Cu")
		(net "PU_FWSPIWP_N_R")
	)
	(segment
		(start 56.0832 -57.175654)
		(end 55.69966 -56.792114)
		(width 0.10668)
		(layer "In4.Cu")
		(net "PU_FWSPIWP_N_R")
	)
	(segment
		(start 55.69966 -56.792114)
		(end 55.69966 -56.566562)
		(width 0.10668)
		(layer "In4.Cu")
		(net "PU_FWSPIWP_N_R")
	)
	(segment
		(start 57.50687 -67.64909)
		(end 57.50687 -66.592704)
		(width 0.10668)
		(layer "In4.Cu")
		(net "PU_FWSPIWP_N_R")
	)
	(segment
		(start 56.094884 -56.971184)
		(end 55.69966 -57.366408)
		(width 0.11684)
		(layer "F.Cu")
		(net "PU_BMC_FWSPIABR_N_R")
	)
	(via
		(at 55.69966 -57.366408)
		(size 0.4572)
		(drill 0.254)
		(layers "F.Cu" "B.Cu")
		(net "PU_BMC_FWSPIABR_N_R")
	)
	(segment
		(start 57.15 -61.468)
		(end 56.7182 -61.8998)
		(width 0.11684)
		(layer "B.Cu")
		(net "PU_BMC_FWSPIABR_N_R")
	)
	(segment
		(start 56.7182 -61.8998)
		(end 56.7182 -62.24905)
		(width 0.11684)
		(layer "B.Cu")
		(net "PU_BMC_FWSPIABR_N_R")
	)
	(segment
		(start 56.752236 -59.387994)
		(end 56.752236 -59.672982)
		(width 0.11684)
		(layer "B.Cu")
		(net "PU_BMC_FWSPIABR_N_R")
	)
	(segment
		(start 56.752236 -59.672982)
		(end 57.15 -60.070746)
		(width 0.11684)
		(layer "B.Cu")
		(net "PU_BMC_FWSPIABR_N_R")
	)
	(segment
		(start 56.093614 -58.333894)
		(end 56.398668 -58.638948)
		(width 0.11684)
		(layer "B.Cu")
		(net "PU_BMC_FWSPIABR_N_R")
	)
	(segment
		(start 57.15 -60.070746)
		(end 57.15 -61.468)
		(width 0.11684)
		(layer "B.Cu")
		(net "PU_BMC_FWSPIABR_N_R")
	)
	(segment
		(start 56.093614 -57.760362)
		(end 56.093614 -58.333894)
		(width 0.11684)
		(layer "B.Cu")
		(net "PU_BMC_FWSPIABR_N_R")
	)
	(segment
		(start 56.398668 -59.034426)
		(end 56.752236 -59.387994)
		(width 0.11684)
		(layer "B.Cu")
		(net "PU_BMC_FWSPIABR_N_R")
	)
	(segment
		(start 55.69966 -57.366408)
		(end 56.093614 -57.760362)
		(width 0.11684)
		(layer "B.Cu")
		(net "PU_BMC_FWSPIABR_N_R")
	)
	(segment
		(start 56.398668 -58.638948)
		(end 56.398668 -59.034426)
		(width 0.11684)
		(layer "B.Cu")
		(net "PU_BMC_FWSPIABR_N_R")
	)
	(segment
		(start 56.7182 -62.24905)
		(end 56.53405 -62.4332)
		(width 0.11684)
		(layer "B.Cu")
		(net "PU_BMC_FWSPIABR_N_R")
	)
	(segment
		(start 18.034 -102.34295)
		(end 18.034 -101.473254)
		(width 0.11684)
		(layer "F.Cu")
		(net "SMB_BMC_MM16_R4_SDA")
	)
	(segment
		(start 17.4498 -100.889054)
		(end 17.4498 -99.177348)
		(width 0.11684)
		(layer "F.Cu")
		(net "SMB_BMC_MM16_R4_SDA")
	)
	(segment
		(start 18.034 -101.473254)
		(end 17.4498 -100.889054)
		(width 0.11684)
		(layer "F.Cu")
		(net "SMB_BMC_MM16_R4_SDA")
	)
	(segment
		(start 17.4498 -99.177348)
		(end 17.059402 -98.78695)
		(width 0.11684)
		(layer "F.Cu")
		(net "SMB_BMC_MM16_R4_SDA")
	)
	(segment
		(start 16.259556 -101.584506)
		(end 16.259556 -99.58705)
		(width 0.11684)
		(layer "F.Cu")
		(net "SMB_BMC_MM16_R4_SCL")
	)
	(segment
		(start 17.018 -102.34295)
		(end 16.259556 -101.584506)
		(width 0.11684)
		(layer "F.Cu")
		(net "SMB_BMC_MM16_R4_SCL")
	)
	(segment
		(start 19.864324 -87.99195)
		(end 20.259548 -88.387174)
		(width 0.11684)
		(layer "F.Cu")
		(net "PU_PT20D")
	)
	(segment
		(start 18.7706 -85.957664)
		(end 19.0246 -86.211664)
		(width 0.11684)
		(layer "F.Cu")
		(net "PU_PT20D")
	)
	(segment
		(start 19.848068 -87.513668)
		(end 19.864324 -87.529924)
		(width 0.11684)
		(layer "F.Cu")
		(net "PU_PT20D")
	)
	(segment
		(start 19.0246 -86.211664)
		(end 19.0246 -86.60257)
		(width 0.11684)
		(layer "F.Cu")
		(net "PU_PT20D")
	)
	(segment
		(start 19.848068 -87.426038)
		(end 19.848068 -87.513668)
		(width 0.11684)
		(layer "F.Cu")
		(net "PU_PT20D")
	)
	(segment
		(start 19.409664 -84.12607)
		(end 18.7706 -84.765134)
		(width 0.11684)
		(layer "F.Cu")
		(net "PU_PT20D")
	)
	(segment
		(start 19.0246 -86.60257)
		(end 19.848068 -87.426038)
		(width 0.11684)
		(layer "F.Cu")
		(net "PU_PT20D")
	)
	(segment
		(start 18.7706 -84.765134)
		(end 18.7706 -85.957664)
		(width 0.11684)
		(layer "F.Cu")
		(net "PU_PT20D")
	)
	(segment
		(start 19.431 -84.12607)
		(end 19.409664 -84.12607)
		(width 0.11684)
		(layer "F.Cu")
		(net "PU_PT20D")
	)
	(segment
		(start 19.864324 -87.529924)
		(end 19.864324 -87.99195)
		(width 0.11684)
		(layer "F.Cu")
		(net "PU_PT20D")
	)
	(segment
		(start 19.05 -99.177602)
		(end 18.659348 -98.78695)
		(width 0.11684)
		(layer "F.Cu")
		(net "PU_PB25A")
	)
	(segment
		(start 19.05 -102.34295)
		(end 19.05 -99.177602)
		(width 0.11684)
		(layer "F.Cu")
		(net "PU_PB25A")
	)
	(segment
		(start 47.295054 -44.171362)
		(end 46.89983 -43.776138)
		(width 0.11684)
		(layer "F.Cu")
		(net "FM_JTAG_SEL")
	)
	(via
		(at 34.3662 -44.4754)
		(size 0.508)
		(drill 0.254)
		(layers "F.Cu" "B.Cu")
		(net "FM_JTAG_SEL")
	)
	(via
		(at 31.28518 -110.0328)
		(size 0.508)
		(drill 0.254)
		(layers "F.Cu" "B.Cu")
		(net "FM_JTAG_SEL")
	)
	(via
		(at 46.89983 -43.776138)
		(size 0.4572)
		(drill 0.254)
		(layers "F.Cu" "B.Cu")
		(net "FM_JTAG_SEL")
	)
	(segment
		(start 31.28518 -110.0328)
		(end 31.28518 -111.10722)
		(width 0.11684)
		(layer "B.Cu")
		(net "FM_JTAG_SEL")
	)
	(segment
		(start 30.545024 -117.257576)
		(end 30.545024 -118.460012)
		(width 0.11684)
		(layer "B.Cu")
		(net "FM_JTAG_SEL")
	)
	(segment
		(start 30.7594 -111.633)
		(end 30.7594 -117.0432)
		(width 0.11684)
		(layer "B.Cu")
		(net "FM_JTAG_SEL")
	)
	(segment
		(start 31.28518 -111.10722)
		(end 30.7594 -111.633)
		(width 0.11684)
		(layer "B.Cu")
		(net "FM_JTAG_SEL")
	)
	(segment
		(start 30.7594 -117.0432)
		(end 30.545024 -117.257576)
		(width 0.11684)
		(layer "B.Cu")
		(net "FM_JTAG_SEL")
	)
	(segment
		(start 45.157644 -44.167552)
		(end 44.90974 -43.919648)
		(width 0.08382)
		(layer "In2.Cu")
		(net "FM_JTAG_SEL")
	)
	(segment
		(start 44.342812 -43.387518)
		(end 43.739562 -43.990768)
		(width 0.08382)
		(layer "In2.Cu")
		(net "FM_JTAG_SEL")
	)
	(segment
		(start 44.90974 -43.919648)
		(end 44.90974 -43.565572)
		(width 0.08382)
		(layer "In2.Cu")
		(net "FM_JTAG_SEL")
	)
	(segment
		(start 46.89983 -43.776138)
		(end 46.508416 -44.167552)
		(width 0.08382)
		(layer "In2.Cu")
		(net "FM_JTAG_SEL")
	)
	(segment
		(start 43.739562 -43.990768)
		(end 36.120832 -43.990768)
		(width 0.08382)
		(layer "In2.Cu")
		(net "FM_JTAG_SEL")
	)
	(segment
		(start 44.90974 -43.565572)
		(end 44.731686 -43.387518)
		(width 0.08382)
		(layer "In2.Cu")
		(net "FM_JTAG_SEL")
	)
	(segment
		(start 35.6362 -44.4754)
		(end 34.3662 -44.4754)
		(width 0.08382)
		(layer "In2.Cu")
		(net "FM_JTAG_SEL")
	)
	(segment
		(start 44.731686 -43.387518)
		(end 44.342812 -43.387518)
		(width 0.08382)
		(layer "In2.Cu")
		(net "FM_JTAG_SEL")
	)
	(segment
		(start 36.120832 -43.990768)
		(end 35.6362 -44.4754)
		(width 0.08382)
		(layer "In2.Cu")
		(net "FM_JTAG_SEL")
	)
	(segment
		(start 46.508416 -44.167552)
		(end 45.157644 -44.167552)
		(width 0.08382)
		(layer "In2.Cu")
		(net "FM_JTAG_SEL")
	)
	(segment
		(start 32.253936 -106.582972)
		(end 32.253936 -107.837224)
		(width 0.10668)
		(layer "In4.Cu")
		(net "FM_JTAG_SEL")
	)
	(segment
		(start 32.253936 -107.837224)
		(end 31.28518 -108.80598)
		(width 0.10668)
		(layer "In4.Cu")
		(net "FM_JTAG_SEL")
	)
	(segment
		(start 28.346654 -93.6498)
		(end 28.02128 -93.975174)
		(width 0.10668)
		(layer "In4.Cu")
		(net "FM_JTAG_SEL")
	)
	(segment
		(start 30.763718 -103.51008)
		(end 31.56458 -104.310942)
		(width 0.10668)
		(layer "In4.Cu")
		(net "FM_JTAG_SEL")
	)
	(segment
		(start 28.752546 -93.6498)
		(end 28.346654 -93.6498)
		(width 0.10668)
		(layer "In4.Cu")
		(net "FM_JTAG_SEL")
	)
	(segment
		(start 28.63596 -97.67824)
		(end 28.63596 -100.877116)
		(width 0.10668)
		(layer "In4.Cu")
		(net "FM_JTAG_SEL")
	)
	(segment
		(start 31.33344 -91.71432)
		(end 30.21965 -92.82811)
		(width 0.10668)
		(layer "In4.Cu")
		(net "FM_JTAG_SEL")
	)
	(segment
		(start 30.1498 -83.932776)
		(end 30.08122 -84.001356)
		(width 0.10668)
		(layer "In4.Cu")
		(net "FM_JTAG_SEL")
	)
	(segment
		(start 31.72714 -73.42886)
		(end 31.72714 -76.970382)
		(width 0.10668)
		(layer "In4.Cu")
		(net "FM_JTAG_SEL")
	)
	(segment
		(start 29.0068 -97.3074)
		(end 28.63596 -97.67824)
		(width 0.10668)
		(layer "In4.Cu")
		(net "FM_JTAG_SEL")
	)
	(segment
		(start 31.56458 -105.893616)
		(end 32.253936 -106.582972)
		(width 0.10668)
		(layer "In4.Cu")
		(net "FM_JTAG_SEL")
	)
	(segment
		(start 32.015684 -56.142636)
		(end 32.015684 -61.251084)
		(width 0.10668)
		(layer "In4.Cu")
		(net "FM_JTAG_SEL")
	)
	(segment
		(start 33.32226 -65.2399)
		(end 33.86582 -65.78346)
		(width 0.10668)
		(layer "In4.Cu")
		(net "FM_JTAG_SEL")
	)
	(segment
		(start 30.08122 -89.617296)
		(end 31.33344 -90.869516)
		(width 0.10668)
		(layer "In4.Cu")
		(net "FM_JTAG_SEL")
	)
	(segment
		(start 31.56458 -104.310942)
		(end 31.56458 -105.893616)
		(width 0.10668)
		(layer "In4.Cu")
		(net "FM_JTAG_SEL")
	)
	(segment
		(start 29.574236 -92.82811)
		(end 28.752546 -93.6498)
		(width 0.10668)
		(layer "In4.Cu")
		(net "FM_JTAG_SEL")
	)
	(segment
		(start 30.2768 -80.27797)
		(end 30.2768 -83.805522)
		(width 0.10668)
		(layer "In4.Cu")
		(net "FM_JTAG_SEL")
	)
	(segment
		(start 33.6804 -46.336458)
		(end 33.6804 -48.102012)
		(width 0.10668)
		(layer "In4.Cu")
		(net "FM_JTAG_SEL")
	)
	(segment
		(start 34.3662 -44.4754)
		(end 33.62198 -45.21962)
		(width 0.10668)
		(layer "In4.Cu")
		(net "FM_JTAG_SEL")
	)
	(segment
		(start 28.63596 -100.877116)
		(end 30.763718 -103.004874)
		(width 0.10668)
		(layer "In4.Cu")
		(net "FM_JTAG_SEL")
	)
	(segment
		(start 33.62198 -45.21962)
		(end 33.62198 -46.278038)
		(width 0.10668)
		(layer "In4.Cu")
		(net "FM_JTAG_SEL")
	)
	(segment
		(start 35.307524 -70.889876)
		(end 34.665158 -71.532242)
		(width 0.10668)
		(layer "In4.Cu")
		(net "FM_JTAG_SEL")
	)
	(segment
		(start 30.08122 -84.001356)
		(end 30.08122 -89.617296)
		(width 0.10668)
		(layer "In4.Cu")
		(net "FM_JTAG_SEL")
	)
	(segment
		(start 32.015684 -61.251084)
		(end 32.3088 -61.5442)
		(width 0.10668)
		(layer "In4.Cu")
		(net "FM_JTAG_SEL")
	)
	(segment
		(start 29.0068 -95.4532)
		(end 29.0068 -97.3074)
		(width 0.10668)
		(layer "In4.Cu")
		(net "FM_JTAG_SEL")
	)
	(segment
		(start 31.28518 -108.80598)
		(end 31.28518 -110.0328)
		(width 0.10668)
		(layer "In4.Cu")
		(net "FM_JTAG_SEL")
	)
	(segment
		(start 35.307524 -69.62394)
		(end 35.307524 -70.889876)
		(width 0.10668)
		(layer "In4.Cu")
		(net "FM_JTAG_SEL")
	)
	(segment
		(start 32.3088 -63.246)
		(end 33.32226 -64.25946)
		(width 0.10668)
		(layer "In4.Cu")
		(net "FM_JTAG_SEL")
	)
	(segment
		(start 32.77108 -50.297588)
		(end 32.77108 -54.318408)
		(width 0.10668)
		(layer "In4.Cu")
		(net "FM_JTAG_SEL")
	)
	(segment
		(start 31.33344 -90.869516)
		(end 31.33344 -91.71432)
		(width 0.10668)
		(layer "In4.Cu")
		(net "FM_JTAG_SEL")
	)
	(segment
		(start 33.86582 -65.78346)
		(end 33.86582 -68.08851)
		(width 0.10668)
		(layer "In4.Cu")
		(net "FM_JTAG_SEL")
	)
	(segment
		(start 33.86582 -68.08851)
		(end 35.237166 -69.459856)
		(width 0.10668)
		(layer "In4.Cu")
		(net "FM_JTAG_SEL")
	)
	(segment
		(start 30.2768 -83.805522)
		(end 30.1498 -83.932522)
		(width 0.10668)
		(layer "In4.Cu")
		(net "FM_JTAG_SEL")
	)
	(segment
		(start 33.6804 -48.102012)
		(end 32.77108 -50.297588)
		(width 0.10668)
		(layer "In4.Cu")
		(net "FM_JTAG_SEL")
	)
	(segment
		(start 28.02128 -93.975174)
		(end 28.02128 -94.46768)
		(width 0.10668)
		(layer "In4.Cu")
		(net "FM_JTAG_SEL")
	)
	(segment
		(start 35.237166 -69.459856)
		(end 35.307524 -69.62394)
		(width 0.10668)
		(layer "In4.Cu")
		(net "FM_JTAG_SEL")
	)
	(segment
		(start 33.62198 -46.278038)
		(end 33.6804 -46.336458)
		(width 0.10668)
		(layer "In4.Cu")
		(net "FM_JTAG_SEL")
	)
	(segment
		(start 31.72714 -76.970382)
		(end 30.5562 -78.141322)
		(width 0.10668)
		(layer "In4.Cu")
		(net "FM_JTAG_SEL")
	)
	(segment
		(start 30.5562 -78.141322)
		(end 30.5562 -79.99857)
		(width 0.10668)
		(layer "In4.Cu")
		(net "FM_JTAG_SEL")
	)
	(segment
		(start 30.1498 -83.932522)
		(end 30.1498 -83.932776)
		(width 0.10668)
		(layer "In4.Cu")
		(net "FM_JTAG_SEL")
	)
	(segment
		(start 30.763718 -103.004874)
		(end 30.763718 -103.51008)
		(width 0.10668)
		(layer "In4.Cu")
		(net "FM_JTAG_SEL")
	)
	(segment
		(start 33.32226 -64.25946)
		(end 33.32226 -65.2399)
		(width 0.10668)
		(layer "In4.Cu")
		(net "FM_JTAG_SEL")
	)
	(segment
		(start 32.77108 -54.318408)
		(end 32.015684 -56.142636)
		(width 0.10668)
		(layer "In4.Cu")
		(net "FM_JTAG_SEL")
	)
	(segment
		(start 34.665158 -71.532242)
		(end 33.623758 -71.532242)
		(width 0.10668)
		(layer "In4.Cu")
		(net "FM_JTAG_SEL")
	)
	(segment
		(start 32.3088 -61.5442)
		(end 32.3088 -63.246)
		(width 0.10668)
		(layer "In4.Cu")
		(net "FM_JTAG_SEL")
	)
	(segment
		(start 30.21965 -92.82811)
		(end 29.574236 -92.82811)
		(width 0.10668)
		(layer "In4.Cu")
		(net "FM_JTAG_SEL")
	)
	(segment
		(start 33.623758 -71.532242)
		(end 31.72714 -73.42886)
		(width 0.10668)
		(layer "In4.Cu")
		(net "FM_JTAG_SEL")
	)
	(segment
		(start 28.02128 -94.46768)
		(end 29.0068 -95.4532)
		(width 0.10668)
		(layer "In4.Cu")
		(net "FM_JTAG_SEL")
	)
	(segment
		(start 30.5562 -79.99857)
		(end 30.2768 -80.27797)
		(width 0.10668)
		(layer "In4.Cu")
		(net "FM_JTAG_SEL")
	)
	(segment
		(start 70.3072 -66.7004)
		(end 67.4116 -63.8048)
		(width 0.11684)
		(layer "F.Cu")
		(net "ESPI_HOST_LPC_BMC_LFRAME_N_R")
	)
	(segment
		(start 69.663056 -75.908662)
		(end 69.663056 -72.60082)
		(width 0.11684)
		(layer "F.Cu")
		(net "ESPI_HOST_LPC_BMC_LFRAME_N_R")
	)
	(segment
		(start 64.0969 -104.8639)
		(end 65.0113 -104.8639)
		(width 0.11684)
		(layer "F.Cu")
		(net "ESPI_HOST_LPC_BMC_LFRAME_N_R")
	)
	(segment
		(start 67.4116 -63.1952)
		(end 65.3923 -61.1759)
		(width 0.11684)
		(layer "F.Cu")
		(net "ESPI_HOST_LPC_BMC_LFRAME_N_R")
	)
	(segment
		(start 60.094876 -60.34405)
		(end 60.094876 -59.37123)
		(width 0.11684)
		(layer "F.Cu")
		(net "ESPI_HOST_LPC_BMC_LFRAME_N_R")
	)
	(segment
		(start 65.0113 -104.8639)
		(end 65.5066 -105.3592)
		(width 0.11684)
		(layer "F.Cu")
		(net "ESPI_HOST_LPC_BMC_LFRAME_N_R")
	)
	(segment
		(start 64.60617 -76.346558)
		(end 65.551812 -77.2922)
		(width 0.11684)
		(layer "F.Cu")
		(net "ESPI_HOST_LPC_BMC_LFRAME_N_R")
	)
	(segment
		(start 68.279518 -77.2922)
		(end 69.663056 -75.908662)
		(width 0.11684)
		(layer "F.Cu")
		(net "ESPI_HOST_LPC_BMC_LFRAME_N_R")
	)
	(segment
		(start 67.4116 -63.8048)
		(end 67.4116 -63.1952)
		(width 0.11684)
		(layer "F.Cu")
		(net "ESPI_HOST_LPC_BMC_LFRAME_N_R")
	)
	(segment
		(start 60.926726 -61.1759)
		(end 60.094876 -60.34405)
		(width 0.11684)
		(layer "F.Cu")
		(net "ESPI_HOST_LPC_BMC_LFRAME_N_R")
	)
	(segment
		(start 70.3072 -70.32244)
		(end 70.3072 -66.7004)
		(width 0.11684)
		(layer "F.Cu")
		(net "ESPI_HOST_LPC_BMC_LFRAME_N_R")
	)
	(segment
		(start 65.3923 -61.1759)
		(end 60.926726 -61.1759)
		(width 0.11684)
		(layer "F.Cu")
		(net "ESPI_HOST_LPC_BMC_LFRAME_N_R")
	)
	(segment
		(start 65.5066 -105.8418)
		(end 65.5066 -107.60075)
		(width 0.11684)
		(layer "F.Cu")
		(net "ESPI_HOST_LPC_BMC_LFRAME_N_R")
	)
	(segment
		(start 71.034402 -71.229474)
		(end 71.034402 -71.049642)
		(width 0.11684)
		(layer "F.Cu")
		(net "ESPI_HOST_LPC_BMC_LFRAME_N_R")
	)
	(segment
		(start 71.034402 -71.049642)
		(end 70.3072 -70.32244)
		(width 0.11684)
		(layer "F.Cu")
		(net "ESPI_HOST_LPC_BMC_LFRAME_N_R")
	)
	(segment
		(start 69.663056 -72.60082)
		(end 71.034402 -71.229474)
		(width 0.11684)
		(layer "F.Cu")
		(net "ESPI_HOST_LPC_BMC_LFRAME_N_R")
	)
	(segment
		(start 65.5066 -105.3592)
		(end 65.5066 -105.8418)
		(width 0.11684)
		(layer "F.Cu")
		(net "ESPI_HOST_LPC_BMC_LFRAME_N_R")
	)
	(segment
		(start 65.551812 -77.2922)
		(end 68.279518 -77.2922)
		(width 0.11684)
		(layer "F.Cu")
		(net "ESPI_HOST_LPC_BMC_LFRAME_N_R")
	)
	(via
		(at 64.60617 -76.346558)
		(size 0.508)
		(drill 0.254)
		(layers "F.Cu" "B.Cu")
		(net "ESPI_HOST_LPC_BMC_LFRAME_N_R")
	)
	(via
		(at 65.5066 -105.8418)
		(size 0.762)
		(drill 0.381)
		(layers "F.Cu" "B.Cu")
		(net "ESPI_HOST_LPC_BMC_LFRAME_N_R")
	)
	(via
		(at 64.0969 -104.8639)
		(size 0.508)
		(drill 0.254)
		(layers "F.Cu" "B.Cu")
		(net "ESPI_HOST_LPC_BMC_LFRAME_N_R")
	)
	(segment
		(start 63.59398 -85.30082)
		(end 64.8462 -84.0486)
		(width 0.10668)
		(layer "In4.Cu")
		(net "ESPI_HOST_LPC_BMC_LFRAME_N_R")
	)
	(segment
		(start 62.5602 -99.7966)
		(end 62.5602 -97.483168)
		(width 0.10668)
		(layer "In4.Cu")
		(net "ESPI_HOST_LPC_BMC_LFRAME_N_R")
	)
	(segment
		(start 64.999108 -81.960212)
		(end 64.89446 -81.855564)
		(width 0.10668)
		(layer "In4.Cu")
		(net "ESPI_HOST_LPC_BMC_LFRAME_N_R")
	)
	(segment
		(start 64.666114 -83.37804)
		(end 64.518286 -83.37804)
		(width 0.10668)
		(layer "In4.Cu")
		(net "ESPI_HOST_LPC_BMC_LFRAME_N_R")
	)
	(segment
		(start 64.3382 -83.197954)
		(end 64.3382 -82.943446)
		(width 0.10668)
		(layer "In4.Cu")
		(net "ESPI_HOST_LPC_BMC_LFRAME_N_R")
	)
	(segment
		(start 63.59398 -96.449388)
		(end 63.59398 -85.30082)
		(width 0.10668)
		(layer "In4.Cu")
		(net "ESPI_HOST_LPC_BMC_LFRAME_N_R")
	)
	(segment
		(start 63.97498 -103.076248)
		(end 63.97498 -101.21138)
		(width 0.10668)
		(layer "In4.Cu")
		(net "ESPI_HOST_LPC_BMC_LFRAME_N_R")
	)
	(segment
		(start 64.3382 -82.943446)
		(end 64.518286 -82.76336)
		(width 0.10668)
		(layer "In4.Cu")
		(net "ESPI_HOST_LPC_BMC_LFRAME_N_R")
	)
	(segment
		(start 64.8462 -84.0486)
		(end 64.8462 -83.558126)
		(width 0.10668)
		(layer "In4.Cu")
		(net "ESPI_HOST_LPC_BMC_LFRAME_N_R")
	)
	(segment
		(start 64.518286 -82.76336)
		(end 64.81064 -82.76336)
		(width 0.10668)
		(layer "In4.Cu")
		(net "ESPI_HOST_LPC_BMC_LFRAME_N_R")
	)
	(segment
		(start 64.30264 -103.403908)
		(end 63.97498 -103.076248)
		(width 0.10668)
		(layer "In4.Cu")
		(net "ESPI_HOST_LPC_BMC_LFRAME_N_R")
	)
	(segment
		(start 64.999108 -82.574892)
		(end 64.999108 -81.960212)
		(width 0.10668)
		(layer "In4.Cu")
		(net "ESPI_HOST_LPC_BMC_LFRAME_N_R")
	)
	(segment
		(start 64.81064 -82.76336)
		(end 64.999108 -82.574892)
		(width 0.10668)
		(layer "In4.Cu")
		(net "ESPI_HOST_LPC_BMC_LFRAME_N_R")
	)
	(segment
		(start 64.89446 -81.855564)
		(end 64.89446 -77.042772)
		(width 0.10668)
		(layer "In4.Cu")
		(net "ESPI_HOST_LPC_BMC_LFRAME_N_R")
	)
	(segment
		(start 64.0969 -104.8639)
		(end 64.30264 -104.65816)
		(width 0.10668)
		(layer "In4.Cu")
		(net "ESPI_HOST_LPC_BMC_LFRAME_N_R")
	)
	(segment
		(start 64.518286 -83.37804)
		(end 64.3382 -83.197954)
		(width 0.10668)
		(layer "In4.Cu")
		(net "ESPI_HOST_LPC_BMC_LFRAME_N_R")
	)
	(segment
		(start 62.5602 -97.483168)
		(end 63.59398 -96.449388)
		(width 0.10668)
		(layer "In4.Cu")
		(net "ESPI_HOST_LPC_BMC_LFRAME_N_R")
	)
	(segment
		(start 64.8462 -83.558126)
		(end 64.666114 -83.37804)
		(width 0.10668)
		(layer "In4.Cu")
		(net "ESPI_HOST_LPC_BMC_LFRAME_N_R")
	)
	(segment
		(start 64.89446 -77.042772)
		(end 64.60617 -76.346558)
		(width 0.10668)
		(layer "In4.Cu")
		(net "ESPI_HOST_LPC_BMC_LFRAME_N_R")
	)
	(segment
		(start 63.97498 -101.21138)
		(end 62.5602 -99.7966)
		(width 0.10668)
		(layer "In4.Cu")
		(net "ESPI_HOST_LPC_BMC_LFRAME_N_R")
	)
	(segment
		(start 64.30264 -104.65816)
		(end 64.30264 -103.403908)
		(width 0.10668)
		(layer "In4.Cu")
		(net "ESPI_HOST_LPC_BMC_LFRAME_N_R")
	)
	(segment
		(start 66.5226 -106.438192)
		(end 66.136774 -105.506774)
		(width 0.11684)
		(layer "F.Cu")
		(net "ESPI_HOST_LPC_BMC_CLK_R")
	)
	(segment
		(start 63.3984 -77.6224)
		(end 68.386198 -77.6224)
		(width 0.11684)
		(layer "F.Cu")
		(net "ESPI_HOST_LPC_BMC_CLK_R")
	)
	(segment
		(start 71.394574 -71.489062)
		(end 71.394574 -70.530974)
		(width 0.11684)
		(layer "F.Cu")
		(net "ESPI_HOST_LPC_BMC_CLK_R")
	)
	(segment
		(start 70.130416 -72.75322)
		(end 71.394574 -71.489062)
		(width 0.11684)
		(layer "F.Cu")
		(net "ESPI_HOST_LPC_BMC_CLK_R")
	)
	(segment
		(start 63.2206 -77.4446)
		(end 63.3984 -77.6224)
		(width 0.11684)
		(layer "F.Cu")
		(net "ESPI_HOST_LPC_BMC_CLK_R")
	)
	(segment
		(start 66.5226 -107.60075)
		(end 66.5226 -106.438192)
		(width 0.11684)
		(layer "F.Cu")
		(net "ESPI_HOST_LPC_BMC_CLK_R")
	)
	(segment
		(start 63.7921 -60.8203)
		(end 63.3222 -60.3504)
		(width 0.11684)
		(layer "F.Cu")
		(net "ESPI_HOST_LPC_BMC_CLK_R")
	)
	(segment
		(start 67.8942 -63.754)
		(end 67.8942 -63.0428)
		(width 0.11684)
		(layer "F.Cu")
		(net "ESPI_HOST_LPC_BMC_CLK_R")
	)
	(segment
		(start 70.130416 -76.046584)
		(end 70.130416 -72.75322)
		(width 0.11684)
		(layer "F.Cu")
		(net "ESPI_HOST_LPC_BMC_CLK_R")
	)
	(segment
		(start 70.6374 -66.4972)
		(end 67.8942 -63.754)
		(width 0.11684)
		(layer "F.Cu")
		(net "ESPI_HOST_LPC_BMC_CLK_R")
	)
	(segment
		(start 67.8942 -63.0428)
		(end 65.6717 -60.8203)
		(width 0.11684)
		(layer "F.Cu")
		(net "ESPI_HOST_LPC_BMC_CLK_R")
	)
	(segment
		(start 70.6374 -69.7738)
		(end 70.6374 -66.4972)
		(width 0.11684)
		(layer "F.Cu")
		(net "ESPI_HOST_LPC_BMC_CLK_R")
	)
	(segment
		(start 64.08039 -103.45039)
		(end 61.272674 -103.45039)
		(width 0.11684)
		(layer "F.Cu")
		(net "ESPI_HOST_LPC_BMC_CLK_R")
	)
	(segment
		(start 65.6717 -60.8203)
		(end 63.7921 -60.8203)
		(width 0.11684)
		(layer "F.Cu")
		(net "ESPI_HOST_LPC_BMC_CLK_R")
	)
	(segment
		(start 66.136774 -105.506774)
		(end 64.08039 -103.45039)
		(width 0.11684)
		(layer "F.Cu")
		(net "ESPI_HOST_LPC_BMC_CLK_R")
	)
	(segment
		(start 68.673726 -77.503274)
		(end 70.130416 -76.046584)
		(width 0.11684)
		(layer "F.Cu")
		(net "ESPI_HOST_LPC_BMC_CLK_R")
	)
	(segment
		(start 60.094876 -58.57113)
		(end 59.699652 -58.175906)
		(width 0.11684)
		(layer "F.Cu")
		(net "ESPI_HOST_LPC_BMC_CLK_R")
	)
	(segment
		(start 68.386198 -77.6224)
		(end 68.673726 -77.503274)
		(width 0.11684)
		(layer "F.Cu")
		(net "ESPI_HOST_LPC_BMC_CLK_R")
	)
	(segment
		(start 71.394574 -70.530974)
		(end 70.6374 -69.7738)
		(width 0.11684)
		(layer "F.Cu")
		(net "ESPI_HOST_LPC_BMC_CLK_R")
	)
	(via
		(at 59.699652 -58.175906)
		(size 0.4572)
		(drill 0.254)
		(layers "F.Cu" "B.Cu")
		(net "ESPI_HOST_LPC_BMC_CLK_R")
	)
	(via
		(at 63.2206 -77.4446)
		(size 0.508)
		(drill 0.254)
		(layers "F.Cu" "B.Cu")
		(net "ESPI_HOST_LPC_BMC_CLK_R")
	)
	(via
		(at 63.3222 -60.3504)
		(size 0.508)
		(drill 0.254)
		(layers "F.Cu" "B.Cu")
		(net "ESPI_HOST_LPC_BMC_CLK_R")
	)
	(via
		(at 61.272674 -103.45039)
		(size 0.762)
		(drill 0.254)
		(layers "F.Cu" "B.Cu")
		(net "ESPI_HOST_LPC_BMC_CLK_R")
	)
	(segment
		(start 61.2902 -93.429074)
		(end 61.2902 -96.37522)
		(width 0.10668)
		(layer "In4.Cu")
		(net "ESPI_HOST_LPC_BMC_CLK_R")
	)
	(segment
		(start 61.5696 -84.594954)
		(end 61.5696 -92.754196)
		(width 0.10668)
		(layer "In4.Cu")
		(net "ESPI_HOST_LPC_BMC_CLK_R")
	)
	(segment
		(start 59.63666 -99.77882)
		(end 59.63666 -100.38334)
		(width 0.10668)
		(layer "In4.Cu")
		(net "ESPI_HOST_LPC_BMC_CLK_R")
	)
	(segment
		(start 62.0268 -81.026)
		(end 60.85586 -82.19694)
		(width 0.10668)
		(layer "In4.Cu")
		(net "ESPI_HOST_LPC_BMC_CLK_R")
	)
	(segment
		(start 61.2902 -96.37522)
		(end 61.07938 -96.58604)
		(width 0.10668)
		(layer "In4.Cu")
		(net "ESPI_HOST_LPC_BMC_CLK_R")
	)
	(segment
		(start 61.158628 -84.183982)
		(end 61.5696 -84.594954)
		(width 0.10668)
		(layer "In4.Cu")
		(net "ESPI_HOST_LPC_BMC_CLK_R")
	)
	(segment
		(start 61.5696 -92.754196)
		(end 61.2902 -93.429074)
		(width 0.10668)
		(layer "In4.Cu")
		(net "ESPI_HOST_LPC_BMC_CLK_R")
	)
	(segment
		(start 60.85586 -82.19694)
		(end 60.85586 -83.5279)
		(width 0.10668)
		(layer "In4.Cu")
		(net "ESPI_HOST_LPC_BMC_CLK_R")
	)
	(segment
		(start 63.2206 -77.4446)
		(end 63.2206 -78.53426)
		(width 0.10668)
		(layer "In4.Cu")
		(net "ESPI_HOST_LPC_BMC_CLK_R")
	)
	(segment
		(start 59.9186 -101.06406)
		(end 60.232036 -101.377496)
		(width 0.10668)
		(layer "In4.Cu")
		(net "ESPI_HOST_LPC_BMC_CLK_R")
	)
	(segment
		(start 60.85586 -83.5279)
		(end 61.158628 -83.830668)
		(width 0.10668)
		(layer "In4.Cu")
		(net "ESPI_HOST_LPC_BMC_CLK_R")
	)
	(segment
		(start 59.63666 -100.38334)
		(end 59.9186 -101.06406)
		(width 0.10668)
		(layer "In4.Cu")
		(net "ESPI_HOST_LPC_BMC_CLK_R")
	)
	(segment
		(start 61.158628 -83.830668)
		(end 61.158628 -84.183982)
		(width 0.10668)
		(layer "In4.Cu")
		(net "ESPI_HOST_LPC_BMC_CLK_R")
	)
	(segment
		(start 62.0268 -79.72806)
		(end 62.0268 -81.026)
		(width 0.10668)
		(layer "In4.Cu")
		(net "ESPI_HOST_LPC_BMC_CLK_R")
	)
	(segment
		(start 61.07938 -96.58604)
		(end 61.07938 -98.3361)
		(width 0.10668)
		(layer "In4.Cu")
		(net "ESPI_HOST_LPC_BMC_CLK_R")
	)
	(segment
		(start 60.962032 -103.140002)
		(end 61.272674 -103.45039)
		(width 0.10668)
		(layer "In4.Cu")
		(net "ESPI_HOST_LPC_BMC_CLK_R")
	)
	(segment
		(start 61.07938 -98.3361)
		(end 59.63666 -99.77882)
		(width 0.10668)
		(layer "In4.Cu")
		(net "ESPI_HOST_LPC_BMC_CLK_R")
	)
	(segment
		(start 63.2206 -78.53426)
		(end 62.0268 -79.72806)
		(width 0.10668)
		(layer "In4.Cu")
		(net "ESPI_HOST_LPC_BMC_CLK_R")
	)
	(segment
		(start 60.232036 -101.377496)
		(end 60.962032 -103.140002)
		(width 0.10668)
		(layer "In4.Cu")
		(net "ESPI_HOST_LPC_BMC_CLK_R")
	)
	(segment
		(start 61.837062 -59.449462)
		(end 62.135258 -59.449462)
		(width 0.08382)
		(layer "In9.Cu")
		(net "ESPI_HOST_LPC_BMC_CLK_R")
	)
	(segment
		(start 60.0964 -57.0484)
		(end 60.19673 -56.94807)
		(width 0.08382)
		(layer "In9.Cu")
		(net "ESPI_HOST_LPC_BMC_CLK_R")
	)
	(segment
		(start 61.6966 -57.0992)
		(end 61.6966 -59.309)
		(width 0.08382)
		(layer "In9.Cu")
		(net "ESPI_HOST_LPC_BMC_CLK_R")
	)
	(segment
		(start 60.19673 -56.94807)
		(end 61.54547 -56.94807)
		(width 0.08382)
		(layer "In9.Cu")
		(net "ESPI_HOST_LPC_BMC_CLK_R")
	)
	(segment
		(start 62.135258 -59.449462)
		(end 63.036196 -60.3504)
		(width 0.08382)
		(layer "In9.Cu")
		(net "ESPI_HOST_LPC_BMC_CLK_R")
	)
	(segment
		(start 59.699652 -58.175906)
		(end 60.0964 -57.779158)
		(width 0.08382)
		(layer "In9.Cu")
		(net "ESPI_HOST_LPC_BMC_CLK_R")
	)
	(segment
		(start 61.6966 -59.309)
		(end 61.837062 -59.449462)
		(width 0.08382)
		(layer "In9.Cu")
		(net "ESPI_HOST_LPC_BMC_CLK_R")
	)
	(segment
		(start 60.0964 -57.779158)
		(end 60.0964 -57.0484)
		(width 0.08382)
		(layer "In9.Cu")
		(net "ESPI_HOST_LPC_BMC_CLK_R")
	)
	(segment
		(start 61.54547 -56.94807)
		(end 61.6966 -57.0992)
		(width 0.08382)
		(layer "In9.Cu")
		(net "ESPI_HOST_LPC_BMC_CLK_R")
	)
	(segment
		(start 63.036196 -60.3504)
		(end 63.3222 -60.3504)
		(width 0.08382)
		(layer "In9.Cu")
		(net "ESPI_HOST_LPC_BMC_CLK_R")
	)
	(segment
		(start 21.463 -15.24)
		(end 21.770086 -14.932914)
		(width 0.11684)
		(layer "B.Cu")
		(net "SMB_BMC_ALERT16_R_N")
	)
	(segment
		(start 21.770086 -14.932914)
		(end 21.770086 -13.269976)
		(width 0.11684)
		(layer "B.Cu")
		(net "SMB_BMC_ALERT16_R_N")
	)
	(segment
		(start 21.463 -15.93596)
		(end 21.463 -15.24)
		(width 0.11684)
		(layer "B.Cu")
		(net "SMB_BMC_ALERT16_R_N")
	)
	(segment
		(start 20.955 -16.44396)
		(end 21.463 -15.93596)
		(width 0.11684)
		(layer "B.Cu")
		(net "SMB_BMC_ALERT16_R_N")
	)
	(segment
		(start 20.955 -17.50695)
		(end 20.955 -16.44396)
		(width 0.11684)
		(layer "B.Cu")
		(net "SMB_BMC_ALERT16_R_N")
	)
	(via
		(at 26.853388 -15.169388)
		(size 0.6604)
		(drill 0.3302)
		(layers "F.Cu" "B.Cu")
		(net "TMC75_A2")
	)
	(segment
		(start 25.235916 -18.650966)
		(end 25.019 -18.43405)
		(width 0.11684)
		(layer "B.Cu")
		(net "TMC75_A2")
	)
	(segment
		(start 26.853388 -15.169388)
		(end 27.405584 -15.721584)
		(width 0.11684)
		(layer "B.Cu")
		(net "TMC75_A2")
	)
	(segment
		(start 25.77465 -18.650966)
		(end 25.235916 -18.650966)
		(width 0.11684)
		(layer "B.Cu")
		(net "TMC75_A2")
	)
	(segment
		(start 25.3746 -11.821668)
		(end 25.3746 -14.099794)
		(width 0.11684)
		(layer "B.Cu")
		(net "TMC75_A2")
	)
	(segment
		(start 27.405584 -15.721584)
		(end 27.405584 -17.020032)
		(width 0.11684)
		(layer "B.Cu")
		(net "TMC75_A2")
	)
	(segment
		(start 26.416 -14.732)
		(end 26.853388 -15.169388)
		(width 0.11684)
		(layer "B.Cu")
		(net "TMC75_A2")
	)
	(segment
		(start 25.019 -18.43405)
		(end 24.003 -18.43405)
		(width 0.11684)
		(layer "B.Cu")
		(net "TMC75_A2")
	)
	(segment
		(start 24.310086 -10.757154)
		(end 25.3746 -11.821668)
		(width 0.11684)
		(layer "B.Cu")
		(net "TMC75_A2")
	)
	(segment
		(start 24.310086 -10.729976)
		(end 24.310086 -10.757154)
		(width 0.11684)
		(layer "B.Cu")
		(net "TMC75_A2")
	)
	(segment
		(start 25.3746 -14.099794)
		(end 26.006806 -14.732)
		(width 0.11684)
		(layer "B.Cu")
		(net "TMC75_A2")
	)
	(segment
		(start 27.405584 -17.020032)
		(end 25.77465 -18.650966)
		(width 0.11684)
		(layer "B.Cu")
		(net "TMC75_A2")
	)
	(segment
		(start 26.006806 -14.732)
		(end 26.416 -14.732)
		(width 0.11684)
		(layer "B.Cu")
		(net "TMC75_A2")
	)
	(segment
		(start 19.431 -18.30705)
		(end 20.046696 -18.922746)
		(width 0.11684)
		(layer "B.Cu")
		(net "TMC75_A1")
	)
	(segment
		(start 20.483322 -14.422628)
		(end 18.936208 -15.969742)
		(width 0.11684)
		(layer "B.Cu")
		(net "TMC75_A1")
	)
	(segment
		(start 21.770086 -10.729976)
		(end 20.483322 -12.01674)
		(width 0.11684)
		(layer "B.Cu")
		(net "TMC75_A1")
	)
	(segment
		(start 18.936208 -18.007838)
		(end 19.23542 -18.30705)
		(width 0.11684)
		(layer "B.Cu")
		(net "TMC75_A1")
	)
	(segment
		(start 18.936208 -15.969742)
		(end 18.936208 -18.007838)
		(width 0.11684)
		(layer "B.Cu")
		(net "TMC75_A1")
	)
	(segment
		(start 20.567904 -19.304)
		(end 20.59305 -19.304)
		(width 0.11684)
		(layer "B.Cu")
		(net "TMC75_A1")
	)
	(segment
		(start 20.483322 -12.01674)
		(end 20.483322 -14.422628)
		(width 0.11684)
		(layer "B.Cu")
		(net "TMC75_A1")
	)
	(segment
		(start 20.046696 -18.922746)
		(end 20.18665 -18.922746)
		(width 0.11684)
		(layer "B.Cu")
		(net "TMC75_A1")
	)
	(segment
		(start 19.23542 -18.30705)
		(end 19.431 -18.30705)
		(width 0.11684)
		(layer "B.Cu")
		(net "TMC75_A1")
	)
	(segment
		(start 20.18665 -18.922746)
		(end 20.567904 -19.304)
		(width 0.11684)
		(layer "B.Cu")
		(net "TMC75_A1")
	)
	(segment
		(start 17.399 -18.30705)
		(end 18.30705 -19.2151)
		(width 0.11684)
		(layer "B.Cu")
		(net "TMC75_A0")
	)
	(segment
		(start 18.30705 -19.2151)
		(end 18.30705 -19.431)
		(width 0.11684)
		(layer "B.Cu")
		(net "TMC75_A0")
	)
	(segment
		(start 17.907 -12.573)
		(end 19.230086 -11.249914)
		(width 0.11684)
		(layer "B.Cu")
		(net "TMC75_A0")
	)
	(segment
		(start 17.907 -13.97)
		(end 17.907 -12.573)
		(width 0.11684)
		(layer "B.Cu")
		(net "TMC75_A0")
	)
	(segment
		(start 16.903446 -17.811496)
		(end 16.903446 -14.973554)
		(width 0.11684)
		(layer "B.Cu")
		(net "TMC75_A0")
	)
	(segment
		(start 17.399 -18.30705)
		(end 16.903446 -17.811496)
		(width 0.11684)
		(layer "B.Cu")
		(net "TMC75_A0")
	)
	(segment
		(start 16.903446 -14.973554)
		(end 17.907 -13.97)
		(width 0.11684)
		(layer "B.Cu")
		(net "TMC75_A0")
	)
	(segment
		(start 19.230086 -11.249914)
		(end 19.230086 -10.729976)
		(width 0.11684)
		(layer "B.Cu")
		(net "TMC75_A0")
	)
	(segment
		(start 25.45461 -90.391742)
		(end 25.059386 -90.786966)
		(width 0.381)
		(layer "F.Cu")
		(net "VCCIO5")
	)
	(via
		(at 25.45461 -90.391742)
		(size 0.4572)
		(drill 0.254)
		(layers "F.Cu" "B.Cu")
		(net "VCCIO5")
	)
	(segment
		(start 25.859232 -89.98712)
		(end 25.859486 -89.98712)
		(width 0.254)
		(layer "B.Cu")
		(net "VCCIO5")
	)
	(segment
		(start 26.26995 -90.805)
		(end 25.867868 -90.805)
		(width 0.254)
		(layer "B.Cu")
		(net "VCCIO5")
	)
	(segment
		(start 25.45461 -90.391742)
		(end 25.859232 -89.98712)
		(width 0.254)
		(layer "B.Cu")
		(net "VCCIO5")
	)
	(segment
		(start 26.26995 -91.5289)
		(end 26.26995 -90.805)
		(width 0.254)
		(layer "B.Cu")
		(net "VCCIO5")
	)
	(segment
		(start 25.867868 -90.805)
		(end 25.45461 -90.391742)
		(width 0.254)
		(layer "B.Cu")
		(net "VCCIO5")
	)
	(segment
		(start 26.416 -91.67495)
		(end 26.26995 -91.5289)
		(width 0.254)
		(layer "B.Cu")
		(net "VCCIO5")
	)
	(segment
		(start 23.054564 -92.791788)
		(end 22.65934 -93.187012)
		(width 0.381)
		(layer "F.Cu")
		(net "VCCIO4")
	)
	(segment
		(start 23.054564 -94.382336)
		(end 22.65934 -93.987112)
		(width 0.381)
		(layer "F.Cu")
		(net "VCCIO4")
	)
	(via
		(at 23.054564 -92.791788)
		(size 0.4572)
		(drill 0.254)
		(layers "F.Cu" "B.Cu")
		(net "VCCIO4")
	)
	(via
		(at 23.054564 -94.382336)
		(size 0.4572)
		(drill 0.254)
		(layers "F.Cu" "B.Cu")
		(net "VCCIO4")
	)
	(segment
		(start 25.45461 -96.782382)
		(end 25.059386 -96.387158)
		(width 0.381)
		(layer "F.Cu")
		(net "VCCIO3")
	)
	(via
		(at 26.8986 -95.7326)
		(size 0.6604)
		(drill 0.3302)
		(layers "F.Cu" "B.Cu")
		(net "VCCIO3")
	)
	(via
		(at 25.45461 -96.782382)
		(size 0.4572)
		(drill 0.254)
		(layers "F.Cu" "B.Cu")
		(net "VCCIO3")
	)
	(segment
		(start 19.05 -103.14305)
		(end 18.789904 -103.403146)
		(width 0.3556)
		(layer "F.Cu")
		(net "VCCIO2")
	)
	(segment
		(start 19.431 -83.32597)
		(end 19.431 -82.677)
		(width 0.381)
		(layer "F.Cu")
		(net "VCCIO2")
	)
	(segment
		(start 24.654764 -97.582228)
		(end 24.25954 -97.187004)
		(width 0.3556)
		(layer "F.Cu")
		(net "VCCIO2")
	)
	(segment
		(start 18.264124 -97.582228)
		(end 18.659348 -97.187004)
		(width 0.381)
		(layer "F.Cu")
		(net "VCCIO2")
	)
	(segment
		(start 20.66417 -95.182182)
		(end 21.059394 -94.786958)
		(width 0.381)
		(layer "F.Cu")
		(net "VCCIO2")
	)
	(segment
		(start 22.254718 -95.182182)
		(end 21.859494 -94.786958)
		(width 0.381)
		(layer "F.Cu")
		(net "VCCIO2")
	)
	(segment
		(start 18.789904 -103.403146)
		(end 18.789904 -103.80091)
		(width 0.3556)
		(layer "F.Cu")
		(net "VCCIO2")
	)
	(via
		(at 22.254718 -95.182182)
		(size 0.4572)
		(drill 0.254)
		(layers "F.Cu" "B.Cu")
		(net "VCCIO2")
	)
	(via
		(at 19.431 -82.677)
		(size 0.508)
		(drill 0.254)
		(layers "F.Cu" "B.Cu")
		(net "VCCIO2")
	)
	(via
		(at 20.66417 -95.182182)
		(size 0.4572)
		(drill 0.254)
		(layers "F.Cu" "B.Cu")
		(net "VCCIO2")
	)
	(via
		(at 18.264124 -97.582228)
		(size 0.4572)
		(drill 0.254)
		(layers "F.Cu" "B.Cu")
		(net "VCCIO2")
	)
	(via
		(at 18.789904 -103.80091)
		(size 0.508)
		(drill 0.254)
		(layers "F.Cu" "B.Cu")
		(net "VCCIO2")
	)
	(via
		(at 24.654764 -97.582228)
		(size 0.4572)
		(drill 0.254)
		(layers "F.Cu" "B.Cu")
		(net "VCCIO2")
	)
	(segment
		(start 22.254718 -95.296482)
		(end 22.254718 -95.254318)
		(width 0.254)
		(layer "B.Cu")
		(net "VCCIO2")
	)
	(segment
		(start 22.65934 -95.587058)
		(end 22.587458 -95.587058)
		(width 0.254)
		(layer "B.Cu")
		(net "VCCIO2")
	)
	(segment
		(start 24.96185 -97.18675)
		(end 25.060656 -97.18675)
		(width 0.254)
		(layer "B.Cu")
		(net "VCCIO2")
	)
	(segment
		(start 18.664428 -97.187004)
		(end 18.659348 -97.187004)
		(width 0.254)
		(layer "B.Cu")
		(net "VCCIO2")
	)
	(segment
		(start 20.66417 -95.333058)
		(end 20.91817 -95.587058)
		(width 0.254)
		(layer "B.Cu")
		(net "VCCIO2")
	)
	(segment
		(start 22.587458 -95.587058)
		(end 22.254718 -95.254318)
		(width 0.254)
		(layer "B.Cu")
		(net "VCCIO2")
	)
	(segment
		(start 21.964142 -95.587058)
		(end 22.254718 -95.296482)
		(width 0.254)
		(layer "B.Cu")
		(net "VCCIO2")
	)
	(segment
		(start 20.66417 -95.182182)
		(end 20.66417 -95.333058)
		(width 0.254)
		(layer "B.Cu")
		(net "VCCIO2")
	)
	(segment
		(start 18.960846 -98.27895)
		(end 19.05 -98.27895)
		(width 0.254)
		(layer "B.Cu")
		(net "VCCIO2")
	)
	(segment
		(start 18.264124 -97.582228)
		(end 18.960846 -98.27895)
		(width 0.254)
		(layer "B.Cu")
		(net "VCCIO2")
	)
	(segment
		(start 21.859494 -95.587058)
		(end 21.964142 -95.587058)
		(width 0.254)
		(layer "B.Cu")
		(net "VCCIO2")
	)
	(segment
		(start 24.654764 -97.493836)
		(end 24.96185 -97.18675)
		(width 0.254)
		(layer "B.Cu")
		(net "VCCIO2")
	)
	(segment
		(start 20.91817 -95.587058)
		(end 21.059394 -95.587058)
		(width 0.254)
		(layer "B.Cu")
		(net "VCCIO2")
	)
	(segment
		(start 24.25954 -97.187004)
		(end 24.654764 -97.582228)
		(width 0.254)
		(layer "B.Cu")
		(net "VCCIO2")
	)
	(segment
		(start 18.659348 -97.187004)
		(end 18.264124 -97.582228)
		(width 0.254)
		(layer "B.Cu")
		(net "VCCIO2")
	)
	(segment
		(start 22.254718 -95.254318)
		(end 22.254718 -95.182182)
		(width 0.254)
		(layer "B.Cu")
		(net "VCCIO2")
	)
	(segment
		(start 24.654764 -97.582228)
		(end 24.654764 -97.493836)
		(width 0.254)
		(layer "B.Cu")
		(net "VCCIO2")
	)
	(segment
		(start 21.059394 -95.587058)
		(end 21.859494 -95.587058)
		(width 0.254)
		(layer "B.Cu")
		(net "VCCIO2")
	)
	(segment
		(start 17.464278 -90.391742)
		(end 17.859502 -90.786966)
		(width 0.381)
		(layer "F.Cu")
		(net "VCCIO1")
	)
	(segment
		(start 19.864324 -94.382336)
		(end 20.259548 -93.987112)
		(width 0.381)
		(layer "F.Cu")
		(net "VCCIO1")
	)
	(segment
		(start 18.254726 -96.782382)
		(end 17.859502 -96.387158)
		(width 0.381)
		(layer "F.Cu")
		(net "VCCIO1")
	)
	(segment
		(start 20.259548 -93.187012)
		(end 19.864324 -92.791788)
		(width 0.3556)
		(layer "F.Cu")
		(net "VCCIO1")
	)
	(via
		(at 16.51 -95.885)
		(size 0.6604)
		(drill 0.3302)
		(layers "F.Cu" "B.Cu")
		(net "VCCIO1")
	)
	(via
		(at 19.864324 -94.382336)
		(size 0.4572)
		(drill 0.254)
		(layers "F.Cu" "B.Cu")
		(net "VCCIO1")
	)
	(via
		(at 18.254726 -96.782382)
		(size 0.4572)
		(drill 0.254)
		(layers "F.Cu" "B.Cu")
		(net "VCCIO1")
	)
	(via
		(at 17.464278 -90.391742)
		(size 0.4572)
		(drill 0.254)
		(layers "F.Cu" "B.Cu")
		(net "VCCIO1")
	)
	(via
		(at 19.864324 -92.791788)
		(size 0.4572)
		(drill 0.254)
		(layers "F.Cu" "B.Cu")
		(net "VCCIO1")
	)
	(via
		(at 18.264124 -98.382328)
		(size 0.4572)
		(drill 0.254)
		(layers "F.Cu" "B.Cu")
		(net "VCCIO1")
	)
	(segment
		(start 18.264124 -98.382328)
		(end 18.160746 -98.27895)
		(width 0.3556)
		(layer "B.Cu")
		(net "VCCIO1")
	)
	(segment
		(start 19.864324 -94.382336)
		(end 19.757136 -94.382336)
		(width 0.254)
		(layer "B.Cu")
		(net "VCCIO1")
	)
	(segment
		(start 19.864324 -92.791788)
		(end 19.864324 -92.711524)
		(width 0.254)
		(layer "B.Cu")
		(net "VCCIO1")
	)
	(segment
		(start 19.864324 -92.711524)
		(end 19.539966 -92.387166)
		(width 0.254)
		(layer "B.Cu")
		(net "VCCIO1")
	)
	(segment
		(start 17.464278 -90.391742)
		(end 17.859502 -90.786966)
		(width 0.254)
		(layer "B.Cu")
		(net "VCCIO1")
	)
	(segment
		(start 18.160746 -98.27895)
		(end 17.526 -98.27895)
		(width 0.3556)
		(layer "B.Cu")
		(net "VCCIO1")
	)
	(segment
		(start 19.757136 -94.382336)
		(end 19.453606 -94.078806)
		(width 0.254)
		(layer "B.Cu")
		(net "VCCIO1")
	)
	(segment
		(start 19.453606 -94.078806)
		(end 19.453606 -93.98)
		(width 0.254)
		(layer "B.Cu")
		(net "VCCIO1")
	)
	(segment
		(start 19.539966 -92.387166)
		(end 19.459448 -92.387166)
		(width 0.254)
		(layer "B.Cu")
		(net "VCCIO1")
	)
	(segment
		(start 18.264124 -89.591896)
		(end 18.659348 -89.98712)
		(width 0.381)
		(layer "F.Cu")
		(net "VCCIO0")
	)
	(segment
		(start 24.654764 -89.591896)
		(end 24.25954 -89.98712)
		(width 0.381)
		(layer "F.Cu")
		(net "VCCIO0")
	)
	(segment
		(start 22.254718 -91.991942)
		(end 21.859494 -92.387166)
		(width 0.381)
		(layer "F.Cu")
		(net "VCCIO0")
	)
	(segment
		(start 20.66417 -91.991942)
		(end 21.059394 -92.387166)
		(width 0.381)
		(layer "F.Cu")
		(net "VCCIO0")
	)
	(via
		(at 20.66417 -91.991942)
		(size 0.4572)
		(drill 0.254)
		(layers "F.Cu" "B.Cu")
		(net "VCCIO0")
	)
	(via
		(at 24.654764 -89.591896)
		(size 0.4572)
		(drill 0.254)
		(layers "F.Cu" "B.Cu")
		(net "VCCIO0")
	)
	(via
		(at 18.264124 -89.591896)
		(size 0.4572)
		(drill 0.254)
		(layers "F.Cu" "B.Cu")
		(net "VCCIO0")
	)
	(via
		(at 22.254718 -91.991942)
		(size 0.4572)
		(drill 0.254)
		(layers "F.Cu" "B.Cu")
		(net "VCCIO0")
	)
	(segment
		(start 18.192496 -89.591896)
		(end 18.264124 -89.591896)
		(width 0.254)
		(layer "B.Cu")
		(net "VCCIO0")
	)
	(segment
		(start 17.859248 -89.18702)
		(end 17.859248 -89.258648)
		(width 0.254)
		(layer "B.Cu")
		(net "VCCIO0")
	)
	(segment
		(start 20.66417 -91.991942)
		(end 20.702778 -92.03055)
		(width 0.254)
		(layer "B.Cu")
		(net "VCCIO0")
	)
	(segment
		(start 18.180304 -89.591896)
		(end 18.192496 -89.591896)
		(width 0.254)
		(layer "B.Cu")
		(net "VCCIO0")
	)
	(segment
		(start 17.859502 -89.912698)
		(end 18.180304 -89.591896)
		(width 0.254)
		(layer "B.Cu")
		(net "VCCIO0")
	)
	(segment
		(start 22.65934 -91.58732)
		(end 22.65934 -91.587066)
		(width 0.254)
		(layer "B.Cu")
		(net "VCCIO0")
	)
	(segment
		(start 24.654764 -89.591896)
		(end 25.059386 -89.187274)
		(width 0.254)
		(layer "B.Cu")
		(net "VCCIO0")
	)
	(segment
		(start 20.702778 -92.03055)
		(end 21.301456 -92.03055)
		(width 0.254)
		(layer "B.Cu")
		(net "VCCIO0")
	)
	(segment
		(start 17.859502 -89.98712)
		(end 17.859502 -89.912698)
		(width 0.254)
		(layer "B.Cu")
		(net "VCCIO0")
	)
	(segment
		(start 22.254718 -91.991942)
		(end 22.65934 -91.58732)
		(width 0.254)
		(layer "B.Cu")
		(net "VCCIO0")
	)
	(segment
		(start 25.059386 -89.187274)
		(end 25.059386 -89.18702)
		(width 0.254)
		(layer "B.Cu")
		(net "VCCIO0")
	)
	(segment
		(start 17.859248 -89.258648)
		(end 18.192496 -89.591896)
		(width 0.254)
		(layer "B.Cu")
		(net "VCCIO0")
	)
	(segment
		(start 73.25995 -116.952522)
		(end 73.25995 -118.460012)
		(width 0.11684)
		(layer "F.Cu")
		(net "UART_BIC_GF_TXD")
	)
	(segment
		(start 73.360026 -114.908838)
		(end 73.360026 -116.852446)
		(width 0.11684)
		(layer "F.Cu")
		(net "UART_BIC_GF_TXD")
	)
	(segment
		(start 73.360026 -116.852446)
		(end 73.25995 -116.952522)
		(width 0.11684)
		(layer "F.Cu")
		(net "UART_BIC_GF_TXD")
	)
	(segment
		(start 73.760838 -114.508026)
		(end 73.360026 -114.908838)
		(width 0.11684)
		(layer "F.Cu")
		(net "UART_BIC_GF_TXD")
	)
	(segment
		(start 16.728186 -63.591186)
		(end 17.4752 -64.3382)
		(width 0.11684)
		(layer "F.Cu")
		(net "UART_BIC_GF_TXD")
	)
	(segment
		(start 16.728186 -63.306198)
		(end 16.728186 -63.591186)
		(width 0.11684)
		(layer "F.Cu")
		(net "UART_BIC_GF_TXD")
	)
	(segment
		(start 74.092562 -114.508026)
		(end 73.760838 -114.508026)
		(width 0.11684)
		(layer "F.Cu")
		(net "UART_BIC_GF_TXD")
	)
	(via
		(at 17.4752 -64.3382)
		(size 0.508)
		(drill 0.254)
		(layers "F.Cu" "B.Cu")
		(net "UART_BIC_GF_TXD")
	)
	(via
		(at 74.092562 -114.508026)
		(size 0.508)
		(drill 0.254)
		(layers "F.Cu" "B.Cu")
		(net "UART_BIC_GF_TXD")
	)
	(via
		(at 59.563 -74.549)
		(size 0.762)
		(drill 0.254)
		(layers "F.Cu" "B.Cu")
		(net "UART_BIC_GF_TXD")
	)
	(segment
		(start 50.01768 -63.61049)
		(end 50.261774 -63.711582)
		(width 0.08382)
		(layer "In2.Cu")
		(net "UART_BIC_GF_TXD")
	)
	(segment
		(start 55.242714 -73.39838)
		(end 58.41238 -73.39838)
		(width 0.08382)
		(layer "In2.Cu")
		(net "UART_BIC_GF_TXD")
	)
	(segment
		(start 20.38477 -63.94577)
		(end 22.47646 -66.03746)
		(width 0.08382)
		(layer "In2.Cu")
		(net "UART_BIC_GF_TXD")
	)
	(segment
		(start 37.3126 -61.467746)
		(end 37.3126 -61.8744)
		(width 0.08382)
		(layer "In2.Cu")
		(net "UART_BIC_GF_TXD")
	)
	(segment
		(start 30.269688 -63.21806)
		(end 30.751018 -63.69939)
		(width 0.08382)
		(layer "In2.Cu")
		(net "UART_BIC_GF_TXD")
	)
	(segment
		(start 23.249128 -66.03746)
		(end 23.51151 -65.775078)
		(width 0.08382)
		(layer "In2.Cu")
		(net "UART_BIC_GF_TXD")
	)
	(segment
		(start 50.04308 -65.90538)
		(end 47.67072 -68.27774)
		(width 0.08382)
		(layer "In2.Cu")
		(net "UART_BIC_GF_TXD")
	)
	(segment
		(start 22.47646 -66.03746)
		(end 23.249128 -66.03746)
		(width 0.08382)
		(layer "In2.Cu")
		(net "UART_BIC_GF_TXD")
	)
	(segment
		(start 29.759402 -63.21806)
		(end 30.269688 -63.21806)
		(width 0.08382)
		(layer "In2.Cu")
		(net "UART_BIC_GF_TXD")
	)
	(segment
		(start 38.19398 -62.75578)
		(end 43.22826 -62.75578)
		(width 0.08382)
		(layer "In2.Cu")
		(net "UART_BIC_GF_TXD")
	)
	(segment
		(start 23.51151 -65.775078)
		(end 23.51151 -65.326006)
		(width 0.08382)
		(layer "In2.Cu")
		(net "UART_BIC_GF_TXD")
	)
	(segment
		(start 17.4752 -64.3382)
		(end 17.86763 -63.94577)
		(width 0.08382)
		(layer "In2.Cu")
		(net "UART_BIC_GF_TXD")
	)
	(segment
		(start 29.361892 -63.61557)
		(end 29.759402 -63.21806)
		(width 0.08382)
		(layer "In2.Cu")
		(net "UART_BIC_GF_TXD")
	)
	(segment
		(start 17.86763 -63.94577)
		(end 20.38477 -63.94577)
		(width 0.08382)
		(layer "In2.Cu")
		(net "UART_BIC_GF_TXD")
	)
	(segment
		(start 50.261774 -63.711582)
		(end 51.42484 -64.874648)
		(width 0.08382)
		(layer "In2.Cu")
		(net "UART_BIC_GF_TXD")
	)
	(segment
		(start 28.090114 -63.363856)
		(end 28.341828 -63.61557)
		(width 0.08382)
		(layer "In2.Cu")
		(net "UART_BIC_GF_TXD")
	)
	(segment
		(start 51.42484 -65.62598)
		(end 51.14544 -65.90538)
		(width 0.08382)
		(layer "In2.Cu")
		(net "UART_BIC_GF_TXD")
	)
	(segment
		(start 48.30826 -70.2056)
		(end 52.049934 -70.2056)
		(width 0.08382)
		(layer "In2.Cu")
		(net "UART_BIC_GF_TXD")
	)
	(segment
		(start 43.22826 -62.75578)
		(end 43.55846 -62.42558)
		(width 0.08382)
		(layer "In2.Cu")
		(net "UART_BIC_GF_TXD")
	)
	(segment
		(start 52.049934 -70.2056)
		(end 55.242714 -73.39838)
		(width 0.08382)
		(layer "In2.Cu")
		(net "UART_BIC_GF_TXD")
	)
	(segment
		(start 28.341828 -63.61557)
		(end 29.361892 -63.61557)
		(width 0.08382)
		(layer "In2.Cu")
		(net "UART_BIC_GF_TXD")
	)
	(segment
		(start 47.67072 -68.27774)
		(end 47.67072 -69.56806)
		(width 0.08382)
		(layer "In2.Cu")
		(net "UART_BIC_GF_TXD")
	)
	(segment
		(start 35.148012 -61.274706)
		(end 37.11956 -61.274706)
		(width 0.08382)
		(layer "In2.Cu")
		(net "UART_BIC_GF_TXD")
	)
	(segment
		(start 37.3126 -61.8744)
		(end 38.19398 -62.75578)
		(width 0.08382)
		(layer "In2.Cu")
		(net "UART_BIC_GF_TXD")
	)
	(segment
		(start 23.51151 -65.326006)
		(end 25.47366 -63.363856)
		(width 0.08382)
		(layer "In2.Cu")
		(net "UART_BIC_GF_TXD")
	)
	(segment
		(start 47.44974 -62.42558)
		(end 48.63465 -63.61049)
		(width 0.08382)
		(layer "In2.Cu")
		(net "UART_BIC_GF_TXD")
	)
	(segment
		(start 30.751018 -63.69939)
		(end 32.723328 -63.69939)
		(width 0.08382)
		(layer "In2.Cu")
		(net "UART_BIC_GF_TXD")
	)
	(segment
		(start 58.41238 -73.39838)
		(end 59.563 -74.549)
		(width 0.08382)
		(layer "In2.Cu")
		(net "UART_BIC_GF_TXD")
	)
	(segment
		(start 51.42484 -64.874648)
		(end 51.42484 -65.62598)
		(width 0.08382)
		(layer "In2.Cu")
		(net "UART_BIC_GF_TXD")
	)
	(segment
		(start 37.11956 -61.274706)
		(end 37.3126 -61.467746)
		(width 0.08382)
		(layer "In2.Cu")
		(net "UART_BIC_GF_TXD")
	)
	(segment
		(start 32.723328 -63.69939)
		(end 35.148012 -61.274706)
		(width 0.08382)
		(layer "In2.Cu")
		(net "UART_BIC_GF_TXD")
	)
	(segment
		(start 51.14544 -65.90538)
		(end 50.04308 -65.90538)
		(width 0.08382)
		(layer "In2.Cu")
		(net "UART_BIC_GF_TXD")
	)
	(segment
		(start 25.47366 -63.363856)
		(end 28.090114 -63.363856)
		(width 0.08382)
		(layer "In2.Cu")
		(net "UART_BIC_GF_TXD")
	)
	(segment
		(start 47.67072 -69.56806)
		(end 48.30826 -70.2056)
		(width 0.08382)
		(layer "In2.Cu")
		(net "UART_BIC_GF_TXD")
	)
	(segment
		(start 48.63465 -63.61049)
		(end 50.01768 -63.61049)
		(width 0.08382)
		(layer "In2.Cu")
		(net "UART_BIC_GF_TXD")
	)
	(segment
		(start 43.55846 -62.42558)
		(end 47.44974 -62.42558)
		(width 0.08382)
		(layer "In2.Cu")
		(net "UART_BIC_GF_TXD")
	)
	(segment
		(start 59.563 -74.549)
		(end 59.563 -75.268328)
		(width 0.10668)
		(layer "In7.Cu")
		(net "UART_BIC_GF_TXD")
	)
	(segment
		(start 72.81672 -106.13136)
		(end 72.81672 -111.99495)
		(width 0.10668)
		(layer "In7.Cu")
		(net "UART_BIC_GF_TXD")
	)
	(segment
		(start 63.11138 -81.609438)
		(end 63.11138 -82.395568)
		(width 0.10668)
		(layer "In7.Cu")
		(net "UART_BIC_GF_TXD")
	)
	(segment
		(start 61.1124 -78.240382)
		(end 62.777878 -79.90586)
		(width 0.10668)
		(layer "In7.Cu")
		(net "UART_BIC_GF_TXD")
	)
	(segment
		(start 72.5424 -105.85704)
		(end 72.81672 -106.13136)
		(width 0.10668)
		(layer "In7.Cu")
		(net "UART_BIC_GF_TXD")
	)
	(segment
		(start 61.1124 -76.817728)
		(end 61.1124 -78.240382)
		(width 0.10668)
		(layer "In7.Cu")
		(net "UART_BIC_GF_TXD")
	)
	(segment
		(start 63.432182 -81.288636)
		(end 63.11138 -81.609438)
		(width 0.10668)
		(layer "In7.Cu")
		(net "UART_BIC_GF_TXD")
	)
	(segment
		(start 72.48144 -103.152194)
		(end 72.48144 -104.417876)
		(width 0.10668)
		(layer "In7.Cu")
		(net "UART_BIC_GF_TXD")
	)
	(segment
		(start 69.98462 -100.655374)
		(end 72.48144 -103.152194)
		(width 0.10668)
		(layer "In7.Cu")
		(net "UART_BIC_GF_TXD")
	)
	(segment
		(start 63.281306 -82.805524)
		(end 63.925196 -83.449414)
		(width 0.10668)
		(layer "In7.Cu")
		(net "UART_BIC_GF_TXD")
	)
	(segment
		(start 63.925196 -83.449414)
		(end 63.925196 -89.312242)
		(width 0.10668)
		(layer "In7.Cu")
		(net "UART_BIC_GF_TXD")
	)
	(segment
		(start 72.81672 -111.99495)
		(end 73.572116 -112.750346)
		(width 0.10668)
		(layer "In7.Cu")
		(net "UART_BIC_GF_TXD")
	)
	(segment
		(start 63.219584 -82.657188)
		(end 63.281306 -82.805524)
		(width 0.10668)
		(layer "In7.Cu")
		(net "UART_BIC_GF_TXD")
	)
	(segment
		(start 69.82587 -99.120706)
		(end 69.98462 -99.503992)
		(width 0.10668)
		(layer "In7.Cu")
		(net "UART_BIC_GF_TXD")
	)
	(segment
		(start 68.10502 -97.399856)
		(end 69.82587 -99.120706)
		(width 0.10668)
		(layer "In7.Cu")
		(net "UART_BIC_GF_TXD")
	)
	(segment
		(start 68.10502 -93.492066)
		(end 68.10502 -97.399856)
		(width 0.10668)
		(layer "In7.Cu")
		(net "UART_BIC_GF_TXD")
	)
	(segment
		(start 63.162942 -79.90586)
		(end 63.432182 -80.1751)
		(width 0.10668)
		(layer "In7.Cu")
		(net "UART_BIC_GF_TXD")
	)
	(segment
		(start 72.5424 -104.478836)
		(end 72.5424 -105.85704)
		(width 0.10668)
		(layer "In7.Cu")
		(net "UART_BIC_GF_TXD")
	)
	(segment
		(start 63.432182 -80.1751)
		(end 63.432182 -81.288636)
		(width 0.10668)
		(layer "In7.Cu")
		(net "UART_BIC_GF_TXD")
	)
	(segment
		(start 69.98462 -99.503992)
		(end 69.98462 -100.655374)
		(width 0.10668)
		(layer "In7.Cu")
		(net "UART_BIC_GF_TXD")
	)
	(segment
		(start 73.572116 -113.98758)
		(end 74.092562 -114.508026)
		(width 0.10668)
		(layer "In7.Cu")
		(net "UART_BIC_GF_TXD")
	)
	(segment
		(start 59.563 -75.268328)
		(end 61.1124 -76.817728)
		(width 0.10668)
		(layer "In7.Cu")
		(net "UART_BIC_GF_TXD")
	)
	(segment
		(start 73.572116 -112.750346)
		(end 73.572116 -113.98758)
		(width 0.10668)
		(layer "In7.Cu")
		(net "UART_BIC_GF_TXD")
	)
	(segment
		(start 62.777878 -79.90586)
		(end 63.162942 -79.90586)
		(width 0.10668)
		(layer "In7.Cu")
		(net "UART_BIC_GF_TXD")
	)
	(segment
		(start 63.11138 -82.395568)
		(end 63.219584 -82.657188)
		(width 0.10668)
		(layer "In7.Cu")
		(net "UART_BIC_GF_TXD")
	)
	(segment
		(start 63.925196 -89.312242)
		(end 68.10502 -93.492066)
		(width 0.10668)
		(layer "In7.Cu")
		(net "UART_BIC_GF_TXD")
	)
	(segment
		(start 72.48144 -104.417876)
		(end 72.5424 -104.478836)
		(width 0.10668)
		(layer "In7.Cu")
		(net "UART_BIC_GF_TXD")
	)
	(segment
		(start 23.749 -63.2206)
		(end 23.749 -64.78905)
		(width 0.11684)
		(layer "F.Cu")
		(net "UART_BIC_GF_RXD")
	)
	(segment
		(start 74.072242 -113.727738)
		(end 73.736454 -113.727738)
		(width 0.11684)
		(layer "F.Cu")
		(net "UART_BIC_GF_RXD")
	)
	(segment
		(start 23.749 -64.78905)
		(end 23.64105 -64.897)
		(width 0.11684)
		(layer "F.Cu")
		(net "UART_BIC_GF_RXD")
	)
	(segment
		(start 22.874986 -63.306198)
		(end 22.874986 -62.88024)
		(width 0.11684)
		(layer "F.Cu")
		(net "UART_BIC_GF_RXD")
	)
	(segment
		(start 73.736454 -113.727738)
		(end 72.954896 -114.509296)
		(width 0.11684)
		(layer "F.Cu")
		(net "UART_BIC_GF_RXD")
	)
	(segment
		(start 72.660002 -116.904008)
		(end 72.660002 -118.460012)
		(width 0.11684)
		(layer "F.Cu")
		(net "UART_BIC_GF_RXD")
	)
	(segment
		(start 72.954896 -114.509296)
		(end 72.954896 -116.609114)
		(width 0.11684)
		(layer "F.Cu")
		(net "UART_BIC_GF_RXD")
	)
	(segment
		(start 22.874986 -62.88024)
		(end 23.068026 -62.6872)
		(width 0.11684)
		(layer "F.Cu")
		(net "UART_BIC_GF_RXD")
	)
	(segment
		(start 72.954896 -116.609114)
		(end 72.660002 -116.904008)
		(width 0.11684)
		(layer "F.Cu")
		(net "UART_BIC_GF_RXD")
	)
	(segment
		(start 23.068026 -62.6872)
		(end 24.13 -62.6872)
		(width 0.11684)
		(layer "F.Cu")
		(net "UART_BIC_GF_RXD")
	)
	(segment
		(start 24.13 -62.6872)
		(end 24.2062 -62.7634)
		(width 0.11684)
		(layer "F.Cu")
		(net "UART_BIC_GF_RXD")
	)
	(segment
		(start 24.2062 -62.7634)
		(end 23.749 -63.2206)
		(width 0.11684)
		(layer "F.Cu")
		(net "UART_BIC_GF_RXD")
	)
	(via
		(at 24.369776 -38.020498)
		(size 0.508)
		(drill 0.254)
		(layers "F.Cu" "B.Cu")
		(net "UART_BIC_GF_RXD")
	)
	(via
		(at 73.025 -105.6894)
		(size 0.508)
		(drill 0.254)
		(layers "F.Cu" "B.Cu")
		(net "UART_BIC_GF_RXD")
	)
	(via
		(at 48.1838 -35.6616)
		(size 0.508)
		(drill 0.254)
		(layers "F.Cu" "B.Cu")
		(net "UART_BIC_GF_RXD")
	)
	(via
		(at 71.31431 -109.615224)
		(size 0.6604)
		(drill 0.3302)
		(layers "F.Cu" "B.Cu")
		(net "UART_BIC_GF_RXD")
	)
	(via
		(at 74.072242 -113.727738)
		(size 0.508)
		(drill 0.254)
		(layers "F.Cu" "B.Cu")
		(net "UART_BIC_GF_RXD")
	)
	(via
		(at 24.2062 -62.7634)
		(size 0.508)
		(drill 0.254)
		(layers "F.Cu" "B.Cu")
		(net "UART_BIC_GF_RXD")
	)
	(segment
		(start 74.072242 -113.010188)
		(end 74.072242 -113.727738)
		(width 0.11684)
		(layer "B.Cu")
		(net "UART_BIC_GF_RXD")
	)
	(segment
		(start 73.025 -106.553)
		(end 73.025 -105.6894)
		(width 0.11684)
		(layer "B.Cu")
		(net "UART_BIC_GF_RXD")
	)
	(segment
		(start 71.31431 -108.26369)
		(end 73.025 -106.553)
		(width 0.11684)
		(layer "B.Cu")
		(net "UART_BIC_GF_RXD")
	)
	(segment
		(start 71.31431 -109.615224)
		(end 71.31431 -110.252256)
		(width 0.11684)
		(layer "B.Cu")
		(net "UART_BIC_GF_RXD")
	)
	(segment
		(start 71.31431 -109.615224)
		(end 71.31431 -108.26369)
		(width 0.11684)
		(layer "B.Cu")
		(net "UART_BIC_GF_RXD")
	)
	(segment
		(start 71.31431 -110.252256)
		(end 74.072242 -113.010188)
		(width 0.11684)
		(layer "B.Cu")
		(net "UART_BIC_GF_RXD")
	)
	(segment
		(start 48.1838 -35.6616)
		(end 47.48784 -35.6616)
		(width 0.08382)
		(layer "In2.Cu")
		(net "UART_BIC_GF_RXD")
	)
	(segment
		(start 47.48784 -35.6616)
		(end 46.22546 -34.39922)
		(width 0.08382)
		(layer "In2.Cu")
		(net "UART_BIC_GF_RXD")
	)
	(segment
		(start 36.6014 -37.2872)
		(end 35.37204 -38.51656)
		(width 0.08382)
		(layer "In2.Cu")
		(net "UART_BIC_GF_RXD")
	)
	(segment
		(start 36.682172 -33.000188)
		(end 35.846258 -33.836102)
		(width 0.08382)
		(layer "In2.Cu")
		(net "UART_BIC_GF_RXD")
	)
	(segment
		(start 46.22546 -34.39922)
		(end 41.591484 -34.39922)
		(width 0.08382)
		(layer "In2.Cu")
		(net "UART_BIC_GF_RXD")
	)
	(segment
		(start 41.591484 -34.39922)
		(end 40.458136 -33.265872)
		(width 0.08382)
		(layer "In2.Cu")
		(net "UART_BIC_GF_RXD")
	)
	(segment
		(start 24.865838 -38.51656)
		(end 24.369776 -38.020498)
		(width 0.08382)
		(layer "In2.Cu")
		(net "UART_BIC_GF_RXD")
	)
	(segment
		(start 38.276022 -32.9692)
		(end 38.245034 -33.000188)
		(width 0.08382)
		(layer "In2.Cu")
		(net "UART_BIC_GF_RXD")
	)
	(segment
		(start 40.458136 -33.265872)
		(end 39.541196 -33.265872)
		(width 0.08382)
		(layer "In2.Cu")
		(net "UART_BIC_GF_RXD")
	)
	(segment
		(start 38.245034 -33.000188)
		(end 36.682172 -33.000188)
		(width 0.08382)
		(layer "In2.Cu")
		(net "UART_BIC_GF_RXD")
	)
	(segment
		(start 35.846258 -35.1536)
		(end 36.6014 -35.908742)
		(width 0.08382)
		(layer "In2.Cu")
		(net "UART_BIC_GF_RXD")
	)
	(segment
		(start 39.244524 -32.9692)
		(end 38.276022 -32.9692)
		(width 0.08382)
		(layer "In2.Cu")
		(net "UART_BIC_GF_RXD")
	)
	(segment
		(start 39.541196 -33.265872)
		(end 39.244524 -32.9692)
		(width 0.08382)
		(layer "In2.Cu")
		(net "UART_BIC_GF_RXD")
	)
	(segment
		(start 35.846258 -33.836102)
		(end 35.846258 -35.1536)
		(width 0.08382)
		(layer "In2.Cu")
		(net "UART_BIC_GF_RXD")
	)
	(segment
		(start 35.37204 -38.51656)
		(end 24.865838 -38.51656)
		(width 0.08382)
		(layer "In2.Cu")
		(net "UART_BIC_GF_RXD")
	)
	(segment
		(start 36.6014 -35.908742)
		(end 36.6014 -37.2872)
		(width 0.08382)
		(layer "In2.Cu")
		(net "UART_BIC_GF_RXD")
	)
	(segment
		(start 47.6504 -35.1282)
		(end 44.5262 -35.1282)
		(width 0.10668)
		(layer "In7.Cu")
		(net "UART_BIC_GF_RXD")
	)
	(segment
		(start 63.44666 -82.328766)
		(end 63.529464 -82.528664)
		(width 0.10668)
		(layer "In7.Cu")
		(net "UART_BIC_GF_RXD")
	)
	(segment
		(start 61.933328 -76.91882)
		(end 63.820548 -76.91882)
		(width 0.10668)
		(layer "In7.Cu")
		(net "UART_BIC_GF_RXD")
	)
	(segment
		(start 43.129708 -64.058546)
		(end 43.129708 -64.82715)
		(width 0.10668)
		(layer "In7.Cu")
		(net "UART_BIC_GF_RXD")
	)
	(segment
		(start 43.4848 -65.4304)
		(end 43.6118 -65.5574)
		(width 0.10668)
		(layer "In7.Cu")
		(net "UART_BIC_GF_RXD")
	)
	(segment
		(start 70.3199 -100.516436)
		(end 72.81672 -103.013256)
		(width 0.10668)
		(layer "In7.Cu")
		(net "UART_BIC_GF_RXD")
	)
	(segment
		(start 54.03342 -70.472554)
		(end 56.807608 -70.472554)
		(width 0.10668)
		(layer "In7.Cu")
		(net "UART_BIC_GF_RXD")
	)
	(segment
		(start 43.480482 -65.178178)
		(end 43.4848 -65.182496)
		(width 0.10668)
		(layer "In7.Cu")
		(net "UART_BIC_GF_RXD")
	)
	(segment
		(start 43.68546 -57.872122)
		(end 43.42892 -58.128662)
		(width 0.10668)
		(layer "In7.Cu")
		(net "UART_BIC_GF_RXD")
	)
	(segment
		(start 48.1838 -35.6616)
		(end 47.6504 -35.1282)
		(width 0.10668)
		(layer "In7.Cu")
		(net "UART_BIC_GF_RXD")
	)
	(segment
		(start 64.20866 -77.306932)
		(end 64.20866 -80.986376)
		(width 0.10668)
		(layer "In7.Cu")
		(net "UART_BIC_GF_RXD")
	)
	(segment
		(start 51.270916 -69.19468)
		(end 52.755546 -69.19468)
		(width 0.10668)
		(layer "In7.Cu")
		(net "UART_BIC_GF_RXD")
	)
	(segment
		(start 43.956986 -45.612304)
		(end 43.956986 -46.187868)
		(width 0.10668)
		(layer "In7.Cu")
		(net "UART_BIC_GF_RXD")
	)
	(segment
		(start 46.4058 -65.5066)
		(end 48.488854 -65.5066)
		(width 0.10668)
		(layer "In7.Cu")
		(net "UART_BIC_GF_RXD")
	)
	(segment
		(start 43.74134 -55.32374)
		(end 44.2468 -55.8292)
		(width 0.10668)
		(layer "In7.Cu")
		(net "UART_BIC_GF_RXD")
	)
	(segment
		(start 64.260476 -83.310476)
		(end 64.260476 -89.173304)
		(width 0.10668)
		(layer "In7.Cu")
		(net "UART_BIC_GF_RXD")
	)
	(segment
		(start 56.807608 -70.472554)
		(end 57.820814 -71.48576)
		(width 0.10668)
		(layer "In7.Cu")
		(net "UART_BIC_GF_RXD")
	)
	(segment
		(start 63.529464 -82.528664)
		(end 63.565532 -82.615532)
		(width 0.10668)
		(layer "In7.Cu")
		(net "UART_BIC_GF_RXD")
	)
	(segment
		(start 64.260476 -89.173304)
		(end 68.4403 -93.353128)
		(width 0.10668)
		(layer "In7.Cu")
		(net "UART_BIC_GF_RXD")
	)
	(segment
		(start 72.81672 -103.013256)
		(end 72.81672 -104.278938)
		(width 0.10668)
		(layer "In7.Cu")
		(net "UART_BIC_GF_RXD")
	)
	(segment
		(start 70.126352 -98.94697)
		(end 70.3199 -99.414076)
		(width 0.10668)
		(layer "In7.Cu")
		(net "UART_BIC_GF_RXD")
	)
	(segment
		(start 43.68546 -57.0611)
		(end 43.68546 -57.872122)
		(width 0.10668)
		(layer "In7.Cu")
		(net "UART_BIC_GF_RXD")
	)
	(segment
		(start 44.9072 -44.66209)
		(end 43.956986 -45.612304)
		(width 0.10668)
		(layer "In7.Cu")
		(net "UART_BIC_GF_RXD")
	)
	(segment
		(start 46.51629 -42.016934)
		(end 46.51629 -42.35831)
		(width 0.10668)
		(layer "In7.Cu")
		(net "UART_BIC_GF_RXD")
	)
	(segment
		(start 42.5958 -52.56657)
		(end 42.5958 -52.977542)
		(width 0.10668)
		(layer "In7.Cu")
		(net "UART_BIC_GF_RXD")
	)
	(segment
		(start 58.41238 -71.48576)
		(end 58.74131 -71.81469)
		(width 0.10668)
		(layer "In7.Cu")
		(net "UART_BIC_GF_RXD")
	)
	(segment
		(start 47.28337 -41.59123)
		(end 47.082202 -41.792398)
		(width 0.10668)
		(layer "In7.Cu")
		(net "UART_BIC_GF_RXD")
	)
	(segment
		(start 42.715434 -53.097176)
		(end 42.715434 -53.317394)
		(width 0.10668)
		(layer "In7.Cu")
		(net "UART_BIC_GF_RXD")
	)
	(segment
		(start 43.4848 -65.182496)
		(end 43.4848 -65.4304)
		(width 0.10668)
		(layer "In7.Cu")
		(net "UART_BIC_GF_RXD")
	)
	(segment
		(start 47.28337 -38.817042)
		(end 47.28337 -41.59123)
		(width 0.10668)
		(layer "In7.Cu")
		(net "UART_BIC_GF_RXD")
	)
	(segment
		(start 42.57548 -48.111156)
		(end 42.57548 -52.03825)
		(width 0.10668)
		(layer "In7.Cu")
		(net "UART_BIC_GF_RXD")
	)
	(segment
		(start 43.956986 -46.187868)
		(end 42.958766 -47.186088)
		(width 0.10668)
		(layer "In7.Cu")
		(net "UART_BIC_GF_RXD")
	)
	(segment
		(start 58.74131 -71.81469)
		(end 58.74131 -72.71131)
		(width 0.10668)
		(layer "In7.Cu")
		(net "UART_BIC_GF_RXD")
	)
	(segment
		(start 43.42892 -58.128662)
		(end 43.42892 -63.759334)
		(width 0.10668)
		(layer "In7.Cu")
		(net "UART_BIC_GF_RXD")
	)
	(segment
		(start 43.33748 -38.02888)
		(end 46.495208 -38.02888)
		(width 0.10668)
		(layer "In7.Cu")
		(net "UART_BIC_GF_RXD")
	)
	(segment
		(start 63.565532 -82.615532)
		(end 64.260476 -83.310476)
		(width 0.10668)
		(layer "In7.Cu")
		(net "UART_BIC_GF_RXD")
	)
	(segment
		(start 63.44666 -81.748376)
		(end 63.44666 -82.328766)
		(width 0.10668)
		(layer "In7.Cu")
		(net "UART_BIC_GF_RXD")
	)
	(segment
		(start 42.6593 -52.50307)
		(end 42.5958 -52.56657)
		(width 0.10668)
		(layer "In7.Cu")
		(net "UART_BIC_GF_RXD")
	)
	(segment
		(start 43.42892 -63.759334)
		(end 43.129708 -64.058546)
		(width 0.10668)
		(layer "In7.Cu")
		(net "UART_BIC_GF_RXD")
	)
	(segment
		(start 42.958766 -47.186088)
		(end 42.57548 -48.111156)
		(width 0.10668)
		(layer "In7.Cu")
		(net "UART_BIC_GF_RXD")
	)
	(segment
		(start 42.8498 -37.5412)
		(end 43.33748 -38.02888)
		(width 0.10668)
		(layer "In7.Cu")
		(net "UART_BIC_GF_RXD")
	)
	(segment
		(start 43.129708 -64.82715)
		(end 43.480482 -65.178178)
		(width 0.10668)
		(layer "In7.Cu")
		(net "UART_BIC_GF_RXD")
	)
	(segment
		(start 46.740826 -41.792398)
		(end 46.51629 -42.016934)
		(width 0.10668)
		(layer "In7.Cu")
		(net "UART_BIC_GF_RXD")
	)
	(segment
		(start 46.51629 -42.35831)
		(end 46.315122 -42.559478)
		(width 0.10668)
		(layer "In7.Cu")
		(net "UART_BIC_GF_RXD")
	)
	(segment
		(start 72.81672 -104.278938)
		(end 73.025 -104.487218)
		(width 0.10668)
		(layer "In7.Cu")
		(net "UART_BIC_GF_RXD")
	)
	(segment
		(start 45.070522 -42.559478)
		(end 44.9072 -42.7228)
		(width 0.10668)
		(layer "In7.Cu")
		(net "UART_BIC_GF_RXD")
	)
	(segment
		(start 47.082202 -41.792398)
		(end 46.740826 -41.792398)
		(width 0.10668)
		(layer "In7.Cu")
		(net "UART_BIC_GF_RXD")
	)
	(segment
		(start 43.74134 -54.3433)
		(end 43.74134 -55.32374)
		(width 0.10668)
		(layer "In7.Cu")
		(net "UART_BIC_GF_RXD")
	)
	(segment
		(start 44.2468 -55.8292)
		(end 44.2468 -56.49976)
		(width 0.10668)
		(layer "In7.Cu")
		(net "UART_BIC_GF_RXD")
	)
	(segment
		(start 43.6118 -65.5574)
		(end 45.370242 -65.5574)
		(width 0.10668)
		(layer "In7.Cu")
		(net "UART_BIC_GF_RXD")
	)
	(segment
		(start 58.74131 -72.71131)
		(end 60.071 -74.041)
		(width 0.10668)
		(layer "In7.Cu")
		(net "UART_BIC_GF_RXD")
	)
	(segment
		(start 57.820814 -71.48576)
		(end 58.41238 -71.48576)
		(width 0.10668)
		(layer "In7.Cu")
		(net "UART_BIC_GF_RXD")
	)
	(segment
		(start 46.495208 -38.02888)
		(end 47.28337 -38.817042)
		(width 0.10668)
		(layer "In7.Cu")
		(net "UART_BIC_GF_RXD")
	)
	(segment
		(start 70.3199 -99.414076)
		(end 70.3199 -100.516436)
		(width 0.10668)
		(layer "In7.Cu")
		(net "UART_BIC_GF_RXD")
	)
	(segment
		(start 46.315122 -42.559478)
		(end 45.070522 -42.559478)
		(width 0.10668)
		(layer "In7.Cu")
		(net "UART_BIC_GF_RXD")
	)
	(segment
		(start 42.8498 -36.8046)
		(end 42.8498 -37.5412)
		(width 0.10668)
		(layer "In7.Cu")
		(net "UART_BIC_GF_RXD")
	)
	(segment
		(start 68.4403 -97.260918)
		(end 70.126352 -98.94697)
		(width 0.10668)
		(layer "In7.Cu")
		(net "UART_BIC_GF_RXD")
	)
	(segment
		(start 42.5958 -52.977542)
		(end 42.715434 -53.097176)
		(width 0.10668)
		(layer "In7.Cu")
		(net "UART_BIC_GF_RXD")
	)
	(segment
		(start 63.820548 -76.91882)
		(end 64.20866 -77.306932)
		(width 0.10668)
		(layer "In7.Cu")
		(net "UART_BIC_GF_RXD")
	)
	(segment
		(start 45.645832 -65.28181)
		(end 46.18101 -65.28181)
		(width 0.10668)
		(layer "In7.Cu")
		(net "UART_BIC_GF_RXD")
	)
	(segment
		(start 42.57548 -52.03825)
		(end 42.6593 -52.12207)
		(width 0.10668)
		(layer "In7.Cu")
		(net "UART_BIC_GF_RXD")
	)
	(segment
		(start 44.5262 -35.1282)
		(end 42.8498 -36.8046)
		(width 0.10668)
		(layer "In7.Cu")
		(net "UART_BIC_GF_RXD")
	)
	(segment
		(start 44.9072 -42.7228)
		(end 44.9072 -44.66209)
		(width 0.10668)
		(layer "In7.Cu")
		(net "UART_BIC_GF_RXD")
	)
	(segment
		(start 42.715434 -53.317394)
		(end 43.74134 -54.3433)
		(width 0.10668)
		(layer "In7.Cu")
		(net "UART_BIC_GF_RXD")
	)
	(segment
		(start 42.6593 -52.12207)
		(end 42.6593 -52.50307)
		(width 0.10668)
		(layer "In7.Cu")
		(net "UART_BIC_GF_RXD")
	)
	(segment
		(start 52.755546 -69.19468)
		(end 54.03342 -70.472554)
		(width 0.10668)
		(layer "In7.Cu")
		(net "UART_BIC_GF_RXD")
	)
	(segment
		(start 73.025 -104.487218)
		(end 73.025 -105.6894)
		(width 0.10668)
		(layer "In7.Cu")
		(net "UART_BIC_GF_RXD")
	)
	(segment
		(start 46.18101 -65.28181)
		(end 46.4058 -65.5066)
		(width 0.10668)
		(layer "In7.Cu")
		(net "UART_BIC_GF_RXD")
	)
	(segment
		(start 64.20866 -80.986376)
		(end 63.44666 -81.748376)
		(width 0.10668)
		(layer "In7.Cu")
		(net "UART_BIC_GF_RXD")
	)
	(segment
		(start 68.4403 -93.353128)
		(end 68.4403 -97.260918)
		(width 0.10668)
		(layer "In7.Cu")
		(net "UART_BIC_GF_RXD")
	)
	(segment
		(start 50.74412 -67.761866)
		(end 50.74412 -68.667884)
		(width 0.10668)
		(layer "In7.Cu")
		(net "UART_BIC_GF_RXD")
	)
	(segment
		(start 45.370242 -65.5574)
		(end 45.645832 -65.28181)
		(width 0.10668)
		(layer "In7.Cu")
		(net "UART_BIC_GF_RXD")
	)
	(segment
		(start 50.74412 -68.667884)
		(end 51.270916 -69.19468)
		(width 0.10668)
		(layer "In7.Cu")
		(net "UART_BIC_GF_RXD")
	)
	(segment
		(start 60.071 -75.056492)
		(end 61.933328 -76.91882)
		(width 0.10668)
		(layer "In7.Cu")
		(net "UART_BIC_GF_RXD")
	)
	(segment
		(start 60.071 -74.041)
		(end 60.071 -75.056492)
		(width 0.10668)
		(layer "In7.Cu")
		(net "UART_BIC_GF_RXD")
	)
	(segment
		(start 48.488854 -65.5066)
		(end 50.74412 -67.761866)
		(width 0.10668)
		(layer "In7.Cu")
		(net "UART_BIC_GF_RXD")
	)
	(segment
		(start 44.2468 -56.49976)
		(end 43.68546 -57.0611)
		(width 0.10668)
		(layer "In7.Cu")
		(net "UART_BIC_GF_RXD")
	)
	(segment
		(start 20.14982 -47.888652)
		(end 20.14982 -48.088296)
		(width 0.08382)
		(layer "In9.Cu")
		(net "UART_BIC_GF_RXD")
	)
	(segment
		(start 19.80692 -50.684938)
		(end 20.07997 -50.957988)
		(width 0.08382)
		(layer "In9.Cu")
		(net "UART_BIC_GF_RXD")
	)
	(segment
		(start 19.80692 -48.916844)
		(end 19.80692 -50.684938)
		(width 0.08382)
		(layer "In9.Cu")
		(net "UART_BIC_GF_RXD")
	)
	(segment
		(start 20.07997 -50.957988)
		(end 20.07997 -58.81497)
		(width 0.08382)
		(layer "In9.Cu")
		(net "UART_BIC_GF_RXD")
	)
	(segment
		(start 20.14982 -44.614846)
		(end 20.14982 -45.201332)
		(width 0.08382)
		(layer "In9.Cu")
		(net "UART_BIC_GF_RXD")
	)
	(segment
		(start 20.14982 -48.088296)
		(end 19.80692 -48.916844)
		(width 0.08382)
		(layer "In9.Cu")
		(net "UART_BIC_GF_RXD")
	)
	(segment
		(start 20.07997 -58.81497)
		(end 24.0284 -62.7634)
		(width 0.08382)
		(layer "In9.Cu")
		(net "UART_BIC_GF_RXD")
	)
	(segment
		(start 24.369776 -38.096698)
		(end 23.92299 -38.543484)
		(width 0.08382)
		(layer "In9.Cu")
		(net "UART_BIC_GF_RXD")
	)
	(segment
		(start 20.35937 -45.410882)
		(end 20.35937 -47.38243)
		(width 0.08382)
		(layer "In9.Cu")
		(net "UART_BIC_GF_RXD")
	)
	(segment
		(start 24.369776 -38.020498)
		(end 24.369776 -38.096698)
		(width 0.08382)
		(layer "In9.Cu")
		(net "UART_BIC_GF_RXD")
	)
	(segment
		(start 24.0284 -62.7634)
		(end 24.2062 -62.7634)
		(width 0.08382)
		(layer "In9.Cu")
		(net "UART_BIC_GF_RXD")
	)
	(segment
		(start 23.92299 -38.543484)
		(end 23.92299 -40.841676)
		(width 0.08382)
		(layer "In9.Cu")
		(net "UART_BIC_GF_RXD")
	)
	(segment
		(start 20.35937 -47.38243)
		(end 20.14982 -47.888652)
		(width 0.08382)
		(layer "In9.Cu")
		(net "UART_BIC_GF_RXD")
	)
	(segment
		(start 23.92299 -40.841676)
		(end 20.14982 -44.614846)
		(width 0.08382)
		(layer "In9.Cu")
		(net "UART_BIC_GF_RXD")
	)
	(segment
		(start 20.14982 -45.201332)
		(end 20.35937 -45.410882)
		(width 0.08382)
		(layer "In9.Cu")
		(net "UART_BIC_GF_RXD")
	)
	(segment
		(start 21.575014 -61.306202)
		(end 21.575014 -58.9534)
		(width 0.11684)
		(layer "F.Cu")
		(net "UART_BIC_DBG_TX_R")
	)
	(segment
		(start 18.6436 -56.58485)
		(end 21.01215 -58.9534)
		(width 0.11684)
		(layer "F.Cu")
		(net "UART_BIC_DBG_TX_R")
	)
	(segment
		(start 21.01215 -58.9534)
		(end 21.575014 -58.9534)
		(width 0.11684)
		(layer "F.Cu")
		(net "UART_BIC_DBG_TX_R")
	)
	(via
		(at 21.575014 -58.9534)
		(size 0.762)
		(drill 0.381)
		(layers "F.Cu" "B.Cu")
		(net "UART_BIC_DBG_TX_R")
	)
	(segment
		(start 23.9776 -58.883296)
		(end 21.67636 -56.582056)
		(width 0.11684)
		(layer "F.Cu")
		(net "UART_BIC_DBG_TX")
	)
	(segment
		(start 17.46758 -54.60873)
		(end 17.46758 -54.2163)
		(width 0.11684)
		(layer "F.Cu")
		(net "UART_BIC_DBG_TX")
	)
	(segment
		(start 21.67636 -56.582056)
		(end 21.67636 -54.41696)
		(width 0.11684)
		(layer "F.Cu")
		(net "UART_BIC_DBG_TX")
	)
	(segment
		(start 23.9776 -60.50788)
		(end 23.9776 -58.883296)
		(width 0.11684)
		(layer "F.Cu")
		(net "UART_BIC_DBG_TX")
	)
	(segment
		(start 21.19122 -53.93182)
		(end 20.574 -53.93182)
		(width 0.11684)
		(layer "F.Cu")
		(net "UART_BIC_DBG_TX")
	)
	(segment
		(start 17.96288 -53.721)
		(end 20.36318 -53.721)
		(width 0.11684)
		(layer "F.Cu")
		(net "UART_BIC_DBG_TX")
	)
	(segment
		(start 24.218138 -60.748418)
		(end 23.9776 -60.50788)
		(width 0.11684)
		(layer "F.Cu")
		(net "UART_BIC_DBG_TX")
	)
	(segment
		(start 21.67636 -54.41696)
		(end 21.19122 -53.93182)
		(width 0.11684)
		(layer "F.Cu")
		(net "UART_BIC_DBG_TX")
	)
	(segment
		(start 17.46758 -54.2163)
		(end 17.96288 -53.721)
		(width 0.11684)
		(layer "F.Cu")
		(net "UART_BIC_DBG_TX")
	)
	(segment
		(start 20.36318 -53.721)
		(end 20.574 -53.93182)
		(width 0.11684)
		(layer "F.Cu")
		(net "UART_BIC_DBG_TX")
	)
	(segment
		(start 18.6436 -55.78475)
		(end 17.46758 -54.60873)
		(width 0.11684)
		(layer "F.Cu")
		(net "UART_BIC_DBG_TX")
	)
	(segment
		(start 24.218138 -60.95619)
		(end 24.218138 -60.748418)
		(width 0.11684)
		(layer "F.Cu")
		(net "UART_BIC_DBG_TX")
	)
	(via
		(at 20.574 -53.93182)
		(size 0.762)
		(drill 0.381)
		(layers "F.Cu" "B.Cu")
		(net "UART_BIC_DBG_TX")
	)
	(segment
		(start 15.428214 -61.306202)
		(end 15.428214 -60.342526)
		(width 0.11684)
		(layer "F.Cu")
		(net "UART_BIC_DBG_RX_R")
	)
	(segment
		(start 15.88008 -59.334146)
		(end 15.88008 -59.3344)
		(width 0.11684)
		(layer "F.Cu")
		(net "UART_BIC_DBG_RX_R")
	)
	(segment
		(start 15.88008 -59.89066)
		(end 15.88008 -59.3344)
		(width 0.11684)
		(layer "F.Cu")
		(net "UART_BIC_DBG_RX_R")
	)
	(segment
		(start 15.548864 -59.00293)
		(end 15.88008 -59.334146)
		(width 0.11684)
		(layer "F.Cu")
		(net "UART_BIC_DBG_RX_R")
	)
	(segment
		(start 15.428214 -60.342526)
		(end 15.88008 -59.89066)
		(width 0.11684)
		(layer "F.Cu")
		(net "UART_BIC_DBG_RX_R")
	)
	(segment
		(start 15.548864 -58.13425)
		(end 15.548864 -59.00293)
		(width 0.11684)
		(layer "F.Cu")
		(net "UART_BIC_DBG_RX_R")
	)
	(via
		(at 15.88008 -59.3344)
		(size 0.762)
		(drill 0.381)
		(layers "F.Cu" "B.Cu")
		(net "UART_BIC_DBG_RX_R")
	)
	(segment
		(start 18.8722 -59.639454)
		(end 18.8722 -60.223146)
		(width 0.11684)
		(layer "F.Cu")
		(net "UART_BIC_DBG_RX")
	)
	(segment
		(start 18.655538 -60.439808)
		(end 18.655538 -60.98159)
		(width 0.11684)
		(layer "F.Cu")
		(net "UART_BIC_DBG_RX")
	)
	(segment
		(start 15.548864 -57.33415)
		(end 16.088614 -56.7944)
		(width 0.11684)
		(layer "F.Cu")
		(net "UART_BIC_DBG_RX")
	)
	(segment
		(start 16.088614 -56.7944)
		(end 17.34058 -56.7944)
		(width 0.11684)
		(layer "F.Cu")
		(net "UART_BIC_DBG_RX")
	)
	(segment
		(start 17.34058 -56.7944)
		(end 17.853406 -57.307226)
		(width 0.11684)
		(layer "F.Cu")
		(net "UART_BIC_DBG_RX")
	)
	(segment
		(start 17.853406 -57.790334)
		(end 18.655538 -58.592466)
		(width 0.11684)
		(layer "F.Cu")
		(net "UART_BIC_DBG_RX")
	)
	(segment
		(start 18.655538 -59.422792)
		(end 18.8722 -59.639454)
		(width 0.11684)
		(layer "F.Cu")
		(net "UART_BIC_DBG_RX")
	)
	(segment
		(start 17.853406 -57.307226)
		(end 17.853406 -57.790334)
		(width 0.11684)
		(layer "F.Cu")
		(net "UART_BIC_DBG_RX")
	)
	(segment
		(start 18.655538 -58.592466)
		(end 18.655538 -59.422792)
		(width 0.11684)
		(layer "F.Cu")
		(net "UART_BIC_DBG_RX")
	)
	(segment
		(start 18.8722 -60.223146)
		(end 18.655538 -60.439808)
		(width 0.11684)
		(layer "F.Cu")
		(net "UART_BIC_DBG_RX")
	)
	(via
		(at 17.853406 -57.790334)
		(size 0.762)
		(drill 0.381)
		(layers "F.Cu" "B.Cu")
		(net "UART_BIC_DBG_RX")
	)
	(segment
		(start 16.564864 -58.543444)
		(end 17.195546 -59.174126)
		(width 0.11684)
		(layer "F.Cu")
		(net "UART_6_BMC_TXD_R")
	)
	(segment
		(start 16.728186 -60.25388)
		(end 17.195546 -59.78652)
		(width 0.11684)
		(layer "F.Cu")
		(net "UART_6_BMC_TXD_R")
	)
	(segment
		(start 16.564864 -58.13425)
		(end 16.564864 -58.543444)
		(width 0.11684)
		(layer "F.Cu")
		(net "UART_6_BMC_TXD_R")
	)
	(segment
		(start 17.195546 -59.174126)
		(end 17.195546 -59.78652)
		(width 0.11684)
		(layer "F.Cu")
		(net "UART_6_BMC_TXD_R")
	)
	(segment
		(start 16.728186 -61.306202)
		(end 16.728186 -60.25388)
		(width 0.11684)
		(layer "F.Cu")
		(net "UART_6_BMC_TXD_R")
	)
	(via
		(at 17.195546 -59.78652)
		(size 0.762)
		(drill 0.381)
		(layers "F.Cu" "B.Cu")
		(net "UART_6_BMC_TXD_R")
	)
	(segment
		(start 17.1958 -57.553098)
		(end 17.1958 -58.35015)
		(width 0.11684)
		(layer "F.Cu")
		(net "UART_6_BMC_TXD")
	)
	(segment
		(start 16.976852 -57.33415)
		(end 17.1958 -57.553098)
		(width 0.11684)
		(layer "F.Cu")
		(net "UART_6_BMC_TXD")
	)
	(segment
		(start 16.564864 -57.33415)
		(end 16.976852 -57.33415)
		(width 0.11684)
		(layer "F.Cu")
		(net "UART_6_BMC_TXD")
	)
	(via
		(at 17.1958 -58.35015)
		(size 0.508)
		(drill 0.254)
		(layers "F.Cu" "B.Cu")
		(net "UART_6_BMC_TXD")
	)
	(via
		(at 18.065496 -45.35551)
		(size 0.508)
		(drill 0.254)
		(layers "F.Cu" "B.Cu")
		(net "UART_6_BMC_TXD")
	)
	(via
		(at 38.5572 -29.591)
		(size 0.508)
		(drill 0.254)
		(layers "F.Cu" "B.Cu")
		(net "UART_6_BMC_TXD")
	)
	(segment
		(start 38.5572 -29.591)
		(end 38.788086 -29.591)
		(width 0.11684)
		(layer "B.Cu")
		(net "UART_6_BMC_TXD")
	)
	(segment
		(start 38.788086 -29.591)
		(end 39.45255 -30.255464)
		(width 0.11684)
		(layer "B.Cu")
		(net "UART_6_BMC_TXD")
	)
	(segment
		(start 39.45255 -30.255464)
		(end 39.45255 -30.2768)
		(width 0.11684)
		(layer "B.Cu")
		(net "UART_6_BMC_TXD")
	)
	(segment
		(start 30.932882 -32.151574)
		(end 29.187648 -32.151574)
		(width 0.08382)
		(layer "In2.Cu")
		(net "UART_6_BMC_TXD")
	)
	(segment
		(start 38.5572 -29.591)
		(end 37.897816 -28.931616)
		(width 0.08382)
		(layer "In2.Cu")
		(net "UART_6_BMC_TXD")
	)
	(segment
		(start 37.717984 -28.931616)
		(end 37.581332 -29.068268)
		(width 0.08382)
		(layer "In2.Cu")
		(net "UART_6_BMC_TXD")
	)
	(segment
		(start 33.465262 -30.61335)
		(end 32.471106 -30.61335)
		(width 0.08382)
		(layer "In2.Cu")
		(net "UART_6_BMC_TXD")
	)
	(segment
		(start 29.187648 -32.151574)
		(end 25.22728 -36.111942)
		(width 0.08382)
		(layer "In2.Cu")
		(net "UART_6_BMC_TXD")
	)
	(segment
		(start 37.581332 -29.068268)
		(end 35.010344 -29.068268)
		(width 0.08382)
		(layer "In2.Cu")
		(net "UART_6_BMC_TXD")
	)
	(segment
		(start 37.897816 -28.931616)
		(end 37.717984 -28.931616)
		(width 0.08382)
		(layer "In2.Cu")
		(net "UART_6_BMC_TXD")
	)
	(segment
		(start 32.471106 -30.61335)
		(end 30.932882 -32.151574)
		(width 0.08382)
		(layer "In2.Cu")
		(net "UART_6_BMC_TXD")
	)
	(segment
		(start 23.25497 -37.024818)
		(end 23.25497 -40.80637)
		(width 0.08382)
		(layer "In2.Cu")
		(net "UART_6_BMC_TXD")
	)
	(segment
		(start 21.162518 -42.898822)
		(end 20.18157 -42.898822)
		(width 0.08382)
		(layer "In2.Cu")
		(net "UART_6_BMC_TXD")
	)
	(segment
		(start 35.010344 -29.068268)
		(end 33.465262 -30.61335)
		(width 0.08382)
		(layer "In2.Cu")
		(net "UART_6_BMC_TXD")
	)
	(segment
		(start 18.065496 -45.014896)
		(end 18.065496 -45.35551)
		(width 0.08382)
		(layer "In2.Cu")
		(net "UART_6_BMC_TXD")
	)
	(segment
		(start 24.167846 -36.111942)
		(end 23.25497 -37.024818)
		(width 0.08382)
		(layer "In2.Cu")
		(net "UART_6_BMC_TXD")
	)
	(segment
		(start 25.22728 -36.111942)
		(end 24.167846 -36.111942)
		(width 0.08382)
		(layer "In2.Cu")
		(net "UART_6_BMC_TXD")
	)
	(segment
		(start 20.18157 -42.898822)
		(end 18.065496 -45.014896)
		(width 0.08382)
		(layer "In2.Cu")
		(net "UART_6_BMC_TXD")
	)
	(segment
		(start 23.25497 -40.80637)
		(end 21.162518 -42.898822)
		(width 0.08382)
		(layer "In2.Cu")
		(net "UART_6_BMC_TXD")
	)
	(segment
		(start 19.5961 -47.333408)
		(end 19.5961 -45.6565)
		(width 0.08382)
		(layer "In9.Cu")
		(net "UART_6_BMC_TXD")
	)
	(segment
		(start 19.29511 -45.35551)
		(end 18.065496 -45.35551)
		(width 0.08382)
		(layer "In9.Cu")
		(net "UART_6_BMC_TXD")
	)
	(segment
		(start 17.21231 -54.18328)
		(end 19.03984 -52.35575)
		(width 0.08382)
		(layer "In9.Cu")
		(net "UART_6_BMC_TXD")
	)
	(segment
		(start 17.21231 -58.33364)
		(end 17.21231 -54.18328)
		(width 0.08382)
		(layer "In9.Cu")
		(net "UART_6_BMC_TXD")
	)
	(segment
		(start 19.5961 -45.6565)
		(end 19.29511 -45.35551)
		(width 0.08382)
		(layer "In9.Cu")
		(net "UART_6_BMC_TXD")
	)
	(segment
		(start 17.1958 -58.35015)
		(end 17.21231 -58.33364)
		(width 0.08382)
		(layer "In9.Cu")
		(net "UART_6_BMC_TXD")
	)
	(segment
		(start 19.03984 -52.35575)
		(end 19.03984 -47.889668)
		(width 0.08382)
		(layer "In9.Cu")
		(net "UART_6_BMC_TXD")
	)
	(segment
		(start 19.03984 -47.889668)
		(end 19.5961 -47.333408)
		(width 0.08382)
		(layer "In9.Cu")
		(net "UART_6_BMC_TXD")
	)
	(segment
		(start 22.874986 -58.758836)
		(end 21.791676 -57.675526)
		(width 0.11684)
		(layer "F.Cu")
		(net "UART_6_BMC_RXD_R")
	)
	(segment
		(start 21.791676 -57.675526)
		(end 20.701 -56.58485)
		(width 0.11684)
		(layer "F.Cu")
		(net "UART_6_BMC_RXD_R")
	)
	(segment
		(start 22.874986 -61.306202)
		(end 22.874986 -58.758836)
		(width 0.11684)
		(layer "F.Cu")
		(net "UART_6_BMC_RXD_R")
	)
	(segment
		(start 20.701 -56.58485)
		(end 19.685 -56.58485)
		(width 0.11684)
		(layer "F.Cu")
		(net "UART_6_BMC_RXD_R")
	)
	(via
		(at 21.791676 -57.675526)
		(size 0.762)
		(drill 0.381)
		(layers "F.Cu" "B.Cu")
		(net "UART_6_BMC_RXD_R")
	)
	(segment
		(start 19.685 -55.314596)
		(end 19.56816 -55.197756)
		(width 0.11684)
		(layer "F.Cu")
		(net "UART_6_BMC_RXD")
	)
	(segment
		(start 19.56816 -55.197756)
		(end 18.944082 -55.197756)
		(width 0.11684)
		(layer "F.Cu")
		(net "UART_6_BMC_RXD")
	)
	(segment
		(start 44.704 -34.025332)
		(end 44.306744 -33.628076)
		(width 0.11684)
		(layer "F.Cu")
		(net "UART_6_BMC_RXD")
	)
	(segment
		(start 44.704 -34.22015)
		(end 44.704 -34.025332)
		(width 0.11684)
		(layer "F.Cu")
		(net "UART_6_BMC_RXD")
	)
	(segment
		(start 19.685 -55.78475)
		(end 19.685 -55.314596)
		(width 0.11684)
		(layer "F.Cu")
		(net "UART_6_BMC_RXD")
	)
	(via
		(at 44.306744 -33.628076)
		(size 0.508)
		(drill 0.254)
		(layers "F.Cu" "B.Cu")
		(net "UART_6_BMC_RXD")
	)
	(via
		(at 18.807684 -47.36846)
		(size 0.508)
		(drill 0.254)
		(layers "F.Cu" "B.Cu")
		(net "UART_6_BMC_RXD")
	)
	(via
		(at 18.944082 -55.197756)
		(size 0.508)
		(drill 0.254)
		(layers "F.Cu" "B.Cu")
		(net "UART_6_BMC_RXD")
	)
	(segment
		(start 44.12996 -33.628076)
		(end 43.521884 -33.02)
		(width 0.08382)
		(layer "In2.Cu")
		(net "UART_6_BMC_RXD")
	)
	(segment
		(start 38.248336 -31.347664)
		(end 38.248336 -32.112966)
		(width 0.08382)
		(layer "In2.Cu")
		(net "UART_6_BMC_RXD")
	)
	(segment
		(start 36.27755 -32.375348)
		(end 36.04133 -32.611568)
		(width 0.08382)
		(layer "In2.Cu")
		(net "UART_6_BMC_RXD")
	)
	(segment
		(start 21.069808 -43.875452)
		(end 20.551902 -43.875452)
		(width 0.08382)
		(layer "In2.Cu")
		(net "UART_6_BMC_RXD")
	)
	(segment
		(start 24.426926 -36.736782)
		(end 23.90902 -37.254688)
		(width 0.08382)
		(layer "In2.Cu")
		(net "UART_6_BMC_RXD")
	)
	(segment
		(start 19.45894 -47.36846)
		(end 18.807684 -47.36846)
		(width 0.08382)
		(layer "In2.Cu")
		(net "UART_6_BMC_RXD")
	)
	(segment
		(start 42.15511 -33.13811)
		(end 41.95953 -32.94253)
		(width 0.08382)
		(layer "In2.Cu")
		(net "UART_6_BMC_RXD")
	)
	(segment
		(start 41.901872 -32.803338)
		(end 41.901872 -32.097472)
		(width 0.08382)
		(layer "In2.Cu")
		(net "UART_6_BMC_RXD")
	)
	(segment
		(start 19.92122 -46.90618)
		(end 19.45894 -47.36846)
		(width 0.08382)
		(layer "In2.Cu")
		(net "UART_6_BMC_RXD")
	)
	(segment
		(start 23.90902 -37.254688)
		(end 23.90902 -41.03624)
		(width 0.08382)
		(layer "In2.Cu")
		(net "UART_6_BMC_RXD")
	)
	(segment
		(start 19.92122 -44.506134)
		(end 19.92122 -46.90618)
		(width 0.08382)
		(layer "In2.Cu")
		(net "UART_6_BMC_RXD")
	)
	(segment
		(start 23.90902 -41.03624)
		(end 21.069808 -43.875452)
		(width 0.08382)
		(layer "In2.Cu")
		(net "UART_6_BMC_RXD")
	)
	(segment
		(start 38.248336 -32.112966)
		(end 37.985954 -32.375348)
		(width 0.08382)
		(layer "In2.Cu")
		(net "UART_6_BMC_RXD")
	)
	(segment
		(start 36.04133 -32.611568)
		(end 35.181032 -32.611568)
		(width 0.08382)
		(layer "In2.Cu")
		(net "UART_6_BMC_RXD")
	)
	(segment
		(start 43.521884 -33.02)
		(end 42.75836 -33.02)
		(width 0.08382)
		(layer "In2.Cu")
		(net "UART_6_BMC_RXD")
	)
	(segment
		(start 41.95953 -32.94253)
		(end 41.901872 -32.803338)
		(width 0.08382)
		(layer "In2.Cu")
		(net "UART_6_BMC_RXD")
	)
	(segment
		(start 40.93337 -31.12897)
		(end 38.46703 -31.12897)
		(width 0.08382)
		(layer "In2.Cu")
		(net "UART_6_BMC_RXD")
	)
	(segment
		(start 38.46703 -31.12897)
		(end 38.248336 -31.347664)
		(width 0.08382)
		(layer "In2.Cu")
		(net "UART_6_BMC_RXD")
	)
	(segment
		(start 20.551902 -43.875452)
		(end 19.92122 -44.506134)
		(width 0.08382)
		(layer "In2.Cu")
		(net "UART_6_BMC_RXD")
	)
	(segment
		(start 35.181032 -32.611568)
		(end 31.055818 -36.736782)
		(width 0.08382)
		(layer "In2.Cu")
		(net "UART_6_BMC_RXD")
	)
	(segment
		(start 44.306744 -33.628076)
		(end 44.12996 -33.628076)
		(width 0.08382)
		(layer "In2.Cu")
		(net "UART_6_BMC_RXD")
	)
	(segment
		(start 31.055818 -36.736782)
		(end 24.426926 -36.736782)
		(width 0.08382)
		(layer "In2.Cu")
		(net "UART_6_BMC_RXD")
	)
	(segment
		(start 37.985954 -32.375348)
		(end 36.27755 -32.375348)
		(width 0.08382)
		(layer "In2.Cu")
		(net "UART_6_BMC_RXD")
	)
	(segment
		(start 42.64025 -33.13811)
		(end 42.15511 -33.13811)
		(width 0.08382)
		(layer "In2.Cu")
		(net "UART_6_BMC_RXD")
	)
	(segment
		(start 42.75836 -33.02)
		(end 42.64025 -33.13811)
		(width 0.08382)
		(layer "In2.Cu")
		(net "UART_6_BMC_RXD")
	)
	(segment
		(start 41.901872 -32.097472)
		(end 40.93337 -31.12897)
		(width 0.08382)
		(layer "In2.Cu")
		(net "UART_6_BMC_RXD")
	)
	(segment
		(start 17.95526 -54.765194)
		(end 17.95526 -53.54828)
		(width 0.10668)
		(layer "In4.Cu")
		(net "UART_6_BMC_RXD")
	)
	(segment
		(start 19.2659 -52.23764)
		(end 19.2659 -49.424082)
		(width 0.10668)
		(layer "In4.Cu")
		(net "UART_6_BMC_RXD")
	)
	(segment
		(start 18.387822 -55.197756)
		(end 17.95526 -54.765194)
		(width 0.10668)
		(layer "In4.Cu")
		(net "UART_6_BMC_RXD")
	)
	(segment
		(start 18.944082 -55.197756)
		(end 18.387822 -55.197756)
		(width 0.10668)
		(layer "In4.Cu")
		(net "UART_6_BMC_RXD")
	)
	(segment
		(start 18.58772 -47.588424)
		(end 18.807684 -47.36846)
		(width 0.10668)
		(layer "In4.Cu")
		(net "UART_6_BMC_RXD")
	)
	(segment
		(start 19.2659 -49.424082)
		(end 18.58772 -48.745902)
		(width 0.10668)
		(layer "In4.Cu")
		(net "UART_6_BMC_RXD")
	)
	(segment
		(start 18.58772 -48.745902)
		(end 18.58772 -47.588424)
		(width 0.10668)
		(layer "In4.Cu")
		(net "UART_6_BMC_RXD")
	)
	(segment
		(start 17.95526 -53.54828)
		(end 19.2659 -52.23764)
		(width 0.10668)
		(layer "In4.Cu")
		(net "UART_6_BMC_RXD")
	)
	(segment
		(start 19.064224 -90.391742)
		(end 19.459448 -90.786966)
		(width 0.11684)
		(layer "F.Cu")
		(net "TP_PLD_19D")
	)
	(via
		(at 19.064224 -90.391742)
		(size 0.4572)
		(drill 0.254)
		(layers "F.Cu" "B.Cu")
		(net "TP_PLD_19D")
	)
	(segment
		(start 30.6578 -114.858546)
		(end 30.6578 -112.446054)
		(width 0.11684)
		(layer "F.Cu")
		(net "TP_GF1_B44")
	)
	(segment
		(start 28.4353 -109.6264)
		(end 27.9908 -109.6264)
		(width 0.11684)
		(layer "F.Cu")
		(net "TP_GF1_B44")
	)
	(segment
		(start 29.945076 -115.57127)
		(end 30.6578 -114.858546)
		(width 0.11684)
		(layer "F.Cu")
		(net "TP_GF1_B44")
	)
	(segment
		(start 29.0195 -110.807754)
		(end 29.0195 -110.2106)
		(width 0.11684)
		(layer "F.Cu")
		(net "TP_GF1_B44")
	)
	(segment
		(start 30.6578 -112.446054)
		(end 29.0195 -110.807754)
		(width 0.11684)
		(layer "F.Cu")
		(net "TP_GF1_B44")
	)
	(segment
		(start 29.945076 -118.25986)
		(end 29.945076 -115.57127)
		(width 0.11684)
		(layer "F.Cu")
		(net "TP_GF1_B44")
	)
	(segment
		(start 29.0195 -110.2106)
		(end 28.4353 -109.6264)
		(width 0.11684)
		(layer "F.Cu")
		(net "TP_GF1_B44")
	)
	(via
		(at 27.9908 -109.6264)
		(size 0.762)
		(drill 0.381)
		(layers "F.Cu" "B.Cu")
		(net "TP_GF1_B44")
	)
	(segment
		(start 54.099714 -57.37606)
		(end 54.890162 -57.37606)
		(width 0.11684)
		(layer "F.Cu")
		(net "TP_BMC_SPICS2_N")
	)
	(segment
		(start 54.890162 -57.37606)
		(end 55.295038 -56.971184)
		(width 0.11684)
		(layer "F.Cu")
		(net "TP_BMC_SPICS2_N")
	)
	(via
		(at 54.099714 -57.37606)
		(size 0.4572)
		(drill 0.254)
		(layers "F.Cu" "B.Cu")
		(net "TP_BMC_SPICS2_N")
	)
	(segment
		(start 56.894984 -56.971184)
		(end 56.49976 -57.366408)
		(width 0.11684)
		(layer "F.Cu")
		(net "SPI_BMC_TPM_MOSI_R1")
	)
	(via
		(at 56.49976 -57.366408)
		(size 0.4572)
		(drill 0.254)
		(layers "F.Cu" "B.Cu")
		(net "SPI_BMC_TPM_MOSI_R1")
	)
	(via
		(at 66.5734 -71.2978)
		(size 0.762)
		(drill 0.254)
		(layers "F.Cu" "B.Cu")
		(net "SPI_BMC_TPM_MOSI_R1")
	)
	(segment
		(start 66.4718 -71.542656)
		(end 66.4718 -72.04075)
		(width 0.11684)
		(layer "B.Cu")
		(net "SPI_BMC_TPM_MOSI_R1")
	)
	(segment
		(start 66.4718 -72.04075)
		(end 66.4972 -72.06615)
		(width 0.11684)
		(layer "B.Cu")
		(net "SPI_BMC_TPM_MOSI_R1")
	)
	(segment
		(start 66.5734 -71.2978)
		(end 66.4718 -71.542656)
		(width 0.11684)
		(layer "B.Cu")
		(net "SPI_BMC_TPM_MOSI_R1")
	)
	(segment
		(start 57.7088 -57.1246)
		(end 57.5564 -56.9722)
		(width 0.08382)
		(layer "In9.Cu")
		(net "SPI_BMC_TPM_MOSI_R1")
	)
	(segment
		(start 57.7088 -61.0108)
		(end 57.7088 -57.1246)
		(width 0.08382)
		(layer "In9.Cu")
		(net "SPI_BMC_TPM_MOSI_R1")
	)
	(segment
		(start 64.72936 -71.30796)
		(end 64.72936 -70.575678)
		(width 0.08382)
		(layer "In9.Cu")
		(net "SPI_BMC_TPM_MOSI_R1")
	)
	(segment
		(start 61.902594 -66.272664)
		(end 59.762644 -66.272664)
		(width 0.08382)
		(layer "In9.Cu")
		(net "SPI_BMC_TPM_MOSI_R1")
	)
	(segment
		(start 59.762644 -66.272664)
		(end 59.22264 -65.73266)
		(width 0.08382)
		(layer "In9.Cu")
		(net "SPI_BMC_TPM_MOSI_R1")
	)
	(segment
		(start 66.5734 -71.2978)
		(end 66.1416 -71.7296)
		(width 0.08382)
		(layer "In9.Cu")
		(net "SPI_BMC_TPM_MOSI_R1")
	)
	(segment
		(start 64.9478 -70.357238)
		(end 64.9478 -69.31787)
		(width 0.08382)
		(layer "In9.Cu")
		(net "SPI_BMC_TPM_MOSI_R1")
	)
	(segment
		(start 57.5564 -56.9722)
		(end 56.893968 -56.9722)
		(width 0.08382)
		(layer "In9.Cu")
		(net "SPI_BMC_TPM_MOSI_R1")
	)
	(segment
		(start 58.00598 -61.30798)
		(end 57.7088 -61.0108)
		(width 0.08382)
		(layer "In9.Cu")
		(net "SPI_BMC_TPM_MOSI_R1")
	)
	(segment
		(start 59.22264 -65.73266)
		(end 59.22264 -64.24168)
		(width 0.08382)
		(layer "In9.Cu")
		(net "SPI_BMC_TPM_MOSI_R1")
	)
	(segment
		(start 56.893968 -56.9722)
		(end 56.49976 -57.366408)
		(width 0.08382)
		(layer "In9.Cu")
		(net "SPI_BMC_TPM_MOSI_R1")
	)
	(segment
		(start 58.00598 -63.02502)
		(end 58.00598 -61.30798)
		(width 0.08382)
		(layer "In9.Cu")
		(net "SPI_BMC_TPM_MOSI_R1")
	)
	(segment
		(start 65.151 -71.7296)
		(end 64.72936 -71.30796)
		(width 0.08382)
		(layer "In9.Cu")
		(net "SPI_BMC_TPM_MOSI_R1")
	)
	(segment
		(start 64.72936 -70.575678)
		(end 64.9478 -70.357238)
		(width 0.08382)
		(layer "In9.Cu")
		(net "SPI_BMC_TPM_MOSI_R1")
	)
	(segment
		(start 64.9478 -69.31787)
		(end 61.902594 -66.272664)
		(width 0.08382)
		(layer "In9.Cu")
		(net "SPI_BMC_TPM_MOSI_R1")
	)
	(segment
		(start 59.22264 -64.24168)
		(end 58.00598 -63.02502)
		(width 0.08382)
		(layer "In9.Cu")
		(net "SPI_BMC_TPM_MOSI_R1")
	)
	(segment
		(start 66.1416 -71.7296)
		(end 65.151 -71.7296)
		(width 0.08382)
		(layer "In9.Cu")
		(net "SPI_BMC_TPM_MOSI_R1")
	)
	(segment
		(start 84.60105 -94.488)
		(end 85.2678 -94.488)
		(width 0.11684)
		(layer "F.Cu")
		(net "SPI_BMC_TPM_MOSI")
	)
	(segment
		(start 85.2678 -94.488)
		(end 85.269832 -94.490032)
		(width 0.11684)
		(layer "F.Cu")
		(net "SPI_BMC_TPM_MOSI")
	)
	(via
		(at 66.421 -73.77176)
		(size 0.508)
		(drill 0.254)
		(layers "F.Cu" "B.Cu")
		(net "SPI_BMC_TPM_MOSI")
	)
	(via
		(at 85.269832 -94.490032)
		(size 0.508)
		(drill 0.254)
		(layers "F.Cu" "B.Cu")
		(net "SPI_BMC_TPM_MOSI")
	)
	(via
		(at 62.17666 -95.48114)
		(size 0.508)
		(drill 0.254)
		(layers "F.Cu" "B.Cu")
		(net "SPI_BMC_TPM_MOSI")
	)
	(via
		(at 72.129142 -97.168462)
		(size 0.508)
		(drill 0.254)
		(layers "F.Cu" "B.Cu")
		(net "SPI_BMC_TPM_MOSI")
	)
	(segment
		(start 72.625204 -96.6724)
		(end 74.549 -96.6724)
		(width 0.11684)
		(layer "B.Cu")
		(net "SPI_BMC_TPM_MOSI")
	)
	(segment
		(start 83.82 -92.583)
		(end 83.3628 -92.1258)
		(width 0.11684)
		(layer "B.Cu")
		(net "SPI_BMC_TPM_MOSI")
	)
	(segment
		(start 66.4972 -72.86625)
		(end 66.421 -72.94245)
		(width 0.11684)
		(layer "B.Cu")
		(net "SPI_BMC_TPM_MOSI")
	)
	(segment
		(start 78.7146 -92.6846)
		(end 77.4192 -92.6846)
		(width 0.11684)
		(layer "B.Cu")
		(net "SPI_BMC_TPM_MOSI")
	)
	(segment
		(start 74.7522 -96.8756)
		(end 74.7522 -97.16516)
		(width 0.11684)
		(layer "B.Cu")
		(net "SPI_BMC_TPM_MOSI")
	)
	(segment
		(start 75.665838 -96.596962)
		(end 75.665838 -97.509838)
		(width 0.11684)
		(layer "B.Cu")
		(net "SPI_BMC_TPM_MOSI")
	)
	(segment
		(start 85.269832 -94.490032)
		(end 83.82 -93.0402)
		(width 0.11684)
		(layer "B.Cu")
		(net "SPI_BMC_TPM_MOSI")
	)
	(segment
		(start 77.4192 -92.6846)
		(end 76.9874 -93.1164)
		(width 0.11684)
		(layer "B.Cu")
		(net "SPI_BMC_TPM_MOSI")
	)
	(segment
		(start 66.421 -72.94245)
		(end 66.421 -73.77176)
		(width 0.11684)
		(layer "B.Cu")
		(net "SPI_BMC_TPM_MOSI")
	)
	(segment
		(start 76.9874 -95.2754)
		(end 75.665838 -96.596962)
		(width 0.11684)
		(layer "B.Cu")
		(net "SPI_BMC_TPM_MOSI")
	)
	(segment
		(start 75.096878 -97.509838)
		(end 75.665838 -97.509838)
		(width 0.11684)
		(layer "B.Cu")
		(net "SPI_BMC_TPM_MOSI")
	)
	(segment
		(start 76.9874 -93.1164)
		(end 76.9874 -95.2754)
		(width 0.11684)
		(layer "B.Cu")
		(net "SPI_BMC_TPM_MOSI")
	)
	(segment
		(start 79.2734 -92.1258)
		(end 78.7146 -92.6846)
		(width 0.11684)
		(layer "B.Cu")
		(net "SPI_BMC_TPM_MOSI")
	)
	(segment
		(start 74.549 -96.6724)
		(end 74.7522 -96.8756)
		(width 0.11684)
		(layer "B.Cu")
		(net "SPI_BMC_TPM_MOSI")
	)
	(segment
		(start 83.82 -93.0402)
		(end 83.82 -92.583)
		(width 0.11684)
		(layer "B.Cu")
		(net "SPI_BMC_TPM_MOSI")
	)
	(segment
		(start 83.3628 -92.1258)
		(end 79.2734 -92.1258)
		(width 0.11684)
		(layer "B.Cu")
		(net "SPI_BMC_TPM_MOSI")
	)
	(segment
		(start 72.129142 -97.168462)
		(end 72.625204 -96.6724)
		(width 0.11684)
		(layer "B.Cu")
		(net "SPI_BMC_TPM_MOSI")
	)
	(segment
		(start 74.7522 -97.16516)
		(end 75.096878 -97.509838)
		(width 0.11684)
		(layer "B.Cu")
		(net "SPI_BMC_TPM_MOSI")
	)
	(segment
		(start 72.263 -95.76054)
		(end 71.52386 -95.76054)
		(width 0.08382)
		(layer "In2.Cu")
		(net "SPI_BMC_TPM_MOSI")
	)
	(segment
		(start 67.606418 -96.3422)
		(end 65.527428 -95.48114)
		(width 0.08382)
		(layer "In2.Cu")
		(net "SPI_BMC_TPM_MOSI")
	)
	(segment
		(start 71.52386 -95.76054)
		(end 70.9422 -96.3422)
		(width 0.08382)
		(layer "In2.Cu")
		(net "SPI_BMC_TPM_MOSI")
	)
	(segment
		(start 72.61098 -96.686624)
		(end 72.61098 -96.10852)
		(width 0.08382)
		(layer "In2.Cu")
		(net "SPI_BMC_TPM_MOSI")
	)
	(segment
		(start 72.129142 -97.168462)
		(end 72.61098 -96.686624)
		(width 0.08382)
		(layer "In2.Cu")
		(net "SPI_BMC_TPM_MOSI")
	)
	(segment
		(start 70.9422 -96.3422)
		(end 67.606418 -96.3422)
		(width 0.08382)
		(layer "In2.Cu")
		(net "SPI_BMC_TPM_MOSI")
	)
	(segment
		(start 72.61098 -96.10852)
		(end 72.263 -95.76054)
		(width 0.08382)
		(layer "In2.Cu")
		(net "SPI_BMC_TPM_MOSI")
	)
	(segment
		(start 65.527428 -95.48114)
		(end 62.17666 -95.48114)
		(width 0.08382)
		(layer "In2.Cu")
		(net "SPI_BMC_TPM_MOSI")
	)
	(segment
		(start 64.89954 -82.725006)
		(end 63.08598 -84.538566)
		(width 0.08382)
		(layer "In9.Cu")
		(net "SPI_BMC_TPM_MOSI")
	)
	(segment
		(start 63.06439 -84.636864)
		(end 63.06439 -94.59341)
		(width 0.08382)
		(layer "In9.Cu")
		(net "SPI_BMC_TPM_MOSI")
	)
	(segment
		(start 66.421 -73.77176)
		(end 66.10731 -74.08545)
		(width 0.08382)
		(layer "In9.Cu")
		(net "SPI_BMC_TPM_MOSI")
	)
	(segment
		(start 63.08598 -84.615274)
		(end 63.06439 -84.636864)
		(width 0.08382)
		(layer "In9.Cu")
		(net "SPI_BMC_TPM_MOSI")
	)
	(segment
		(start 64.516 -78.9178)
		(end 64.516 -79.7814)
		(width 0.08382)
		(layer "In9.Cu")
		(net "SPI_BMC_TPM_MOSI")
	)
	(segment
		(start 66.10731 -77.32649)
		(end 64.516 -78.9178)
		(width 0.08382)
		(layer "In9.Cu")
		(net "SPI_BMC_TPM_MOSI")
	)
	(segment
		(start 63.06439 -94.59341)
		(end 62.17666 -95.48114)
		(width 0.08382)
		(layer "In9.Cu")
		(net "SPI_BMC_TPM_MOSI")
	)
	(segment
		(start 64.89954 -80.16494)
		(end 64.89954 -82.725006)
		(width 0.08382)
		(layer "In9.Cu")
		(net "SPI_BMC_TPM_MOSI")
	)
	(segment
		(start 63.08598 -84.538566)
		(end 63.08598 -84.615274)
		(width 0.08382)
		(layer "In9.Cu")
		(net "SPI_BMC_TPM_MOSI")
	)
	(segment
		(start 66.10731 -74.08545)
		(end 66.10731 -77.32649)
		(width 0.08382)
		(layer "In9.Cu")
		(net "SPI_BMC_TPM_MOSI")
	)
	(segment
		(start 64.516 -79.7814)
		(end 64.89954 -80.16494)
		(width 0.08382)
		(layer "In9.Cu")
		(net "SPI_BMC_TPM_MOSI")
	)
	(segment
		(start 84.963 -96.774)
		(end 84.60105 -96.774)
		(width 0.11684)
		(layer "F.Cu")
		(net "SPI_BMC_TPM_MISO")
	)
	(segment
		(start 85.217 -96.52)
		(end 84.963 -96.774)
		(width 0.11684)
		(layer "F.Cu")
		(net "SPI_BMC_TPM_MISO")
	)
	(segment
		(start 84.60105 -96.774)
		(end 84.60105 -95.631)
		(width 0.11684)
		(layer "F.Cu")
		(net "SPI_BMC_TPM_MISO")
	)
	(via
		(at 64.34328 -82.125058)
		(size 0.508)
		(drill 0.254)
		(layers "F.Cu" "B.Cu")
		(net "SPI_BMC_TPM_MISO")
	)
	(via
		(at 62.85738 -68.57746)
		(size 0.508)
		(drill 0.254)
		(layers "F.Cu" "B.Cu")
		(net "SPI_BMC_TPM_MISO")
	)
	(via
		(at 85.217 -96.52)
		(size 0.508)
		(drill 0.254)
		(layers "F.Cu" "B.Cu")
		(net "SPI_BMC_TPM_MISO")
	)
	(segment
		(start 62.85738 -68.57746)
		(end 62.85738 -67.884294)
		(width 0.11684)
		(layer "B.Cu")
		(net "SPI_BMC_TPM_MISO")
	)
	(segment
		(start 62.85738 -67.884294)
		(end 61.64326 -66.670174)
		(width 0.11684)
		(layer "B.Cu")
		(net "SPI_BMC_TPM_MISO")
	)
	(segment
		(start 61.64326 -66.670174)
		(end 61.64326 -66.2559)
		(width 0.11684)
		(layer "B.Cu")
		(net "SPI_BMC_TPM_MISO")
	)
	(segment
		(start 76.291694 -101.958648)
		(end 76.088494 -101.958648)
		(width 0.10668)
		(layer "In7.Cu")
		(net "SPI_BMC_TPM_MISO")
	)
	(segment
		(start 65.3034 -86.29904)
		(end 65.63614 -85.9663)
		(width 0.10668)
		(layer "In7.Cu")
		(net "SPI_BMC_TPM_MISO")
	)
	(segment
		(start 76.435204 -102.102158)
		(end 76.291694 -101.958648)
		(width 0.10668)
		(layer "In7.Cu")
		(net "SPI_BMC_TPM_MISO")
	)
	(segment
		(start 85.54974 -96.85274)
		(end 85.54974 -97.590864)
		(width 0.10668)
		(layer "In7.Cu")
		(net "SPI_BMC_TPM_MISO")
	)
	(segment
		(start 69.13626 -95.457264)
		(end 69.13626 -93.064584)
		(width 0.10668)
		(layer "In7.Cu")
		(net "SPI_BMC_TPM_MISO")
	)
	(segment
		(start 76.088494 -101.958648)
		(end 75.944984 -102.102158)
		(width 0.10668)
		(layer "In7.Cu")
		(net "SPI_BMC_TPM_MISO")
	)
	(segment
		(start 79.66583 -99.417886)
		(end 77.905864 -101.177852)
		(width 0.10668)
		(layer "In7.Cu")
		(net "SPI_BMC_TPM_MISO")
	)
	(segment
		(start 76.578714 -102.8446)
		(end 76.435204 -102.70109)
		(width 0.10668)
		(layer "In7.Cu")
		(net "SPI_BMC_TPM_MISO")
	)
	(segment
		(start 75.801474 -102.8446)
		(end 75.598274 -102.8446)
		(width 0.10668)
		(layer "In7.Cu")
		(net "SPI_BMC_TPM_MISO")
	)
	(segment
		(start 77.905864 -101.177852)
		(end 77.905864 -102.92969)
		(width 0.10668)
		(layer "In7.Cu")
		(net "SPI_BMC_TPM_MISO")
	)
	(segment
		(start 82.863944 -99.651312)
		(end 81.845912 -99.651312)
		(width 0.10668)
		(layer "In7.Cu")
		(net "SPI_BMC_TPM_MISO")
	)
	(segment
		(start 77.415644 -102.102158)
		(end 77.272134 -101.958648)
		(width 0.10668)
		(layer "In7.Cu")
		(net "SPI_BMC_TPM_MISO")
	)
	(segment
		(start 77.272134 -101.958648)
		(end 77.068934 -101.958648)
		(width 0.10668)
		(layer "In7.Cu")
		(net "SPI_BMC_TPM_MISO")
	)
	(segment
		(start 85.217 -96.52)
		(end 85.54974 -96.85274)
		(width 0.10668)
		(layer "In7.Cu")
		(net "SPI_BMC_TPM_MISO")
	)
	(segment
		(start 77.068934 -101.958648)
		(end 76.925424 -102.102158)
		(width 0.10668)
		(layer "In7.Cu")
		(net "SPI_BMC_TPM_MISO")
	)
	(segment
		(start 70.70852 -96.54032)
		(end 70.217538 -96.049338)
		(width 0.10668)
		(layer "In7.Cu")
		(net "SPI_BMC_TPM_MISO")
	)
	(segment
		(start 65.3034 -89.231724)
		(end 65.3034 -86.29904)
		(width 0.10668)
		(layer "In7.Cu")
		(net "SPI_BMC_TPM_MISO")
	)
	(segment
		(start 65.63614 -85.9663)
		(end 65.63614 -83.665822)
		(width 0.10668)
		(layer "In7.Cu")
		(net "SPI_BMC_TPM_MISO")
	)
	(segment
		(start 76.435204 -102.70109)
		(end 76.435204 -102.102158)
		(width 0.10668)
		(layer "In7.Cu")
		(net "SPI_BMC_TPM_MISO")
	)
	(segment
		(start 70.70852 -98.503486)
		(end 70.70852 -96.54032)
		(width 0.10668)
		(layer "In7.Cu")
		(net "SPI_BMC_TPM_MISO")
	)
	(segment
		(start 75.454764 -102.102158)
		(end 75.311254 -101.958648)
		(width 0.10668)
		(layer "In7.Cu")
		(net "SPI_BMC_TPM_MISO")
	)
	(segment
		(start 75.454764 -102.70109)
		(end 75.454764 -102.102158)
		(width 0.10668)
		(layer "In7.Cu")
		(net "SPI_BMC_TPM_MISO")
	)
	(segment
		(start 81.845912 -99.651312)
		(end 81.612486 -99.417886)
		(width 0.10668)
		(layer "In7.Cu")
		(net "SPI_BMC_TPM_MISO")
	)
	(segment
		(start 76.925424 -102.70109)
		(end 76.781914 -102.8446)
		(width 0.10668)
		(layer "In7.Cu")
		(net "SPI_BMC_TPM_MISO")
	)
	(segment
		(start 85.54974 -97.590864)
		(end 85.221064 -97.91954)
		(width 0.10668)
		(layer "In7.Cu")
		(net "SPI_BMC_TPM_MISO")
	)
	(segment
		(start 81.612486 -99.417886)
		(end 79.66583 -99.417886)
		(width 0.10668)
		(layer "In7.Cu")
		(net "SPI_BMC_TPM_MISO")
	)
	(segment
		(start 77.584554 -103.0478)
		(end 77.415644 -102.87889)
		(width 0.10668)
		(layer "In7.Cu")
		(net "SPI_BMC_TPM_MISO")
	)
	(segment
		(start 64.34328 -82.372962)
		(end 64.34328 -82.125058)
		(width 0.10668)
		(layer "In7.Cu")
		(net "SPI_BMC_TPM_MISO")
	)
	(segment
		(start 77.787754 -103.0478)
		(end 77.584554 -103.0478)
		(width 0.10668)
		(layer "In7.Cu")
		(net "SPI_BMC_TPM_MISO")
	)
	(segment
		(start 71.01586 -99.245674)
		(end 70.70852 -98.503486)
		(width 0.10668)
		(layer "In7.Cu")
		(net "SPI_BMC_TPM_MISO")
	)
	(segment
		(start 75.311254 -101.958648)
		(end 72.746616 -101.958648)
		(width 0.10668)
		(layer "In7.Cu")
		(net "SPI_BMC_TPM_MISO")
	)
	(segment
		(start 85.221064 -97.91954)
		(end 84.595716 -97.91954)
		(width 0.10668)
		(layer "In7.Cu")
		(net "SPI_BMC_TPM_MISO")
	)
	(segment
		(start 71.01586 -100.227892)
		(end 71.01586 -99.245674)
		(width 0.10668)
		(layer "In7.Cu")
		(net "SPI_BMC_TPM_MISO")
	)
	(segment
		(start 84.595716 -97.91954)
		(end 82.863944 -99.651312)
		(width 0.10668)
		(layer "In7.Cu")
		(net "SPI_BMC_TPM_MISO")
	)
	(segment
		(start 69.13626 -93.064584)
		(end 65.3034 -89.231724)
		(width 0.10668)
		(layer "In7.Cu")
		(net "SPI_BMC_TPM_MISO")
	)
	(segment
		(start 77.415644 -102.87889)
		(end 77.415644 -102.102158)
		(width 0.10668)
		(layer "In7.Cu")
		(net "SPI_BMC_TPM_MISO")
	)
	(segment
		(start 75.944984 -102.70109)
		(end 75.801474 -102.8446)
		(width 0.10668)
		(layer "In7.Cu")
		(net "SPI_BMC_TPM_MISO")
	)
	(segment
		(start 75.944984 -102.102158)
		(end 75.944984 -102.70109)
		(width 0.10668)
		(layer "In7.Cu")
		(net "SPI_BMC_TPM_MISO")
	)
	(segment
		(start 69.728334 -96.049338)
		(end 69.13626 -95.457264)
		(width 0.10668)
		(layer "In7.Cu")
		(net "SPI_BMC_TPM_MISO")
	)
	(segment
		(start 76.781914 -102.8446)
		(end 76.578714 -102.8446)
		(width 0.10668)
		(layer "In7.Cu")
		(net "SPI_BMC_TPM_MISO")
	)
	(segment
		(start 70.217538 -96.049338)
		(end 69.728334 -96.049338)
		(width 0.10668)
		(layer "In7.Cu")
		(net "SPI_BMC_TPM_MISO")
	)
	(segment
		(start 77.905864 -102.92969)
		(end 77.787754 -103.0478)
		(width 0.10668)
		(layer "In7.Cu")
		(net "SPI_BMC_TPM_MISO")
	)
	(segment
		(start 65.63614 -83.665822)
		(end 64.34328 -82.372962)
		(width 0.10668)
		(layer "In7.Cu")
		(net "SPI_BMC_TPM_MISO")
	)
	(segment
		(start 72.746616 -101.958648)
		(end 71.01586 -100.227892)
		(width 0.10668)
		(layer "In7.Cu")
		(net "SPI_BMC_TPM_MISO")
	)
	(segment
		(start 76.925424 -102.102158)
		(end 76.925424 -102.70109)
		(width 0.10668)
		(layer "In7.Cu")
		(net "SPI_BMC_TPM_MISO")
	)
	(segment
		(start 75.598274 -102.8446)
		(end 75.454764 -102.70109)
		(width 0.10668)
		(layer "In7.Cu")
		(net "SPI_BMC_TPM_MISO")
	)
	(segment
		(start 62.85738 -69.564758)
		(end 62.85738 -68.57746)
		(width 0.08382)
		(layer "In9.Cu")
		(net "SPI_BMC_TPM_MISO")
	)
	(segment
		(start 64.34328 -82.125058)
		(end 64.34328 -80.14208)
		(width 0.08382)
		(layer "In9.Cu")
		(net "SPI_BMC_TPM_MISO")
	)
	(segment
		(start 65.3034 -76.073)
		(end 64.656716 -75.426316)
		(width 0.08382)
		(layer "In9.Cu")
		(net "SPI_BMC_TPM_MISO")
	)
	(segment
		(start 64.656716 -75.426316)
		(end 64.656716 -71.971662)
		(width 0.08382)
		(layer "In9.Cu")
		(net "SPI_BMC_TPM_MISO")
	)
	(segment
		(start 64.34328 -80.14208)
		(end 64.1096 -79.9084)
		(width 0.08382)
		(layer "In9.Cu")
		(net "SPI_BMC_TPM_MISO")
	)
	(segment
		(start 64.1096 -79.9084)
		(end 64.1096 -78.8416)
		(width 0.08382)
		(layer "In9.Cu")
		(net "SPI_BMC_TPM_MISO")
	)
	(segment
		(start 64.3128 -71.627746)
		(end 64.3128 -71.020178)
		(width 0.08382)
		(layer "In9.Cu")
		(net "SPI_BMC_TPM_MISO")
	)
	(segment
		(start 64.3128 -71.020178)
		(end 62.85738 -69.564758)
		(width 0.08382)
		(layer "In9.Cu")
		(net "SPI_BMC_TPM_MISO")
	)
	(segment
		(start 64.656716 -71.971662)
		(end 64.3128 -71.627746)
		(width 0.08382)
		(layer "In9.Cu")
		(net "SPI_BMC_TPM_MISO")
	)
	(segment
		(start 65.3034 -77.6478)
		(end 65.3034 -76.073)
		(width 0.08382)
		(layer "In9.Cu")
		(net "SPI_BMC_TPM_MISO")
	)
	(segment
		(start 64.1096 -78.8416)
		(end 65.3034 -77.6478)
		(width 0.08382)
		(layer "In9.Cu")
		(net "SPI_BMC_TPM_MISO")
	)
	(segment
		(start 84.60105 -91.059)
		(end 85.21065 -91.059)
		(width 0.11684)
		(layer "F.Cu")
		(net "SPI_BMC_TPM_CLK")
	)
	(segment
		(start 66.41465 -66.0146)
		(end 66.7258 -66.32575)
		(width 0.11684)
		(layer "F.Cu")
		(net "SPI_BMC_TPM_CLK")
	)
	(segment
		(start 84.60105 -91.059)
		(end 84.60105 -92.202)
		(width 0.11684)
		(layer "F.Cu")
		(net "SPI_BMC_TPM_CLK")
	)
	(segment
		(start 66.7258 -66.32575)
		(end 66.7258 -67.3354)
		(width 0.11684)
		(layer "F.Cu")
		(net "SPI_BMC_TPM_CLK")
	)
	(via
		(at 85.21065 -91.059)
		(size 0.508)
		(drill 0.254)
		(layers "F.Cu" "B.Cu")
		(net "SPI_BMC_TPM_CLK")
	)
	(via
		(at 65.5066 -79.2734)
		(size 0.762)
		(drill 0.254)
		(layers "F.Cu" "B.Cu")
		(net "SPI_BMC_TPM_CLK")
	)
	(via
		(at 66.7258 -67.3354)
		(size 0.508)
		(drill 0.254)
		(layers "F.Cu" "B.Cu")
		(net "SPI_BMC_TPM_CLK")
	)
	(segment
		(start 79.403194 -99.006406)
		(end 76.862432 -101.547168)
		(width 0.10668)
		(layer "In7.Cu")
		(net "SPI_BMC_TPM_CLK")
	)
	(segment
		(start 84.20608 -92.06357)
		(end 84.20608 -95.598488)
		(width 0.10668)
		(layer "In7.Cu")
		(net "SPI_BMC_TPM_CLK")
	)
	(segment
		(start 69.32803 -91.400376)
		(end 69.316092 -91.39047)
		(width 0.10668)
		(layer "In7.Cu")
		(net "SPI_BMC_TPM_CLK")
	)
	(segment
		(start 76.862432 -101.547168)
		(end 72.917304 -101.547168)
		(width 0.10668)
		(layer "In7.Cu")
		(net "SPI_BMC_TPM_CLK")
	)
	(segment
		(start 83.566 -97.078546)
		(end 83.21294 -97.431606)
		(width 0.10668)
		(layer "In7.Cu")
		(net "SPI_BMC_TPM_CLK")
	)
	(segment
		(start 69.3039 -91.3892)
		(end 68.070984 -91.3892)
		(width 0.10668)
		(layer "In7.Cu")
		(net "SPI_BMC_TPM_CLK")
	)
	(segment
		(start 83.566 -96.238568)
		(end 83.566 -97.078546)
		(width 0.10668)
		(layer "In7.Cu")
		(net "SPI_BMC_TPM_CLK")
	)
	(segment
		(start 71.020178 -96.081596)
		(end 71.020178 -93.092524)
		(width 0.10668)
		(layer "In7.Cu")
		(net "SPI_BMC_TPM_CLK")
	)
	(segment
		(start 64.95542 -82.402934)
		(end 64.95542 -79.824834)
		(width 0.10668)
		(layer "In7.Cu")
		(net "SPI_BMC_TPM_CLK")
	)
	(segment
		(start 71.4502 -99.121976)
		(end 71.12 -98.32467)
		(width 0.10668)
		(layer "In7.Cu")
		(net "SPI_BMC_TPM_CLK")
	)
	(segment
		(start 71.020178 -93.092524)
		(end 69.32803 -91.400376)
		(width 0.10668)
		(layer "In7.Cu")
		(net "SPI_BMC_TPM_CLK")
	)
	(segment
		(start 67.05727 -84.506816)
		(end 67.047364 -84.494878)
		(width 0.10668)
		(layer "In7.Cu")
		(net "SPI_BMC_TPM_CLK")
	)
	(segment
		(start 68.070984 -91.3892)
		(end 66.7004 -90.018616)
		(width 0.10668)
		(layer "In7.Cu")
		(net "SPI_BMC_TPM_CLK")
	)
	(segment
		(start 67.05854 -84.519008)
		(end 67.05727 -84.506816)
		(width 0.10668)
		(layer "In7.Cu")
		(net "SPI_BMC_TPM_CLK")
	)
	(segment
		(start 66.7004 -85.4202)
		(end 67.04838 -85.07222)
		(width 0.10668)
		(layer "In7.Cu")
		(net "SPI_BMC_TPM_CLK")
	)
	(segment
		(start 85.21065 -91.059)
		(end 84.20608 -92.06357)
		(width 0.10668)
		(layer "In7.Cu")
		(net "SPI_BMC_TPM_CLK")
	)
	(segment
		(start 72.917304 -101.547168)
		(end 71.4502 -100.080064)
		(width 0.10668)
		(layer "In7.Cu")
		(net "SPI_BMC_TPM_CLK")
	)
	(segment
		(start 83.21294 -97.764346)
		(end 82.854546 -98.12274)
		(width 0.10668)
		(layer "In7.Cu")
		(net "SPI_BMC_TPM_CLK")
	)
	(segment
		(start 71.12 -98.32467)
		(end 71.12 -96.181418)
		(width 0.10668)
		(layer "In7.Cu")
		(net "SPI_BMC_TPM_CLK")
	)
	(segment
		(start 81.84896 -99.006406)
		(end 79.403194 -99.006406)
		(width 0.10668)
		(layer "In7.Cu")
		(net "SPI_BMC_TPM_CLK")
	)
	(segment
		(start 67.05727 -85.061298)
		(end 67.05854 -85.049106)
		(width 0.10668)
		(layer "In7.Cu")
		(net "SPI_BMC_TPM_CLK")
	)
	(segment
		(start 67.047364 -84.494878)
		(end 64.95542 -82.402934)
		(width 0.10668)
		(layer "In7.Cu")
		(net "SPI_BMC_TPM_CLK")
	)
	(segment
		(start 82.732626 -98.12274)
		(end 81.84896 -99.006406)
		(width 0.10668)
		(layer "In7.Cu")
		(net "SPI_BMC_TPM_CLK")
	)
	(segment
		(start 67.04838 -85.07222)
		(end 67.05727 -85.061298)
		(width 0.10668)
		(layer "In7.Cu")
		(net "SPI_BMC_TPM_CLK")
	)
	(segment
		(start 65.2526 -79.5274)
		(end 65.5066 -79.2734)
		(width 0.10668)
		(layer "In7.Cu")
		(net "SPI_BMC_TPM_CLK")
	)
	(segment
		(start 82.854546 -98.12274)
		(end 82.732626 -98.12274)
		(width 0.10668)
		(layer "In7.Cu")
		(net "SPI_BMC_TPM_CLK")
	)
	(segment
		(start 71.4502 -100.080064)
		(end 71.4502 -99.121976)
		(width 0.10668)
		(layer "In7.Cu")
		(net "SPI_BMC_TPM_CLK")
	)
	(segment
		(start 66.7004 -90.018616)
		(end 66.7004 -85.4202)
		(width 0.10668)
		(layer "In7.Cu")
		(net "SPI_BMC_TPM_CLK")
	)
	(segment
		(start 69.316092 -91.39047)
		(end 69.3039 -91.3892)
		(width 0.10668)
		(layer "In7.Cu")
		(net "SPI_BMC_TPM_CLK")
	)
	(segment
		(start 83.21294 -97.431606)
		(end 83.21294 -97.764346)
		(width 0.10668)
		(layer "In7.Cu")
		(net "SPI_BMC_TPM_CLK")
	)
	(segment
		(start 84.20608 -95.598488)
		(end 83.566 -96.238568)
		(width 0.10668)
		(layer "In7.Cu")
		(net "SPI_BMC_TPM_CLK")
	)
	(segment
		(start 67.05854 -85.049106)
		(end 67.05854 -84.519008)
		(width 0.10668)
		(layer "In7.Cu")
		(net "SPI_BMC_TPM_CLK")
	)
	(segment
		(start 64.95542 -79.824834)
		(end 65.2526 -79.5274)
		(width 0.10668)
		(layer "In7.Cu")
		(net "SPI_BMC_TPM_CLK")
	)
	(segment
		(start 71.12 -96.181418)
		(end 71.020178 -96.081596)
		(width 0.10668)
		(layer "In7.Cu")
		(net "SPI_BMC_TPM_CLK")
	)
	(segment
		(start 67.5132 -74.0918)
		(end 67.5132 -69.59981)
		(width 0.08382)
		(layer "In9.Cu")
		(net "SPI_BMC_TPM_CLK")
	)
	(segment
		(start 66.446654 -67.3354)
		(end 66.7258 -67.3354)
		(width 0.08382)
		(layer "In9.Cu")
		(net "SPI_BMC_TPM_CLK")
	)
	(segment
		(start 67.5132 -69.59981)
		(end 66.13271 -68.21932)
		(width 0.08382)
		(layer "In9.Cu")
		(net "SPI_BMC_TPM_CLK")
	)
	(segment
		(start 67.01409 -74.59091)
		(end 67.5132 -74.0918)
		(width 0.08382)
		(layer "In9.Cu")
		(net "SPI_BMC_TPM_CLK")
	)
	(segment
		(start 66.13271 -67.649344)
		(end 66.446654 -67.3354)
		(width 0.08382)
		(layer "In9.Cu")
		(net "SPI_BMC_TPM_CLK")
	)
	(segment
		(start 66.13271 -68.21932)
		(end 66.13271 -67.649344)
		(width 0.08382)
		(layer "In9.Cu")
		(net "SPI_BMC_TPM_CLK")
	)
	(segment
		(start 65.5066 -79.2734)
		(end 67.01409 -77.76591)
		(width 0.08382)
		(layer "In9.Cu")
		(net "SPI_BMC_TPM_CLK")
	)
	(segment
		(start 67.01409 -77.76591)
		(end 67.01409 -74.59091)
		(width 0.08382)
		(layer "In9.Cu")
		(net "SPI_BMC_TPM_CLK")
	)
	(segment
		(start 16.690086 -13.949426)
		(end 16.690086 -13.269976)
		(width 0.11684)
		(layer "B.Cu")
		(net "SMB_TMP421_BMC_MM2_SDA")
	)
	(segment
		(start 16.497046 -14.142466)
		(end 16.690086 -13.949426)
		(width 0.11684)
		(layer "B.Cu")
		(net "SMB_TMP421_BMC_MM2_SDA")
	)
	(segment
		(start 16.383 -17.50695)
		(end 16.497046 -17.392904)
		(width 0.11684)
		(layer "B.Cu")
		(net "SMB_TMP421_BMC_MM2_SDA")
	)
	(segment
		(start 16.497046 -17.392904)
		(end 16.497046 -14.142466)
		(width 0.11684)
		(layer "B.Cu")
		(net "SMB_TMP421_BMC_MM2_SDA")
	)
	(segment
		(start 17.898618 -14.601444)
		(end 17.898618 -17.790668)
		(width 0.11684)
		(layer "B.Cu")
		(net "SMB_TMP421_BMC_MM2_SCL")
	)
	(segment
		(start 19.230086 -13.269976)
		(end 17.898618 -14.601444)
		(width 0.11684)
		(layer "B.Cu")
		(net "SMB_TMP421_BMC_MM2_SCL")
	)
	(segment
		(start 17.898618 -17.790668)
		(end 18.415 -18.30705)
		(width 0.11684)
		(layer "B.Cu")
		(net "SMB_TMP421_BMC_MM2_SCL")
	)
	(via
		(at 10.20445 -7.547102)
		(size 0.6604)
		(drill 0.3302)
		(layers "F.Cu" "B.Cu")
		(net "PWR_LED_P5V_AUX")
	)
	(segment
		(start 16.228822 -6.291326)
		(end 15.866364 -6.291326)
		(width 0.11684)
		(layer "B.Cu")
		(net "PWR_LED_P5V_AUX")
	)
	(segment
		(start 15.113 -17.76095)
		(end 15.089632 -17.784318)
		(width 0.11684)
		(layer "B.Cu")
		(net "PWR_LED_P5V_AUX")
	)
	(segment
		(start 9.937496 -7.814056)
		(end 9.937496 -13.711682)
		(width 0.11684)
		(layer "B.Cu")
		(net "PWR_LED_P5V_AUX")
	)
	(segment
		(start 15.217648 -6.940042)
		(end 10.81151 -6.940042)
		(width 0.11684)
		(layer "B.Cu")
		(net "PWR_LED_P5V_AUX")
	)
	(segment
		(start 13.986764 -17.76095)
		(end 14.097 -17.76095)
		(width 0.11684)
		(layer "B.Cu")
		(net "PWR_LED_P5V_AUX")
	)
	(segment
		(start 16.230092 -6.290056)
		(end 16.228822 -6.291326)
		(width 0.11684)
		(layer "B.Cu")
		(net "PWR_LED_P5V_AUX")
	)
	(segment
		(start 10.20445 -7.547102)
		(end 9.937496 -7.814056)
		(width 0.11684)
		(layer "B.Cu")
		(net "PWR_LED_P5V_AUX")
	)
	(segment
		(start 14.120368 -17.784318)
		(end 14.097 -17.76095)
		(width 0.11684)
		(layer "B.Cu")
		(net "PWR_LED_P5V_AUX")
	)
	(segment
		(start 15.866364 -6.291326)
		(end 15.217648 -6.940042)
		(width 0.11684)
		(layer "B.Cu")
		(net "PWR_LED_P5V_AUX")
	)
	(segment
		(start 15.089632 -17.784318)
		(end 14.120368 -17.784318)
		(width 0.11684)
		(layer "B.Cu")
		(net "PWR_LED_P5V_AUX")
	)
	(segment
		(start 9.937496 -13.711682)
		(end 13.986764 -17.76095)
		(width 0.11684)
		(layer "B.Cu")
		(net "PWR_LED_P5V_AUX")
	)
	(segment
		(start 10.81151 -6.940042)
		(end 10.20445 -7.547102)
		(width 0.11684)
		(layer "B.Cu")
		(net "PWR_LED_P5V_AUX")
	)
	(via
		(at 20.010374 -16.41729)
		(size 0.6604)
		(drill 0.3302)
		(layers "F.Cu" "B.Cu")
		(net "PCH_BEEP_LED")
	)
	(via
		(at 13.7414 -113.9444)
		(size 0.508)
		(drill 0.254)
		(layers "F.Cu" "B.Cu")
		(net "PCH_BEEP_LED")
	)
	(via
		(at 13.7668 -6.4516)
		(size 0.508)
		(drill 0.254)
		(layers "F.Cu" "B.Cu")
		(net "PCH_BEEP_LED")
	)
	(segment
		(start 16.76781 -19.909028)
		(end 20.887944 -19.909028)
		(width 0.11684)
		(layer "B.Cu")
		(net "PCH_BEEP_LED")
	)
	(segment
		(start 20.79879 -15.628874)
		(end 20.79879 -12.425426)
		(width 0.11684)
		(layer "B.Cu")
		(net "PCH_BEEP_LED")
	)
	(segment
		(start 22.255226 -11.879326)
		(end 22.752812 -11.38174)
		(width 0.11684)
		(layer "B.Cu")
		(net "PCH_BEEP_LED")
	)
	(segment
		(start 20.010374 -16.41729)
		(end 20.79879 -15.628874)
		(width 0.11684)
		(layer "B.Cu")
		(net "PCH_BEEP_LED")
	)
	(segment
		(start 14.224 -22.8473)
		(end 14.622018 -22.449282)
		(width 0.11684)
		(layer "B.Cu")
		(net "PCH_BEEP_LED")
	)
	(segment
		(start 20.8534 -5.0292)
		(end 15.1892 -5.0292)
		(width 0.11684)
		(layer "B.Cu")
		(net "PCH_BEEP_LED")
	)
	(segment
		(start 9.6774 -107.2896)
		(end 13.7414 -111.3536)
		(width 0.11684)
		(layer "B.Cu")
		(net "PCH_BEEP_LED")
	)
	(segment
		(start 9.6774 -106.1212)
		(end 9.6774 -107.2896)
		(width 0.11684)
		(layer "B.Cu")
		(net "PCH_BEEP_LED")
	)
	(segment
		(start 9.82345 -105.97515)
		(end 9.6774 -106.1212)
		(width 0.11684)
		(layer "B.Cu")
		(net "PCH_BEEP_LED")
	)
	(segment
		(start 20.965668 -18.796)
		(end 20.447 -18.796)
		(width 0.11684)
		(layer "B.Cu")
		(net "PCH_BEEP_LED")
	)
	(segment
		(start 20.447 -18.796)
		(end 19.943318 -18.292318)
		(width 0.11684)
		(layer "B.Cu")
		(net "PCH_BEEP_LED")
	)
	(segment
		(start 14.622018 -22.449282)
		(end 15.252954 -22.449282)
		(width 0.11684)
		(layer "B.Cu")
		(net "PCH_BEEP_LED")
	)
	(segment
		(start 15.519908 -22.182328)
		(end 15.519908 -21.15693)
		(width 0.11684)
		(layer "B.Cu")
		(net "PCH_BEEP_LED")
	)
	(segment
		(start 19.943318 -16.484346)
		(end 20.010374 -16.41729)
		(width 0.11684)
		(layer "B.Cu")
		(net "PCH_BEEP_LED")
	)
	(segment
		(start 22.752812 -9.595612)
		(end 21.8186 -8.6614)
		(width 0.11684)
		(layer "B.Cu")
		(net "PCH_BEEP_LED")
	)
	(segment
		(start 19.943318 -18.292318)
		(end 19.943318 -16.484346)
		(width 0.11684)
		(layer "B.Cu")
		(net "PCH_BEEP_LED")
	)
	(segment
		(start 20.79879 -12.425426)
		(end 21.34489 -11.879326)
		(width 0.11684)
		(layer "B.Cu")
		(net "PCH_BEEP_LED")
	)
	(segment
		(start 10.2616 -105.97515)
		(end 11.2776 -105.97515)
		(width 0.11684)
		(layer "B.Cu")
		(net "PCH_BEEP_LED")
	)
	(segment
		(start 15.1892 -5.0292)
		(end 13.7668 -6.4516)
		(width 0.11684)
		(layer "B.Cu")
		(net "PCH_BEEP_LED")
	)
	(segment
		(start 10.2616 -105.97515)
		(end 9.82345 -105.97515)
		(width 0.11684)
		(layer "B.Cu")
		(net "PCH_BEEP_LED")
	)
	(segment
		(start 21.209 -19.039332)
		(end 20.965668 -18.796)
		(width 0.11684)
		(layer "B.Cu")
		(net "PCH_BEEP_LED")
	)
	(segment
		(start 14.224 -23.18004)
		(end 14.224 -22.8473)
		(width 0.11684)
		(layer "B.Cu")
		(net "PCH_BEEP_LED")
	)
	(segment
		(start 21.209 -19.587972)
		(end 21.209 -19.039332)
		(width 0.11684)
		(layer "B.Cu")
		(net "PCH_BEEP_LED")
	)
	(segment
		(start 15.252954 -22.449282)
		(end 15.519908 -22.182328)
		(width 0.11684)
		(layer "B.Cu")
		(net "PCH_BEEP_LED")
	)
	(segment
		(start 21.34489 -11.879326)
		(end 22.255226 -11.879326)
		(width 0.11684)
		(layer "B.Cu")
		(net "PCH_BEEP_LED")
	)
	(segment
		(start 22.752812 -11.38174)
		(end 22.752812 -9.595612)
		(width 0.11684)
		(layer "B.Cu")
		(net "PCH_BEEP_LED")
	)
	(segment
		(start 21.8186 -8.6614)
		(end 21.8186 -5.9944)
		(width 0.11684)
		(layer "B.Cu")
		(net "PCH_BEEP_LED")
	)
	(segment
		(start 21.8186 -5.9944)
		(end 20.8534 -5.0292)
		(width 0.11684)
		(layer "B.Cu")
		(net "PCH_BEEP_LED")
	)
	(segment
		(start 13.7414 -111.3536)
		(end 13.7414 -113.9444)
		(width 0.11684)
		(layer "B.Cu")
		(net "PCH_BEEP_LED")
	)
	(segment
		(start 20.887944 -19.909028)
		(end 21.209 -19.587972)
		(width 0.11684)
		(layer "B.Cu")
		(net "PCH_BEEP_LED")
	)
	(segment
		(start 15.519908 -21.15693)
		(end 16.76781 -19.909028)
		(width 0.11684)
		(layer "B.Cu")
		(net "PCH_BEEP_LED")
	)
	(segment
		(start 4.072636 -84.862924)
		(end 4.072636 -80.684624)
		(width 0.10668)
		(layer "In7.Cu")
		(net "PCH_BEEP_LED")
	)
	(segment
		(start 3.556 -7.0866)
		(end 13.1318 -7.0866)
		(width 0.10668)
		(layer "In7.Cu")
		(net "PCH_BEEP_LED")
	)
	(segment
		(start 1.8542 -104.648)
		(end 1.8542 -87.473536)
		(width 0.10668)
		(layer "In7.Cu")
		(net "PCH_BEEP_LED")
	)
	(segment
		(start 1.8542 -87.473536)
		(end 3.795268 -85.532468)
		(width 0.10668)
		(layer "In7.Cu")
		(net "PCH_BEEP_LED")
	)
	(segment
		(start 9.779 -112.5728)
		(end 1.8542 -104.648)
		(width 0.10668)
		(layer "In7.Cu")
		(net "PCH_BEEP_LED")
	)
	(segment
		(start 1.322832 -77.93482)
		(end 1.322832 -9.319768)
		(width 0.10668)
		(layer "In7.Cu")
		(net "PCH_BEEP_LED")
	)
	(segment
		(start 13.1318 -7.0866)
		(end 13.7668 -6.4516)
		(width 0.10668)
		(layer "In7.Cu")
		(net "PCH_BEEP_LED")
	)
	(segment
		(start 3.795268 -85.532468)
		(end 4.072636 -84.862924)
		(width 0.10668)
		(layer "In7.Cu")
		(net "PCH_BEEP_LED")
	)
	(segment
		(start 13.7414 -113.538)
		(end 12.7762 -112.5728)
		(width 0.10668)
		(layer "In7.Cu")
		(net "PCH_BEEP_LED")
	)
	(segment
		(start 13.7414 -113.9444)
		(end 13.7414 -113.538)
		(width 0.10668)
		(layer "In7.Cu")
		(net "PCH_BEEP_LED")
	)
	(segment
		(start 4.072636 -80.684624)
		(end 1.322832 -77.93482)
		(width 0.10668)
		(layer "In7.Cu")
		(net "PCH_BEEP_LED")
	)
	(segment
		(start 1.322832 -9.319768)
		(end 3.556 -7.0866)
		(width 0.10668)
		(layer "In7.Cu")
		(net "PCH_BEEP_LED")
	)
	(segment
		(start 12.7762 -112.5728)
		(end 9.779 -112.5728)
		(width 0.10668)
		(layer "In7.Cu")
		(net "PCH_BEEP_LED")
	)
	(segment
		(start 65.666366 -68.49364)
		(end 64.83477 -68.149216)
		(width 0.14224)
		(layer "B.Cu")
		(net "P2E_PCH_TX_C_DP")
	)
	(segment
		(start 72.3392 -86.334346)
		(end 71.1962 -85.191346)
		(width 0.14224)
		(layer "B.Cu")
		(net "P2E_PCH_TX_C_DP")
	)
	(segment
		(start 66.529966 -102.866952)
		(end 69.557646 -101.612954)
		(width 0.14224)
		(layer "B.Cu")
		(net "P2E_PCH_TX_C_DP")
	)
	(segment
		(start 51.949096 -116.64569)
		(end 53.0479 -113.992406)
		(width 0.14224)
		(layer "B.Cu")
		(net "P2E_PCH_TX_C_DP")
	)
	(segment
		(start 52.06492 -117.52072)
		(end 51.949096 -117.404896)
		(width 0.14224)
		(layer "B.Cu")
		(net "P2E_PCH_TX_C_DP")
	)
	(segment
		(start 62.2935 -63.11519)
		(end 62.2935 -62.685676)
		(width 0.14224)
		(layer "B.Cu")
		(net "P2E_PCH_TX_C_DP")
	)
	(segment
		(start 70.99808 -95.165926)
		(end 72.3392 -91.927934)
		(width 0.14224)
		(layer "B.Cu")
		(net "P2E_PCH_TX_C_DP")
	)
	(segment
		(start 71.1962 -85.191346)
		(end 71.1962 -79.480664)
		(width 0.14224)
		(layer "B.Cu")
		(net "P2E_PCH_TX_C_DP")
	)
	(segment
		(start 70.820534 -99.109022)
		(end 70.820534 -97.461832)
		(width 0.14224)
		(layer "B.Cu")
		(net "P2E_PCH_TX_C_DP")
	)
	(segment
		(start 72.3392 -91.927934)
		(end 72.3392 -86.334346)
		(width 0.14224)
		(layer "B.Cu")
		(net "P2E_PCH_TX_C_DP")
	)
	(segment
		(start 66.63309 -68.893944)
		(end 65.666366 -68.49364)
		(width 0.14224)
		(layer "B.Cu")
		(net "P2E_PCH_TX_C_DP")
	)
	(segment
		(start 69.943218 -101.227382)
		(end 70.820534 -99.109022)
		(width 0.14224)
		(layer "B.Cu")
		(net "P2E_PCH_TX_C_DP")
	)
	(segment
		(start 69.557646 -101.612954)
		(end 69.943218 -101.227382)
		(width 0.14224)
		(layer "B.Cu")
		(net "P2E_PCH_TX_C_DP")
	)
	(segment
		(start 64.27724 -67.591686)
		(end 63.938658 -67.085464)
		(width 0.14224)
		(layer "B.Cu")
		(net "P2E_PCH_TX_C_DP")
	)
	(segment
		(start 63.938658 -67.085464)
		(end 62.2935 -63.11519)
		(width 0.14224)
		(layer "B.Cu")
		(net "P2E_PCH_TX_C_DP")
	)
	(segment
		(start 70.99808 -97.03308)
		(end 70.99808 -95.165926)
		(width 0.14224)
		(layer "B.Cu")
		(net "P2E_PCH_TX_C_DP")
	)
	(segment
		(start 66.93535 -69.196204)
		(end 66.63309 -68.893944)
		(width 0.14224)
		(layer "B.Cu")
		(net "P2E_PCH_TX_C_DP")
	)
	(segment
		(start 51.949096 -117.404896)
		(end 51.949096 -116.64569)
		(width 0.14224)
		(layer "B.Cu")
		(net "P2E_PCH_TX_C_DP")
	)
	(segment
		(start 53.9877 -103.822246)
		(end 54.942994 -102.866952)
		(width 0.14224)
		(layer "B.Cu")
		(net "P2E_PCH_TX_C_DP")
	)
	(segment
		(start 52.06492 -118.25986)
		(end 52.06492 -117.52072)
		(width 0.14224)
		(layer "B.Cu")
		(net "P2E_PCH_TX_C_DP")
	)
	(segment
		(start 53.9877 -105.816654)
		(end 53.9877 -103.822246)
		(width 0.14224)
		(layer "B.Cu")
		(net "P2E_PCH_TX_C_DP")
	)
	(segment
		(start 70.820534 -97.461832)
		(end 70.99808 -97.03308)
		(width 0.14224)
		(layer "B.Cu")
		(net "P2E_PCH_TX_C_DP")
	)
	(segment
		(start 53.0479 -108.085636)
		(end 53.9877 -105.816654)
		(width 0.14224)
		(layer "B.Cu")
		(net "P2E_PCH_TX_C_DP")
	)
	(segment
		(start 71.1962 -79.480664)
		(end 66.93535 -69.196204)
		(width 0.14224)
		(layer "B.Cu")
		(net "P2E_PCH_TX_C_DP")
	)
	(segment
		(start 54.942994 -102.866952)
		(end 66.529966 -102.866952)
		(width 0.14224)
		(layer "B.Cu")
		(net "P2E_PCH_TX_C_DP")
	)
	(segment
		(start 53.0479 -113.992406)
		(end 53.0479 -108.085636)
		(width 0.14224)
		(layer "B.Cu")
		(net "P2E_PCH_TX_C_DP")
	)
	(segment
		(start 64.83477 -68.149216)
		(end 64.27724 -67.591686)
		(width 0.14224)
		(layer "B.Cu")
		(net "P2E_PCH_TX_C_DP")
	)
	(segment
		(start 62.2935 -62.685676)
		(end 62.59322 -62.385956)
		(width 0.14224)
		(layer "B.Cu")
		(net "P2E_PCH_TX_C_DP")
	)
	(segment
		(start 53.6194 -103.669592)
		(end 54.79034 -102.498652)
		(width 0.14224)
		(layer "B.Cu")
		(net "P2E_PCH_TX_C_DN")
	)
	(segment
		(start 54.79034 -102.498652)
		(end 66.45656 -102.498652)
		(width 0.14224)
		(layer "B.Cu")
		(net "P2E_PCH_TX_C_DN")
	)
	(segment
		(start 70.8279 -79.55407)
		(end 66.62293 -69.404992)
		(width 0.14224)
		(layer "B.Cu")
		(net "P2E_PCH_TX_C_DN")
	)
	(segment
		(start 52.6796 -108.01223)
		(end 53.6194 -105.743248)
		(width 0.14224)
		(layer "B.Cu")
		(net "P2E_PCH_TX_C_DN")
	)
	(segment
		(start 70.8279 -85.344)
		(end 70.8279 -79.55407)
		(width 0.14224)
		(layer "B.Cu")
		(net "P2E_PCH_TX_C_DN")
	)
	(segment
		(start 71.9709 -91.854528)
		(end 71.9709 -86.487)
		(width 0.14224)
		(layer "B.Cu")
		(net "P2E_PCH_TX_C_DN")
	)
	(segment
		(start 71.9709 -86.487)
		(end 70.8279 -85.344)
		(width 0.14224)
		(layer "B.Cu")
		(net "P2E_PCH_TX_C_DN")
	)
	(segment
		(start 70.452234 -99.035616)
		(end 70.452234 -97.388426)
		(width 0.14224)
		(layer "B.Cu")
		(net "P2E_PCH_TX_C_DN")
	)
	(segment
		(start 66.424302 -69.206364)
		(end 64.625982 -68.461636)
		(width 0.14224)
		(layer "B.Cu")
		(net "P2E_PCH_TX_C_DN")
	)
	(segment
		(start 66.45656 -102.498652)
		(end 69.348858 -101.300534)
		(width 0.14224)
		(layer "B.Cu")
		(net "P2E_PCH_TX_C_DN")
	)
	(segment
		(start 64.625982 -68.461636)
		(end 63.990982 -67.826636)
		(width 0.14224)
		(layer "B.Cu")
		(net "P2E_PCH_TX_C_DN")
	)
	(segment
		(start 69.630798 -101.018594)
		(end 70.452234 -99.035616)
		(width 0.14224)
		(layer "B.Cu")
		(net "P2E_PCH_TX_C_DN")
	)
	(segment
		(start 61.9252 -63.188596)
		(end 61.9252 -62.733936)
		(width 0.14224)
		(layer "B.Cu")
		(net "P2E_PCH_TX_C_DN")
	)
	(segment
		(start 61.9252 -62.733936)
		(end 61.57722 -62.385956)
		(width 0.14224)
		(layer "B.Cu")
		(net "P2E_PCH_TX_C_DN")
	)
	(segment
		(start 70.62978 -96.959674)
		(end 70.62978 -95.09252)
		(width 0.14224)
		(layer "B.Cu")
		(net "P2E_PCH_TX_C_DN")
	)
	(segment
		(start 53.6194 -105.743248)
		(end 53.6194 -103.669592)
		(width 0.14224)
		(layer "B.Cu")
		(net "P2E_PCH_TX_C_DN")
	)
	(segment
		(start 66.62293 -69.404992)
		(end 66.424302 -69.206364)
		(width 0.14224)
		(layer "B.Cu")
		(net "P2E_PCH_TX_C_DN")
	)
	(segment
		(start 52.6796 -113.919)
		(end 52.6796 -108.01223)
		(width 0.14224)
		(layer "B.Cu")
		(net "P2E_PCH_TX_C_DN")
	)
	(segment
		(start 63.990982 -67.826636)
		(end 63.612268 -67.259962)
		(width 0.14224)
		(layer "B.Cu")
		(net "P2E_PCH_TX_C_DN")
	)
	(segment
		(start 70.452234 -97.388426)
		(end 70.62978 -96.959674)
		(width 0.14224)
		(layer "B.Cu")
		(net "P2E_PCH_TX_C_DN")
	)
	(segment
		(start 70.62978 -95.09252)
		(end 71.9709 -91.854528)
		(width 0.14224)
		(layer "B.Cu")
		(net "P2E_PCH_TX_C_DN")
	)
	(segment
		(start 51.464972 -117.546628)
		(end 51.580796 -117.430804)
		(width 0.14224)
		(layer "B.Cu")
		(net "P2E_PCH_TX_C_DN")
	)
	(segment
		(start 51.464972 -118.25986)
		(end 51.464972 -117.546628)
		(width 0.14224)
		(layer "B.Cu")
		(net "P2E_PCH_TX_C_DN")
	)
	(segment
		(start 63.612268 -67.259962)
		(end 61.9252 -63.188596)
		(width 0.14224)
		(layer "B.Cu")
		(net "P2E_PCH_TX_C_DN")
	)
	(segment
		(start 69.348858 -101.300534)
		(end 69.630798 -101.018594)
		(width 0.14224)
		(layer "B.Cu")
		(net "P2E_PCH_TX_C_DN")
	)
	(segment
		(start 51.580796 -116.572284)
		(end 52.6796 -113.919)
		(width 0.14224)
		(layer "B.Cu")
		(net "P2E_PCH_TX_C_DN")
	)
	(segment
		(start 51.580796 -117.430804)
		(end 51.580796 -116.572284)
		(width 0.14224)
		(layer "B.Cu")
		(net "P2E_PCH_TX_C_DN")
	)
	(segment
		(start 61.479176 -59.58713)
		(end 61.479176 -60.13958)
		(width 0.13716)
		(layer "F.Cu")
		(net "P2E_PCH_RX_DP")
	)
	(segment
		(start 61.695076 -59.37123)
		(end 61.479176 -59.58713)
		(width 0.13716)
		(layer "F.Cu")
		(net "P2E_PCH_RX_DP")
	)
	(segment
		(start 61.479176 -60.13958)
		(end 61.68898 -60.349384)
		(width 0.13716)
		(layer "F.Cu")
		(net "P2E_PCH_RX_DP")
	)
	(via
		(at 55.04815 -112.32388)
		(size 0.508)
		(drill 0.254)
		(layers "F.Cu" "B.Cu")
		(net "P2E_PCH_RX_DP")
	)
	(via
		(at 61.68898 -60.349384)
		(size 0.4572)
		(drill 0.254)
		(layers "F.Cu" "B.Cu")
		(net "P2E_PCH_RX_DP")
	)
	(segment
		(start 54.7878 -112.58423)
		(end 54.7878 -114.998754)
		(width 0.14224)
		(layer "B.Cu")
		(net "P2E_PCH_RX_DP")
	)
	(segment
		(start 53.749194 -116.989352)
		(end 53.749194 -117.42674)
		(width 0.14224)
		(layer "B.Cu")
		(net "P2E_PCH_RX_DP")
	)
	(segment
		(start 54.7878 -114.998754)
		(end 54.1147 -115.671854)
		(width 0.14224)
		(layer "B.Cu")
		(net "P2E_PCH_RX_DP")
	)
	(segment
		(start 53.749194 -117.42674)
		(end 53.865018 -117.542564)
		(width 0.14224)
		(layer "B.Cu")
		(net "P2E_PCH_RX_DP")
	)
	(segment
		(start 54.1147 -116.623846)
		(end 53.749194 -116.989352)
		(width 0.14224)
		(layer "B.Cu")
		(net "P2E_PCH_RX_DP")
	)
	(segment
		(start 53.865018 -117.542564)
		(end 53.865018 -118.25986)
		(width 0.14224)
		(layer "B.Cu")
		(net "P2E_PCH_RX_DP")
	)
	(segment
		(start 55.04815 -112.32388)
		(end 54.7878 -112.58423)
		(width 0.14224)
		(layer "B.Cu")
		(net "P2E_PCH_RX_DP")
	)
	(segment
		(start 54.1147 -115.671854)
		(end 54.1147 -116.623846)
		(width 0.14224)
		(layer "B.Cu")
		(net "P2E_PCH_RX_DP")
	)
	(segment
		(start 69.60108 -81.146396)
		(end 69.37248 -81.698338)
		(width 0.1143)
		(layer "In9.Cu")
		(net "P2E_PCH_RX_DP")
	)
	(segment
		(start 58.40857 -104.574848)
		(end 56.56453 -106.418888)
		(width 0.1143)
		(layer "In9.Cu")
		(net "P2E_PCH_RX_DP")
	)
	(segment
		(start 65.00368 -92.31884)
		(end 65.00368 -98.716592)
		(width 0.1143)
		(layer "In9.Cu")
		(net "P2E_PCH_RX_DP")
	)
	(segment
		(start 70.4596 -69.35343)
		(end 69.60108 -71.426832)
		(width 0.1143)
		(layer "In9.Cu")
		(net "P2E_PCH_RX_DP")
	)
	(segment
		(start 55.485538 -111.71428)
		(end 54.942232 -111.71428)
		(width 0.1143)
		(layer "In9.Cu")
		(net "P2E_PCH_RX_DP")
	)
	(segment
		(start 70.4596 -67.005454)
		(end 70.4596 -69.35343)
		(width 0.1143)
		(layer "In9.Cu")
		(net "P2E_PCH_RX_DP")
	)
	(segment
		(start 59.651138 -102.44328)
		(end 59.03722 -103.057198)
		(width 0.1143)
		(layer "In9.Cu")
		(net "P2E_PCH_RX_DP")
	)
	(segment
		(start 54.77129 -111.885222)
		(end 54.77129 -112.04702)
		(width 0.1143)
		(layer "In9.Cu")
		(net "P2E_PCH_RX_DP")
	)
	(segment
		(start 59.03722 -103.057198)
		(end 58.40857 -104.574848)
		(width 0.1143)
		(layer "In9.Cu")
		(net "P2E_PCH_RX_DP")
	)
	(segment
		(start 66.778124 -88.034876)
		(end 65.00368 -92.31884)
		(width 0.1143)
		(layer "In9.Cu")
		(net "P2E_PCH_RX_DP")
	)
	(segment
		(start 56.56453 -106.418888)
		(end 56.56453 -110.635288)
		(width 0.1143)
		(layer "In9.Cu")
		(net "P2E_PCH_RX_DP")
	)
	(segment
		(start 69.37248 -82.663538)
		(end 68.3387 -83.697318)
		(width 0.1143)
		(layer "In9.Cu")
		(net "P2E_PCH_RX_DP")
	)
	(segment
		(start 65.00368 -98.716592)
		(end 63.809626 -99.910646)
		(width 0.1143)
		(layer "In9.Cu")
		(net "P2E_PCH_RX_DP")
	)
	(segment
		(start 61.77153 -60.8838)
		(end 62.857126 -60.8838)
		(width 0.1143)
		(layer "In9.Cu")
		(net "P2E_PCH_RX_DP")
	)
	(segment
		(start 69.37248 -81.698338)
		(end 69.37248 -82.663538)
		(width 0.1143)
		(layer "In9.Cu")
		(net "P2E_PCH_RX_DP")
	)
	(segment
		(start 56.56453 -110.635288)
		(end 55.485538 -111.71428)
		(width 0.1143)
		(layer "In9.Cu")
		(net "P2E_PCH_RX_DP")
	)
	(segment
		(start 68.3387 -83.697318)
		(end 67.49288 -85.739224)
		(width 0.1143)
		(layer "In9.Cu")
		(net "P2E_PCH_RX_DP")
	)
	(segment
		(start 65.71615 -61.64072)
		(end 66.62928 -62.55385)
		(width 0.1143)
		(layer "In9.Cu")
		(net "P2E_PCH_RX_DP")
	)
	(segment
		(start 61.911738 -102.44328)
		(end 59.651138 -102.44328)
		(width 0.1143)
		(layer "In9.Cu")
		(net "P2E_PCH_RX_DP")
	)
	(segment
		(start 67.49288 -87.32012)
		(end 66.778124 -88.034876)
		(width 0.1143)
		(layer "In9.Cu")
		(net "P2E_PCH_RX_DP")
	)
	(segment
		(start 54.77129 -112.04702)
		(end 55.04815 -112.32388)
		(width 0.1143)
		(layer "In9.Cu")
		(net "P2E_PCH_RX_DP")
	)
	(segment
		(start 66.62928 -62.55385)
		(end 66.62928 -63.175134)
		(width 0.1143)
		(layer "In9.Cu")
		(net "P2E_PCH_RX_DP")
	)
	(segment
		(start 61.585602 -60.806584)
		(end 61.77153 -60.8838)
		(width 0.1143)
		(layer "In9.Cu")
		(net "P2E_PCH_RX_DP")
	)
	(segment
		(start 61.68898 -60.349384)
		(end 61.47308 -60.565284)
		(width 0.1143)
		(layer "In9.Cu")
		(net "P2E_PCH_RX_DP")
	)
	(segment
		(start 67.49288 -85.739224)
		(end 67.49288 -87.32012)
		(width 0.1143)
		(layer "In9.Cu")
		(net "P2E_PCH_RX_DP")
	)
	(segment
		(start 63.809626 -99.910646)
		(end 63.360554 -100.994464)
		(width 0.1143)
		(layer "In9.Cu")
		(net "P2E_PCH_RX_DP")
	)
	(segment
		(start 61.47308 -60.565284)
		(end 61.47308 -60.694062)
		(width 0.1143)
		(layer "In9.Cu")
		(net "P2E_PCH_RX_DP")
	)
	(segment
		(start 61.47308 -60.694062)
		(end 61.585602 -60.806584)
		(width 0.1143)
		(layer "In9.Cu")
		(net "P2E_PCH_RX_DP")
	)
	(segment
		(start 62.857126 -60.8838)
		(end 64.684402 -61.64072)
		(width 0.1143)
		(layer "In9.Cu")
		(net "P2E_PCH_RX_DP")
	)
	(segment
		(start 69.60108 -71.426832)
		(end 69.60108 -81.146396)
		(width 0.1143)
		(layer "In9.Cu")
		(net "P2E_PCH_RX_DP")
	)
	(segment
		(start 64.684402 -61.64072)
		(end 65.71615 -61.64072)
		(width 0.1143)
		(layer "In9.Cu")
		(net "P2E_PCH_RX_DP")
	)
	(segment
		(start 54.942232 -111.71428)
		(end 54.77129 -111.885222)
		(width 0.1143)
		(layer "In9.Cu")
		(net "P2E_PCH_RX_DP")
	)
	(segment
		(start 66.62928 -63.175134)
		(end 70.4596 -67.005454)
		(width 0.1143)
		(layer "In9.Cu")
		(net "P2E_PCH_RX_DP")
	)
	(segment
		(start 63.360554 -100.994464)
		(end 61.911738 -102.44328)
		(width 0.1143)
		(layer "In9.Cu")
		(net "P2E_PCH_RX_DP")
	)
	(segment
		(start 60.894976 -59.37123)
		(end 61.110876 -59.58713)
		(width 0.13716)
		(layer "F.Cu")
		(net "P2E_PCH_RX_DN")
	)
	(segment
		(start 61.110876 -59.58713)
		(end 61.110876 -60.165488)
		(width 0.13716)
		(layer "F.Cu")
		(net "P2E_PCH_RX_DN")
	)
	(segment
		(start 61.110876 -60.165488)
		(end 60.92698 -60.349384)
		(width 0.13716)
		(layer "F.Cu")
		(net "P2E_PCH_RX_DN")
	)
	(via
		(at 60.92698 -60.349384)
		(size 0.4572)
		(drill 0.254)
		(layers "F.Cu" "B.Cu")
		(net "P2E_PCH_RX_DN")
	)
	(via
		(at 54.15915 -112.32388)
		(size 0.508)
		(drill 0.254)
		(layers "F.Cu" "B.Cu")
		(net "P2E_PCH_RX_DN")
	)
	(segment
		(start 53.7464 -115.5192)
		(end 53.7464 -116.471192)
		(width 0.14224)
		(layer "B.Cu")
		(net "P2E_PCH_RX_DN")
	)
	(segment
		(start 54.4195 -114.8461)
		(end 53.7464 -115.5192)
		(width 0.14224)
		(layer "B.Cu")
		(net "P2E_PCH_RX_DN")
	)
	(segment
		(start 53.7464 -116.471192)
		(end 53.380894 -116.836698)
		(width 0.14224)
		(layer "B.Cu")
		(net "P2E_PCH_RX_DN")
	)
	(segment
		(start 53.26507 -117.524276)
		(end 53.26507 -118.25986)
		(width 0.14224)
		(layer "B.Cu")
		(net "P2E_PCH_RX_DN")
	)
	(segment
		(start 54.4195 -112.58423)
		(end 54.4195 -114.8461)
		(width 0.14224)
		(layer "B.Cu")
		(net "P2E_PCH_RX_DN")
	)
	(segment
		(start 54.15915 -112.32388)
		(end 54.4195 -112.58423)
		(width 0.14224)
		(layer "B.Cu")
		(net "P2E_PCH_RX_DN")
	)
	(segment
		(start 53.380894 -116.836698)
		(end 53.380894 -117.408452)
		(width 0.14224)
		(layer "B.Cu")
		(net "P2E_PCH_RX_DN")
	)
	(segment
		(start 53.380894 -117.408452)
		(end 53.26507 -117.524276)
		(width 0.14224)
		(layer "B.Cu")
		(net "P2E_PCH_RX_DN")
	)
	(segment
		(start 66.294 -62.692788)
		(end 66.294 -63.314072)
		(width 0.1143)
		(layer "In9.Cu")
		(net "P2E_PCH_RX_DN")
	)
	(segment
		(start 66.294 -63.314072)
		(end 70.12432 -67.144392)
		(width 0.1143)
		(layer "In9.Cu")
		(net "P2E_PCH_RX_DN")
	)
	(segment
		(start 61.39561 -61.09081)
		(end 61.704474 -61.21908)
		(width 0.1143)
		(layer "In9.Cu")
		(net "P2E_PCH_RX_DN")
	)
	(segment
		(start 62.790324 -61.21908)
		(end 64.6176 -61.976)
		(width 0.1143)
		(layer "In9.Cu")
		(net "P2E_PCH_RX_DN")
	)
	(segment
		(start 67.1576 -85.672422)
		(end 67.1576 -87.181182)
		(width 0.1143)
		(layer "In9.Cu")
		(net "P2E_PCH_RX_DN")
	)
	(segment
		(start 61.7728 -102.108)
		(end 59.5122 -102.108)
		(width 0.1143)
		(layer "In9.Cu")
		(net "P2E_PCH_RX_DN")
	)
	(segment
		(start 68.054474 -83.507326)
		(end 67.1576 -85.672422)
		(width 0.1143)
		(layer "In9.Cu")
		(net "P2E_PCH_RX_DN")
	)
	(segment
		(start 63.076328 -100.804472)
		(end 61.7728 -102.108)
		(width 0.1143)
		(layer "In9.Cu")
		(net "P2E_PCH_RX_DN")
	)
	(segment
		(start 70.12432 -69.286628)
		(end 69.2658 -71.36003)
		(width 0.1143)
		(layer "In9.Cu")
		(net "P2E_PCH_RX_DN")
	)
	(segment
		(start 64.6176 -61.976)
		(end 65.577212 -61.976)
		(width 0.1143)
		(layer "In9.Cu")
		(net "P2E_PCH_RX_DN")
	)
	(segment
		(start 64.6684 -98.577654)
		(end 63.5254 -99.720654)
		(width 0.1143)
		(layer "In9.Cu")
		(net "P2E_PCH_RX_DN")
	)
	(segment
		(start 58.752994 -102.867206)
		(end 58.124344 -104.384856)
		(width 0.1143)
		(layer "In9.Cu")
		(net "P2E_PCH_RX_DN")
	)
	(segment
		(start 64.6684 -92.252038)
		(end 64.6684 -98.577654)
		(width 0.1143)
		(layer "In9.Cu")
		(net "P2E_PCH_RX_DN")
	)
	(segment
		(start 56.22925 -106.27995)
		(end 56.22925 -110.49635)
		(width 0.1143)
		(layer "In9.Cu")
		(net "P2E_PCH_RX_DN")
	)
	(segment
		(start 69.0372 -81.631536)
		(end 69.0372 -82.5246)
		(width 0.1143)
		(layer "In9.Cu")
		(net "P2E_PCH_RX_DN")
	)
	(segment
		(start 65.577212 -61.976)
		(end 66.294 -62.692788)
		(width 0.1143)
		(layer "In9.Cu")
		(net "P2E_PCH_RX_DN")
	)
	(segment
		(start 58.124344 -104.384856)
		(end 56.22925 -106.27995)
		(width 0.1143)
		(layer "In9.Cu")
		(net "P2E_PCH_RX_DN")
	)
	(segment
		(start 66.493898 -87.844884)
		(end 64.6684 -92.252038)
		(width 0.1143)
		(layer "In9.Cu")
		(net "P2E_PCH_RX_DN")
	)
	(segment
		(start 67.1576 -87.181182)
		(end 66.493898 -87.844884)
		(width 0.1143)
		(layer "In9.Cu")
		(net "P2E_PCH_RX_DN")
	)
	(segment
		(start 56.22925 -110.49635)
		(end 55.3466 -111.379)
		(width 0.1143)
		(layer "In9.Cu")
		(net "P2E_PCH_RX_DN")
	)
	(segment
		(start 55.3466 -111.379)
		(end 54.803294 -111.379)
		(width 0.1143)
		(layer "In9.Cu")
		(net "P2E_PCH_RX_DN")
	)
	(segment
		(start 54.43601 -111.746284)
		(end 54.43601 -112.04702)
		(width 0.1143)
		(layer "In9.Cu")
		(net "P2E_PCH_RX_DN")
	)
	(segment
		(start 69.0372 -82.5246)
		(end 68.054474 -83.507326)
		(width 0.1143)
		(layer "In9.Cu")
		(net "P2E_PCH_RX_DN")
	)
	(segment
		(start 63.5254 -99.720654)
		(end 63.076328 -100.804472)
		(width 0.1143)
		(layer "In9.Cu")
		(net "P2E_PCH_RX_DN")
	)
	(segment
		(start 54.803294 -111.379)
		(end 54.43601 -111.746284)
		(width 0.1143)
		(layer "In9.Cu")
		(net "P2E_PCH_RX_DN")
	)
	(segment
		(start 59.5122 -102.108)
		(end 58.752994 -102.867206)
		(width 0.1143)
		(layer "In9.Cu")
		(net "P2E_PCH_RX_DN")
	)
	(segment
		(start 70.12432 -67.144392)
		(end 70.12432 -69.286628)
		(width 0.1143)
		(layer "In9.Cu")
		(net "P2E_PCH_RX_DN")
	)
	(segment
		(start 61.1378 -60.833)
		(end 61.39561 -61.09081)
		(width 0.1143)
		(layer "In9.Cu")
		(net "P2E_PCH_RX_DN")
	)
	(segment
		(start 61.704474 -61.21908)
		(end 62.790324 -61.21908)
		(width 0.1143)
		(layer "In9.Cu")
		(net "P2E_PCH_RX_DN")
	)
	(segment
		(start 69.2658 -71.36003)
		(end 69.2658 -81.079594)
		(width 0.1143)
		(layer "In9.Cu")
		(net "P2E_PCH_RX_DN")
	)
	(segment
		(start 60.92698 -60.349384)
		(end 61.1378 -60.560204)
		(width 0.1143)
		(layer "In9.Cu")
		(net "P2E_PCH_RX_DN")
	)
	(segment
		(start 54.43601 -112.04702)
		(end 54.15915 -112.32388)
		(width 0.1143)
		(layer "In9.Cu")
		(net "P2E_PCH_RX_DN")
	)
	(segment
		(start 69.2658 -81.079594)
		(end 69.0372 -81.631536)
		(width 0.1143)
		(layer "In9.Cu")
		(net "P2E_PCH_RX_DN")
	)
	(segment
		(start 61.1378 -60.560204)
		(end 61.1378 -60.833)
		(width 0.1143)
		(layer "In9.Cu")
		(net "P2E_PCH_RX_DN")
	)
	(segment
		(start 64.094868 -59.37123)
		(end 64.490092 -59.766454)
		(width 0.11684)
		(layer "F.Cu")
		(net "P2E_GPU_TX_DN")
	)
	(segment
		(start 13.65885 -108.6231)
		(end 13.335 -108.94695)
		(width 0.14224)
		(layer "F.Cu")
		(net "P2E_GPU_TX_DN")
	)
	(segment
		(start 13.65885 -108.00715)
		(end 13.65885 -108.6231)
		(width 0.14224)
		(layer "F.Cu")
		(net "P2E_GPU_TX_DN")
	)
	(segment
		(start 13.3985 -107.7468)
		(end 13.65885 -108.00715)
		(width 0.14224)
		(layer "F.Cu")
		(net "P2E_GPU_TX_DN")
	)
	(via
		(at 64.490092 -59.766454)
		(size 0.4572)
		(drill 0.254)
		(layers "F.Cu" "B.Cu")
		(net "P2E_GPU_TX_DN")
	)
	(via
		(at 13.3985 -107.7468)
		(size 0.508)
		(drill 0.254)
		(layers "F.Cu" "B.Cu")
		(net "P2E_GPU_TX_DN")
	)
	(segment
		(start 63.7032 -108.23829)
		(end 63.7032 -108.731304)
		(width 0.1143)
		(layer "In9.Cu")
		(net "P2E_GPU_TX_DN")
	)
	(segment
		(start 64.257936 -59.974226)
		(end 64.257936 -60.202318)
		(width 0.1143)
		(layer "In9.Cu")
		(net "P2E_GPU_TX_DN")
	)
	(segment
		(start 69.765418 -85.4456)
		(end 69.0372 -85.4456)
		(width 0.1143)
		(layer "In9.Cu")
		(net "P2E_GPU_TX_DN")
	)
	(segment
		(start 55.69712 -113.97488)
		(end 53.572664 -113.97488)
		(width 0.1143)
		(layer "In9.Cu")
		(net "P2E_GPU_TX_DN")
	)
	(segment
		(start 73.5076 -67.030346)
		(end 73.5076 -68.961)
		(width 0.1143)
		(layer "In9.Cu")
		(net "P2E_GPU_TX_DN")
	)
	(segment
		(start 52.414424 -112.180624)
		(end 50.390298 -111.34217)
		(width 0.1143)
		(layer "In9.Cu")
		(net "P2E_GPU_TX_DN")
	)
	(segment
		(start 24.663654 -110.6678)
		(end 18.101818 -110.6678)
		(width 0.1143)
		(layer "In9.Cu")
		(net "P2E_GPU_TX_DN")
	)
	(segment
		(start 63.507112 -109.204506)
		(end 61.454538 -111.25708)
		(width 0.1143)
		(layer "In9.Cu")
		(net "P2E_GPU_TX_DN")
	)
	(segment
		(start 39.457884 -110.06328)
		(end 38.548564 -110.9726)
		(width 0.1143)
		(layer "In9.Cu")
		(net "P2E_GPU_TX_DN")
	)
	(segment
		(start 70.64248 -72.87895)
		(end 70.64248 -78.577694)
		(width 0.1143)
		(layer "In9.Cu")
		(net "P2E_GPU_TX_DN")
	)
	(segment
		(start 50.390298 -111.34217)
		(end 47.954692 -111.34217)
		(width 0.1143)
		(layer "In9.Cu")
		(net "P2E_GPU_TX_DN")
	)
	(segment
		(start 70.64248 -78.577694)
		(end 71.1708 -79.853536)
		(width 0.1143)
		(layer "In9.Cu")
		(net "P2E_GPU_TX_DN")
	)
	(segment
		(start 65.8495 -60.59932)
		(end 67.49288 -62.2427)
		(width 0.1143)
		(layer "In9.Cu")
		(net "P2E_GPU_TX_DN")
	)
	(segment
		(start 64.39662 -59.859926)
		(end 64.372236 -59.859926)
		(width 0.1143)
		(layer "In9.Cu")
		(net "P2E_GPU_TX_DN")
	)
	(segment
		(start 64.947546 -60.3758)
		(end 65.171066 -60.59932)
		(width 0.1143)
		(layer "In9.Cu")
		(net "P2E_GPU_TX_DN")
	)
	(segment
		(start 59.498738 -111.25708)
		(end 58.716418 -112.0394)
		(width 0.1143)
		(layer "In9.Cu")
		(net "P2E_GPU_TX_DN")
	)
	(segment
		(start 65.84188 -99.097338)
		(end 64.97828 -99.960938)
		(width 0.1143)
		(layer "In9.Cu")
		(net "P2E_GPU_TX_DN")
	)
	(segment
		(start 38.548564 -110.9726)
		(end 30.616144 -110.9726)
		(width 0.1143)
		(layer "In9.Cu")
		(net "P2E_GPU_TX_DN")
	)
	(segment
		(start 14.503146 -110.9218)
		(end 13.67536 -110.094014)
		(width 0.1143)
		(layer "In9.Cu")
		(net "P2E_GPU_TX_DN")
	)
	(segment
		(start 73.5076 -68.961)
		(end 72.456802 -70.011798)
		(width 0.1143)
		(layer "In9.Cu")
		(net "P2E_GPU_TX_DN")
	)
	(segment
		(start 71.2724 -71.357998)
		(end 70.64248 -72.87895)
		(width 0.1143)
		(layer "In9.Cu")
		(net "P2E_GPU_TX_DN")
	)
	(segment
		(start 53.572664 -113.97488)
		(end 52.75072 -113.152936)
		(width 0.1143)
		(layer "In9.Cu")
		(net "P2E_GPU_TX_DN")
	)
	(segment
		(start 64.490092 -59.766454)
		(end 64.39662 -59.859926)
		(width 0.1143)
		(layer "In9.Cu")
		(net "P2E_GPU_TX_DN")
	)
	(segment
		(start 58.716418 -112.0394)
		(end 57.6326 -112.0394)
		(width 0.1143)
		(layer "In9.Cu")
		(net "P2E_GPU_TX_DN")
	)
	(segment
		(start 65.84188 -92.611448)
		(end 65.84188 -99.097338)
		(width 0.1143)
		(layer "In9.Cu")
		(net "P2E_GPU_TX_DN")
	)
	(segment
		(start 64.257936 -60.202318)
		(end 64.431418 -60.3758)
		(width 0.1143)
		(layer "In9.Cu")
		(net "P2E_GPU_TX_DN")
	)
	(segment
		(start 68.4276 -86.0552)
		(end 68.4276 -87.596218)
		(width 0.1143)
		(layer "In9.Cu")
		(net "P2E_GPU_TX_DN")
	)
	(segment
		(start 67.49288 -62.852808)
		(end 70.420992 -65.78092)
		(width 0.1143)
		(layer "In9.Cu")
		(net "P2E_GPU_TX_DN")
	)
	(segment
		(start 47.954692 -111.34217)
		(end 46.844712 -110.88243)
		(width 0.1143)
		(layer "In9.Cu")
		(net "P2E_GPU_TX_DN")
	)
	(segment
		(start 64.372236 -59.859926)
		(end 64.257936 -59.974226)
		(width 0.1143)
		(layer "In9.Cu")
		(net "P2E_GPU_TX_DN")
	)
	(segment
		(start 65.171066 -60.59932)
		(end 65.8495 -60.59932)
		(width 0.1143)
		(layer "In9.Cu")
		(net "P2E_GPU_TX_DN")
	)
	(segment
		(start 52.75072 -112.51692)
		(end 52.414424 -112.180624)
		(width 0.1143)
		(layer "In9.Cu")
		(net "P2E_GPU_TX_DN")
	)
	(segment
		(start 61.454538 -111.25708)
		(end 59.498738 -111.25708)
		(width 0.1143)
		(layer "In9.Cu")
		(net "P2E_GPU_TX_DN")
	)
	(segment
		(start 40.653716 -110.06328)
		(end 39.457884 -110.06328)
		(width 0.1143)
		(layer "In9.Cu")
		(net "P2E_GPU_TX_DN")
	)
	(segment
		(start 72.258174 -65.78092)
		(end 73.5076 -67.030346)
		(width 0.1143)
		(layer "In9.Cu")
		(net "P2E_GPU_TX_DN")
	)
	(segment
		(start 64.97828 -99.960938)
		(end 64.97828 -105.159556)
		(width 0.1143)
		(layer "In9.Cu")
		(net "P2E_GPU_TX_DN")
	)
	(segment
		(start 67.559428 -88.46439)
		(end 65.84188 -92.611448)
		(width 0.1143)
		(layer "In9.Cu")
		(net "P2E_GPU_TX_DN")
	)
	(segment
		(start 18.101818 -110.6678)
		(end 17.488408 -110.9218)
		(width 0.1143)
		(layer "In9.Cu")
		(net "P2E_GPU_TX_DN")
	)
	(segment
		(start 57.6326 -112.0394)
		(end 55.69712 -113.97488)
		(width 0.1143)
		(layer "In9.Cu")
		(net "P2E_GPU_TX_DN")
	)
	(segment
		(start 71.923402 -70.011798)
		(end 71.2724 -70.6628)
		(width 0.1143)
		(layer "In9.Cu")
		(net "P2E_GPU_TX_DN")
	)
	(segment
		(start 30.616144 -110.9726)
		(end 29.561282 -111.40948)
		(width 0.1143)
		(layer "In9.Cu")
		(net "P2E_GPU_TX_DN")
	)
	(segment
		(start 69.0372 -85.4456)
		(end 68.4276 -86.0552)
		(width 0.1143)
		(layer "In9.Cu")
		(net "P2E_GPU_TX_DN")
	)
	(segment
		(start 71.1708 -84.040218)
		(end 69.765418 -85.4456)
		(width 0.1143)
		(layer "In9.Cu")
		(net "P2E_GPU_TX_DN")
	)
	(segment
		(start 13.67536 -110.094014)
		(end 13.67536 -108.02366)
		(width 0.1143)
		(layer "In9.Cu")
		(net "P2E_GPU_TX_DN")
	)
	(segment
		(start 13.67536 -108.02366)
		(end 13.3985 -107.7468)
		(width 0.1143)
		(layer "In9.Cu")
		(net "P2E_GPU_TX_DN")
	)
	(segment
		(start 25.405334 -111.40948)
		(end 24.663654 -110.6678)
		(width 0.1143)
		(layer "In9.Cu")
		(net "P2E_GPU_TX_DN")
	)
	(segment
		(start 64.431418 -60.3758)
		(end 64.947546 -60.3758)
		(width 0.1143)
		(layer "In9.Cu")
		(net "P2E_GPU_TX_DN")
	)
	(segment
		(start 67.49288 -62.2427)
		(end 67.49288 -62.852808)
		(width 0.1143)
		(layer "In9.Cu")
		(net "P2E_GPU_TX_DN")
	)
	(segment
		(start 64.97828 -105.159556)
		(end 63.7032 -108.23829)
		(width 0.1143)
		(layer "In9.Cu")
		(net "P2E_GPU_TX_DN")
	)
	(segment
		(start 71.1708 -79.853536)
		(end 71.1708 -84.040218)
		(width 0.1143)
		(layer "In9.Cu")
		(net "P2E_GPU_TX_DN")
	)
	(segment
		(start 17.488408 -110.9218)
		(end 14.503146 -110.9218)
		(width 0.1143)
		(layer "In9.Cu")
		(net "P2E_GPU_TX_DN")
	)
	(segment
		(start 72.456802 -70.011798)
		(end 71.923402 -70.011798)
		(width 0.1143)
		(layer "In9.Cu")
		(net "P2E_GPU_TX_DN")
	)
	(segment
		(start 41.472866 -110.88243)
		(end 40.653716 -110.06328)
		(width 0.1143)
		(layer "In9.Cu")
		(net "P2E_GPU_TX_DN")
	)
	(segment
		(start 52.75072 -113.152936)
		(end 52.75072 -112.51692)
		(width 0.1143)
		(layer "In9.Cu")
		(net "P2E_GPU_TX_DN")
	)
	(segment
		(start 71.2724 -70.6628)
		(end 71.2724 -71.357998)
		(width 0.1143)
		(layer "In9.Cu")
		(net "P2E_GPU_TX_DN")
	)
	(segment
		(start 46.844712 -110.88243)
		(end 41.472866 -110.88243)
		(width 0.1143)
		(layer "In9.Cu")
		(net "P2E_GPU_TX_DN")
	)
	(segment
		(start 68.4276 -87.596218)
		(end 67.559428 -88.46439)
		(width 0.1143)
		(layer "In9.Cu")
		(net "P2E_GPU_TX_DN")
	)
	(segment
		(start 63.7032 -108.731304)
		(end 63.507112 -109.204506)
		(width 0.1143)
		(layer "In9.Cu")
		(net "P2E_GPU_TX_DN")
	)
	(segment
		(start 70.420992 -65.78092)
		(end 72.258174 -65.78092)
		(width 0.1143)
		(layer "In9.Cu")
		(net "P2E_GPU_TX_DN")
	)
	(segment
		(start 29.561282 -111.40948)
		(end 25.405334 -111.40948)
		(width 0.1143)
		(layer "In9.Cu")
		(net "P2E_GPU_TX_DN")
	)
	(segment
		(start 14.02715 -108.00715)
		(end 14.02715 -108.6231)
		(width 0.14224)
		(layer "F.Cu")
		(net "P2E_GPU_TX_DP")
	)
	(segment
		(start 14.02715 -108.6231)
		(end 14.351 -108.94695)
		(width 0.14224)
		(layer "F.Cu")
		(net "P2E_GPU_TX_DP")
	)
	(segment
		(start 14.2875 -107.7468)
		(end 14.02715 -108.00715)
		(width 0.14224)
		(layer "F.Cu")
		(net "P2E_GPU_TX_DP")
	)
	(segment
		(start 63.295022 -59.37123)
		(end 63.690246 -59.766454)
		(width 0.14224)
		(layer "F.Cu")
		(net "P2E_GPU_TX_DP")
	)
	(via
		(at 14.2875 -107.7468)
		(size 0.508)
		(drill 0.254)
		(layers "F.Cu" "B.Cu")
		(net "P2E_GPU_TX_DP")
	)
	(via
		(at 63.690246 -59.766454)
		(size 0.4572)
		(drill 0.254)
		(layers "F.Cu" "B.Cu")
		(net "P2E_GPU_TX_DP")
	)
	(segment
		(start 70.3072 -72.812148)
		(end 70.3072 -78.644496)
		(width 0.1143)
		(layer "In9.Cu")
		(net "P2E_GPU_TX_DP")
	)
	(segment
		(start 53.711602 -113.6396)
		(end 53.086 -113.013998)
		(width 0.1143)
		(layer "In9.Cu")
		(net "P2E_GPU_TX_DP")
	)
	(segment
		(start 14.642084 -110.58652)
		(end 14.01064 -109.955076)
		(width 0.1143)
		(layer "In9.Cu")
		(net "P2E_GPU_TX_DP")
	)
	(segment
		(start 63.222886 -109.014514)
		(end 61.3156 -110.9218)
		(width 0.1143)
		(layer "In9.Cu")
		(net "P2E_GPU_TX_DP")
	)
	(segment
		(start 50.4571 -111.00689)
		(end 48.021494 -111.00689)
		(width 0.1143)
		(layer "In9.Cu")
		(net "P2E_GPU_TX_DP")
	)
	(segment
		(start 53.086 -113.013998)
		(end 53.086 -112.377982)
		(width 0.1143)
		(layer "In9.Cu")
		(net "P2E_GPU_TX_DP")
	)
	(segment
		(start 63.690246 -59.766454)
		(end 63.922656 -59.998864)
		(width 0.1143)
		(layer "In9.Cu")
		(net "P2E_GPU_TX_DP")
	)
	(segment
		(start 61.3156 -110.9218)
		(end 59.3598 -110.9218)
		(width 0.1143)
		(layer "In9.Cu")
		(net "P2E_GPU_TX_DP")
	)
	(segment
		(start 36.45789 -110.4265)
		(end 36.24707 -110.63732)
		(width 0.1143)
		(layer "In9.Cu")
		(net "P2E_GPU_TX_DP")
	)
	(segment
		(start 14.01064 -109.617256)
		(end 14.22146 -109.406436)
		(width 0.1143)
		(layer "In9.Cu")
		(net "P2E_GPU_TX_DP")
	)
	(segment
		(start 45.45965 -110.35157)
		(end 45.11675 -110.35157)
		(width 0.1143)
		(layer "In9.Cu")
		(net "P2E_GPU_TX_DP")
	)
	(segment
		(start 68.898262 -85.11032)
		(end 68.09232 -85.916262)
		(width 0.1143)
		(layer "In9.Cu")
		(net "P2E_GPU_TX_DP")
	)
	(segment
		(start 67.1576 -62.991746)
		(end 70.282054 -66.1162)
		(width 0.1143)
		(layer "In9.Cu")
		(net "P2E_GPU_TX_DP")
	)
	(segment
		(start 35.14979 -110.63732)
		(end 30.549342 -110.63732)
		(width 0.1143)
		(layer "In9.Cu")
		(net "P2E_GPU_TX_DP")
	)
	(segment
		(start 45.65523 -110.54715)
		(end 45.45965 -110.35157)
		(width 0.1143)
		(layer "In9.Cu")
		(net "P2E_GPU_TX_DP")
	)
	(segment
		(start 29.49448 -111.0742)
		(end 25.544272 -111.0742)
		(width 0.1143)
		(layer "In9.Cu")
		(net "P2E_GPU_TX_DP")
	)
	(segment
		(start 65.5066 -92.544646)
		(end 65.5066 -98.9584)
		(width 0.1143)
		(layer "In9.Cu")
		(net "P2E_GPU_TX_DP")
	)
	(segment
		(start 43.00855 -110.35157)
		(end 42.81297 -110.54715)
		(width 0.1143)
		(layer "In9.Cu")
		(net "P2E_GPU_TX_DP")
	)
	(segment
		(start 70.3072 -78.644496)
		(end 70.83552 -79.920338)
		(width 0.1143)
		(layer "In9.Cu")
		(net "P2E_GPU_TX_DP")
	)
	(segment
		(start 70.83552 -83.90128)
		(end 69.62648 -85.11032)
		(width 0.1143)
		(layer "In9.Cu")
		(net "P2E_GPU_TX_DP")
	)
	(segment
		(start 17.421606 -110.58652)
		(end 14.642084 -110.58652)
		(width 0.1143)
		(layer "In9.Cu")
		(net "P2E_GPU_TX_DP")
	)
	(segment
		(start 63.36792 -108.171488)
		(end 63.36792 -108.664502)
		(width 0.1143)
		(layer "In9.Cu")
		(net "P2E_GPU_TX_DP")
	)
	(segment
		(start 30.549342 -110.63732)
		(end 29.49448 -111.0742)
		(width 0.1143)
		(layer "In9.Cu")
		(net "P2E_GPU_TX_DP")
	)
	(segment
		(start 56.259476 -112.661446)
		(end 56.259476 -112.938306)
		(width 0.1143)
		(layer "In9.Cu")
		(net "P2E_GPU_TX_DP")
	)
	(segment
		(start 70.282054 -66.1162)
		(end 72.119236 -66.1162)
		(width 0.1143)
		(layer "In9.Cu")
		(net "P2E_GPU_TX_DP")
	)
	(segment
		(start 14.22146 -109.406436)
		(end 14.22146 -109.068616)
		(width 0.1143)
		(layer "In9.Cu")
		(net "P2E_GPU_TX_DP")
	)
	(segment
		(start 70.83552 -79.920338)
		(end 70.83552 -83.90128)
		(width 0.1143)
		(layer "In9.Cu")
		(net "P2E_GPU_TX_DP")
	)
	(segment
		(start 59.3598 -110.9218)
		(end 58.57748 -111.70412)
		(width 0.1143)
		(layer "In9.Cu")
		(net "P2E_GPU_TX_DP")
	)
	(segment
		(start 24.802592 -110.33252)
		(end 19.78533 -110.33252)
		(width 0.1143)
		(layer "In9.Cu")
		(net "P2E_GPU_TX_DP")
	)
	(segment
		(start 73.17232 -67.169284)
		(end 73.17232 -68.822062)
		(width 0.1143)
		(layer "In9.Cu")
		(net "P2E_GPU_TX_DP")
	)
	(segment
		(start 56.259476 -112.938306)
		(end 55.558182 -113.6396)
		(width 0.1143)
		(layer "In9.Cu")
		(net "P2E_GPU_TX_DP")
	)
	(segment
		(start 19.78533 -110.33252)
		(end 19.57451 -110.1217)
		(width 0.1143)
		(layer "In9.Cu")
		(net "P2E_GPU_TX_DP")
	)
	(segment
		(start 53.086 -112.377982)
		(end 52.604416 -111.896398)
		(width 0.1143)
		(layer "In9.Cu")
		(net "P2E_GPU_TX_DP")
	)
	(segment
		(start 67.1576 -62.381638)
		(end 67.1576 -62.991746)
		(width 0.1143)
		(layer "In9.Cu")
		(net "P2E_GPU_TX_DP")
	)
	(segment
		(start 40.792654 -109.728)
		(end 39.318946 -109.728)
		(width 0.1143)
		(layer "In9.Cu")
		(net "P2E_GPU_TX_DP")
	)
	(segment
		(start 43.35145 -110.35157)
		(end 43.00855 -110.35157)
		(width 0.1143)
		(layer "In9.Cu")
		(net "P2E_GPU_TX_DP")
	)
	(segment
		(start 42.81297 -110.54715)
		(end 41.611804 -110.54715)
		(width 0.1143)
		(layer "In9.Cu")
		(net "P2E_GPU_TX_DP")
	)
	(segment
		(start 57.493662 -111.70412)
		(end 56.778906 -112.418876)
		(width 0.1143)
		(layer "In9.Cu")
		(net "P2E_GPU_TX_DP")
	)
	(segment
		(start 44.92117 -110.54715)
		(end 43.54703 -110.54715)
		(width 0.1143)
		(layer "In9.Cu")
		(net "P2E_GPU_TX_DP")
	)
	(segment
		(start 45.11675 -110.35157)
		(end 44.92117 -110.54715)
		(width 0.1143)
		(layer "In9.Cu")
		(net "P2E_GPU_TX_DP")
	)
	(segment
		(start 65.710562 -60.9346)
		(end 67.1576 -62.381638)
		(width 0.1143)
		(layer "In9.Cu")
		(net "P2E_GPU_TX_DP")
	)
	(segment
		(start 36.24707 -110.63732)
		(end 35.90925 -110.63732)
		(width 0.1143)
		(layer "In9.Cu")
		(net "P2E_GPU_TX_DP")
	)
	(segment
		(start 48.021494 -111.00689)
		(end 46.911514 -110.54715)
		(width 0.1143)
		(layer "In9.Cu")
		(net "P2E_GPU_TX_DP")
	)
	(segment
		(start 63.922656 -60.341256)
		(end 64.29248 -60.71108)
		(width 0.1143)
		(layer "In9.Cu")
		(net "P2E_GPU_TX_DP")
	)
	(segment
		(start 64.643 -105.092754)
		(end 63.36792 -108.171488)
		(width 0.1143)
		(layer "In9.Cu")
		(net "P2E_GPU_TX_DP")
	)
	(segment
		(start 65.032128 -60.9346)
		(end 65.710562 -60.9346)
		(width 0.1143)
		(layer "In9.Cu")
		(net "P2E_GPU_TX_DP")
	)
	(segment
		(start 14.01064 -108.857796)
		(end 14.01064 -108.02366)
		(width 0.1143)
		(layer "In9.Cu")
		(net "P2E_GPU_TX_DP")
	)
	(segment
		(start 68.09232 -87.45728)
		(end 67.275202 -88.274398)
		(width 0.1143)
		(layer "In9.Cu")
		(net "P2E_GPU_TX_DP")
	)
	(segment
		(start 67.275202 -88.274398)
		(end 65.5066 -92.544646)
		(width 0.1143)
		(layer "In9.Cu")
		(net "P2E_GPU_TX_DP")
	)
	(segment
		(start 72.317864 -69.676518)
		(end 71.784464 -69.676518)
		(width 0.1143)
		(layer "In9.Cu")
		(net "P2E_GPU_TX_DP")
	)
	(segment
		(start 35.69843 -110.4265)
		(end 35.36061 -110.4265)
		(width 0.1143)
		(layer "In9.Cu")
		(net "P2E_GPU_TX_DP")
	)
	(segment
		(start 38.409626 -110.63732)
		(end 37.00653 -110.63732)
		(width 0.1143)
		(layer "In9.Cu")
		(net "P2E_GPU_TX_DP")
	)
	(segment
		(start 19.23669 -110.1217)
		(end 19.02587 -110.33252)
		(width 0.1143)
		(layer "In9.Cu")
		(net "P2E_GPU_TX_DP")
	)
	(segment
		(start 70.93712 -71.291196)
		(end 70.3072 -72.812148)
		(width 0.1143)
		(layer "In9.Cu")
		(net "P2E_GPU_TX_DP")
	)
	(segment
		(start 35.36061 -110.4265)
		(end 35.14979 -110.63732)
		(width 0.1143)
		(layer "In9.Cu")
		(net "P2E_GPU_TX_DP")
	)
	(segment
		(start 71.784464 -69.676518)
		(end 70.93712 -70.523862)
		(width 0.1143)
		(layer "In9.Cu")
		(net "P2E_GPU_TX_DP")
	)
	(segment
		(start 63.922656 -59.998864)
		(end 63.922656 -60.341256)
		(width 0.1143)
		(layer "In9.Cu")
		(net "P2E_GPU_TX_DP")
	)
	(segment
		(start 63.36792 -108.664502)
		(end 63.222886 -109.014514)
		(width 0.1143)
		(layer "In9.Cu")
		(net "P2E_GPU_TX_DP")
	)
	(segment
		(start 19.02587 -110.33252)
		(end 18.035016 -110.33252)
		(width 0.1143)
		(layer "In9.Cu")
		(net "P2E_GPU_TX_DP")
	)
	(segment
		(start 69.62648 -85.11032)
		(end 68.898262 -85.11032)
		(width 0.1143)
		(layer "In9.Cu")
		(net "P2E_GPU_TX_DP")
	)
	(segment
		(start 56.778906 -112.418876)
		(end 56.502046 -112.418876)
		(width 0.1143)
		(layer "In9.Cu")
		(net "P2E_GPU_TX_DP")
	)
	(segment
		(start 68.09232 -85.916262)
		(end 68.09232 -87.45728)
		(width 0.1143)
		(layer "In9.Cu")
		(net "P2E_GPU_TX_DP")
	)
	(segment
		(start 64.643 -99.822)
		(end 64.643 -105.092754)
		(width 0.1143)
		(layer "In9.Cu")
		(net "P2E_GPU_TX_DP")
	)
	(segment
		(start 58.57748 -111.70412)
		(end 57.493662 -111.70412)
		(width 0.1143)
		(layer "In9.Cu")
		(net "P2E_GPU_TX_DP")
	)
	(segment
		(start 39.318946 -109.728)
		(end 38.409626 -110.63732)
		(width 0.1143)
		(layer "In9.Cu")
		(net "P2E_GPU_TX_DP")
	)
	(segment
		(start 19.57451 -110.1217)
		(end 19.23669 -110.1217)
		(width 0.1143)
		(layer "In9.Cu")
		(net "P2E_GPU_TX_DP")
	)
	(segment
		(start 56.502046 -112.418876)
		(end 56.259476 -112.661446)
		(width 0.1143)
		(layer "In9.Cu")
		(net "P2E_GPU_TX_DP")
	)
	(segment
		(start 70.93712 -70.523862)
		(end 70.93712 -71.291196)
		(width 0.1143)
		(layer "In9.Cu")
		(net "P2E_GPU_TX_DP")
	)
	(segment
		(start 46.911514 -110.54715)
		(end 45.65523 -110.54715)
		(width 0.1143)
		(layer "In9.Cu")
		(net "P2E_GPU_TX_DP")
	)
	(segment
		(start 43.54703 -110.54715)
		(end 43.35145 -110.35157)
		(width 0.1143)
		(layer "In9.Cu")
		(net "P2E_GPU_TX_DP")
	)
	(segment
		(start 14.01064 -108.02366)
		(end 14.2875 -107.7468)
		(width 0.1143)
		(layer "In9.Cu")
		(net "P2E_GPU_TX_DP")
	)
	(segment
		(start 18.035016 -110.33252)
		(end 17.421606 -110.58652)
		(width 0.1143)
		(layer "In9.Cu")
		(net "P2E_GPU_TX_DP")
	)
	(segment
		(start 65.5066 -98.9584)
		(end 64.643 -99.822)
		(width 0.1143)
		(layer "In9.Cu")
		(net "P2E_GPU_TX_DP")
	)
	(segment
		(start 72.119236 -66.1162)
		(end 73.17232 -67.169284)
		(width 0.1143)
		(layer "In9.Cu")
		(net "P2E_GPU_TX_DP")
	)
	(segment
		(start 14.22146 -109.068616)
		(end 14.01064 -108.857796)
		(width 0.1143)
		(layer "In9.Cu")
		(net "P2E_GPU_TX_DP")
	)
	(segment
		(start 35.90925 -110.63732)
		(end 35.69843 -110.4265)
		(width 0.1143)
		(layer "In9.Cu")
		(net "P2E_GPU_TX_DP")
	)
	(segment
		(start 14.01064 -109.955076)
		(end 14.01064 -109.617256)
		(width 0.1143)
		(layer "In9.Cu")
		(net "P2E_GPU_TX_DP")
	)
	(segment
		(start 36.79571 -110.4265)
		(end 36.45789 -110.4265)
		(width 0.1143)
		(layer "In9.Cu")
		(net "P2E_GPU_TX_DP")
	)
	(segment
		(start 73.17232 -68.822062)
		(end 72.317864 -69.676518)
		(width 0.1143)
		(layer "In9.Cu")
		(net "P2E_GPU_TX_DP")
	)
	(segment
		(start 64.808608 -60.71108)
		(end 65.032128 -60.9346)
		(width 0.1143)
		(layer "In9.Cu")
		(net "P2E_GPU_TX_DP")
	)
	(segment
		(start 52.604416 -111.896398)
		(end 50.4571 -111.00689)
		(width 0.1143)
		(layer "In9.Cu")
		(net "P2E_GPU_TX_DP")
	)
	(segment
		(start 55.558182 -113.6396)
		(end 53.711602 -113.6396)
		(width 0.1143)
		(layer "In9.Cu")
		(net "P2E_GPU_TX_DP")
	)
	(segment
		(start 25.544272 -111.0742)
		(end 24.802592 -110.33252)
		(width 0.1143)
		(layer "In9.Cu")
		(net "P2E_GPU_TX_DP")
	)
	(segment
		(start 37.00653 -110.63732)
		(end 36.79571 -110.4265)
		(width 0.1143)
		(layer "In9.Cu")
		(net "P2E_GPU_TX_DP")
	)
	(segment
		(start 41.611804 -110.54715)
		(end 40.792654 -109.728)
		(width 0.1143)
		(layer "In9.Cu")
		(net "P2E_GPU_TX_DP")
	)
	(segment
		(start 64.29248 -60.71108)
		(end 64.808608 -60.71108)
		(width 0.1143)
		(layer "In9.Cu")
		(net "P2E_GPU_TX_DP")
	)
	(segment
		(start 14.02715 -110.776004)
		(end 16.7005 -113.449354)
		(width 0.14224)
		(layer "F.Cu")
		(net "P2E_GPU_TX_C_DP")
	)
	(segment
		(start 14.351 -109.74705)
		(end 14.02715 -110.0709)
		(width 0.14224)
		(layer "F.Cu")
		(net "P2E_GPU_TX_C_DP")
	)
	(segment
		(start 16.7005 -113.449354)
		(end 17.229074 -114.72545)
		(width 0.14224)
		(layer "F.Cu")
		(net "P2E_GPU_TX_C_DP")
	)
	(segment
		(start 14.02715 -110.0709)
		(end 14.02715 -110.776004)
		(width 0.14224)
		(layer "F.Cu")
		(net "P2E_GPU_TX_C_DP")
	)
	(segment
		(start 17.344898 -117.534436)
		(end 17.344898 -118.25986)
		(width 0.14224)
		(layer "F.Cu")
		(net "P2E_GPU_TX_C_DP")
	)
	(segment
		(start 17.229074 -114.72545)
		(end 17.229074 -117.418612)
		(width 0.14224)
		(layer "F.Cu")
		(net "P2E_GPU_TX_C_DP")
	)
	(segment
		(start 17.229074 -117.418612)
		(end 17.344898 -117.534436)
		(width 0.14224)
		(layer "F.Cu")
		(net "P2E_GPU_TX_C_DP")
	)
	(segment
		(start 16.860774 -117.41404)
		(end 16.74495 -117.529864)
		(width 0.14224)
		(layer "F.Cu")
		(net "P2E_GPU_TX_C_DN")
	)
	(segment
		(start 13.65885 -110.928658)
		(end 16.38808 -113.658142)
		(width 0.14224)
		(layer "F.Cu")
		(net "P2E_GPU_TX_C_DN")
	)
	(segment
		(start 16.74495 -117.529864)
		(end 16.74495 -118.25986)
		(width 0.14224)
		(layer "F.Cu")
		(net "P2E_GPU_TX_C_DN")
	)
	(segment
		(start 16.860774 -114.798856)
		(end 16.860774 -117.41404)
		(width 0.14224)
		(layer "F.Cu")
		(net "P2E_GPU_TX_C_DN")
	)
	(segment
		(start 16.38808 -113.658142)
		(end 16.860774 -114.798856)
		(width 0.14224)
		(layer "F.Cu")
		(net "P2E_GPU_TX_C_DN")
	)
	(segment
		(start 13.65885 -110.0709)
		(end 13.65885 -110.928658)
		(width 0.14224)
		(layer "F.Cu")
		(net "P2E_GPU_TX_C_DN")
	)
	(segment
		(start 13.335 -109.74705)
		(end 13.65885 -110.0709)
		(width 0.14224)
		(layer "F.Cu")
		(net "P2E_GPU_TX_C_DN")
	)
	(segment
		(start 64.094868 -57.771284)
		(end 64.490092 -58.166508)
		(width 0.1143)
		(layer "F.Cu")
		(net "P2E_GPU_RX_DP")
	)
	(via
		(at 16.146526 -115.149376)
		(size 0.508)
		(drill 0.254)
		(layers "F.Cu" "B.Cu")
		(net "P2E_GPU_RX_DP")
	)
	(via
		(at 64.490092 -58.166508)
		(size 0.4572)
		(drill 0.254)
		(layers "F.Cu" "B.Cu")
		(net "P2E_GPU_RX_DP")
	)
	(segment
		(start 16.146526 -115.149376)
		(end 16.406876 -115.409726)
		(width 0.14224)
		(layer "B.Cu")
		(net "P2E_GPU_RX_DP")
	)
	(segment
		(start 17.229074 -117.410484)
		(end 17.344898 -117.526308)
		(width 0.14224)
		(layer "B.Cu")
		(net "P2E_GPU_RX_DP")
	)
	(segment
		(start 17.344898 -117.526308)
		(end 17.344898 -118.25986)
		(width 0.14224)
		(layer "B.Cu")
		(net "P2E_GPU_RX_DP")
	)
	(segment
		(start 16.406876 -115.409726)
		(end 16.78178 -115.409726)
		(width 0.14224)
		(layer "B.Cu")
		(net "P2E_GPU_RX_DP")
	)
	(segment
		(start 17.229074 -115.85702)
		(end 17.229074 -117.410484)
		(width 0.14224)
		(layer "B.Cu")
		(net "P2E_GPU_RX_DP")
	)
	(segment
		(start 16.78178 -115.409726)
		(end 17.229074 -115.85702)
		(width 0.14224)
		(layer "B.Cu")
		(net "P2E_GPU_RX_DP")
	)
	(segment
		(start 48.50384 -113.333022)
		(end 46.41088 -112.46612)
		(width 0.1143)
		(layer "In9.Cu")
		(net "P2E_GPU_RX_DP")
	)
	(segment
		(start 77.5716 -70.13067)
		(end 77.36078 -70.34149)
		(width 0.1143)
		(layer "In9.Cu")
		(net "P2E_GPU_RX_DP")
	)
	(segment
		(start 70.376034 -62.3824)
		(end 73.69937 -62.3824)
		(width 0.1143)
		(layer "In9.Cu")
		(net "P2E_GPU_RX_DP")
	)
	(segment
		(start 77.36078 -70.67931)
		(end 77.5716 -70.89013)
		(width 0.1143)
		(layer "In9.Cu")
		(net "P2E_GPU_RX_DP")
	)
	(segment
		(start 46.41088 -112.46612)
		(end 43.875198 -112.46612)
		(width 0.1143)
		(layer "In9.Cu")
		(net "P2E_GPU_RX_DP")
	)
	(segment
		(start 66.0654 -110.701582)
		(end 63.246 -113.520982)
		(width 0.1143)
		(layer "In9.Cu")
		(net "P2E_GPU_RX_DP")
	)
	(segment
		(start 77.36078 -67.54749)
		(end 77.36078 -67.88531)
		(width 0.1143)
		(layer "In9.Cu")
		(net "P2E_GPU_RX_DP")
	)
	(segment
		(start 76.070206 -74.306176)
		(end 76.070206 -77.041248)
		(width 0.1143)
		(layer "In9.Cu")
		(net "P2E_GPU_RX_DP")
	)
	(segment
		(start 43.875198 -112.46612)
		(end 42.349928 -113.098072)
		(width 0.1143)
		(layer "In9.Cu")
		(net "P2E_GPU_RX_DP")
	)
	(segment
		(start 77.5716 -72.804782)
		(end 77.056996 -73.319386)
		(width 0.1143)
		(layer "In9.Cu")
		(net "P2E_GPU_RX_DP")
	)
	(segment
		(start 68.413376 -60.909454)
		(end 68.655946 -61.152024)
		(width 0.1143)
		(layer "In9.Cu")
		(net "P2E_GPU_RX_DP")
	)
	(segment
		(start 77.5716 -66.701416)
		(end 77.5716 -67.33667)
		(width 0.1143)
		(layer "In9.Cu")
		(net "P2E_GPU_RX_DP")
	)
	(segment
		(start 76.524104 -64.723772)
		(end 76.799948 -64.838072)
		(width 0.1143)
		(layer "In9.Cu")
		(net "P2E_GPU_RX_DP")
	)
	(segment
		(start 41.111678 -114.336322)
		(end 40.716454 -115.290346)
		(width 0.1143)
		(layer "In9.Cu")
		(net "P2E_GPU_RX_DP")
	)
	(segment
		(start 77.36078 -67.88531)
		(end 77.5716 -68.09613)
		(width 0.1143)
		(layer "In9.Cu")
		(net "P2E_GPU_RX_DP")
	)
	(segment
		(start 49.775618 -114.6048)
		(end 48.50384 -113.333022)
		(width 0.1143)
		(layer "In9.Cu")
		(net "P2E_GPU_RX_DP")
	)
	(segment
		(start 77.5716 -70.89013)
		(end 77.5716 -72.804782)
		(width 0.1143)
		(layer "In9.Cu")
		(net "P2E_GPU_RX_DP")
	)
	(segment
		(start 77.028548 -65.39103)
		(end 77.028802 -65.39103)
		(width 0.1143)
		(layer "In9.Cu")
		(net "P2E_GPU_RX_DP")
	)
	(segment
		(start 68.0212 -93.878654)
		(end 68.0212 -103.246936)
		(width 0.1143)
		(layer "In9.Cu")
		(net "P2E_GPU_RX_DP")
	)
	(segment
		(start 65.842896 -58.189368)
		(end 66.720974 -59.067446)
		(width 0.1143)
		(layer "In9.Cu")
		(net "P2E_GPU_RX_DP")
	)
	(segment
		(start 76.914756 -65.666366)
		(end 77.044042 -65.978786)
		(width 0.1143)
		(layer "In9.Cu")
		(net "P2E_GPU_RX_DP")
	)
	(segment
		(start 63.246 -113.520982)
		(end 63.246 -115.527582)
		(width 0.1143)
		(layer "In9.Cu")
		(net "P2E_GPU_RX_DP")
	)
	(segment
		(start 18.15084 -115.9256)
		(end 16.945102 -115.426236)
		(width 0.1143)
		(layer "In9.Cu")
		(net "P2E_GPU_RX_DP")
	)
	(segment
		(start 66.0654 -107.968796)
		(end 66.0654 -110.701582)
		(width 0.1143)
		(layer "In9.Cu")
		(net "P2E_GPU_RX_DP")
	)
	(segment
		(start 77.319378 -66.092832)
		(end 77.5716 -66.701416)
		(width 0.1143)
		(layer "In9.Cu")
		(net "P2E_GPU_RX_DP")
	)
	(segment
		(start 69.736208 -62.11697)
		(end 70.376034 -62.3824)
		(width 0.1143)
		(layer "In9.Cu")
		(net "P2E_GPU_RX_DP")
	)
	(segment
		(start 52.975256 -115.43411)
		(end 52.145946 -114.6048)
		(width 0.1143)
		(layer "In9.Cu")
		(net "P2E_GPU_RX_DP")
	)
	(segment
		(start 38.5572 -115.7986)
		(end 35.0774 -112.3188)
		(width 0.1143)
		(layer "In9.Cu")
		(net "P2E_GPU_RX_DP")
	)
	(segment
		(start 68.0212 -103.246936)
		(end 66.0654 -107.968796)
		(width 0.1143)
		(layer "In9.Cu")
		(net "P2E_GPU_RX_DP")
	)
	(segment
		(start 76.070206 -77.041248)
		(end 75.48372 -77.627734)
		(width 0.1143)
		(layer "In9.Cu")
		(net "P2E_GPU_RX_DP")
	)
	(segment
		(start 76.394818 -64.411606)
		(end 76.524104 -64.723772)
		(width 0.1143)
		(layer "In9.Cu")
		(net "P2E_GPU_RX_DP")
	)
	(segment
		(start 32.071564 -112.3188)
		(end 31.536894 -112.540288)
		(width 0.1143)
		(layer "In9.Cu")
		(net "P2E_GPU_RX_DP")
	)
	(segment
		(start 77.5716 -67.33667)
		(end 77.36078 -67.54749)
		(width 0.1143)
		(layer "In9.Cu")
		(net "P2E_GPU_RX_DP")
	)
	(segment
		(start 35.0774 -112.3188)
		(end 32.071564 -112.3188)
		(width 0.1143)
		(layer "In9.Cu")
		(net "P2E_GPU_RX_DP")
	)
	(segment
		(start 60.825126 -116.53012)
		(end 58.691018 -115.6462)
		(width 0.1143)
		(layer "In9.Cu")
		(net "P2E_GPU_RX_DP")
	)
	(segment
		(start 55.399178 -115.6462)
		(end 54.887114 -115.43411)
		(width 0.1143)
		(layer "In9.Cu")
		(net "P2E_GPU_RX_DP")
	)
	(segment
		(start 68.932806 -61.152024)
		(end 69.410834 -61.629798)
		(width 0.1143)
		(layer "In9.Cu")
		(net "P2E_GPU_RX_DP")
	)
	(segment
		(start 74.28992 -82.466942)
		(end 74.28992 -86.72068)
		(width 0.1143)
		(layer "In9.Cu")
		(net "P2E_GPU_RX_DP")
	)
	(segment
		(start 73.781666 -87.228934)
		(end 73.527666 -87.228934)
		(width 0.1143)
		(layer "In9.Cu")
		(net "P2E_GPU_RX_DP")
	)
	(segment
		(start 52.145946 -114.6048)
		(end 49.775618 -114.6048)
		(width 0.1143)
		(layer "In9.Cu")
		(net "P2E_GPU_RX_DP")
	)
	(segment
		(start 68.655946 -61.152024)
		(end 68.932806 -61.152024)
		(width 0.1143)
		(layer "In9.Cu")
		(net "P2E_GPU_RX_DP")
	)
	(segment
		(start 75.48372 -77.627734)
		(end 75.48372 -79.60487)
		(width 0.1143)
		(layer "In9.Cu")
		(net "P2E_GPU_RX_DP")
	)
	(segment
		(start 67.422522 -59.997594)
		(end 68.029836 -60.249308)
		(width 0.1143)
		(layer "In9.Cu")
		(net "P2E_GPU_RX_DP")
	)
	(segment
		(start 63.246 -115.527582)
		(end 62.243462 -116.53012)
		(width 0.1143)
		(layer "In9.Cu")
		(net "P2E_GPU_RX_DP")
	)
	(segment
		(start 69.410834 -61.629798)
		(end 69.736208 -62.11697)
		(width 0.1143)
		(layer "In9.Cu")
		(net "P2E_GPU_RX_DP")
	)
	(segment
		(start 54.887114 -115.43411)
		(end 52.975256 -115.43411)
		(width 0.1143)
		(layer "In9.Cu")
		(net "P2E_GPU_RX_DP")
	)
	(segment
		(start 22.826472 -116.8654)
		(end 21.886672 -115.9256)
		(width 0.1143)
		(layer "In9.Cu")
		(net "P2E_GPU_RX_DP")
	)
	(segment
		(start 27.211782 -116.8654)
		(end 22.826472 -116.8654)
		(width 0.1143)
		(layer "In9.Cu")
		(net "P2E_GPU_RX_DP")
	)
	(segment
		(start 75.48372 -81.273142)
		(end 74.28992 -82.466942)
		(width 0.1143)
		(layer "In9.Cu")
		(net "P2E_GPU_RX_DP")
	)
	(segment
		(start 77.028802 -65.39103)
		(end 76.914756 -65.666366)
		(width 0.1143)
		(layer "In9.Cu")
		(net "P2E_GPU_RX_DP")
	)
	(segment
		(start 77.319632 -66.092832)
		(end 77.319378 -66.092832)
		(width 0.1143)
		(layer "In9.Cu")
		(net "P2E_GPU_RX_DP")
	)
	(segment
		(start 65.342516 -58.189368)
		(end 65.363852 -58.189368)
		(width 0.086106)
		(layer "In9.Cu")
		(net "P2E_GPU_RX_DP")
	)
	(segment
		(start 76.379832 -63.824104)
		(end 76.508864 -64.136016)
		(width 0.1143)
		(layer "In9.Cu")
		(net "P2E_GPU_RX_DP")
	)
	(segment
		(start 73.258934 -87.751666)
		(end 72.197214 -88.813386)
		(width 0.1143)
		(layer "In9.Cu")
		(net "P2E_GPU_RX_DP")
	)
	(segment
		(start 75.2729 -79.81569)
		(end 75.2729 -80.15351)
		(width 0.1143)
		(layer "In9.Cu")
		(net "P2E_GPU_RX_DP")
	)
	(segment
		(start 68.413376 -60.632594)
		(end 68.413376 -60.909454)
		(width 0.1143)
		(layer "In9.Cu")
		(net "P2E_GPU_RX_DP")
	)
	(segment
		(start 58.691018 -115.6462)
		(end 55.399178 -115.6462)
		(width 0.1143)
		(layer "In9.Cu")
		(net "P2E_GPU_RX_DP")
	)
	(segment
		(start 40.2082 -115.7986)
		(end 38.5572 -115.7986)
		(width 0.1143)
		(layer "In9.Cu")
		(net "P2E_GPU_RX_DP")
	)
	(segment
		(start 64.8716 -58.0644)
		(end 65.217548 -58.0644)
		(width 0.086106)
		(layer "In9.Cu")
		(net "P2E_GPU_RX_DP")
	)
	(segment
		(start 66.882772 -59.457844)
		(end 67.422522 -59.997594)
		(width 0.1143)
		(layer "In9.Cu")
		(net "P2E_GPU_RX_DP")
	)
	(segment
		(start 74.43343 -62.3824)
		(end 74.938128 -62.3824)
		(width 0.1143)
		(layer "In9.Cu")
		(net "P2E_GPU_RX_DP")
	)
	(segment
		(start 73.89495 -62.57798)
		(end 74.23785 -62.57798)
		(width 0.1143)
		(layer "In9.Cu")
		(net "P2E_GPU_RX_DP")
	)
	(segment
		(start 75.48372 -79.60487)
		(end 75.2729 -79.81569)
		(width 0.1143)
		(layer "In9.Cu")
		(net "P2E_GPU_RX_DP")
	)
	(segment
		(start 77.36078 -68.81749)
		(end 77.36078 -69.15531)
		(width 0.1143)
		(layer "In9.Cu")
		(net "P2E_GPU_RX_DP")
	)
	(segment
		(start 62.243462 -116.53012)
		(end 60.825126 -116.53012)
		(width 0.1143)
		(layer "In9.Cu")
		(net "P2E_GPU_RX_DP")
	)
	(segment
		(start 74.28992 -86.72068)
		(end 73.781666 -87.228934)
		(width 0.1143)
		(layer "In9.Cu")
		(net "P2E_GPU_RX_DP")
	)
	(segment
		(start 76.758546 -73.319386)
		(end 76.519786 -73.558146)
		(width 0.1143)
		(layer "In9.Cu")
		(net "P2E_GPU_RX_DP")
	)
	(segment
		(start 77.36078 -69.15531)
		(end 77.5716 -69.36613)
		(width 0.1143)
		(layer "In9.Cu")
		(net "P2E_GPU_RX_DP")
	)
	(segment
		(start 65.363852 -58.189368)
		(end 65.842896 -58.189368)
		(width 0.1143)
		(layer "In9.Cu")
		(net "P2E_GPU_RX_DP")
	)
	(segment
		(start 75.48372 -80.36433)
		(end 75.48372 -81.273142)
		(width 0.1143)
		(layer "In9.Cu")
		(net "P2E_GPU_RX_DP")
	)
	(segment
		(start 31.536894 -112.540288)
		(end 27.211782 -116.8654)
		(width 0.1143)
		(layer "In9.Cu")
		(net "P2E_GPU_RX_DP")
	)
	(segment
		(start 75.2729 -80.15351)
		(end 75.48372 -80.36433)
		(width 0.1143)
		(layer "In9.Cu")
		(net "P2E_GPU_RX_DP")
	)
	(segment
		(start 77.056996 -73.319386)
		(end 76.758546 -73.319386)
		(width 0.1143)
		(layer "In9.Cu")
		(net "P2E_GPU_RX_DP")
	)
	(segment
		(start 77.044042 -65.978786)
		(end 77.319632 -66.092832)
		(width 0.1143)
		(layer "In9.Cu")
		(net "P2E_GPU_RX_DP")
	)
	(segment
		(start 66.720974 -59.067446)
		(end 66.72072 -59.067446)
		(width 0.1143)
		(layer "In9.Cu")
		(net "P2E_GPU_RX_DP")
	)
	(segment
		(start 76.519786 -73.558146)
		(end 76.519786 -73.856596)
		(width 0.1143)
		(layer "In9.Cu")
		(net "P2E_GPU_RX_DP")
	)
	(segment
		(start 73.258934 -87.497666)
		(end 73.258934 -87.751666)
		(width 0.1143)
		(layer "In9.Cu")
		(net "P2E_GPU_RX_DP")
	)
	(segment
		(start 76.508864 -64.136016)
		(end 76.394818 -64.411606)
		(width 0.1143)
		(layer "In9.Cu")
		(net "P2E_GPU_RX_DP")
	)
	(segment
		(start 64.769492 -58.166508)
		(end 64.8716 -58.0644)
		(width 0.086106)
		(layer "In9.Cu")
		(net "P2E_GPU_RX_DP")
	)
	(segment
		(start 68.029836 -60.249308)
		(end 68.413376 -60.632594)
		(width 0.1143)
		(layer "In9.Cu")
		(net "P2E_GPU_RX_DP")
	)
	(segment
		(start 77.5716 -68.60667)
		(end 77.36078 -68.81749)
		(width 0.1143)
		(layer "In9.Cu")
		(net "P2E_GPU_RX_DP")
	)
	(segment
		(start 40.716454 -115.290346)
		(end 40.2082 -115.7986)
		(width 0.1143)
		(layer "In9.Cu")
		(net "P2E_GPU_RX_DP")
	)
	(segment
		(start 73.69937 -62.3824)
		(end 73.89495 -62.57798)
		(width 0.1143)
		(layer "In9.Cu")
		(net "P2E_GPU_RX_DP")
	)
	(segment
		(start 74.938128 -62.3824)
		(end 76.379832 -63.824104)
		(width 0.1143)
		(layer "In9.Cu")
		(net "P2E_GPU_RX_DP")
	)
	(segment
		(start 21.886672 -115.9256)
		(end 18.15084 -115.9256)
		(width 0.1143)
		(layer "In9.Cu")
		(net "P2E_GPU_RX_DP")
	)
	(segment
		(start 65.217548 -58.0644)
		(end 65.342516 -58.189368)
		(width 0.086106)
		(layer "In9.Cu")
		(net "P2E_GPU_RX_DP")
	)
	(segment
		(start 77.5716 -68.09613)
		(end 77.5716 -68.60667)
		(width 0.1143)
		(layer "In9.Cu")
		(net "P2E_GPU_RX_DP")
	)
	(segment
		(start 72.197214 -88.813386)
		(end 71.56831 -90.331544)
		(width 0.1143)
		(layer "In9.Cu")
		(net "P2E_GPU_RX_DP")
	)
	(segment
		(start 73.527666 -87.228934)
		(end 73.258934 -87.497666)
		(width 0.1143)
		(layer "In9.Cu")
		(net "P2E_GPU_RX_DP")
	)
	(segment
		(start 77.36078 -70.34149)
		(end 77.36078 -70.67931)
		(width 0.1143)
		(layer "In9.Cu")
		(net "P2E_GPU_RX_DP")
	)
	(segment
		(start 76.799694 -64.838072)
		(end 77.028548 -65.39103)
		(width 0.1143)
		(layer "In9.Cu")
		(net "P2E_GPU_RX_DP")
	)
	(segment
		(start 16.945102 -115.426236)
		(end 16.423386 -115.426236)
		(width 0.1143)
		(layer "In9.Cu")
		(net "P2E_GPU_RX_DP")
	)
	(segment
		(start 76.519786 -73.856596)
		(end 76.070206 -74.306176)
		(width 0.1143)
		(layer "In9.Cu")
		(net "P2E_GPU_RX_DP")
	)
	(segment
		(start 76.799948 -64.838072)
		(end 76.799694 -64.838072)
		(width 0.1143)
		(layer "In9.Cu")
		(net "P2E_GPU_RX_DP")
	)
	(segment
		(start 71.56831 -90.331544)
		(end 68.0212 -93.878654)
		(width 0.1143)
		(layer "In9.Cu")
		(net "P2E_GPU_RX_DP")
	)
	(segment
		(start 16.423386 -115.426236)
		(end 16.146526 -115.149376)
		(width 0.1143)
		(layer "In9.Cu")
		(net "P2E_GPU_RX_DP")
	)
	(segment
		(start 42.349928 -113.098072)
		(end 41.111678 -114.336322)
		(width 0.1143)
		(layer "In9.Cu")
		(net "P2E_GPU_RX_DP")
	)
	(segment
		(start 64.490092 -58.166508)
		(end 64.769492 -58.166508)
		(width 0.086106)
		(layer "In9.Cu")
		(net "P2E_GPU_RX_DP")
	)
	(segment
		(start 77.5716 -69.36613)
		(end 77.5716 -70.13067)
		(width 0.1143)
		(layer "In9.Cu")
		(net "P2E_GPU_RX_DP")
	)
	(segment
		(start 66.72072 -59.067446)
		(end 66.882772 -59.457844)
		(width 0.1143)
		(layer "In9.Cu")
		(net "P2E_GPU_RX_DP")
	)
	(segment
		(start 74.23785 -62.57798)
		(end 74.43343 -62.3824)
		(width 0.1143)
		(layer "In9.Cu")
		(net "P2E_GPU_RX_DP")
	)
	(segment
		(start 63.295022 -57.771284)
		(end 63.690246 -58.166508)
		(width 0.1143)
		(layer "F.Cu")
		(net "P2E_GPU_RX_DN")
	)
	(via
		(at 63.690246 -58.166508)
		(size 0.4572)
		(drill 0.254)
		(layers "F.Cu" "B.Cu")
		(net "P2E_GPU_RX_DN")
	)
	(via
		(at 16.146526 -116.038376)
		(size 0.508)
		(drill 0.254)
		(layers "F.Cu" "B.Cu")
		(net "P2E_GPU_RX_DN")
	)
	(segment
		(start 16.146526 -116.038376)
		(end 16.406876 -115.778026)
		(width 0.14224)
		(layer "B.Cu")
		(net "P2E_GPU_RX_DN")
	)
	(segment
		(start 16.629126 -115.778026)
		(end 16.860774 -116.009674)
		(width 0.14224)
		(layer "B.Cu")
		(net "P2E_GPU_RX_DN")
	)
	(segment
		(start 16.406876 -115.778026)
		(end 16.629126 -115.778026)
		(width 0.14224)
		(layer "B.Cu")
		(net "P2E_GPU_RX_DN")
	)
	(segment
		(start 16.74495 -117.516148)
		(end 16.74495 -118.25986)
		(width 0.14224)
		(layer "B.Cu")
		(net "P2E_GPU_RX_DN")
	)
	(segment
		(start 16.860774 -116.009674)
		(end 16.860774 -117.400324)
		(width 0.14224)
		(layer "B.Cu")
		(net "P2E_GPU_RX_DN")
	)
	(segment
		(start 16.860774 -117.400324)
		(end 16.74495 -117.516148)
		(width 0.14224)
		(layer "B.Cu")
		(net "P2E_GPU_RX_DN")
	)
	(segment
		(start 68.219828 -59.965082)
		(end 69.671184 -61.41593)
		(width 0.1143)
		(layer "In9.Cu")
		(net "P2E_GPU_RX_DN")
	)
	(segment
		(start 63.58128 -113.65992)
		(end 63.58128 -115.66652)
		(width 0.1143)
		(layer "In9.Cu")
		(net "P2E_GPU_RX_DN")
	)
	(segment
		(start 70.44309 -62.04712)
		(end 75.077066 -62.04712)
		(width 0.1143)
		(layer "In9.Cu")
		(net "P2E_GPU_RX_DN")
	)
	(segment
		(start 42.53992 -113.382298)
		(end 41.395904 -114.526314)
		(width 0.1143)
		(layer "In9.Cu")
		(net "P2E_GPU_RX_DN")
	)
	(segment
		(start 20.2819 -116.4717)
		(end 19.9517 -116.4717)
		(width 0.1143)
		(layer "In9.Cu")
		(net "P2E_GPU_RX_DN")
	)
	(segment
		(start 62.3824 -116.8654)
		(end 60.758324 -116.8654)
		(width 0.1143)
		(layer "In9.Cu")
		(net "P2E_GPU_RX_DN")
	)
	(segment
		(start 48.313848 -113.617248)
		(end 46.344078 -112.8014)
		(width 0.1143)
		(layer "In9.Cu")
		(net "P2E_GPU_RX_DN")
	)
	(segment
		(start 43.942 -112.8014)
		(end 42.53992 -113.382298)
		(width 0.1143)
		(layer "In9.Cu")
		(net "P2E_GPU_RX_DN")
	)
	(segment
		(start 75.077066 -62.04712)
		(end 76.664058 -63.634112)
		(width 0.1143)
		(layer "In9.Cu")
		(net "P2E_GPU_RX_DN")
	)
	(segment
		(start 75.819 -77.766672)
		(end 75.819 -81.41208)
		(width 0.1143)
		(layer "In9.Cu")
		(net "P2E_GPU_RX_DN")
	)
	(segment
		(start 58.624216 -115.98148)
		(end 55.332376 -115.98148)
		(width 0.1143)
		(layer "In9.Cu")
		(net "P2E_GPU_RX_DN")
	)
	(segment
		(start 54.820312 -115.76939)
		(end 52.836318 -115.76939)
		(width 0.1143)
		(layer "In9.Cu")
		(net "P2E_GPU_RX_DN")
	)
	(segment
		(start 41.00068 -115.480338)
		(end 40.347138 -116.13388)
		(width 0.1143)
		(layer "In9.Cu")
		(net "P2E_GPU_RX_DN")
	)
	(segment
		(start 63.58128 -115.66652)
		(end 62.3824 -116.8654)
		(width 0.1143)
		(layer "In9.Cu")
		(net "P2E_GPU_RX_DN")
	)
	(segment
		(start 67.612514 -59.713368)
		(end 68.219828 -59.965082)
		(width 0.1143)
		(layer "In9.Cu")
		(net "P2E_GPU_RX_DN")
	)
	(segment
		(start 71.852536 -90.521536)
		(end 68.35648 -94.017592)
		(width 0.1143)
		(layer "In9.Cu")
		(net "P2E_GPU_RX_DN")
	)
	(segment
		(start 66.40068 -108.035598)
		(end 66.40068 -110.84052)
		(width 0.1143)
		(layer "In9.Cu")
		(net "P2E_GPU_RX_DN")
	)
	(segment
		(start 76.664058 -63.634112)
		(end 77.90688 -66.634614)
		(width 0.1143)
		(layer "In9.Cu")
		(net "P2E_GPU_RX_DN")
	)
	(segment
		(start 66.40068 -110.84052)
		(end 63.58128 -113.65992)
		(width 0.1143)
		(layer "In9.Cu")
		(net "P2E_GPU_RX_DN")
	)
	(segment
		(start 22.687534 -117.20068)
		(end 21.747734 -116.26088)
		(width 0.1143)
		(layer "In9.Cu")
		(net "P2E_GPU_RX_DN")
	)
	(segment
		(start 52.007008 -114.94008)
		(end 49.63668 -114.94008)
		(width 0.1143)
		(layer "In9.Cu")
		(net "P2E_GPU_RX_DN")
	)
	(segment
		(start 52.836318 -115.76939)
		(end 52.007008 -114.94008)
		(width 0.1143)
		(layer "In9.Cu")
		(net "P2E_GPU_RX_DN")
	)
	(segment
		(start 67.166998 -59.267852)
		(end 67.612514 -59.713368)
		(width 0.1143)
		(layer "In9.Cu")
		(net "P2E_GPU_RX_DN")
	)
	(segment
		(start 64.762888 -57.854088)
		(end 65.363852 -57.854088)
		(width 0.086106)
		(layer "In9.Cu")
		(net "P2E_GPU_RX_DN")
	)
	(segment
		(start 46.344078 -112.8014)
		(end 43.942 -112.8014)
		(width 0.1143)
		(layer "In9.Cu")
		(net "P2E_GPU_RX_DN")
	)
	(segment
		(start 32.138366 -112.65408)
		(end 31.726886 -112.824514)
		(width 0.1143)
		(layer "In9.Cu")
		(net "P2E_GPU_RX_DN")
	)
	(segment
		(start 27.35072 -117.20068)
		(end 22.687534 -117.20068)
		(width 0.1143)
		(layer "In9.Cu")
		(net "P2E_GPU_RX_DN")
	)
	(segment
		(start 41.395904 -114.526314)
		(end 41.00068 -115.480338)
		(width 0.1143)
		(layer "In9.Cu")
		(net "P2E_GPU_RX_DN")
	)
	(segment
		(start 27.940762 -116.610638)
		(end 27.35072 -117.20068)
		(width 0.1143)
		(layer "In9.Cu")
		(net "P2E_GPU_RX_DN")
	)
	(segment
		(start 65.363852 -57.854088)
		(end 65.981834 -57.854088)
		(width 0.1143)
		(layer "In9.Cu")
		(net "P2E_GPU_RX_DN")
	)
	(segment
		(start 31.726886 -112.824514)
		(end 28.472638 -116.078762)
		(width 0.1143)
		(layer "In9.Cu")
		(net "P2E_GPU_RX_DN")
	)
	(segment
		(start 19.9517 -116.4717)
		(end 19.74088 -116.26088)
		(width 0.1143)
		(layer "In9.Cu")
		(net "P2E_GPU_RX_DN")
	)
	(segment
		(start 49.63668 -114.94008)
		(end 48.313848 -113.617248)
		(width 0.1143)
		(layer "In9.Cu")
		(net "P2E_GPU_RX_DN")
	)
	(segment
		(start 65.981834 -57.854088)
		(end 67.0052 -58.877454)
		(width 0.1143)
		(layer "In9.Cu")
		(net "P2E_GPU_RX_DN")
	)
	(segment
		(start 77.90688 -72.94372)
		(end 76.405486 -74.445114)
		(width 0.1143)
		(layer "In9.Cu")
		(net "P2E_GPU_RX_DN")
	)
	(segment
		(start 38.418262 -116.13388)
		(end 34.938462 -112.65408)
		(width 0.1143)
		(layer "In9.Cu")
		(net "P2E_GPU_RX_DN")
	)
	(segment
		(start 67.0052 -58.877454)
		(end 67.166998 -59.267852)
		(width 0.1143)
		(layer "In9.Cu")
		(net "P2E_GPU_RX_DN")
	)
	(segment
		(start 40.347138 -116.13388)
		(end 38.418262 -116.13388)
		(width 0.1143)
		(layer "In9.Cu")
		(net "P2E_GPU_RX_DN")
	)
	(segment
		(start 68.35648 -94.017592)
		(end 68.35648 -103.313738)
		(width 0.1143)
		(layer "In9.Cu")
		(net "P2E_GPU_RX_DN")
	)
	(segment
		(start 63.962026 -58.166508)
		(end 64.335406 -57.793128)
		(width 0.086106)
		(layer "In9.Cu")
		(net "P2E_GPU_RX_DN")
	)
	(segment
		(start 16.8783 -115.761516)
		(end 16.423386 -115.761516)
		(width 0.1143)
		(layer "In9.Cu")
		(net "P2E_GPU_RX_DN")
	)
	(segment
		(start 28.472638 -116.377212)
		(end 28.239212 -116.610638)
		(width 0.1143)
		(layer "In9.Cu")
		(net "P2E_GPU_RX_DN")
	)
	(segment
		(start 76.405486 -74.445114)
		(end 76.405486 -77.180186)
		(width 0.1143)
		(layer "In9.Cu")
		(net "P2E_GPU_RX_DN")
	)
	(segment
		(start 34.938462 -112.65408)
		(end 32.138366 -112.65408)
		(width 0.1143)
		(layer "In9.Cu")
		(net "P2E_GPU_RX_DN")
	)
	(segment
		(start 74.6252 -82.60588)
		(end 74.6252 -86.859618)
		(width 0.1143)
		(layer "In9.Cu")
		(net "P2E_GPU_RX_DN")
	)
	(segment
		(start 16.423386 -115.761516)
		(end 16.146526 -116.038376)
		(width 0.1143)
		(layer "In9.Cu")
		(net "P2E_GPU_RX_DN")
	)
	(segment
		(start 19.74088 -116.26088)
		(end 18.084038 -116.26088)
		(width 0.1143)
		(layer "In9.Cu")
		(net "P2E_GPU_RX_DN")
	)
	(segment
		(start 64.335406 -57.793128)
		(end 64.701928 -57.793128)
		(width 0.086106)
		(layer "In9.Cu")
		(net "P2E_GPU_RX_DN")
	)
	(segment
		(start 55.332376 -115.98148)
		(end 54.820312 -115.76939)
		(width 0.1143)
		(layer "In9.Cu")
		(net "P2E_GPU_RX_DN")
	)
	(segment
		(start 72.48144 -89.003378)
		(end 71.852536 -90.521536)
		(width 0.1143)
		(layer "In9.Cu")
		(net "P2E_GPU_RX_DN")
	)
	(segment
		(start 60.758324 -116.8654)
		(end 58.624216 -115.98148)
		(width 0.1143)
		(layer "In9.Cu")
		(net "P2E_GPU_RX_DN")
	)
	(segment
		(start 75.819 -81.41208)
		(end 74.6252 -82.60588)
		(width 0.1143)
		(layer "In9.Cu")
		(net "P2E_GPU_RX_DN")
	)
	(segment
		(start 63.690246 -58.166508)
		(end 63.962026 -58.166508)
		(width 0.086106)
		(layer "In9.Cu")
		(net "P2E_GPU_RX_DN")
	)
	(segment
		(start 68.35648 -103.313738)
		(end 66.40068 -108.035598)
		(width 0.1143)
		(layer "In9.Cu")
		(net "P2E_GPU_RX_DN")
	)
	(segment
		(start 28.472638 -116.078762)
		(end 28.472638 -116.377212)
		(width 0.1143)
		(layer "In9.Cu")
		(net "P2E_GPU_RX_DN")
	)
	(segment
		(start 69.671184 -61.41593)
		(end 69.958712 -61.845952)
		(width 0.1143)
		(layer "In9.Cu")
		(net "P2E_GPU_RX_DN")
	)
	(segment
		(start 21.747734 -116.26088)
		(end 20.49272 -116.26088)
		(width 0.1143)
		(layer "In9.Cu")
		(net "P2E_GPU_RX_DN")
	)
	(segment
		(start 64.701928 -57.793128)
		(end 64.762888 -57.854088)
		(width 0.086106)
		(layer "In9.Cu")
		(net "P2E_GPU_RX_DN")
	)
	(segment
		(start 77.90688 -66.634614)
		(end 77.90688 -72.94372)
		(width 0.1143)
		(layer "In9.Cu")
		(net "P2E_GPU_RX_DN")
	)
	(segment
		(start 18.084038 -116.26088)
		(end 16.8783 -115.761516)
		(width 0.1143)
		(layer "In9.Cu")
		(net "P2E_GPU_RX_DN")
	)
	(segment
		(start 76.405486 -77.180186)
		(end 75.819 -77.766672)
		(width 0.1143)
		(layer "In9.Cu")
		(net "P2E_GPU_RX_DN")
	)
	(segment
		(start 74.6252 -86.859618)
		(end 72.48144 -89.003378)
		(width 0.1143)
		(layer "In9.Cu")
		(net "P2E_GPU_RX_DN")
	)
	(segment
		(start 28.239212 -116.610638)
		(end 27.940762 -116.610638)
		(width 0.1143)
		(layer "In9.Cu")
		(net "P2E_GPU_RX_DN")
	)
	(segment
		(start 20.49272 -116.26088)
		(end 20.2819 -116.4717)
		(width 0.1143)
		(layer "In9.Cu")
		(net "P2E_GPU_RX_DN")
	)
	(segment
		(start 69.958712 -61.845952)
		(end 70.44309 -62.04712)
		(width 0.1143)
		(layer "In9.Cu")
		(net "P2E_GPU_RX_DN")
	)
	(segment
		(start 19.864324 -88.791796)
		(end 20.259548 -89.18702)
		(width 0.11684)
		(layer "F.Cu")
		(net "JTAG_SCM_PLD_R_JTAGEN")
	)
	(via
		(at 19.864324 -88.791796)
		(size 0.4572)
		(drill 0.254)
		(layers "F.Cu" "B.Cu")
		(net "JTAG_SCM_PLD_R_JTAGEN")
	)
	(segment
		(start 18.42262 -85.98662)
		(end 18.796 -86.36)
		(width 0.11684)
		(layer "B.Cu")
		(net "JTAG_SCM_PLD_R_JTAGEN")
	)
	(segment
		(start 17.41805 -84.09305)
		(end 18.42262 -85.09762)
		(width 0.11684)
		(layer "B.Cu")
		(net "JTAG_SCM_PLD_R_JTAGEN")
	)
	(segment
		(start 17.2974 -84.09305)
		(end 17.41805 -84.09305)
		(width 0.11684)
		(layer "B.Cu")
		(net "JTAG_SCM_PLD_R_JTAGEN")
	)
	(segment
		(start 18.796 -86.741)
		(end 19.864324 -87.809324)
		(width 0.11684)
		(layer "B.Cu")
		(net "JTAG_SCM_PLD_R_JTAGEN")
	)
	(segment
		(start 18.796 -86.36)
		(end 18.796 -86.741)
		(width 0.11684)
		(layer "B.Cu")
		(net "JTAG_SCM_PLD_R_JTAGEN")
	)
	(segment
		(start 19.864324 -87.809324)
		(end 19.864324 -88.791796)
		(width 0.11684)
		(layer "B.Cu")
		(net "JTAG_SCM_PLD_R_JTAGEN")
	)
	(segment
		(start 18.42262 -85.09762)
		(end 18.42262 -85.98662)
		(width 0.11684)
		(layer "B.Cu")
		(net "JTAG_SCM_PLD_R_JTAGEN")
	)
	(segment
		(start 52.894992 -40.971216)
		(end 52.499768 -40.575992)
		(width 0.11684)
		(layer "F.Cu")
		(net "JTAG_1_BMC_TDO")
	)
	(via
		(at 35.990276 -49.835816)
		(size 0.6604)
		(drill 0.3302)
		(layers "F.Cu" "B.Cu")
		(net "JTAG_1_BMC_TDO")
	)
	(via
		(at 52.499768 -40.575992)
		(size 0.4572)
		(drill 0.254)
		(layers "F.Cu" "B.Cu")
		(net "JTAG_1_BMC_TDO")
	)
	(via
		(at 36.64712 -49.56302)
		(size 0.508)
		(drill 0.254)
		(layers "F.Cu" "B.Cu")
		(net "JTAG_1_BMC_TDO")
	)
	(segment
		(start 36.263072 -49.56302)
		(end 36.64712 -49.56302)
		(width 0.11684)
		(layer "B.Cu")
		(net "JTAG_1_BMC_TDO")
	)
	(segment
		(start 35.990276 -49.835816)
		(end 36.263072 -49.56302)
		(width 0.11684)
		(layer "B.Cu")
		(net "JTAG_1_BMC_TDO")
	)
	(segment
		(start 34.995866 -49.835816)
		(end 35.990276 -49.835816)
		(width 0.11684)
		(layer "B.Cu")
		(net "JTAG_1_BMC_TDO")
	)
	(segment
		(start 34.84245 -49.6824)
		(end 34.995866 -49.835816)
		(width 0.11684)
		(layer "B.Cu")
		(net "JTAG_1_BMC_TDO")
	)
	(segment
		(start 37.919406 -46.514766)
		(end 38.170104 -46.41088)
		(width 0.10668)
		(layer "In4.Cu")
		(net "JTAG_1_BMC_TDO")
	)
	(segment
		(start 45.011594 -39.46906)
		(end 45.792644 -38.68801)
		(width 0.10668)
		(layer "In4.Cu")
		(net "JTAG_1_BMC_TDO")
	)
	(segment
		(start 36.881562 -49.328578)
		(end 37.3888 -48.104044)
		(width 0.10668)
		(layer "In4.Cu")
		(net "JTAG_1_BMC_TDO")
	)
	(segment
		(start 36.64712 -49.56302)
		(end 36.881562 -49.328578)
		(width 0.10668)
		(layer "In4.Cu")
		(net "JTAG_1_BMC_TDO")
	)
	(segment
		(start 41.08196 -44.53636)
		(end 44.831508 -40.786812)
		(width 0.10668)
		(layer "In4.Cu")
		(net "JTAG_1_BMC_TDO")
	)
	(segment
		(start 39.248588 -46.129194)
		(end 40.671242 -44.70654)
		(width 0.10668)
		(layer "In4.Cu")
		(net "JTAG_1_BMC_TDO")
	)
	(segment
		(start 49.433988 -38.428676)
		(end 51.202082 -39.160958)
		(width 0.10668)
		(layer "In4.Cu")
		(net "JTAG_1_BMC_TDO")
	)
	(segment
		(start 52.499768 -40.458644)
		(end 52.499768 -40.575992)
		(width 0.10668)
		(layer "In4.Cu")
		(net "JTAG_1_BMC_TDO")
	)
	(segment
		(start 38.56863 -46.41088)
		(end 39.248588 -46.129194)
		(width 0.10668)
		(layer "In4.Cu")
		(net "JTAG_1_BMC_TDO")
	)
	(segment
		(start 44.916344 -40.582088)
		(end 44.916344 -39.699184)
		(width 0.10668)
		(layer "In4.Cu")
		(net "JTAG_1_BMC_TDO")
	)
	(segment
		(start 38.170104 -46.41088)
		(end 38.56863 -46.41088)
		(width 0.10668)
		(layer "In4.Cu")
		(net "JTAG_1_BMC_TDO")
	)
	(segment
		(start 46.418754 -38.428676)
		(end 49.433988 -38.428676)
		(width 0.10668)
		(layer "In4.Cu")
		(net "JTAG_1_BMC_TDO")
	)
	(segment
		(start 37.3888 -48.104044)
		(end 37.3888 -47.045372)
		(width 0.10668)
		(layer "In4.Cu")
		(net "JTAG_1_BMC_TDO")
	)
	(segment
		(start 44.831508 -40.786812)
		(end 44.916344 -40.582088)
		(width 0.10668)
		(layer "In4.Cu")
		(net "JTAG_1_BMC_TDO")
	)
	(segment
		(start 40.671242 -44.70654)
		(end 41.08196 -44.53636)
		(width 0.10668)
		(layer "In4.Cu")
		(net "JTAG_1_BMC_TDO")
	)
	(segment
		(start 45.792644 -38.68801)
		(end 46.418754 -38.428676)
		(width 0.10668)
		(layer "In4.Cu")
		(net "JTAG_1_BMC_TDO")
	)
	(segment
		(start 37.3888 -47.045372)
		(end 37.919406 -46.514766)
		(width 0.10668)
		(layer "In4.Cu")
		(net "JTAG_1_BMC_TDO")
	)
	(segment
		(start 44.916344 -39.699184)
		(end 45.011594 -39.46906)
		(width 0.10668)
		(layer "In4.Cu")
		(net "JTAG_1_BMC_TDO")
	)
	(segment
		(start 51.202082 -39.160958)
		(end 52.499768 -40.458644)
		(width 0.10668)
		(layer "In4.Cu")
		(net "JTAG_1_BMC_TDO")
	)
	(segment
		(start 31.2674 -11.938)
		(end 31.2674 -10.8712)
		(width 0.11684)
		(layer "F.Cu")
		(net "ID_LED_BUF")
	)
	(segment
		(start 31.2674 -10.8712)
		(end 31.496 -10.6426)
		(width 0.11684)
		(layer "F.Cu")
		(net "ID_LED_BUF")
	)
	(segment
		(start 30.028896 -12.13104)
		(end 31.07436 -12.13104)
		(width 0.11684)
		(layer "F.Cu")
		(net "ID_LED_BUF")
	)
	(segment
		(start 31.07436 -12.13104)
		(end 31.2674 -11.938)
		(width 0.11684)
		(layer "F.Cu")
		(net "ID_LED_BUF")
	)
	(segment
		(start 31.496 -10.6426)
		(end 31.81604 -10.6426)
		(width 0.11684)
		(layer "F.Cu")
		(net "ID_LED_BUF")
	)
	(segment
		(start 11.377168 -108.970318)
		(end 12.321032 -108.970318)
		(width 0.11684)
		(layer "F.Cu")
		(net "HDD_LED_N")
	)
	(segment
		(start 11.303 -16.836644)
		(end 11.303 -16.44904)
		(width 0.11684)
		(layer "F.Cu")
		(net "HDD_LED_N")
	)
	(segment
		(start 12.268962 -17.048988)
		(end 11.515344 -17.048988)
		(width 0.11684)
		(layer "F.Cu")
		(net "HDD_LED_N")
	)
	(segment
		(start 12.321032 -108.970318)
		(end 12.3444 -108.94695)
		(width 0.11684)
		(layer "F.Cu")
		(net "HDD_LED_N")
	)
	(segment
		(start 13.335 -15.98295)
		(end 13.950442 -15.98295)
		(width 0.11684)
		(layer "F.Cu")
		(net "HDD_LED_N")
	)
	(segment
		(start 6.894322 -107.224322)
		(end 4.81838 -105.14838)
		(width 0.11684)
		(layer "F.Cu")
		(net "HDD_LED_N")
	)
	(segment
		(start 8.382 -87.503)
		(end 7.874 -86.995)
		(width 0.11684)
		(layer "F.Cu")
		(net "HDD_LED_N")
	)
	(segment
		(start 8.6106 -110.4392)
		(end 7.112 -110.4392)
		(width 0.11684)
		(layer "F.Cu")
		(net "HDD_LED_N")
	)
	(segment
		(start 8.382 -89.535)
		(end 8.382 -87.503)
		(width 0.11684)
		(layer "F.Cu")
		(net "HDD_LED_N")
	)
	(segment
		(start 11.3538 -108.97235)
		(end 10.59815 -109.728)
		(width 0.11684)
		(layer "F.Cu")
		(net "HDD_LED_N")
	)
	(segment
		(start 5.45338 -90.17)
		(end 7.747 -90.17)
		(width 0.11684)
		(layer "F.Cu")
		(net "HDD_LED_N")
	)
	(segment
		(start 13.950442 -15.98295)
		(end 15.04696 -17.079468)
		(width 0.11684)
		(layer "F.Cu")
		(net "HDD_LED_N")
	)
	(segment
		(start 9.3218 -109.728)
		(end 8.6106 -110.4392)
		(width 0.11684)
		(layer "F.Cu")
		(net "HDD_LED_N")
	)
	(segment
		(start 6.894322 -110.221522)
		(end 6.894322 -107.224322)
		(width 0.11684)
		(layer "F.Cu")
		(net "HDD_LED_N")
	)
	(segment
		(start 11.3538 -108.94695)
		(end 11.3538 -108.97235)
		(width 0.11684)
		(layer "F.Cu")
		(net "HDD_LED_N")
	)
	(segment
		(start 4.81838 -105.14838)
		(end 4.81838 -90.805)
		(width 0.11684)
		(layer "F.Cu")
		(net "HDD_LED_N")
	)
	(segment
		(start 7.112 -110.4392)
		(end 6.894322 -110.221522)
		(width 0.11684)
		(layer "F.Cu")
		(net "HDD_LED_N")
	)
	(segment
		(start 11.3538 -108.94695)
		(end 11.377168 -108.970318)
		(width 0.11684)
		(layer "F.Cu")
		(net "HDD_LED_N")
	)
	(segment
		(start 10.59815 -109.728)
		(end 9.3218 -109.728)
		(width 0.11684)
		(layer "F.Cu")
		(net "HDD_LED_N")
	)
	(segment
		(start 7.747 -90.17)
		(end 8.382 -89.535)
		(width 0.11684)
		(layer "F.Cu")
		(net "HDD_LED_N")
	)
	(segment
		(start 13.335 -15.98295)
		(end 12.268962 -17.048988)
		(width 0.11684)
		(layer "F.Cu")
		(net "HDD_LED_N")
	)
	(segment
		(start 4.81838 -90.805)
		(end 5.45338 -90.17)
		(width 0.11684)
		(layer "F.Cu")
		(net "HDD_LED_N")
	)
	(segment
		(start 11.515344 -17.048988)
		(end 11.303 -16.836644)
		(width 0.11684)
		(layer "F.Cu")
		(net "HDD_LED_N")
	)
	(via
		(at 15.04696 -17.079468)
		(size 0.508)
		(drill 0.254)
		(layers "F.Cu" "B.Cu")
		(net "HDD_LED_N")
	)
	(via
		(at 7.874 -86.995)
		(size 0.508)
		(drill 0.254)
		(layers "F.Cu" "B.Cu")
		(net "HDD_LED_N")
	)
	(segment
		(start 7.48284 -30.12948)
		(end 4.304792 -30.12948)
		(width 0.10668)
		(layer "In4.Cu")
		(net "HDD_LED_N")
	)
	(segment
		(start 6.75894 -80.54848)
		(end 7.0358 -80.82534)
		(width 0.10668)
		(layer "In4.Cu")
		(net "HDD_LED_N")
	)
	(segment
		(start 7.0358 -84.3788)
		(end 7.874 -85.217)
		(width 0.10668)
		(layer "In4.Cu")
		(net "HDD_LED_N")
	)
	(segment
		(start 12.745466 -29.66212)
		(end 7.9502 -29.66212)
		(width 0.10668)
		(layer "In4.Cu")
		(net "HDD_LED_N")
	)
	(segment
		(start 7.0358 -80.82534)
		(end 7.0358 -84.3788)
		(width 0.10668)
		(layer "In4.Cu")
		(net "HDD_LED_N")
	)
	(segment
		(start 7.9502 -29.66212)
		(end 7.48284 -30.12948)
		(width 0.10668)
		(layer "In4.Cu")
		(net "HDD_LED_N")
	)
	(segment
		(start 4.304792 -30.12948)
		(end 3.029204 -31.405068)
		(width 0.10668)
		(layer "In4.Cu")
		(net "HDD_LED_N")
	)
	(segment
		(start 15.7734 -17.805908)
		(end 15.7734 -19.4818)
		(width 0.10668)
		(layer "In4.Cu")
		(net "HDD_LED_N")
	)
	(segment
		(start 15.04696 -17.079468)
		(end 15.7734 -17.805908)
		(width 0.10668)
		(layer "In4.Cu")
		(net "HDD_LED_N")
	)
	(segment
		(start 15.7734 -19.4818)
		(end 14.77518 -20.48002)
		(width 0.10668)
		(layer "In4.Cu")
		(net "HDD_LED_N")
	)
	(segment
		(start 14.77518 -27.632406)
		(end 12.745466 -29.66212)
		(width 0.10668)
		(layer "In4.Cu")
		(net "HDD_LED_N")
	)
	(segment
		(start 5.84073 -80.54848)
		(end 6.75894 -80.54848)
		(width 0.10668)
		(layer "In4.Cu")
		(net "HDD_LED_N")
	)
	(segment
		(start 3.029204 -31.405068)
		(end 3.029204 -77.736954)
		(width 0.10668)
		(layer "In4.Cu")
		(net "HDD_LED_N")
	)
	(segment
		(start 7.874 -85.217)
		(end 7.874 -86.995)
		(width 0.10668)
		(layer "In4.Cu")
		(net "HDD_LED_N")
	)
	(segment
		(start 3.029204 -77.736954)
		(end 5.84073 -80.54848)
		(width 0.10668)
		(layer "In4.Cu")
		(net "HDD_LED_N")
	)
	(segment
		(start 14.77518 -20.48002)
		(end 14.77518 -27.632406)
		(width 0.10668)
		(layer "In4.Cu")
		(net "HDD_LED_N")
	)
	(segment
		(start 22.254718 -98.382328)
		(end 21.859494 -97.987104)
		(width 0.11684)
		(layer "F.Cu")
		(net "GPU_FPGA_RST_N")
	)
	(segment
		(start 47.295054 -43.371262)
		(end 46.89983 -42.976038)
		(width 0.11684)
		(layer "F.Cu")
		(net "GPU_FPGA_RST_N")
	)
	(via
		(at 22.254718 -98.382328)
		(size 0.4572)
		(drill 0.254)
		(layers "F.Cu" "B.Cu")
		(net "GPU_FPGA_RST_N")
	)
	(via
		(at 46.89983 -42.976038)
		(size 0.4572)
		(drill 0.254)
		(layers "F.Cu" "B.Cu")
		(net "GPU_FPGA_RST_N")
	)
	(via
		(at 3.556 -102.6668)
		(size 0.508)
		(drill 0.254)
		(layers "F.Cu" "B.Cu")
		(net "GPU_FPGA_RST_N")
	)
	(via
		(at 17.141444 -48.000158)
		(size 0.508)
		(drill 0.254)
		(layers "F.Cu" "B.Cu")
		(net "GPU_FPGA_RST_N")
	)
	(via
		(at 13.9954 -57.277)
		(size 0.6604)
		(drill 0.3302)
		(layers "F.Cu" "B.Cu")
		(net "GPU_FPGA_RST_N")
	)
	(segment
		(start 15.25778 -54.75478)
		(end 14.11986 -54.75478)
		(width 0.11684)
		(layer "B.Cu")
		(net "GPU_FPGA_RST_N")
	)
	(segment
		(start 7.9756 -81.5086)
		(end 6.604 -80.137)
		(width 0.11684)
		(layer "B.Cu")
		(net "GPU_FPGA_RST_N")
	)
	(segment
		(start 14.5542 -52.057046)
		(end 15.41018 -52.913026)
		(width 0.11684)
		(layer "B.Cu")
		(net "GPU_FPGA_RST_N")
	)
	(segment
		(start 11.2014 -81.1276)
		(end 9.372346 -81.1276)
		(width 0.11684)
		(layer "B.Cu")
		(net "GPU_FPGA_RST_N")
	)
	(segment
		(start 13.9954 -54.87924)
		(end 13.9954 -57.277)
		(width 0.11684)
		(layer "B.Cu")
		(net "GPU_FPGA_RST_N")
	)
	(segment
		(start 8.991346 -81.5086)
		(end 7.9756 -81.5086)
		(width 0.11684)
		(layer "B.Cu")
		(net "GPU_FPGA_RST_N")
	)
	(segment
		(start 13.6398 -77.341222)
		(end 12.69492 -78.286102)
		(width 0.11684)
		(layer "B.Cu")
		(net "GPU_FPGA_RST_N")
	)
	(segment
		(start 12.69492 -79.63408)
		(end 11.2014 -81.1276)
		(width 0.11684)
		(layer "B.Cu")
		(net "GPU_FPGA_RST_N")
	)
	(segment
		(start 4.0894 -86.487)
		(end 2.9464 -87.63)
		(width 0.11684)
		(layer "B.Cu")
		(net "GPU_FPGA_RST_N")
	)
	(segment
		(start 6.604 -80.137)
		(end 4.191 -80.137)
		(width 0.11684)
		(layer "B.Cu")
		(net "GPU_FPGA_RST_N")
	)
	(segment
		(start 14.5542 -49.4284)
		(end 14.5542 -52.057046)
		(width 0.11684)
		(layer "B.Cu")
		(net "GPU_FPGA_RST_N")
	)
	(segment
		(start 13.9954 -57.277)
		(end 13.9954 -66.0908)
		(width 0.11684)
		(layer "B.Cu")
		(net "GPU_FPGA_RST_N")
	)
	(segment
		(start 4.0894 -81.362042)
		(end 4.0894 -86.487)
		(width 0.11684)
		(layer "B.Cu")
		(net "GPU_FPGA_RST_N")
	)
	(segment
		(start 12.69492 -78.286102)
		(end 12.69492 -79.63408)
		(width 0.11684)
		(layer "B.Cu")
		(net "GPU_FPGA_RST_N")
	)
	(segment
		(start 16.492474 -48.7172)
		(end 15.2654 -48.7172)
		(width 0.11684)
		(layer "B.Cu")
		(net "GPU_FPGA_RST_N")
	)
	(segment
		(start 4.064 -80.264)
		(end 4.064 -81.336642)
		(width 0.11684)
		(layer "B.Cu")
		(net "GPU_FPGA_RST_N")
	)
	(segment
		(start 13.9954 -66.0908)
		(end 13.6398 -66.4464)
		(width 0.11684)
		(layer "B.Cu")
		(net "GPU_FPGA_RST_N")
	)
	(segment
		(start 2.9464 -87.63)
		(end 2.9464 -102.25786)
		(width 0.11684)
		(layer "B.Cu")
		(net "GPU_FPGA_RST_N")
	)
	(segment
		(start 17.141444 -48.06823)
		(end 16.492474 -48.7172)
		(width 0.11684)
		(layer "B.Cu")
		(net "GPU_FPGA_RST_N")
	)
	(segment
		(start 4.064 -81.336642)
		(end 4.0894 -81.362042)
		(width 0.11684)
		(layer "B.Cu")
		(net "GPU_FPGA_RST_N")
	)
	(segment
		(start 14.11986 -54.75478)
		(end 13.9954 -54.87924)
		(width 0.11684)
		(layer "B.Cu")
		(net "GPU_FPGA_RST_N")
	)
	(segment
		(start 15.2654 -48.7172)
		(end 14.5542 -49.4284)
		(width 0.11684)
		(layer "B.Cu")
		(net "GPU_FPGA_RST_N")
	)
	(segment
		(start 15.41018 -54.60238)
		(end 15.25778 -54.75478)
		(width 0.11684)
		(layer "B.Cu")
		(net "GPU_FPGA_RST_N")
	)
	(segment
		(start 17.141444 -48.000158)
		(end 17.141444 -48.06823)
		(width 0.11684)
		(layer "B.Cu")
		(net "GPU_FPGA_RST_N")
	)
	(segment
		(start 3.35534 -102.6668)
		(end 3.556 -102.6668)
		(width 0.11684)
		(layer "B.Cu")
		(net "GPU_FPGA_RST_N")
	)
	(segment
		(start 2.9464 -102.25786)
		(end 3.35534 -102.6668)
		(width 0.11684)
		(layer "B.Cu")
		(net "GPU_FPGA_RST_N")
	)
	(segment
		(start 4.191 -80.137)
		(end 4.064 -80.264)
		(width 0.11684)
		(layer "B.Cu")
		(net "GPU_FPGA_RST_N")
	)
	(segment
		(start 15.41018 -52.913026)
		(end 15.41018 -54.60238)
		(width 0.11684)
		(layer "B.Cu")
		(net "GPU_FPGA_RST_N")
	)
	(segment
		(start 13.6398 -66.4464)
		(end 13.6398 -77.341222)
		(width 0.11684)
		(layer "B.Cu")
		(net "GPU_FPGA_RST_N")
	)
	(segment
		(start 9.372346 -81.1276)
		(end 8.991346 -81.5086)
		(width 0.11684)
		(layer "B.Cu")
		(net "GPU_FPGA_RST_N")
	)
	(segment
		(start 9.587484 -102.6668)
		(end 3.556 -102.6668)
		(width 0.08382)
		(layer "In2.Cu")
		(net "GPU_FPGA_RST_N")
	)
	(segment
		(start 21.835872 -98.382328)
		(end 21.221446 -98.996754)
		(width 0.08382)
		(layer "In2.Cu")
		(net "GPU_FPGA_RST_N")
	)
	(segment
		(start 15.771876 -100.36556)
		(end 15.317216 -100.82022)
		(width 0.08382)
		(layer "In2.Cu")
		(net "GPU_FPGA_RST_N")
	)
	(segment
		(start 17.582134 -48.4632)
		(end 17.141444 -48.02251)
		(width 0.08382)
		(layer "In2.Cu")
		(net "GPU_FPGA_RST_N")
	)
	(segment
		(start 37.0078 -41.402)
		(end 34.675318 -39.069518)
		(width 0.08382)
		(layer "In2.Cu")
		(net "GPU_FPGA_RST_N")
	)
	(segment
		(start 16.661638 -100.36556)
		(end 15.771876 -100.36556)
		(width 0.08382)
		(layer "In2.Cu")
		(net "GPU_FPGA_RST_N")
	)
	(segment
		(start 21.171916 -44.269152)
		(end 20.602194 -44.269152)
		(width 0.08382)
		(layer "In2.Cu")
		(net "GPU_FPGA_RST_N")
	)
	(segment
		(start 45.930566 -42.580052)
		(end 45.298106 -41.947592)
		(width 0.08382)
		(layer "In2.Cu")
		(net "GPU_FPGA_RST_N")
	)
	(segment
		(start 22.254718 -98.382328)
		(end 21.835872 -98.382328)
		(width 0.08382)
		(layer "In2.Cu")
		(net "GPU_FPGA_RST_N")
	)
	(segment
		(start 15.317216 -100.82022)
		(end 13.36294 -100.82022)
		(width 0.08382)
		(layer "In2.Cu")
		(net "GPU_FPGA_RST_N")
	)
	(segment
		(start 10.752074 -101.50221)
		(end 9.587484 -102.6668)
		(width 0.08382)
		(layer "In2.Cu")
		(net "GPU_FPGA_RST_N")
	)
	(segment
		(start 38.253162 -41.402)
		(end 37.0078 -41.402)
		(width 0.08382)
		(layer "In2.Cu")
		(net "GPU_FPGA_RST_N")
	)
	(segment
		(start 20.602194 -44.269152)
		(end 20.2438 -44.627546)
		(width 0.08382)
		(layer "In2.Cu")
		(net "GPU_FPGA_RST_N")
	)
	(segment
		(start 18.030444 -98.996754)
		(end 16.661638 -100.36556)
		(width 0.08382)
		(layer "In2.Cu")
		(net "GPU_FPGA_RST_N")
	)
	(segment
		(start 38.910514 -41.236392)
		(end 38.41877 -41.236392)
		(width 0.08382)
		(layer "In2.Cu")
		(net "GPU_FPGA_RST_N")
	)
	(segment
		(start 24.714708 -40.72636)
		(end 21.171916 -44.269152)
		(width 0.08382)
		(layer "In2.Cu")
		(net "GPU_FPGA_RST_N")
	)
	(segment
		(start 13.36294 -100.82022)
		(end 12.68095 -101.50221)
		(width 0.08382)
		(layer "In2.Cu")
		(net "GPU_FPGA_RST_N")
	)
	(segment
		(start 25.46604 -40.72636)
		(end 24.714708 -40.72636)
		(width 0.08382)
		(layer "In2.Cu")
		(net "GPU_FPGA_RST_N")
	)
	(segment
		(start 20.2438 -44.627546)
		(end 20.2438 -47.371)
		(width 0.08382)
		(layer "In2.Cu")
		(net "GPU_FPGA_RST_N")
	)
	(segment
		(start 46.89983 -42.976038)
		(end 46.503844 -42.580052)
		(width 0.08382)
		(layer "In2.Cu")
		(net "GPU_FPGA_RST_N")
	)
	(segment
		(start 21.221446 -98.996754)
		(end 18.030444 -98.996754)
		(width 0.08382)
		(layer "In2.Cu")
		(net "GPU_FPGA_RST_N")
	)
	(segment
		(start 19.1516 -48.4632)
		(end 17.582134 -48.4632)
		(width 0.08382)
		(layer "In2.Cu")
		(net "GPU_FPGA_RST_N")
	)
	(segment
		(start 12.68095 -101.50221)
		(end 10.752074 -101.50221)
		(width 0.08382)
		(layer "In2.Cu")
		(net "GPU_FPGA_RST_N")
	)
	(segment
		(start 39.621714 -41.947592)
		(end 38.910514 -41.236392)
		(width 0.08382)
		(layer "In2.Cu")
		(net "GPU_FPGA_RST_N")
	)
	(segment
		(start 38.41877 -41.236392)
		(end 38.253162 -41.402)
		(width 0.08382)
		(layer "In2.Cu")
		(net "GPU_FPGA_RST_N")
	)
	(segment
		(start 17.141444 -48.02251)
		(end 17.141444 -48.000158)
		(width 0.08382)
		(layer "In2.Cu")
		(net "GPU_FPGA_RST_N")
	)
	(segment
		(start 45.298106 -41.947592)
		(end 39.621714 -41.947592)
		(width 0.08382)
		(layer "In2.Cu")
		(net "GPU_FPGA_RST_N")
	)
	(segment
		(start 46.503844 -42.580052)
		(end 45.930566 -42.580052)
		(width 0.08382)
		(layer "In2.Cu")
		(net "GPU_FPGA_RST_N")
	)
	(segment
		(start 34.675318 -39.069518)
		(end 27.122882 -39.069518)
		(width 0.08382)
		(layer "In2.Cu")
		(net "GPU_FPGA_RST_N")
	)
	(segment
		(start 27.122882 -39.069518)
		(end 25.46604 -40.72636)
		(width 0.08382)
		(layer "In2.Cu")
		(net "GPU_FPGA_RST_N")
	)
	(segment
		(start 20.2438 -47.371)
		(end 19.1516 -48.4632)
		(width 0.08382)
		(layer "In2.Cu")
		(net "GPU_FPGA_RST_N")
	)
	(segment
		(start 19.864324 -95.982282)
		(end 20.259548 -95.587058)
		(width 0.11684)
		(layer "F.Cu")
		(net "FM_UARTSW_MSB_R_N")
	)
	(via
		(at 19.864324 -95.982282)
		(size 0.4572)
		(drill 0.254)
		(layers "F.Cu" "B.Cu")
		(net "FM_UARTSW_MSB_R_N")
	)
	(via
		(at 16.18361 -104.74579)
		(size 0.6604)
		(drill 0.3302)
		(layers "F.Cu" "B.Cu")
		(net "FM_UARTSW_MSB_R_N")
	)
	(segment
		(start 20.825206 -97.171002)
		(end 21.05279 -96.943418)
		(width 0.11684)
		(layer "B.Cu")
		(net "FM_UARTSW_MSB_R_N")
	)
	(segment
		(start 18.188432 -100.9904)
		(end 20.07235 -99.106482)
		(width 0.11684)
		(layer "B.Cu")
		(net "FM_UARTSW_MSB_R_N")
	)
	(segment
		(start 20.07235 -97.624392)
		(end 20.52574 -97.171002)
		(width 0.11684)
		(layer "B.Cu")
		(net "FM_UARTSW_MSB_R_N")
	)
	(segment
		(start 20.07235 -99.106482)
		(end 20.07235 -97.624392)
		(width 0.11684)
		(layer "B.Cu")
		(net "FM_UARTSW_MSB_R_N")
	)
	(segment
		(start 16.55318 -101.764592)
		(end 17.327372 -100.9904)
		(width 0.11684)
		(layer "B.Cu")
		(net "FM_UARTSW_MSB_R_N")
	)
	(segment
		(start 16.3322 -104.89438)
		(end 16.18361 -104.74579)
		(width 0.11684)
		(layer "B.Cu")
		(net "FM_UARTSW_MSB_R_N")
	)
	(segment
		(start 21.05279 -96.621346)
		(end 20.825206 -96.393762)
		(width 0.11684)
		(layer "B.Cu")
		(net "FM_UARTSW_MSB_R_N")
	)
	(segment
		(start 15.367 -106.82605)
		(end 16.05915 -106.82605)
		(width 0.11684)
		(layer "B.Cu")
		(net "FM_UARTSW_MSB_R_N")
	)
	(segment
		(start 16.3322 -106.553)
		(end 16.3322 -104.89438)
		(width 0.11684)
		(layer "B.Cu")
		(net "FM_UARTSW_MSB_R_N")
	)
	(segment
		(start 17.327372 -100.9904)
		(end 18.188432 -100.9904)
		(width 0.11684)
		(layer "B.Cu")
		(net "FM_UARTSW_MSB_R_N")
	)
	(segment
		(start 20.825206 -96.393762)
		(end 20.275804 -96.393762)
		(width 0.11684)
		(layer "B.Cu")
		(net "FM_UARTSW_MSB_R_N")
	)
	(segment
		(start 16.18361 -104.74579)
		(end 16.55318 -104.37622)
		(width 0.11684)
		(layer "B.Cu")
		(net "FM_UARTSW_MSB_R_N")
	)
	(segment
		(start 20.275804 -96.393762)
		(end 19.864324 -95.982282)
		(width 0.11684)
		(layer "B.Cu")
		(net "FM_UARTSW_MSB_R_N")
	)
	(segment
		(start 16.05915 -106.82605)
		(end 16.3322 -106.553)
		(width 0.11684)
		(layer "B.Cu")
		(net "FM_UARTSW_MSB_R_N")
	)
	(segment
		(start 20.52574 -97.171002)
		(end 20.825206 -97.171002)
		(width 0.11684)
		(layer "B.Cu")
		(net "FM_UARTSW_MSB_R_N")
	)
	(segment
		(start 16.55318 -104.37622)
		(end 16.55318 -101.764592)
		(width 0.11684)
		(layer "B.Cu")
		(net "FM_UARTSW_MSB_R_N")
	)
	(segment
		(start 21.05279 -96.943418)
		(end 21.05279 -96.621346)
		(width 0.11684)
		(layer "B.Cu")
		(net "FM_UARTSW_MSB_R_N")
	)
	(segment
		(start 76.356972 -20.648676)
		(end 76.99502 -21.286724)
		(width 0.11684)
		(layer "F.Cu")
		(net "FM_UARTSW_MSB_R1_N")
	)
	(segment
		(start 76.99502 -21.286724)
		(end 76.99502 -21.336)
		(width 0.11684)
		(layer "F.Cu")
		(net "FM_UARTSW_MSB_R1_N")
	)
	(segment
		(start 76.731114 -19.981164)
		(end 76.94295 -20.193)
		(width 0.11684)
		(layer "F.Cu")
		(net "FM_UARTSW_MSB_R1_N")
	)
	(segment
		(start 76.356972 -19.310604)
		(end 76.356972 -20.648676)
		(width 0.11684)
		(layer "F.Cu")
		(net "FM_UARTSW_MSB_R1_N")
	)
	(segment
		(start 76.731114 -18.936462)
		(end 76.356972 -19.310604)
		(width 0.11684)
		(layer "F.Cu")
		(net "FM_UARTSW_MSB_R1_N")
	)
	(segment
		(start 76.731114 -18.936462)
		(end 76.731114 -19.981164)
		(width 0.11684)
		(layer "F.Cu")
		(net "FM_UARTSW_MSB_R1_N")
	)
	(via
		(at 76.731114 -18.936462)
		(size 0.762)
		(drill 0.381)
		(layers "F.Cu" "B.Cu")
		(net "FM_UARTSW_MSB_R1_N")
	)
	(segment
		(start 20.3454 -64.457326)
		(end 19.655536 -64.457326)
		(width 0.11684)
		(layer "F.Cu")
		(net "FM_UARTSW_MSB_N")
	)
	(segment
		(start 21.211794 -63.590932)
		(end 20.3454 -64.457326)
		(width 0.11684)
		(layer "F.Cu")
		(net "FM_UARTSW_MSB_N")
	)
	(segment
		(start 77.100938 -18.19275)
		(end 77.74305 -18.834862)
		(width 0.11684)
		(layer "F.Cu")
		(net "FM_UARTSW_MSB_N")
	)
	(segment
		(start 21.211794 -62.670436)
		(end 21.211794 -63.590932)
		(width 0.11684)
		(layer "F.Cu")
		(net "FM_UARTSW_MSB_N")
	)
	(segment
		(start 75.102212 -18.19275)
		(end 77.100938 -18.19275)
		(width 0.11684)
		(layer "F.Cu")
		(net "FM_UARTSW_MSB_N")
	)
	(segment
		(start 77.74305 -18.834862)
		(end 77.74305 -20.193)
		(width 0.11684)
		(layer "F.Cu")
		(net "FM_UARTSW_MSB_N")
	)
	(segment
		(start 25.218136 -63.65621)
		(end 25.218136 -63.089536)
		(width 0.11684)
		(layer "F.Cu")
		(net "FM_UARTSW_MSB_N")
	)
	(segment
		(start 24.06904 -61.94044)
		(end 23.620984 -61.94044)
		(width 0.11684)
		(layer "F.Cu")
		(net "FM_UARTSW_MSB_N")
	)
	(segment
		(start 25.218136 -63.089536)
		(end 24.06904 -61.94044)
		(width 0.11684)
		(layer "F.Cu")
		(net "FM_UARTSW_MSB_N")
	)
	(segment
		(start 23.620984 -61.94044)
		(end 23.241762 -62.319662)
		(width 0.11684)
		(layer "F.Cu")
		(net "FM_UARTSW_MSB_N")
	)
	(segment
		(start 19.655536 -64.457326)
		(end 19.655536 -63.68161)
		(width 0.11684)
		(layer "F.Cu")
		(net "FM_UARTSW_MSB_N")
	)
	(segment
		(start 23.241762 -62.319662)
		(end 21.562568 -62.319662)
		(width 0.11684)
		(layer "F.Cu")
		(net "FM_UARTSW_MSB_N")
	)
	(segment
		(start 21.562568 -62.319662)
		(end 21.211794 -62.670436)
		(width 0.11684)
		(layer "F.Cu")
		(net "FM_UARTSW_MSB_N")
	)
	(segment
		(start 74.618342 -18.67662)
		(end 75.102212 -18.19275)
		(width 0.11684)
		(layer "F.Cu")
		(net "FM_UARTSW_MSB_N")
	)
	(via
		(at 27.209496 -18.035016)
		(size 0.508)
		(drill 0.254)
		(layers "F.Cu" "B.Cu")
		(net "FM_UARTSW_MSB_N")
	)
	(via
		(at 74.618342 -18.67662)
		(size 0.762)
		(drill 0.254)
		(layers "F.Cu" "B.Cu")
		(net "FM_UARTSW_MSB_N")
	)
	(via
		(at 19.655536 -64.457326)
		(size 0.508)
		(drill 0.254)
		(layers "F.Cu" "B.Cu")
		(net "FM_UARTSW_MSB_N")
	)
	(via
		(at 13.29182 -104.9909)
		(size 0.508)
		(drill 0.254)
		(layers "F.Cu" "B.Cu")
		(net "FM_UARTSW_MSB_N")
	)
	(segment
		(start 14.351 -105.5116)
		(end 13.8303 -104.9909)
		(width 0.11684)
		(layer "B.Cu")
		(net "FM_UARTSW_MSB_N")
	)
	(segment
		(start 14.351 -106.02595)
		(end 14.351 -105.5116)
		(width 0.11684)
		(layer "B.Cu")
		(net "FM_UARTSW_MSB_N")
	)
	(segment
		(start 13.8303 -104.9909)
		(end 13.29182 -104.9909)
		(width 0.11684)
		(layer "B.Cu")
		(net "FM_UARTSW_MSB_N")
	)
	(segment
		(start 15.367 -106.02595)
		(end 14.351 -106.02595)
		(width 0.11684)
		(layer "B.Cu")
		(net "FM_UARTSW_MSB_N")
	)
	(segment
		(start 74.618342 -18.67662)
		(end 73.956164 -18.014442)
		(width 0.08382)
		(layer "In2.Cu")
		(net "FM_UARTSW_MSB_N")
	)
	(segment
		(start 59.618626 -15.578074)
		(end 56.865012 -18.331688)
		(width 0.08382)
		(layer "In2.Cu")
		(net "FM_UARTSW_MSB_N")
	)
	(segment
		(start 41.531032 -19.768312)
		(end 40.943784 -19.181064)
		(width 0.08382)
		(layer "In2.Cu")
		(net "FM_UARTSW_MSB_N")
	)
	(segment
		(start 30.39618 -17.893284)
		(end 28.170632 -17.893284)
		(width 0.08382)
		(layer "In2.Cu")
		(net "FM_UARTSW_MSB_N")
	)
	(segment
		(start 73.956164 -18.014442)
		(end 67.275456 -18.014442)
		(width 0.08382)
		(layer "In2.Cu")
		(net "FM_UARTSW_MSB_N")
	)
	(segment
		(start 40.943784 -18.675096)
		(end 39.948358 -17.67967)
		(width 0.08382)
		(layer "In2.Cu")
		(net "FM_UARTSW_MSB_N")
	)
	(segment
		(start 44.099226 -18.588736)
		(end 42.91965 -19.768312)
		(width 0.08382)
		(layer "In2.Cu")
		(net "FM_UARTSW_MSB_N")
	)
	(segment
		(start 67.275456 -18.014442)
		(end 64.839088 -15.578074)
		(width 0.08382)
		(layer "In2.Cu")
		(net "FM_UARTSW_MSB_N")
	)
	(segment
		(start 37.80282 -17.67967)
		(end 36.66617 -16.54302)
		(width 0.08382)
		(layer "In2.Cu")
		(net "FM_UARTSW_MSB_N")
	)
	(segment
		(start 55.090314 -18.588736)
		(end 44.099226 -18.588736)
		(width 0.08382)
		(layer "In2.Cu")
		(net "FM_UARTSW_MSB_N")
	)
	(segment
		(start 55.347362 -18.331688)
		(end 55.090314 -18.588736)
		(width 0.08382)
		(layer "In2.Cu")
		(net "FM_UARTSW_MSB_N")
	)
	(segment
		(start 28.170632 -17.893284)
		(end 27.946096 -18.11782)
		(width 0.08382)
		(layer "In2.Cu")
		(net "FM_UARTSW_MSB_N")
	)
	(segment
		(start 31.746444 -16.54302)
		(end 30.39618 -17.893284)
		(width 0.08382)
		(layer "In2.Cu")
		(net "FM_UARTSW_MSB_N")
	)
	(segment
		(start 36.66617 -16.54302)
		(end 31.746444 -16.54302)
		(width 0.08382)
		(layer "In2.Cu")
		(net "FM_UARTSW_MSB_N")
	)
	(segment
		(start 42.91965 -19.768312)
		(end 41.531032 -19.768312)
		(width 0.08382)
		(layer "In2.Cu")
		(net "FM_UARTSW_MSB_N")
	)
	(segment
		(start 27.946096 -18.11782)
		(end 27.2923 -18.11782)
		(width 0.08382)
		(layer "In2.Cu")
		(net "FM_UARTSW_MSB_N")
	)
	(segment
		(start 56.865012 -18.331688)
		(end 55.347362 -18.331688)
		(width 0.08382)
		(layer "In2.Cu")
		(net "FM_UARTSW_MSB_N")
	)
	(segment
		(start 27.2923 -18.11782)
		(end 27.209496 -18.035016)
		(width 0.08382)
		(layer "In2.Cu")
		(net "FM_UARTSW_MSB_N")
	)
	(segment
		(start 39.948358 -17.67967)
		(end 37.80282 -17.67967)
		(width 0.08382)
		(layer "In2.Cu")
		(net "FM_UARTSW_MSB_N")
	)
	(segment
		(start 64.839088 -15.578074)
		(end 59.618626 -15.578074)
		(width 0.08382)
		(layer "In2.Cu")
		(net "FM_UARTSW_MSB_N")
	)
	(segment
		(start 40.943784 -19.181064)
		(end 40.943784 -18.675096)
		(width 0.08382)
		(layer "In2.Cu")
		(net "FM_UARTSW_MSB_N")
	)
	(segment
		(start 20.625054 -62.3824)
		(end 20.93087 -62.688216)
		(width 0.08382)
		(layer "In9.Cu")
		(net "FM_UARTSW_MSB_N")
	)
	(segment
		(start 12.39012 -91.35872)
		(end 11.8364 -90.805)
		(width 0.08382)
		(layer "In9.Cu")
		(net "FM_UARTSW_MSB_N")
	)
	(segment
		(start 20.073874 -64.457326)
		(end 19.655536 -64.457326)
		(width 0.08382)
		(layer "In9.Cu")
		(net "FM_UARTSW_MSB_N")
	)
	(segment
		(start 15.23238 -83.083908)
		(end 15.23238 -82.045556)
		(width 0.08382)
		(layer "In9.Cu")
		(net "FM_UARTSW_MSB_N")
	)
	(segment
		(start 17.61236 -49.05248)
		(end 17.159732 -49.505108)
		(width 0.08382)
		(layer "In9.Cu")
		(net "FM_UARTSW_MSB_N")
	)
	(segment
		(start 12.39012 -100.61448)
		(end 12.954 -100.0506)
		(width 0.08382)
		(layer "In9.Cu")
		(net "FM_UARTSW_MSB_N")
	)
	(segment
		(start 23.37435 -33.101026)
		(end 23.37435 -40.613838)
		(width 0.08382)
		(layer "In9.Cu")
		(net "FM_UARTSW_MSB_N")
	)
	(segment
		(start 16.89989 -52.111402)
		(end 16.89989 -57.587642)
		(width 0.08382)
		(layer "In9.Cu")
		(net "FM_UARTSW_MSB_N")
	)
	(segment
		(start 20.93087 -62.688216)
		(end 20.93087 -63.60033)
		(width 0.08382)
		(layer "In9.Cu")
		(net "FM_UARTSW_MSB_N")
	)
	(segment
		(start 24.95042 -29.163264)
		(end 24.80691 -29.306774)
		(width 0.08382)
		(layer "In9.Cu")
		(net "FM_UARTSW_MSB_N")
	)
	(segment
		(start 11.8364 -90.805)
		(end 10.9982 -90.805)
		(width 0.08382)
		(layer "In9.Cu")
		(net "FM_UARTSW_MSB_N")
	)
	(segment
		(start 17.6784 -60.066428)
		(end 18.187162 -60.57519)
		(width 0.08382)
		(layer "In9.Cu")
		(net "FM_UARTSW_MSB_N")
	)
	(segment
		(start 12.39012 -97.8662)
		(end 12.39012 -91.35872)
		(width 0.08382)
		(layer "In9.Cu")
		(net "FM_UARTSW_MSB_N")
	)
	(segment
		(start 17.779746 -63.11646)
		(end 19.120612 -64.457326)
		(width 0.08382)
		(layer "In9.Cu")
		(net "FM_UARTSW_MSB_N")
	)
	(segment
		(start 17.6784 -59.69)
		(end 17.6784 -60.066428)
		(width 0.08382)
		(layer "In9.Cu")
		(net "FM_UARTSW_MSB_N")
	)
	(segment
		(start 16.74749 -57.740042)
		(end 16.74749 -58.75909)
		(width 0.08382)
		(layer "In9.Cu")
		(net "FM_UARTSW_MSB_N")
	)
	(segment
		(start 18.187162 -60.57519)
		(end 18.386044 -60.57519)
		(width 0.08382)
		(layer "In9.Cu")
		(net "FM_UARTSW_MSB_N")
	)
	(segment
		(start 17.159732 -50.180748)
		(end 17.42567 -50.446686)
		(width 0.08382)
		(layer "In9.Cu")
		(net "FM_UARTSW_MSB_N")
	)
	(segment
		(start 17.61236 -44.890436)
		(end 17.61236 -49.05248)
		(width 0.08382)
		(layer "In9.Cu")
		(net "FM_UARTSW_MSB_N")
	)
	(segment
		(start 16.74749 -58.75909)
		(end 17.6784 -59.69)
		(width 0.08382)
		(layer "In9.Cu")
		(net "FM_UARTSW_MSB_N")
	)
	(segment
		(start 12.954 -98.43008)
		(end 12.39012 -97.8662)
		(width 0.08382)
		(layer "In9.Cu")
		(net "FM_UARTSW_MSB_N")
	)
	(segment
		(start 26.0604 -21.7424)
		(end 24.95042 -22.85238)
		(width 0.08382)
		(layer "In9.Cu")
		(net "FM_UARTSW_MSB_N")
	)
	(segment
		(start 16.89989 -57.587642)
		(end 16.74749 -57.740042)
		(width 0.08382)
		(layer "In9.Cu")
		(net "FM_UARTSW_MSB_N")
	)
	(segment
		(start 20.193254 -62.3824)
		(end 20.625054 -62.3824)
		(width 0.08382)
		(layer "In9.Cu")
		(net "FM_UARTSW_MSB_N")
	)
	(segment
		(start 18.635218 -43.46829)
		(end 18.23466 -43.868848)
		(width 0.08382)
		(layer "In9.Cu")
		(net "FM_UARTSW_MSB_N")
	)
	(segment
		(start 13.29182 -104.9909)
		(end 13.29182 -104.341168)
		(width 0.08382)
		(layer "In9.Cu")
		(net "FM_UARTSW_MSB_N")
	)
	(segment
		(start 27.35707 -18.18259)
		(end 27.35707 -19.487642)
		(width 0.08382)
		(layer "In9.Cu")
		(net "FM_UARTSW_MSB_N")
	)
	(segment
		(start 12.8016 -85.514688)
		(end 15.23238 -83.083908)
		(width 0.08382)
		(layer "In9.Cu")
		(net "FM_UARTSW_MSB_N")
	)
	(segment
		(start 17.42567 -50.446686)
		(end 17.42567 -51.585622)
		(width 0.08382)
		(layer "In9.Cu")
		(net "FM_UARTSW_MSB_N")
	)
	(segment
		(start 17.42567 -51.585622)
		(end 16.89989 -52.111402)
		(width 0.08382)
		(layer "In9.Cu")
		(net "FM_UARTSW_MSB_N")
	)
	(segment
		(start 10.9982 -90.805)
		(end 10.795 -90.6018)
		(width 0.08382)
		(layer "In9.Cu")
		(net "FM_UARTSW_MSB_N")
	)
	(segment
		(start 18.23466 -44.268136)
		(end 17.61236 -44.890436)
		(width 0.08382)
		(layer "In9.Cu")
		(net "FM_UARTSW_MSB_N")
	)
	(segment
		(start 20.93087 -63.60033)
		(end 20.073874 -64.457326)
		(width 0.08382)
		(layer "In9.Cu")
		(net "FM_UARTSW_MSB_N")
	)
	(segment
		(start 16.102838 -63.11646)
		(end 17.779746 -63.11646)
		(width 0.08382)
		(layer "In9.Cu")
		(net "FM_UARTSW_MSB_N")
	)
	(segment
		(start 18.23466 -43.868848)
		(end 18.23466 -44.268136)
		(width 0.08382)
		(layer "In9.Cu")
		(net "FM_UARTSW_MSB_N")
	)
	(segment
		(start 20.519898 -43.46829)
		(end 18.635218 -43.46829)
		(width 0.08382)
		(layer "In9.Cu")
		(net "FM_UARTSW_MSB_N")
	)
	(segment
		(start 24.80691 -31.668466)
		(end 23.37435 -33.101026)
		(width 0.08382)
		(layer "In9.Cu")
		(net "FM_UARTSW_MSB_N")
	)
	(segment
		(start 10.795 -90.6018)
		(end 10.795 -90.02522)
		(width 0.08382)
		(layer "In9.Cu")
		(net "FM_UARTSW_MSB_N")
	)
	(segment
		(start 14.42085 -77.472032)
		(end 14.42085 -64.798448)
		(width 0.08382)
		(layer "In9.Cu")
		(net "FM_UARTSW_MSB_N")
	)
	(segment
		(start 23.37435 -40.613838)
		(end 20.519898 -43.46829)
		(width 0.08382)
		(layer "In9.Cu")
		(net "FM_UARTSW_MSB_N")
	)
	(segment
		(start 12.39012 -103.439468)
		(end 12.39012 -100.61448)
		(width 0.08382)
		(layer "In9.Cu")
		(net "FM_UARTSW_MSB_N")
	)
	(segment
		(start 16.002 -79.053182)
		(end 14.42085 -77.472032)
		(width 0.08382)
		(layer "In9.Cu")
		(net "FM_UARTSW_MSB_N")
	)
	(segment
		(start 16.002 -81.275936)
		(end 16.002 -79.053182)
		(width 0.08382)
		(layer "In9.Cu")
		(net "FM_UARTSW_MSB_N")
	)
	(segment
		(start 13.29182 -104.341168)
		(end 12.39012 -103.439468)
		(width 0.08382)
		(layer "In9.Cu")
		(net "FM_UARTSW_MSB_N")
	)
	(segment
		(start 15.23238 -82.045556)
		(end 16.002 -81.275936)
		(width 0.08382)
		(layer "In9.Cu")
		(net "FM_UARTSW_MSB_N")
	)
	(segment
		(start 27.209496 -18.035016)
		(end 27.35707 -18.18259)
		(width 0.08382)
		(layer "In9.Cu")
		(net "FM_UARTSW_MSB_N")
	)
	(segment
		(start 11.00582 -89.8144)
		(end 11.480546 -89.8144)
		(width 0.08382)
		(layer "In9.Cu")
		(net "FM_UARTSW_MSB_N")
	)
	(segment
		(start 27.35707 -19.487642)
		(end 26.0604 -20.784312)
		(width 0.08382)
		(layer "In9.Cu")
		(net "FM_UARTSW_MSB_N")
	)
	(segment
		(start 24.95042 -22.85238)
		(end 24.95042 -29.163264)
		(width 0.08382)
		(layer "In9.Cu")
		(net "FM_UARTSW_MSB_N")
	)
	(segment
		(start 24.80691 -29.306774)
		(end 24.80691 -31.668466)
		(width 0.08382)
		(layer "In9.Cu")
		(net "FM_UARTSW_MSB_N")
	)
	(segment
		(start 26.0604 -20.784312)
		(end 26.0604 -21.7424)
		(width 0.08382)
		(layer "In9.Cu")
		(net "FM_UARTSW_MSB_N")
	)
	(segment
		(start 12.954 -100.0506)
		(end 12.954 -98.43008)
		(width 0.08382)
		(layer "In9.Cu")
		(net "FM_UARTSW_MSB_N")
	)
	(segment
		(start 11.480546 -89.8144)
		(end 12.8016 -88.493346)
		(width 0.08382)
		(layer "In9.Cu")
		(net "FM_UARTSW_MSB_N")
	)
	(segment
		(start 14.42085 -64.798448)
		(end 16.102838 -63.11646)
		(width 0.08382)
		(layer "In9.Cu")
		(net "FM_UARTSW_MSB_N")
	)
	(segment
		(start 17.159732 -49.505108)
		(end 17.159732 -50.180748)
		(width 0.08382)
		(layer "In9.Cu")
		(net "FM_UARTSW_MSB_N")
	)
	(segment
		(start 18.386044 -60.57519)
		(end 20.193254 -62.3824)
		(width 0.08382)
		(layer "In9.Cu")
		(net "FM_UARTSW_MSB_N")
	)
	(segment
		(start 19.120612 -64.457326)
		(end 19.655536 -64.457326)
		(width 0.08382)
		(layer "In9.Cu")
		(net "FM_UARTSW_MSB_N")
	)
	(segment
		(start 12.8016 -88.493346)
		(end 12.8016 -85.514688)
		(width 0.08382)
		(layer "In9.Cu")
		(net "FM_UARTSW_MSB_N")
	)
	(segment
		(start 10.795 -90.02522)
		(end 11.00582 -89.8144)
		(width 0.08382)
		(layer "In9.Cu")
		(net "FM_UARTSW_MSB_N")
	)
	(segment
		(start 20.66417 -96.782382)
		(end 21.059394 -96.387158)
		(width 0.11684)
		(layer "F.Cu")
		(net "FM_UARTSW_LSB_R_N")
	)
	(via
		(at 20.66417 -96.782382)
		(size 0.4572)
		(drill 0.254)
		(layers "F.Cu" "B.Cu")
		(net "FM_UARTSW_LSB_R_N")
	)
	(via
		(at 14.732 -104.8004)
		(size 0.6604)
		(drill 0.3302)
		(layers "F.Cu" "B.Cu")
		(net "FM_UARTSW_LSB_R_N")
	)
	(segment
		(start 13.843 -106.7308)
		(end 13.843 -105.6894)
		(width 0.11684)
		(layer "B.Cu")
		(net "FM_UARTSW_LSB_R_N")
	)
	(segment
		(start 20.66417 -96.782382)
		(end 20.605242 -96.782382)
		(width 0.11684)
		(layer "B.Cu")
		(net "FM_UARTSW_LSB_R_N")
	)
	(segment
		(start 12.827 -105.32618)
		(end 12.827 -104.792272)
		(width 0.11684)
		(layer "B.Cu")
		(net "FM_UARTSW_LSB_R_N")
	)
	(segment
		(start 19.8374 -97.550224)
		(end 19.8374 -99.032314)
		(width 0.11684)
		(layer "B.Cu")
		(net "FM_UARTSW_LSB_R_N")
	)
	(segment
		(start 14.3764 -104.4448)
		(end 14.732 -104.8004)
		(width 0.11684)
		(layer "B.Cu")
		(net "FM_UARTSW_LSB_R_N")
	)
	(segment
		(start 13.6906 -105.537)
		(end 13.03782 -105.537)
		(width 0.11684)
		(layer "B.Cu")
		(net "FM_UARTSW_LSB_R_N")
	)
	(segment
		(start 13.03782 -105.537)
		(end 12.827 -105.32618)
		(width 0.11684)
		(layer "B.Cu")
		(net "FM_UARTSW_LSB_R_N")
	)
	(segment
		(start 17.236948 -100.771706)
		(end 15.494 -102.514654)
		(width 0.11684)
		(layer "B.Cu")
		(net "FM_UARTSW_LSB_R_N")
	)
	(segment
		(start 18.098008 -100.771706)
		(end 17.236948 -100.771706)
		(width 0.11684)
		(layer "B.Cu")
		(net "FM_UARTSW_LSB_R_N")
	)
	(segment
		(start 15.494 -102.514654)
		(end 15.494 -104.0384)
		(width 0.11684)
		(layer "B.Cu")
		(net "FM_UARTSW_LSB_R_N")
	)
	(segment
		(start 15.494 -104.0384)
		(end 14.732 -104.8004)
		(width 0.11684)
		(layer "B.Cu")
		(net "FM_UARTSW_LSB_R_N")
	)
	(segment
		(start 13.74775 -106.82605)
		(end 13.843 -106.7308)
		(width 0.11684)
		(layer "B.Cu")
		(net "FM_UARTSW_LSB_R_N")
	)
	(segment
		(start 13.335 -106.82605)
		(end 13.74775 -106.82605)
		(width 0.11684)
		(layer "B.Cu")
		(net "FM_UARTSW_LSB_R_N")
	)
	(segment
		(start 19.8374 -99.032314)
		(end 18.098008 -100.771706)
		(width 0.11684)
		(layer "B.Cu")
		(net "FM_UARTSW_LSB_R_N")
	)
	(segment
		(start 13.843 -105.6894)
		(end 13.6906 -105.537)
		(width 0.11684)
		(layer "B.Cu")
		(net "FM_UARTSW_LSB_R_N")
	)
	(segment
		(start 13.174472 -104.4448)
		(end 14.3764 -104.4448)
		(width 0.11684)
		(layer "B.Cu")
		(net "FM_UARTSW_LSB_R_N")
	)
	(segment
		(start 12.827 -104.792272)
		(end 13.174472 -104.4448)
		(width 0.11684)
		(layer "B.Cu")
		(net "FM_UARTSW_LSB_R_N")
	)
	(segment
		(start 20.605242 -96.782382)
		(end 19.8374 -97.550224)
		(width 0.11684)
		(layer "B.Cu")
		(net "FM_UARTSW_LSB_R_N")
	)
	(segment
		(start 73.620122 -19.939)
		(end 74.115676 -19.939)
		(width 0.11684)
		(layer "F.Cu")
		(net "FM_UARTSW_LSB_R1_N")
	)
	(segment
		(start 73.592944 -19.966178)
		(end 73.620122 -19.939)
		(width 0.11684)
		(layer "F.Cu")
		(net "FM_UARTSW_LSB_R1_N")
	)
	(segment
		(start 73.592944 -19.998944)
		(end 73.592944 -19.966178)
		(width 0.11684)
		(layer "F.Cu")
		(net "FM_UARTSW_LSB_R1_N")
	)
	(segment
		(start 74.369676 -20.193)
		(end 74.78395 -20.193)
		(width 0.11684)
		(layer "F.Cu")
		(net "FM_UARTSW_LSB_R1_N")
	)
	(segment
		(start 74.58202 -20.98802)
		(end 73.592944 -19.998944)
		(width 0.11684)
		(layer "F.Cu")
		(net "FM_UARTSW_LSB_R1_N")
	)
	(segment
		(start 74.58202 -21.336)
		(end 74.58202 -20.98802)
		(width 0.11684)
		(layer "F.Cu")
		(net "FM_UARTSW_LSB_R1_N")
	)
	(segment
		(start 74.115676 -19.939)
		(end 74.369676 -20.193)
		(width 0.11684)
		(layer "F.Cu")
		(net "FM_UARTSW_LSB_R1_N")
	)
	(via
		(at 73.592944 -19.966178)
		(size 0.762)
		(drill 0.381)
		(layers "F.Cu" "B.Cu")
		(net "FM_UARTSW_LSB_R1_N")
	)
	(segment
		(start 75.58405 -20.193)
		(end 75.58405 -18.729452)
		(width 0.11684)
		(layer "F.Cu")
		(net "FM_UARTSW_LSB_N")
	)
	(segment
		(start 25.718262 -63.056262)
		(end 25.718262 -63.65621)
		(width 0.11684)
		(layer "F.Cu")
		(net "FM_UARTSW_LSB_N")
	)
	(segment
		(start 23.130002 -62.050422)
		(end 23.509224 -61.6712)
		(width 0.11684)
		(layer "F.Cu")
		(net "FM_UARTSW_LSB_N")
	)
	(segment
		(start 24.3332 -61.6712)
		(end 25.718262 -63.056262)
		(width 0.11684)
		(layer "F.Cu")
		(net "FM_UARTSW_LSB_N")
	)
	(segment
		(start 20.38858 -62.94882)
		(end 21.286978 -62.050422)
		(width 0.11684)
		(layer "F.Cu")
		(net "FM_UARTSW_LSB_N")
	)
	(segment
		(start 20.38858 -63.448692)
		(end 20.155662 -63.68161)
		(width 0.11684)
		(layer "F.Cu")
		(net "FM_UARTSW_LSB_N")
	)
	(segment
		(start 21.286978 -62.050422)
		(end 23.130002 -62.050422)
		(width 0.11684)
		(layer "F.Cu")
		(net "FM_UARTSW_LSB_N")
	)
	(segment
		(start 23.509224 -61.6712)
		(end 24.3332 -61.6712)
		(width 0.11684)
		(layer "F.Cu")
		(net "FM_UARTSW_LSB_N")
	)
	(segment
		(start 20.38858 -62.94882)
		(end 20.38858 -63.448692)
		(width 0.11684)
		(layer "F.Cu")
		(net "FM_UARTSW_LSB_N")
	)
	(via
		(at 20.38858 -62.94882)
		(size 0.508)
		(drill 0.254)
		(layers "F.Cu" "B.Cu")
		(net "FM_UARTSW_LSB_N")
	)
	(via
		(at 11.262614 -103.24592)
		(size 0.508)
		(drill 0.254)
		(layers "F.Cu" "B.Cu")
		(net "FM_UARTSW_LSB_N")
	)
	(via
		(at 27.716734 -17.653)
		(size 0.508)
		(drill 0.254)
		(layers "F.Cu" "B.Cu")
		(net "FM_UARTSW_LSB_N")
	)
	(via
		(at 75.58405 -18.729452)
		(size 0.508)
		(drill 0.254)
		(layers "F.Cu" "B.Cu")
		(net "FM_UARTSW_LSB_N")
	)
	(segment
		(start 11.262614 -103.581454)
		(end 12.319 -104.63784)
		(width 0.11684)
		(layer "B.Cu")
		(net "FM_UARTSW_LSB_N")
	)
	(segment
		(start 13.335 -106.02595)
		(end 12.319 -106.02595)
		(width 0.11684)
		(layer "B.Cu")
		(net "FM_UARTSW_LSB_N")
	)
	(segment
		(start 11.262614 -103.24592)
		(end 11.262614 -103.581454)
		(width 0.11684)
		(layer "B.Cu")
		(net "FM_UARTSW_LSB_N")
	)
	(segment
		(start 12.319 -104.63784)
		(end 12.319 -106.02595)
		(width 0.11684)
		(layer "B.Cu")
		(net "FM_UARTSW_LSB_N")
	)
	(segment
		(start 37.805614 -17.3482)
		(end 43.650916 -17.3482)
		(width 0.08382)
		(layer "In2.Cu")
		(net "FM_UARTSW_LSB_N")
	)
	(segment
		(start 56.765444 -18.091404)
		(end 59.519058 -15.33779)
		(width 0.08382)
		(layer "In2.Cu")
		(net "FM_UARTSW_LSB_N")
	)
	(segment
		(start 64.938656 -15.33779)
		(end 67.375024 -17.774158)
		(width 0.08382)
		(layer "In2.Cu")
		(net "FM_UARTSW_LSB_N")
	)
	(segment
		(start 55.247794 -18.091404)
		(end 56.765444 -18.091404)
		(width 0.08382)
		(layer "In2.Cu")
		(net "FM_UARTSW_LSB_N")
	)
	(segment
		(start 59.519058 -15.33779)
		(end 64.938656 -15.33779)
		(width 0.08382)
		(layer "In2.Cu")
		(net "FM_UARTSW_LSB_N")
	)
	(segment
		(start 74.628756 -17.774158)
		(end 75.58405 -18.729452)
		(width 0.08382)
		(layer "In2.Cu")
		(net "FM_UARTSW_LSB_N")
	)
	(segment
		(start 30.3022 -17.653)
		(end 31.6484 -16.3068)
		(width 0.08382)
		(layer "In2.Cu")
		(net "FM_UARTSW_LSB_N")
	)
	(segment
		(start 36.764214 -16.3068)
		(end 37.805614 -17.3482)
		(width 0.08382)
		(layer "In2.Cu")
		(net "FM_UARTSW_LSB_N")
	)
	(segment
		(start 31.6484 -16.3068)
		(end 36.764214 -16.3068)
		(width 0.08382)
		(layer "In2.Cu")
		(net "FM_UARTSW_LSB_N")
	)
	(segment
		(start 27.716734 -17.653)
		(end 30.3022 -17.653)
		(width 0.08382)
		(layer "In2.Cu")
		(net "FM_UARTSW_LSB_N")
	)
	(segment
		(start 44.651168 -18.348452)
		(end 54.990746 -18.348452)
		(width 0.08382)
		(layer "In2.Cu")
		(net "FM_UARTSW_LSB_N")
	)
	(segment
		(start 43.650916 -17.3482)
		(end 44.651168 -18.348452)
		(width 0.08382)
		(layer "In2.Cu")
		(net "FM_UARTSW_LSB_N")
	)
	(segment
		(start 54.990746 -18.348452)
		(end 55.247794 -18.091404)
		(width 0.08382)
		(layer "In2.Cu")
		(net "FM_UARTSW_LSB_N")
	)
	(segment
		(start 67.375024 -17.774158)
		(end 74.628756 -17.774158)
		(width 0.08382)
		(layer "In2.Cu")
		(net "FM_UARTSW_LSB_N")
	)
	(segment
		(start 12.07008 -95.31858)
		(end 12.07008 -92.05722)
		(width 0.08382)
		(layer "In9.Cu")
		(net "FM_UARTSW_LSB_N")
	)
	(segment
		(start 12.71778 -98.528124)
		(end 12.0777 -97.888044)
		(width 0.08382)
		(layer "In9.Cu")
		(net "FM_UARTSW_LSB_N")
	)
	(segment
		(start 17.99844 -43.770804)
		(end 17.99844 -44.170092)
		(width 0.08382)
		(layer "In9.Cu")
		(net "FM_UARTSW_LSB_N")
	)
	(segment
		(start 11.7602 -88.8492)
		(end 12.4968 -88.1126)
		(width 0.08382)
		(layer "In9.Cu")
		(net "FM_UARTSW_LSB_N")
	)
	(segment
		(start 25.13838 -22.330156)
		(end 24.7142 -22.754336)
		(width 0.08382)
		(layer "In9.Cu")
		(net "FM_UARTSW_LSB_N")
	)
	(segment
		(start 25.5524 -19.5326)
		(end 25.13838 -19.94662)
		(width 0.08382)
		(layer "In9.Cu")
		(net "FM_UARTSW_LSB_N")
	)
	(segment
		(start 12.0777 -102.811834)
		(end 12.0777 -100.587556)
		(width 0.08382)
		(layer "In9.Cu")
		(net "FM_UARTSW_LSB_N")
	)
	(segment
		(start 17.18945 -51.487578)
		(end 16.66367 -52.013358)
		(width 0.08382)
		(layer "In9.Cu")
		(net "FM_UARTSW_LSB_N")
	)
	(segment
		(start 17.87779 -62.88024)
		(end 18.37817 -63.38062)
		(width 0.08382)
		(layer "In9.Cu")
		(net "FM_UARTSW_LSB_N")
	)
	(segment
		(start 18.089118 -60.81141)
		(end 18.25117 -60.81141)
		(width 0.08382)
		(layer "In9.Cu")
		(net "FM_UARTSW_LSB_N")
	)
	(segment
		(start 10.5156 -89.4334)
		(end 11.0998 -88.8492)
		(width 0.08382)
		(layer "In9.Cu")
		(net "FM_UARTSW_LSB_N")
	)
	(segment
		(start 24.7142 -22.754336)
		(end 24.7142 -29.06522)
		(width 0.08382)
		(layer "In9.Cu")
		(net "FM_UARTSW_LSB_N")
	)
	(segment
		(start 12.4968 -85.485224)
		(end 14.8844 -83.097624)
		(width 0.08382)
		(layer "In9.Cu")
		(net "FM_UARTSW_LSB_N")
	)
	(segment
		(start 16.138144 -48.21174)
		(end 16.42618 -48.499776)
		(width 0.08382)
		(layer "In9.Cu")
		(net "FM_UARTSW_LSB_N")
	)
	(segment
		(start 12.07008 -92.05722)
		(end 11.93546 -91.9226)
		(width 0.08382)
		(layer "In9.Cu")
		(net "FM_UARTSW_LSB_N")
	)
	(segment
		(start 27.640534 -17.5768)
		(end 26.797 -17.5768)
		(width 0.08382)
		(layer "In9.Cu")
		(net "FM_UARTSW_LSB_N")
	)
	(segment
		(start 12.0777 -100.587556)
		(end 12.71778 -99.947476)
		(width 0.08382)
		(layer "In9.Cu")
		(net "FM_UARTSW_LSB_N")
	)
	(segment
		(start 16.42618 -49.78146)
		(end 17.18945 -50.54473)
		(width 0.08382)
		(layer "In9.Cu")
		(net "FM_UARTSW_LSB_N")
	)
	(segment
		(start 14.18463 -64.700404)
		(end 16.004794 -62.88024)
		(width 0.08382)
		(layer "In9.Cu")
		(net "FM_UARTSW_LSB_N")
	)
	(segment
		(start 16.66367 -57.489598)
		(end 16.51127 -57.641998)
		(width 0.08382)
		(layer "In9.Cu")
		(net "FM_UARTSW_LSB_N")
	)
	(segment
		(start 24.7142 -29.06522)
		(end 24.57069 -29.20873)
		(width 0.08382)
		(layer "In9.Cu")
		(net "FM_UARTSW_LSB_N")
	)
	(segment
		(start 16.42618 -48.499776)
		(end 16.42618 -49.78146)
		(width 0.08382)
		(layer "In9.Cu")
		(net "FM_UARTSW_LSB_N")
	)
	(segment
		(start 12.4968 -88.1126)
		(end 12.4968 -85.485224)
		(width 0.08382)
		(layer "In9.Cu")
		(net "FM_UARTSW_LSB_N")
	)
	(segment
		(start 17.18945 -50.54473)
		(end 17.18945 -51.487578)
		(width 0.08382)
		(layer "In9.Cu")
		(net "FM_UARTSW_LSB_N")
	)
	(segment
		(start 14.8844 -78.554834)
		(end 14.18463 -77.855064)
		(width 0.08382)
		(layer "In9.Cu")
		(net "FM_UARTSW_LSB_N")
	)
	(segment
		(start 11.93546 -91.9226)
		(end 10.6172 -91.9226)
		(width 0.08382)
		(layer "In9.Cu")
		(net "FM_UARTSW_LSB_N")
	)
	(segment
		(start 17.99844 -44.170092)
		(end 17.074134 -45.094398)
		(width 0.08382)
		(layer "In9.Cu")
		(net "FM_UARTSW_LSB_N")
	)
	(segment
		(start 18.537174 -43.23207)
		(end 17.99844 -43.770804)
		(width 0.08382)
		(layer "In9.Cu")
		(net "FM_UARTSW_LSB_N")
	)
	(segment
		(start 19.95678 -63.38062)
		(end 20.38858 -62.94882)
		(width 0.08382)
		(layer "In9.Cu")
		(net "FM_UARTSW_LSB_N")
	)
	(segment
		(start 10.5156 -91.821)
		(end 10.5156 -89.4334)
		(width 0.08382)
		(layer "In9.Cu")
		(net "FM_UARTSW_LSB_N")
	)
	(segment
		(start 16.004794 -62.88024)
		(end 17.87779 -62.88024)
		(width 0.08382)
		(layer "In9.Cu")
		(net "FM_UARTSW_LSB_N")
	)
	(segment
		(start 12.71778 -99.947476)
		(end 12.71778 -98.528124)
		(width 0.08382)
		(layer "In9.Cu")
		(net "FM_UARTSW_LSB_N")
	)
	(segment
		(start 25.5524 -18.8214)
		(end 25.5524 -19.5326)
		(width 0.08382)
		(layer "In9.Cu")
		(net "FM_UARTSW_LSB_N")
	)
	(segment
		(start 24.57069 -29.20873)
		(end 24.57069 -31.570422)
		(width 0.08382)
		(layer "In9.Cu")
		(net "FM_UARTSW_LSB_N")
	)
	(segment
		(start 16.138144 -47.50562)
		(end 16.138144 -48.21174)
		(width 0.08382)
		(layer "In9.Cu")
		(net "FM_UARTSW_LSB_N")
	)
	(segment
		(start 10.6172 -91.9226)
		(end 10.5156 -91.821)
		(width 0.08382)
		(layer "In9.Cu")
		(net "FM_UARTSW_LSB_N")
	)
	(segment
		(start 18.37817 -63.38062)
		(end 19.95678 -63.38062)
		(width 0.08382)
		(layer "In9.Cu")
		(net "FM_UARTSW_LSB_N")
	)
	(segment
		(start 12.0777 -97.888044)
		(end 12.0777 -95.3262)
		(width 0.08382)
		(layer "In9.Cu")
		(net "FM_UARTSW_LSB_N")
	)
	(segment
		(start 23.13813 -40.515794)
		(end 20.421854 -43.23207)
		(width 0.08382)
		(layer "In9.Cu")
		(net "FM_UARTSW_LSB_N")
	)
	(segment
		(start 17.44218 -59.788044)
		(end 17.44218 -60.164472)
		(width 0.08382)
		(layer "In9.Cu")
		(net "FM_UARTSW_LSB_N")
	)
	(segment
		(start 12.0777 -95.3262)
		(end 12.07008 -95.31858)
		(width 0.08382)
		(layer "In9.Cu")
		(net "FM_UARTSW_LSB_N")
	)
	(segment
		(start 14.8844 -83.097624)
		(end 14.8844 -78.554834)
		(width 0.08382)
		(layer "In9.Cu")
		(net "FM_UARTSW_LSB_N")
	)
	(segment
		(start 23.13813 -33.002982)
		(end 23.13813 -40.515794)
		(width 0.08382)
		(layer "In9.Cu")
		(net "FM_UARTSW_LSB_N")
	)
	(segment
		(start 11.262614 -103.24592)
		(end 11.643614 -103.24592)
		(width 0.08382)
		(layer "In9.Cu")
		(net "FM_UARTSW_LSB_N")
	)
	(segment
		(start 24.57069 -31.570422)
		(end 23.13813 -33.002982)
		(width 0.08382)
		(layer "In9.Cu")
		(net "FM_UARTSW_LSB_N")
	)
	(segment
		(start 26.797 -17.5768)
		(end 25.5524 -18.8214)
		(width 0.08382)
		(layer "In9.Cu")
		(net "FM_UARTSW_LSB_N")
	)
	(segment
		(start 17.074134 -45.094398)
		(end 17.074134 -46.56963)
		(width 0.08382)
		(layer "In9.Cu")
		(net "FM_UARTSW_LSB_N")
	)
	(segment
		(start 17.074134 -46.56963)
		(end 16.138144 -47.50562)
		(width 0.08382)
		(layer "In9.Cu")
		(net "FM_UARTSW_LSB_N")
	)
	(segment
		(start 16.51127 -58.857134)
		(end 17.44218 -59.788044)
		(width 0.08382)
		(layer "In9.Cu")
		(net "FM_UARTSW_LSB_N")
	)
	(segment
		(start 20.421854 -43.23207)
		(end 18.537174 -43.23207)
		(width 0.08382)
		(layer "In9.Cu")
		(net "FM_UARTSW_LSB_N")
	)
	(segment
		(start 11.643614 -103.24592)
		(end 12.0777 -102.811834)
		(width 0.08382)
		(layer "In9.Cu")
		(net "FM_UARTSW_LSB_N")
	)
	(segment
		(start 16.66367 -52.013358)
		(end 16.66367 -57.489598)
		(width 0.08382)
		(layer "In9.Cu")
		(net "FM_UARTSW_LSB_N")
	)
	(segment
		(start 18.25117 -60.81141)
		(end 20.38858 -62.94882)
		(width 0.08382)
		(layer "In9.Cu")
		(net "FM_UARTSW_LSB_N")
	)
	(segment
		(start 14.18463 -77.855064)
		(end 14.18463 -64.700404)
		(width 0.08382)
		(layer "In9.Cu")
		(net "FM_UARTSW_LSB_N")
	)
	(segment
		(start 27.716734 -17.653)
		(end 27.640534 -17.5768)
		(width 0.08382)
		(layer "In9.Cu")
		(net "FM_UARTSW_LSB_N")
	)
	(segment
		(start 16.51127 -57.641998)
		(end 16.51127 -58.857134)
		(width 0.08382)
		(layer "In9.Cu")
		(net "FM_UARTSW_LSB_N")
	)
	(segment
		(start 17.44218 -60.164472)
		(end 18.089118 -60.81141)
		(width 0.08382)
		(layer "In9.Cu")
		(net "FM_UARTSW_LSB_N")
	)
	(segment
		(start 11.0998 -88.8492)
		(end 11.7602 -88.8492)
		(width 0.08382)
		(layer "In9.Cu")
		(net "FM_UARTSW_LSB_N")
	)
	(segment
		(start 25.13838 -19.94662)
		(end 25.13838 -22.330156)
		(width 0.08382)
		(layer "In9.Cu")
		(net "FM_UARTSW_LSB_N")
	)
	(segment
		(start 22.254718 -99.182174)
		(end 21.859494 -98.78695)
		(width 0.11684)
		(layer "F.Cu")
		(net "NC_FM_PFR_UPDATE_N")
	)
	(via
		(at 58.3946 -15.494)
		(size 0.762)
		(drill 0.254)
		(layers "F.Cu" "B.Cu")
		(net "NC_FM_PFR_UPDATE_N")
	)
	(via
		(at 3.556 -103.3018)
		(size 0.508)
		(drill 0.254)
		(layers "F.Cu" "B.Cu")
		(net "NC_FM_PFR_UPDATE_N")
	)
	(via
		(at 22.254718 -99.182174)
		(size 0.4572)
		(drill 0.254)
		(layers "F.Cu" "B.Cu")
		(net "NC_FM_PFR_UPDATE_N")
	)
	(segment
		(start 16.7386 -100.55098)
		(end 15.848838 -100.55098)
		(width 0.08382)
		(layer "In2.Cu")
		(net "NC_FM_PFR_UPDATE_N")
	)
	(segment
		(start 15.848838 -100.55098)
		(end 15.343378 -101.05644)
		(width 0.08382)
		(layer "In2.Cu")
		(net "NC_FM_PFR_UPDATE_N")
	)
	(segment
		(start 22.254718 -99.182174)
		(end 18.107406 -99.182174)
		(width 0.08382)
		(layer "In2.Cu")
		(net "NC_FM_PFR_UPDATE_N")
	)
	(segment
		(start 9.685528 -102.90302)
		(end 3.95478 -102.90302)
		(width 0.08382)
		(layer "In2.Cu")
		(net "NC_FM_PFR_UPDATE_N")
	)
	(segment
		(start 10.109708 -102.47884)
		(end 9.685528 -102.90302)
		(width 0.08382)
		(layer "In2.Cu")
		(net "NC_FM_PFR_UPDATE_N")
	)
	(segment
		(start 12.14374 -102.47884)
		(end 10.109708 -102.47884)
		(width 0.08382)
		(layer "In2.Cu")
		(net "NC_FM_PFR_UPDATE_N")
	)
	(segment
		(start 13.56614 -101.05644)
		(end 12.14374 -102.47884)
		(width 0.08382)
		(layer "In2.Cu")
		(net "NC_FM_PFR_UPDATE_N")
	)
	(segment
		(start 3.95478 -102.90302)
		(end 3.556 -103.3018)
		(width 0.08382)
		(layer "In2.Cu")
		(net "NC_FM_PFR_UPDATE_N")
	)
	(segment
		(start 18.107406 -99.182174)
		(end 16.7386 -100.55098)
		(width 0.08382)
		(layer "In2.Cu")
		(net "NC_FM_PFR_UPDATE_N")
	)
	(segment
		(start 15.343378 -101.05644)
		(end 13.56614 -101.05644)
		(width 0.08382)
		(layer "In2.Cu")
		(net "NC_FM_PFR_UPDATE_N")
	)
	(segment
		(start 14.17828 -7.34568)
		(end 15.00632 -8.17372)
		(width 0.10668)
		(layer "In7.Cu")
		(net "NC_FM_PFR_UPDATE_N")
	)
	(segment
		(start 1.581912 -77.827378)
		(end 1.581912 -9.42721)
		(width 0.10668)
		(layer "In7.Cu")
		(net "NC_FM_PFR_UPDATE_N")
	)
	(segment
		(start 4.014724 -85.679788)
		(end 4.331716 -84.914486)
		(width 0.10668)
		(layer "In7.Cu")
		(net "NC_FM_PFR_UPDATE_N")
	)
	(segment
		(start 15.00632 -8.17372)
		(end 50.272442 -8.17372)
		(width 0.10668)
		(layer "In7.Cu")
		(net "NC_FM_PFR_UPDATE_N")
	)
	(segment
		(start 3.663442 -7.34568)
		(end 14.17828 -7.34568)
		(width 0.10668)
		(layer "In7.Cu")
		(net "NC_FM_PFR_UPDATE_N")
	)
	(segment
		(start 54.483 -12.384278)
		(end 54.483 -14.605)
		(width 0.10668)
		(layer "In7.Cu")
		(net "NC_FM_PFR_UPDATE_N")
	)
	(segment
		(start 4.331716 -84.914486)
		(end 4.331716 -80.577182)
		(width 0.10668)
		(layer "In7.Cu")
		(net "NC_FM_PFR_UPDATE_N")
	)
	(segment
		(start 54.483 -14.605)
		(end 54.7878 -14.9098)
		(width 0.10668)
		(layer "In7.Cu")
		(net "NC_FM_PFR_UPDATE_N")
	)
	(segment
		(start 4.331716 -80.577182)
		(end 1.581912 -77.827378)
		(width 0.10668)
		(layer "In7.Cu")
		(net "NC_FM_PFR_UPDATE_N")
	)
	(segment
		(start 54.7878 -14.9098)
		(end 57.8104 -14.9098)
		(width 0.10668)
		(layer "In7.Cu")
		(net "NC_FM_PFR_UPDATE_N")
	)
	(segment
		(start 3.556 -103.3018)
		(end 3.54076 -103.3018)
		(width 0.10668)
		(layer "In7.Cu")
		(net "NC_FM_PFR_UPDATE_N")
	)
	(segment
		(start 2.17424 -101.93528)
		(end 2.17424 -87.520272)
		(width 0.10668)
		(layer "In7.Cu")
		(net "NC_FM_PFR_UPDATE_N")
	)
	(segment
		(start 50.272442 -8.17372)
		(end 54.483 -12.384278)
		(width 0.10668)
		(layer "In7.Cu")
		(net "NC_FM_PFR_UPDATE_N")
	)
	(segment
		(start 1.581912 -9.42721)
		(end 3.663442 -7.34568)
		(width 0.10668)
		(layer "In7.Cu")
		(net "NC_FM_PFR_UPDATE_N")
	)
	(segment
		(start 57.8104 -14.9098)
		(end 58.3946 -15.494)
		(width 0.10668)
		(layer "In7.Cu")
		(net "NC_FM_PFR_UPDATE_N")
	)
	(segment
		(start 3.54076 -103.3018)
		(end 2.17424 -101.93528)
		(width 0.10668)
		(layer "In7.Cu")
		(net "NC_FM_PFR_UPDATE_N")
	)
	(segment
		(start 2.17424 -87.520272)
		(end 4.014724 -85.679788)
		(width 0.10668)
		(layer "In7.Cu")
		(net "NC_FM_PFR_UPDATE_N")
	)
	(segment
		(start 23.054564 -95.982282)
		(end 22.65934 -95.587058)
		(width 0.11684)
		(layer "F.Cu")
		(net "NC_FM_PFR_NO_SERVICE_ACT_N")
	)
	(via
		(at 3.556 -102.0318)
		(size 0.508)
		(drill 0.254)
		(layers "F.Cu" "B.Cu")
		(net "NC_FM_PFR_NO_SERVICE_ACT_N")
	)
	(via
		(at 23.054564 -95.982282)
		(size 0.4572)
		(drill 0.254)
		(layers "F.Cu" "B.Cu")
		(net "NC_FM_PFR_NO_SERVICE_ACT_N")
	)
	(via
		(at 53.6956 -15.046452)
		(size 0.762)
		(drill 0.254)
		(layers "F.Cu" "B.Cu")
		(net "NC_FM_PFR_NO_SERVICE_ACT_N")
	)
	(segment
		(start 10.61593 -100.584)
		(end 15.291054 -100.584)
		(width 0.08382)
		(layer "In2.Cu")
		(net "NC_FM_PFR_NO_SERVICE_ACT_N")
	)
	(segment
		(start 15.694914 -100.18014)
		(end 16.584676 -100.18014)
		(width 0.08382)
		(layer "In2.Cu")
		(net "NC_FM_PFR_NO_SERVICE_ACT_N")
	)
	(segment
		(start 10.2997 -100.90023)
		(end 10.61593 -100.584)
		(width 0.08382)
		(layer "In2.Cu")
		(net "NC_FM_PFR_NO_SERVICE_ACT_N")
	)
	(segment
		(start 15.291054 -100.584)
		(end 15.694914 -100.18014)
		(width 0.08382)
		(layer "In2.Cu")
		(net "NC_FM_PFR_NO_SERVICE_ACT_N")
	)
	(segment
		(start 9.48944 -102.43058)
		(end 10.2997 -101.62032)
		(width 0.08382)
		(layer "In2.Cu")
		(net "NC_FM_PFR_NO_SERVICE_ACT_N")
	)
	(segment
		(start 22.606 -96.5962)
		(end 23.054564 -96.147636)
		(width 0.08382)
		(layer "In2.Cu")
		(net "NC_FM_PFR_NO_SERVICE_ACT_N")
	)
	(segment
		(start 16.584676 -100.18014)
		(end 17.953482 -98.811334)
		(width 0.08382)
		(layer "In2.Cu")
		(net "NC_FM_PFR_NO_SERVICE_ACT_N")
	)
	(segment
		(start 17.953482 -98.811334)
		(end 21.144484 -98.811334)
		(width 0.08382)
		(layer "In2.Cu")
		(net "NC_FM_PFR_NO_SERVICE_ACT_N")
	)
	(segment
		(start 21.5138 -97.2312)
		(end 22.1488 -96.5962)
		(width 0.08382)
		(layer "In2.Cu")
		(net "NC_FM_PFR_NO_SERVICE_ACT_N")
	)
	(segment
		(start 21.5138 -98.442018)
		(end 21.5138 -97.2312)
		(width 0.08382)
		(layer "In2.Cu")
		(net "NC_FM_PFR_NO_SERVICE_ACT_N")
	)
	(segment
		(start 3.556 -102.0318)
		(end 3.95478 -102.43058)
		(width 0.08382)
		(layer "In2.Cu")
		(net "NC_FM_PFR_NO_SERVICE_ACT_N")
	)
	(segment
		(start 3.95478 -102.43058)
		(end 9.48944 -102.43058)
		(width 0.08382)
		(layer "In2.Cu")
		(net "NC_FM_PFR_NO_SERVICE_ACT_N")
	)
	(segment
		(start 21.144484 -98.811334)
		(end 21.5138 -98.442018)
		(width 0.08382)
		(layer "In2.Cu")
		(net "NC_FM_PFR_NO_SERVICE_ACT_N")
	)
	(segment
		(start 23.054564 -96.147636)
		(end 23.054564 -95.982282)
		(width 0.08382)
		(layer "In2.Cu")
		(net "NC_FM_PFR_NO_SERVICE_ACT_N")
	)
	(segment
		(start 10.2997 -101.62032)
		(end 10.2997 -100.90023)
		(width 0.08382)
		(layer "In2.Cu")
		(net "NC_FM_PFR_NO_SERVICE_ACT_N")
	)
	(segment
		(start 22.1488 -96.5962)
		(end 22.606 -96.5962)
		(width 0.08382)
		(layer "In2.Cu")
		(net "NC_FM_PFR_NO_SERVICE_ACT_N")
	)
	(segment
		(start 4.590796 -84.966048)
		(end 4.590796 -80.46974)
		(width 0.10668)
		(layer "In7.Cu")
		(net "NC_FM_PFR_NO_SERVICE_ACT_N")
	)
	(segment
		(start 14.852396 -8.4328)
		(end 50.165 -8.4328)
		(width 0.10668)
		(layer "In7.Cu")
		(net "NC_FM_PFR_NO_SERVICE_ACT_N")
	)
	(segment
		(start 4.234434 -85.8266)
		(end 4.590796 -84.966048)
		(width 0.10668)
		(layer "In7.Cu")
		(net "NC_FM_PFR_NO_SERVICE_ACT_N")
	)
	(segment
		(start 3.770884 -7.60476)
		(end 14.024356 -7.60476)
		(width 0.10668)
		(layer "In7.Cu")
		(net "NC_FM_PFR_NO_SERVICE_ACT_N")
	)
	(segment
		(start 2.43332 -100.90912)
		(end 2.43332 -87.627714)
		(width 0.10668)
		(layer "In7.Cu")
		(net "NC_FM_PFR_NO_SERVICE_ACT_N")
	)
	(segment
		(start 1.840992 -77.719936)
		(end 1.840992 -9.534652)
		(width 0.10668)
		(layer "In7.Cu")
		(net "NC_FM_PFR_NO_SERVICE_ACT_N")
	)
	(segment
		(start 53.6956 -11.9634)
		(end 53.6956 -15.046452)
		(width 0.10668)
		(layer "In7.Cu")
		(net "NC_FM_PFR_NO_SERVICE_ACT_N")
	)
	(segment
		(start 14.024356 -7.60476)
		(end 14.852396 -8.4328)
		(width 0.10668)
		(layer "In7.Cu")
		(net "NC_FM_PFR_NO_SERVICE_ACT_N")
	)
	(segment
		(start 4.590796 -80.46974)
		(end 1.840992 -77.719936)
		(width 0.10668)
		(layer "In7.Cu")
		(net "NC_FM_PFR_NO_SERVICE_ACT_N")
	)
	(segment
		(start 2.43332 -87.627714)
		(end 4.234434 -85.8266)
		(width 0.10668)
		(layer "In7.Cu")
		(net "NC_FM_PFR_NO_SERVICE_ACT_N")
	)
	(segment
		(start 50.165 -8.4328)
		(end 53.6956 -11.9634)
		(width 0.10668)
		(layer "In7.Cu")
		(net "NC_FM_PFR_NO_SERVICE_ACT_N")
	)
	(segment
		(start 3.556 -102.0318)
		(end 2.43332 -100.90912)
		(width 0.10668)
		(layer "In7.Cu")
		(net "NC_FM_PFR_NO_SERVICE_ACT_N")
	)
	(segment
		(start 1.840992 -9.534652)
		(end 3.770884 -7.60476)
		(width 0.10668)
		(layer "In7.Cu")
		(net "NC_FM_PFR_NO_SERVICE_ACT_N")
	)
	(segment
		(start 20.2184 -108.3056)
		(end 20.2184 -109.2962)
		(width 0.11684)
		(layer "F.Cu")
		(net "FM_BMC_UARTSW_MSB_N")
	)
	(segment
		(start 22.1488 -111.2266)
		(end 22.7838 -111.2266)
		(width 0.11684)
		(layer "F.Cu")
		(net "FM_BMC_UARTSW_MSB_N")
	)
	(segment
		(start 20.2184 -109.2962)
		(end 22.1488 -111.2266)
		(width 0.11684)
		(layer "F.Cu")
		(net "FM_BMC_UARTSW_MSB_N")
	)
	(via
		(at 18.788634 -109.0168)
		(size 0.6604)
		(drill 0.3302)
		(layers "F.Cu" "B.Cu")
		(net "FM_BMC_UARTSW_MSB_N")
	)
	(via
		(at 20.2184 -108.3056)
		(size 0.508)
		(drill 0.254)
		(layers "F.Cu" "B.Cu")
		(net "FM_BMC_UARTSW_MSB_N")
	)
	(via
		(at 22.7838 -111.2266)
		(size 0.508)
		(drill 0.254)
		(layers "F.Cu" "B.Cu")
		(net "FM_BMC_UARTSW_MSB_N")
	)
	(segment
		(start 18.788634 -109.0168)
		(end 19.6342 -109.0168)
		(width 0.11684)
		(layer "B.Cu")
		(net "FM_BMC_UARTSW_MSB_N")
	)
	(segment
		(start 16.0274 -107.2896)
		(end 16.6624 -107.9246)
		(width 0.11684)
		(layer "B.Cu")
		(net "FM_BMC_UARTSW_MSB_N")
	)
	(segment
		(start 26.162 -113.157)
		(end 26.162 -112.268)
		(width 0.11684)
		(layer "B.Cu")
		(net "FM_BMC_UARTSW_MSB_N")
	)
	(segment
		(start 16.6624 -108.458)
		(end 17.2212 -109.0168)
		(width 0.11684)
		(layer "B.Cu")
		(net "FM_BMC_UARTSW_MSB_N")
	)
	(segment
		(start 25.781 -111.887)
		(end 23.4442 -111.887)
		(width 0.11684)
		(layer "B.Cu")
		(net "FM_BMC_UARTSW_MSB_N")
	)
	(segment
		(start 14.54785 -106.82605)
		(end 15.0114 -107.2896)
		(width 0.11684)
		(layer "B.Cu")
		(net "FM_BMC_UARTSW_MSB_N")
	)
	(segment
		(start 16.6624 -107.9246)
		(end 16.6624 -108.458)
		(width 0.11684)
		(layer "B.Cu")
		(net "FM_BMC_UARTSW_MSB_N")
	)
	(segment
		(start 25.144984 -118.460012)
		(end 25.144984 -117.220238)
		(width 0.11684)
		(layer "B.Cu")
		(net "FM_BMC_UARTSW_MSB_N")
	)
	(segment
		(start 26.162 -112.268)
		(end 25.781 -111.887)
		(width 0.11684)
		(layer "B.Cu")
		(net "FM_BMC_UARTSW_MSB_N")
	)
	(segment
		(start 17.2212 -109.0168)
		(end 18.788634 -109.0168)
		(width 0.11684)
		(layer "B.Cu")
		(net "FM_BMC_UARTSW_MSB_N")
	)
	(segment
		(start 25.66416 -116.701062)
		(end 25.66416 -113.65484)
		(width 0.11684)
		(layer "B.Cu")
		(net "FM_BMC_UARTSW_MSB_N")
	)
	(segment
		(start 15.0114 -107.2896)
		(end 16.0274 -107.2896)
		(width 0.11684)
		(layer "B.Cu")
		(net "FM_BMC_UARTSW_MSB_N")
	)
	(segment
		(start 23.4442 -111.887)
		(end 22.7838 -111.2266)
		(width 0.11684)
		(layer "B.Cu")
		(net "FM_BMC_UARTSW_MSB_N")
	)
	(segment
		(start 19.6342 -109.0168)
		(end 20.2184 -108.4326)
		(width 0.11684)
		(layer "B.Cu")
		(net "FM_BMC_UARTSW_MSB_N")
	)
	(segment
		(start 25.66416 -113.65484)
		(end 26.162 -113.157)
		(width 0.11684)
		(layer "B.Cu")
		(net "FM_BMC_UARTSW_MSB_N")
	)
	(segment
		(start 14.351 -106.82605)
		(end 14.54785 -106.82605)
		(width 0.11684)
		(layer "B.Cu")
		(net "FM_BMC_UARTSW_MSB_N")
	)
	(segment
		(start 20.2184 -108.4326)
		(end 20.2184 -108.3056)
		(width 0.11684)
		(layer "B.Cu")
		(net "FM_BMC_UARTSW_MSB_N")
	)
	(segment
		(start 25.144984 -117.220238)
		(end 25.66416 -116.701062)
		(width 0.11684)
		(layer "B.Cu")
		(net "FM_BMC_UARTSW_MSB_N")
	)
	(via
		(at 15.86357 -108.42498)
		(size 0.6604)
		(drill 0.3302)
		(layers "F.Cu" "B.Cu")
		(net "FM_BMC_UARTSW_LSB_N")
	)
	(segment
		(start 17.399 -109.5756)
		(end 17.399 -110.1598)
		(width 0.11684)
		(layer "B.Cu")
		(net "FM_BMC_UARTSW_LSB_N")
	)
	(segment
		(start 14.707362 -108.8898)
		(end 15.172182 -108.42498)
		(width 0.11684)
		(layer "B.Cu")
		(net "FM_BMC_UARTSW_LSB_N")
	)
	(segment
		(start 12.319 -108.508546)
		(end 12.700254 -108.8898)
		(width 0.11684)
		(layer "B.Cu")
		(net "FM_BMC_UARTSW_LSB_N")
	)
	(segment
		(start 22.17928 -113.03127)
		(end 22.17928 -115.344448)
		(width 0.11684)
		(layer "B.Cu")
		(net "FM_BMC_UARTSW_LSB_N")
	)
	(segment
		(start 22.871684 -116.800884)
		(end 23.344886 -117.274086)
		(width 0.11684)
		(layer "B.Cu")
		(net "FM_BMC_UARTSW_LSB_N")
	)
	(segment
		(start 15.86357 -108.42498)
		(end 16.24838 -108.42498)
		(width 0.11684)
		(layer "B.Cu")
		(net "FM_BMC_UARTSW_LSB_N")
	)
	(segment
		(start 12.700254 -108.8898)
		(end 14.707362 -108.8898)
		(width 0.11684)
		(layer "B.Cu")
		(net "FM_BMC_UARTSW_LSB_N")
	)
	(segment
		(start 19.90979 -110.76178)
		(end 22.17928 -113.03127)
		(width 0.11684)
		(layer "B.Cu")
		(net "FM_BMC_UARTSW_LSB_N")
	)
	(segment
		(start 17.399 -110.1598)
		(end 18.00098 -110.76178)
		(width 0.11684)
		(layer "B.Cu")
		(net "FM_BMC_UARTSW_LSB_N")
	)
	(segment
		(start 22.871684 -116.036852)
		(end 22.871684 -116.800884)
		(width 0.11684)
		(layer "B.Cu")
		(net "FM_BMC_UARTSW_LSB_N")
	)
	(segment
		(start 16.24838 -108.42498)
		(end 17.399 -109.5756)
		(width 0.11684)
		(layer "B.Cu")
		(net "FM_BMC_UARTSW_LSB_N")
	)
	(segment
		(start 22.17928 -115.344448)
		(end 22.871684 -116.036852)
		(width 0.11684)
		(layer "B.Cu")
		(net "FM_BMC_UARTSW_LSB_N")
	)
	(segment
		(start 15.172182 -108.42498)
		(end 15.86357 -108.42498)
		(width 0.11684)
		(layer "B.Cu")
		(net "FM_BMC_UARTSW_LSB_N")
	)
	(segment
		(start 23.344886 -117.274086)
		(end 23.344886 -118.460012)
		(width 0.11684)
		(layer "B.Cu")
		(net "FM_BMC_UARTSW_LSB_N")
	)
	(segment
		(start 18.00098 -110.76178)
		(end 19.90979 -110.76178)
		(width 0.11684)
		(layer "B.Cu")
		(net "FM_BMC_UARTSW_LSB_N")
	)
	(segment
		(start 12.319 -106.82605)
		(end 12.319 -108.508546)
		(width 0.11684)
		(layer "B.Cu")
		(net "FM_BMC_UARTSW_LSB_N")
	)
	(segment
		(start 39.57955 -40.2082)
		(end 35.6362 -40.2082)
		(width 0.11684)
		(layer "F.Cu")
		(net "FM_BIC_DEBUG_SW_N")
	)
	(segment
		(start 26.9748 -37.319458)
		(end 26.027126 -37.319458)
		(width 0.11684)
		(layer "F.Cu")
		(net "FM_BIC_DEBUG_SW_N")
	)
	(segment
		(start 22.18436 -35.626294)
		(end 22.555454 -35.2552)
		(width 0.11684)
		(layer "F.Cu")
		(net "FM_BIC_DEBUG_SW_N")
	)
	(segment
		(start 29.050742 -39.3954)
		(end 26.9748 -37.319458)
		(width 0.11684)
		(layer "F.Cu")
		(net "FM_BIC_DEBUG_SW_N")
	)
	(segment
		(start 22.18436 -36.143946)
		(end 22.18436 -35.626294)
		(width 0.11684)
		(layer "F.Cu")
		(net "FM_BIC_DEBUG_SW_N")
	)
	(segment
		(start 15.621 -66.624454)
		(end 16.204946 -67.2084)
		(width 0.11684)
		(layer "F.Cu")
		(net "FM_BIC_DEBUG_SW_N")
	)
	(segment
		(start 15.428214 -65.47358)
		(end 15.621 -65.666366)
		(width 0.11684)
		(layer "F.Cu")
		(net "FM_BIC_DEBUG_SW_N")
	)
	(segment
		(start 18.0594 -59.32805)
		(end 18.025872 -59.341766)
		(width 0.11684)
		(layer "F.Cu")
		(net "FM_BIC_DEBUG_SW_N")
	)
	(segment
		(start 17.0434 -62.23)
		(end 15.621 -62.23)
		(width 0.11684)
		(layer "F.Cu")
		(net "FM_BIC_DEBUG_SW_N")
	)
	(segment
		(start 19.42338 -66.27622)
		(end 20.56638 -66.27622)
		(width 0.11684)
		(layer "F.Cu")
		(net "FM_BIC_DEBUG_SW_N")
	)
	(segment
		(start 15.428214 -63.306198)
		(end 15.428214 -65.47358)
		(width 0.11684)
		(layer "F.Cu")
		(net "FM_BIC_DEBUG_SW_N")
	)
	(segment
		(start 22.692614 -36.6522)
		(end 22.18436 -36.143946)
		(width 0.11684)
		(layer "F.Cu")
		(net "FM_BIC_DEBUG_SW_N")
	)
	(segment
		(start 15.621 -65.666366)
		(end 15.621 -66.624454)
		(width 0.11684)
		(layer "F.Cu")
		(net "FM_BIC_DEBUG_SW_N")
	)
	(segment
		(start 18.025872 -59.341766)
		(end 17.50822 -60.591192)
		(width 0.11684)
		(layer "F.Cu")
		(net "FM_BIC_DEBUG_SW_N")
	)
	(segment
		(start 16.204946 -67.2084)
		(end 18.4912 -67.2084)
		(width 0.11684)
		(layer "F.Cu")
		(net "FM_BIC_DEBUG_SW_N")
	)
	(segment
		(start 20.56638 -66.27622)
		(end 20.7264 -66.1162)
		(width 0.11684)
		(layer "F.Cu")
		(net "FM_BIC_DEBUG_SW_N")
	)
	(segment
		(start 21.575014 -64.691514)
		(end 21.575014 -63.306198)
		(width 0.11684)
		(layer "F.Cu")
		(net "FM_BIC_DEBUG_SW_N")
	)
	(segment
		(start 20.7264 -66.1162)
		(end 20.7264 -65.540128)
		(width 0.11684)
		(layer "F.Cu")
		(net "FM_BIC_DEBUG_SW_N")
	)
	(segment
		(start 18.4912 -67.2084)
		(end 19.42338 -66.27622)
		(width 0.11684)
		(layer "F.Cu")
		(net "FM_BIC_DEBUG_SW_N")
	)
	(segment
		(start 24.41321 -36.6522)
		(end 22.692614 -36.6522)
		(width 0.11684)
		(layer "F.Cu")
		(net "FM_BIC_DEBUG_SW_N")
	)
	(segment
		(start 17.50822 -60.591192)
		(end 17.50822 -61.76518)
		(width 0.11684)
		(layer "F.Cu")
		(net "FM_BIC_DEBUG_SW_N")
	)
	(segment
		(start 20.7264 -65.540128)
		(end 21.575014 -64.691514)
		(width 0.11684)
		(layer "F.Cu")
		(net "FM_BIC_DEBUG_SW_N")
	)
	(segment
		(start 17.50822 -61.76518)
		(end 17.0434 -62.23)
		(width 0.11684)
		(layer "F.Cu")
		(net "FM_BIC_DEBUG_SW_N")
	)
	(segment
		(start 26.027126 -37.319458)
		(end 24.41321 -36.6522)
		(width 0.11684)
		(layer "F.Cu")
		(net "FM_BIC_DEBUG_SW_N")
	)
	(segment
		(start 35.052 -39.624)
		(end 32.385 -39.624)
		(width 0.11684)
		(layer "F.Cu")
		(net "FM_BIC_DEBUG_SW_N")
	)
	(segment
		(start 32.385 -39.624)
		(end 32.1564 -39.3954)
		(width 0.11684)
		(layer "F.Cu")
		(net "FM_BIC_DEBUG_SW_N")
	)
	(segment
		(start 15.621 -62.23)
		(end 15.428214 -62.422786)
		(width 0.11684)
		(layer "F.Cu")
		(net "FM_BIC_DEBUG_SW_N")
	)
	(segment
		(start 15.428214 -62.422786)
		(end 15.428214 -63.306198)
		(width 0.11684)
		(layer "F.Cu")
		(net "FM_BIC_DEBUG_SW_N")
	)
	(segment
		(start 35.6362 -40.2082)
		(end 35.052 -39.624)
		(width 0.11684)
		(layer "F.Cu")
		(net "FM_BIC_DEBUG_SW_N")
	)
	(segment
		(start 22.555454 -35.2552)
		(end 22.6568 -35.2552)
		(width 0.11684)
		(layer "F.Cu")
		(net "FM_BIC_DEBUG_SW_N")
	)
	(segment
		(start 32.1564 -39.3954)
		(end 29.050742 -39.3954)
		(width 0.11684)
		(layer "F.Cu")
		(net "FM_BIC_DEBUG_SW_N")
	)
	(via
		(at 18.0594 -58.354214)
		(size 0.6604)
		(drill 0.3302)
		(layers "F.Cu" "B.Cu")
		(net "FM_BIC_DEBUG_SW_N")
	)
	(via
		(at 18.0594 -59.32805)
		(size 0.508)
		(drill 0.254)
		(layers "F.Cu" "B.Cu")
		(net "FM_BIC_DEBUG_SW_N")
	)
	(via
		(at 22.6568 -35.2552)
		(size 0.508)
		(drill 0.254)
		(layers "F.Cu" "B.Cu")
		(net "FM_BIC_DEBUG_SW_N")
	)
	(segment
		(start 22.3774 -35.2552)
		(end 22.18436 -35.44824)
		(width 0.11684)
		(layer "B.Cu")
		(net "FM_BIC_DEBUG_SW_N")
	)
	(segment
		(start 20.0152 -44.0944)
		(end 20.0152 -51.829208)
		(width 0.11684)
		(layer "B.Cu")
		(net "FM_BIC_DEBUG_SW_N")
	)
	(segment
		(start 22.6568 -35.2552)
		(end 22.3774 -35.2552)
		(width 0.11684)
		(layer "B.Cu")
		(net "FM_BIC_DEBUG_SW_N")
	)
	(segment
		(start 22.18436 -36.195)
		(end 22.52726 -36.5379)
		(width 0.11684)
		(layer "B.Cu")
		(net "FM_BIC_DEBUG_SW_N")
	)
	(segment
		(start 18.0594 -57.3278)
		(end 18.0594 -58.354214)
		(width 0.11684)
		(layer "B.Cu")
		(net "FM_BIC_DEBUG_SW_N")
	)
	(segment
		(start 18.0594 -59.32805)
		(end 18.0594 -58.354214)
		(width 0.11684)
		(layer "B.Cu")
		(net "FM_BIC_DEBUG_SW_N")
	)
	(segment
		(start 22.52726 -36.5379)
		(end 22.52726 -41.58234)
		(width 0.11684)
		(layer "B.Cu")
		(net "FM_BIC_DEBUG_SW_N")
	)
	(segment
		(start 17.95018 -53.894228)
		(end 17.95018 -55.38978)
		(width 0.11684)
		(layer "B.Cu")
		(net "FM_BIC_DEBUG_SW_N")
	)
	(segment
		(start 22.52726 -41.58234)
		(end 20.0152 -44.0944)
		(width 0.11684)
		(layer "B.Cu")
		(net "FM_BIC_DEBUG_SW_N")
	)
	(segment
		(start 18.415 -56.9722)
		(end 18.0594 -57.3278)
		(width 0.11684)
		(layer "B.Cu")
		(net "FM_BIC_DEBUG_SW_N")
	)
	(segment
		(start 20.0152 -51.829208)
		(end 17.95018 -53.894228)
		(width 0.11684)
		(layer "B.Cu")
		(net "FM_BIC_DEBUG_SW_N")
	)
	(segment
		(start 17.95018 -55.38978)
		(end 18.415 -55.8546)
		(width 0.11684)
		(layer "B.Cu")
		(net "FM_BIC_DEBUG_SW_N")
	)
	(segment
		(start 18.415 -55.8546)
		(end 18.415 -56.9722)
		(width 0.11684)
		(layer "B.Cu")
		(net "FM_BIC_DEBUG_SW_N")
	)
	(segment
		(start 22.18436 -35.44824)
		(end 22.18436 -36.195)
		(width 0.11684)
		(layer "B.Cu")
		(net "FM_BIC_DEBUG_SW_N")
	)
	(segment
		(start 43.942 -43.2308)
		(end 44.754546 -43.2308)
		(width 0.11684)
		(layer "F.Cu")
		(net "CLK_BUF1_GPU_FPGA_OE_R_N")
	)
	(segment
		(start 22.254718 -97.582228)
		(end 21.859494 -97.187004)
		(width 0.11684)
		(layer "F.Cu")
		(net "CLK_BUF1_GPU_FPGA_OE_R_N")
	)
	(segment
		(start 44.754546 -43.2308)
		(end 44.895008 -43.371262)
		(width 0.11684)
		(layer "F.Cu")
		(net "CLK_BUF1_GPU_FPGA_OE_R_N")
	)
	(via
		(at 17.116044 -48.75149)
		(size 0.508)
		(drill 0.254)
		(layers "F.Cu" "B.Cu")
		(net "CLK_BUF1_GPU_FPGA_OE_R_N")
	)
	(via
		(at 43.942 -43.2308)
		(size 0.4572)
		(drill 0.254)
		(layers "F.Cu" "B.Cu")
		(net "CLK_BUF1_GPU_FPGA_OE_R_N")
	)
	(via
		(at 22.254718 -97.582228)
		(size 0.4572)
		(drill 0.254)
		(layers "F.Cu" "B.Cu")
		(net "CLK_BUF1_GPU_FPGA_OE_R_N")
	)
	(via
		(at 19.7104 -109.5756)
		(size 0.508)
		(drill 0.254)
		(layers "F.Cu" "B.Cu")
		(net "CLK_BUF1_GPU_FPGA_OE_R_N")
	)
	(via
		(at 8.1534 -109.9312)
		(size 0.508)
		(drill 0.254)
		(layers "F.Cu" "B.Cu")
		(net "CLK_BUF1_GPU_FPGA_OE_R_N")
	)
	(via
		(at 8.9662 -82.2706)
		(size 0.6604)
		(drill 0.3302)
		(layers "F.Cu" "B.Cu")
		(net "CLK_BUF1_GPU_FPGA_OE_R_N")
	)
	(segment
		(start 4.572 -80.518)
		(end 4.35864 -80.73136)
		(width 0.11684)
		(layer "B.Cu")
		(net "CLK_BUF1_GPU_FPGA_OE_R_N")
	)
	(segment
		(start 4.318 -86.6394)
		(end 4.318 -107.188)
		(width 0.11684)
		(layer "B.Cu")
		(net "CLK_BUF1_GPU_FPGA_OE_R_N")
	)
	(segment
		(start 4.35864 -86.59876)
		(end 4.318 -86.6394)
		(width 0.11684)
		(layer "B.Cu")
		(net "CLK_BUF1_GPU_FPGA_OE_R_N")
	)
	(segment
		(start 20.24126 -103.880412)
		(end 20.444968 -103.388668)
		(width 0.11684)
		(layer "B.Cu")
		(net "CLK_BUF1_GPU_FPGA_OE_R_N")
	)
	(segment
		(start 12.96416 -78.397862)
		(end 12.96416 -79.74584)
		(width 0.11684)
		(layer "B.Cu")
		(net "CLK_BUF1_GPU_FPGA_OE_R_N")
	)
	(segment
		(start 15.7226 -50.144934)
		(end 15.7226 -56.642)
		(width 0.11684)
		(layer "B.Cu")
		(net "CLK_BUF1_GPU_FPGA_OE_R_N")
	)
	(segment
		(start 20.173188 -107.041188)
		(end 20.173188 -104.156002)
		(width 0.11684)
		(layer "B.Cu")
		(net "CLK_BUF1_GPU_FPGA_OE_R_N")
	)
	(segment
		(start 20.444968 -100.840032)
		(end 21.1328 -100.1522)
		(width 0.11684)
		(layer "B.Cu")
		(net "CLK_BUF1_GPU_FPGA_OE_R_N")
	)
	(segment
		(start 20.173188 -104.156002)
		(end 20.24126 -103.991664)
		(width 0.11684)
		(layer "B.Cu")
		(net "CLK_BUF1_GPU_FPGA_OE_R_N")
	)
	(segment
		(start 7.493 -81.8642)
		(end 7.493 -81.407)
		(width 0.11684)
		(layer "B.Cu")
		(net "CLK_BUF1_GPU_FPGA_OE_R_N")
	)
	(segment
		(start 7.493 -81.407)
		(end 6.604 -80.518)
		(width 0.11684)
		(layer "B.Cu")
		(net "CLK_BUF1_GPU_FPGA_OE_R_N")
	)
	(segment
		(start 5.87756 -108.74756)
		(end 5.87756 -108.91012)
		(width 0.11684)
		(layer "B.Cu")
		(net "CLK_BUF1_GPU_FPGA_OE_R_N")
	)
	(segment
		(start 21.1328 -100.1522)
		(end 21.5138 -100.1522)
		(width 0.11684)
		(layer "B.Cu")
		(net "CLK_BUF1_GPU_FPGA_OE_R_N")
	)
	(segment
		(start 4.35864 -80.73136)
		(end 4.35864 -86.59876)
		(width 0.11684)
		(layer "B.Cu")
		(net "CLK_BUF1_GPU_FPGA_OE_R_N")
	)
	(segment
		(start 21.8186 -98.26879)
		(end 22.254718 -97.832672)
		(width 0.11684)
		(layer "B.Cu")
		(net "CLK_BUF1_GPU_FPGA_OE_R_N")
	)
	(segment
		(start 13.95476 -77.407262)
		(end 12.96416 -78.397862)
		(width 0.11684)
		(layer "B.Cu")
		(net "CLK_BUF1_GPU_FPGA_OE_R_N")
	)
	(segment
		(start 12.96416 -79.74584)
		(end 10.4394 -82.2706)
		(width 0.11684)
		(layer "B.Cu")
		(net "CLK_BUF1_GPU_FPGA_OE_R_N")
	)
	(segment
		(start 13.95476 -66.51244)
		(end 13.95476 -77.407262)
		(width 0.11684)
		(layer "B.Cu")
		(net "CLK_BUF1_GPU_FPGA_OE_R_N")
	)
	(segment
		(start 10.4394 -82.2706)
		(end 8.9662 -82.2706)
		(width 0.11684)
		(layer "B.Cu")
		(net "CLK_BUF1_GPU_FPGA_OE_R_N")
	)
	(segment
		(start 19.7104 -109.5756)
		(end 20.701 -108.585)
		(width 0.11684)
		(layer "B.Cu")
		(net "CLK_BUF1_GPU_FPGA_OE_R_N")
	)
	(segment
		(start 4.318 -107.188)
		(end 5.87756 -108.74756)
		(width 0.11684)
		(layer "B.Cu")
		(net "CLK_BUF1_GPU_FPGA_OE_R_N")
	)
	(segment
		(start 7.8994 -82.2706)
		(end 7.493 -81.8642)
		(width 0.11684)
		(layer "B.Cu")
		(net "CLK_BUF1_GPU_FPGA_OE_R_N")
	)
	(segment
		(start 6.604 -80.518)
		(end 4.572 -80.518)
		(width 0.11684)
		(layer "B.Cu")
		(net "CLK_BUF1_GPU_FPGA_OE_R_N")
	)
	(segment
		(start 14.26464 -58.09996)
		(end 14.26464 -66.20256)
		(width 0.11684)
		(layer "B.Cu")
		(net "CLK_BUF1_GPU_FPGA_OE_R_N")
	)
	(segment
		(start 5.87756 -108.91012)
		(end 6.89864 -109.9312)
		(width 0.11684)
		(layer "B.Cu")
		(net "CLK_BUF1_GPU_FPGA_OE_R_N")
	)
	(segment
		(start 20.444968 -103.388668)
		(end 20.444968 -100.840032)
		(width 0.11684)
		(layer "B.Cu")
		(net "CLK_BUF1_GPU_FPGA_OE_R_N")
	)
	(segment
		(start 20.701 -107.569)
		(end 20.173188 -107.041188)
		(width 0.11684)
		(layer "B.Cu")
		(net "CLK_BUF1_GPU_FPGA_OE_R_N")
	)
	(segment
		(start 17.116044 -48.75149)
		(end 15.7226 -50.144934)
		(width 0.11684)
		(layer "B.Cu")
		(net "CLK_BUF1_GPU_FPGA_OE_R_N")
	)
	(segment
		(start 8.9662 -82.2706)
		(end 7.8994 -82.2706)
		(width 0.11684)
		(layer "B.Cu")
		(net "CLK_BUF1_GPU_FPGA_OE_R_N")
	)
	(segment
		(start 22.254718 -97.832672)
		(end 22.254718 -97.582228)
		(width 0.11684)
		(layer "B.Cu")
		(net "CLK_BUF1_GPU_FPGA_OE_R_N")
	)
	(segment
		(start 20.24126 -103.991664)
		(end 20.24126 -103.880412)
		(width 0.11684)
		(layer "B.Cu")
		(net "CLK_BUF1_GPU_FPGA_OE_R_N")
	)
	(segment
		(start 20.701 -108.585)
		(end 20.701 -107.569)
		(width 0.11684)
		(layer "B.Cu")
		(net "CLK_BUF1_GPU_FPGA_OE_R_N")
	)
	(segment
		(start 21.8186 -99.8474)
		(end 21.8186 -98.26879)
		(width 0.11684)
		(layer "B.Cu")
		(net "CLK_BUF1_GPU_FPGA_OE_R_N")
	)
	(segment
		(start 14.26464 -66.20256)
		(end 13.95476 -66.51244)
		(width 0.11684)
		(layer "B.Cu")
		(net "CLK_BUF1_GPU_FPGA_OE_R_N")
	)
	(segment
		(start 15.7226 -56.642)
		(end 14.26464 -58.09996)
		(width 0.11684)
		(layer "B.Cu")
		(net "CLK_BUF1_GPU_FPGA_OE_R_N")
	)
	(segment
		(start 6.89864 -109.9312)
		(end 8.1534 -109.9312)
		(width 0.11684)
		(layer "B.Cu")
		(net "CLK_BUF1_GPU_FPGA_OE_R_N")
	)
	(segment
		(start 21.5138 -100.1522)
		(end 21.8186 -99.8474)
		(width 0.11684)
		(layer "B.Cu")
		(net "CLK_BUF1_GPU_FPGA_OE_R_N")
	)
	(segment
		(start 38.23335 -42.98315)
		(end 34.555938 -39.305738)
		(width 0.08382)
		(layer "In2.Cu")
		(net "CLK_BUF1_GPU_FPGA_OE_R_N")
	)
	(segment
		(start 17.805146 -109.1692)
		(end 17.287748 -109.686598)
		(width 0.08382)
		(layer "In2.Cu")
		(net "CLK_BUF1_GPU_FPGA_OE_R_N")
	)
	(segment
		(start 19.228308 -48.7934)
		(end 17.157954 -48.7934)
		(width 0.08382)
		(layer "In2.Cu")
		(net "CLK_BUF1_GPU_FPGA_OE_R_N")
	)
	(segment
		(start 12.420854 -109.474)
		(end 8.6106 -109.474)
		(width 0.08382)
		(layer "In2.Cu")
		(net "CLK_BUF1_GPU_FPGA_OE_R_N")
	)
	(segment
		(start 25.585166 -40.96258)
		(end 24.830278 -40.96258)
		(width 0.08382)
		(layer "In2.Cu")
		(net "CLK_BUF1_GPU_FPGA_OE_R_N")
	)
	(segment
		(start 24.830278 -40.96258)
		(end 21.4122 -44.380658)
		(width 0.08382)
		(layer "In2.Cu")
		(net "CLK_BUF1_GPU_FPGA_OE_R_N")
	)
	(segment
		(start 16.770604 -110.68558)
		(end 13.632434 -110.68558)
		(width 0.08382)
		(layer "In2.Cu")
		(net "CLK_BUF1_GPU_FPGA_OE_R_N")
	)
	(segment
		(start 19.7104 -109.5756)
		(end 19.304 -109.1692)
		(width 0.08382)
		(layer "In2.Cu")
		(net "CLK_BUF1_GPU_FPGA_OE_R_N")
	)
	(segment
		(start 17.287748 -110.168436)
		(end 16.770604 -110.68558)
		(width 0.08382)
		(layer "In2.Cu")
		(net "CLK_BUF1_GPU_FPGA_OE_R_N")
	)
	(segment
		(start 21.4122 -44.380658)
		(end 21.4122 -46.609508)
		(width 0.08382)
		(layer "In2.Cu")
		(net "CLK_BUF1_GPU_FPGA_OE_R_N")
	)
	(segment
		(start 27.242008 -39.305738)
		(end 25.585166 -40.96258)
		(width 0.08382)
		(layer "In2.Cu")
		(net "CLK_BUF1_GPU_FPGA_OE_R_N")
	)
	(segment
		(start 8.6106 -109.474)
		(end 8.1534 -109.9312)
		(width 0.08382)
		(layer "In2.Cu")
		(net "CLK_BUF1_GPU_FPGA_OE_R_N")
	)
	(segment
		(start 43.942 -43.2308)
		(end 43.69435 -42.98315)
		(width 0.08382)
		(layer "In2.Cu")
		(net "CLK_BUF1_GPU_FPGA_OE_R_N")
	)
	(segment
		(start 21.4122 -46.609508)
		(end 19.228308 -48.7934)
		(width 0.08382)
		(layer "In2.Cu")
		(net "CLK_BUF1_GPU_FPGA_OE_R_N")
	)
	(segment
		(start 17.287748 -109.686598)
		(end 17.287748 -110.168436)
		(width 0.08382)
		(layer "In2.Cu")
		(net "CLK_BUF1_GPU_FPGA_OE_R_N")
	)
	(segment
		(start 17.157954 -48.7934)
		(end 17.116044 -48.75149)
		(width 0.08382)
		(layer "In2.Cu")
		(net "CLK_BUF1_GPU_FPGA_OE_R_N")
	)
	(segment
		(start 43.69435 -42.98315)
		(end 38.23335 -42.98315)
		(width 0.08382)
		(layer "In2.Cu")
		(net "CLK_BUF1_GPU_FPGA_OE_R_N")
	)
	(segment
		(start 34.555938 -39.305738)
		(end 27.242008 -39.305738)
		(width 0.08382)
		(layer "In2.Cu")
		(net "CLK_BUF1_GPU_FPGA_OE_R_N")
	)
	(segment
		(start 19.304 -109.1692)
		(end 17.805146 -109.1692)
		(width 0.08382)
		(layer "In2.Cu")
		(net "CLK_BUF1_GPU_FPGA_OE_R_N")
	)
	(segment
		(start 13.632434 -110.68558)
		(end 12.420854 -109.474)
		(width 0.08382)
		(layer "In2.Cu")
		(net "CLK_BUF1_GPU_FPGA_OE_R_N")
	)
	(segment
		(start 61.695076 -57.771284)
		(end 61.299852 -57.37606)
		(width 0.13716)
		(layer "F.Cu")
		(net "CLK_100M_PCH_DP")
	)
	(via
		(at 61.299852 -57.37606)
		(size 0.4572)
		(drill 0.254)
		(layers "F.Cu" "B.Cu")
		(net "CLK_100M_PCH_DP")
	)
	(via
		(at 56.19115 -104.1781)
		(size 0.508)
		(drill 0.254)
		(layers "F.Cu" "B.Cu")
		(net "CLK_100M_PCH_DP")
	)
	(segment
		(start 56.21401 -109.889544)
		(end 56.21401 -115.528344)
		(width 0.14224)
		(layer "B.Cu")
		(net "CLK_100M_PCH_DP")
	)
	(segment
		(start 55.665116 -117.514116)
		(end 55.665116 -118.25986)
		(width 0.14224)
		(layer "B.Cu")
		(net "CLK_100M_PCH_DP")
	)
	(segment
		(start 55.9435 -104.42575)
		(end 55.9435 -104.940354)
		(width 0.14224)
		(layer "B.Cu")
		(net "CLK_100M_PCH_DP")
	)
	(segment
		(start 55.9435 -104.940354)
		(end 56.6928 -105.689654)
		(width 0.14224)
		(layer "B.Cu")
		(net "CLK_100M_PCH_DP")
	)
	(segment
		(start 55.549292 -117.398292)
		(end 55.665116 -117.514116)
		(width 0.14224)
		(layer "B.Cu")
		(net "CLK_100M_PCH_DP")
	)
	(segment
		(start 56.21401 -115.528344)
		(end 55.549292 -116.193062)
		(width 0.14224)
		(layer "B.Cu")
		(net "CLK_100M_PCH_DP")
	)
	(segment
		(start 56.6928 -109.410754)
		(end 56.21401 -109.889544)
		(width 0.14224)
		(layer "B.Cu")
		(net "CLK_100M_PCH_DP")
	)
	(segment
		(start 56.19115 -104.1781)
		(end 55.9435 -104.42575)
		(width 0.14224)
		(layer "B.Cu")
		(net "CLK_100M_PCH_DP")
	)
	(segment
		(start 55.549292 -116.193062)
		(end 55.549292 -117.398292)
		(width 0.14224)
		(layer "B.Cu")
		(net "CLK_100M_PCH_DP")
	)
	(segment
		(start 56.6928 -105.689654)
		(end 56.6928 -109.410754)
		(width 0.14224)
		(layer "B.Cu")
		(net "CLK_100M_PCH_DP")
	)
	(segment
		(start 65.552066 -83.789012)
		(end 64.920622 -84.050632)
		(width 0.1143)
		(layer "In9.Cu")
		(net "CLK_100M_PCH_DP")
	)
	(segment
		(start 68.9864 -67.200018)
		(end 68.9864 -69.012816)
		(width 0.1143)
		(layer "In9.Cu")
		(net "CLK_100M_PCH_DP")
	)
	(segment
		(start 63.5254 -64.6176)
		(end 64.0588 -64.0842)
		(width 0.1143)
		(layer "In9.Cu")
		(net "CLK_100M_PCH_DP")
	)
	(segment
		(start 57.556654 -103.584248)
		(end 57.427114 -103.896922)
		(width 0.1143)
		(layer "In9.Cu")
		(net "CLK_100M_PCH_DP")
	)
	(segment
		(start 68.4276 -70.362064)
		(end 68.4276 -80.366616)
		(width 0.1143)
		(layer "In9.Cu")
		(net "CLK_100M_PCH_DP")
	)
	(segment
		(start 62.368684 -99.683316)
		(end 62.093348 -100.34778)
		(width 0.1143)
		(layer "In9.Cu")
		(net "CLK_100M_PCH_DP")
	)
	(segment
		(start 59.78652 -60.717938)
		(end 60.328048 -61.259466)
		(width 0.1143)
		(layer "In9.Cu")
		(net "CLK_100M_PCH_DP")
	)
	(segment
		(start 61.232288 -63.441834)
		(end 62.408054 -64.6176)
		(width 0.1143)
		(layer "In9.Cu")
		(net "CLK_100M_PCH_DP")
	)
	(segment
		(start 56.579516 -104.74452)
		(end 56.02859 -104.74452)
		(width 0.1143)
		(layer "In9.Cu")
		(net "CLK_100M_PCH_DP")
	)
	(segment
		(start 59.15533 -101.289866)
		(end 58.85688 -101.289866)
		(width 0.1143)
		(layer "In9.Cu")
		(net "CLK_100M_PCH_DP")
	)
	(segment
		(start 63.81115 -95.73387)
		(end 63.60033 -95.94469)
		(width 0.1143)
		(layer "In9.Cu")
		(net "CLK_100M_PCH_DP")
	)
	(segment
		(start 59.78652 -59.453526)
		(end 59.78652 -60.717938)
		(width 0.1143)
		(layer "In9.Cu")
		(net "CLK_100M_PCH_DP")
	)
	(segment
		(start 60.328048 -61.259466)
		(end 61.232288 -63.441834)
		(width 0.1143)
		(layer "In9.Cu")
		(net "CLK_100M_PCH_DP")
	)
	(segment
		(start 64.155574 -84.81568)
		(end 63.81115 -85.647276)
		(width 0.1143)
		(layer "In9.Cu")
		(net "CLK_100M_PCH_DP")
	)
	(segment
		(start 62.408054 -64.6176)
		(end 63.5254 -64.6176)
		(width 0.1143)
		(layer "In9.Cu")
		(net "CLK_100M_PCH_DP")
	)
	(segment
		(start 57.57164 -102.996492)
		(end 57.442354 -103.308912)
		(width 0.1143)
		(layer "In9.Cu")
		(net "CLK_100M_PCH_DP")
	)
	(segment
		(start 67.045332 -83.170522)
		(end 67.045078 -83.170522)
		(width 0.1143)
		(layer "In9.Cu")
		(net "CLK_100M_PCH_DP")
	)
	(segment
		(start 65.666112 -83.513422)
		(end 65.552066 -83.789012)
		(width 0.1143)
		(layer "In9.Cu")
		(net "CLK_100M_PCH_DP")
	)
	(segment
		(start 62.607444 -99.444556)
		(end 62.368684 -99.683316)
		(width 0.1143)
		(layer "In9.Cu")
		(net "CLK_100M_PCH_DP")
	)
	(segment
		(start 63.81115 -96.90227)
		(end 63.60033 -97.11309)
		(width 0.1143)
		(layer "In9.Cu")
		(net "CLK_100M_PCH_DP")
	)
	(segment
		(start 61.299852 -57.37606)
		(end 61.022992 -57.65292)
		(width 0.1143)
		(layer "In9.Cu")
		(net "CLK_100M_PCH_DP")
	)
	(segment
		(start 55.91429 -104.63022)
		(end 55.91429 -104.45496)
		(width 0.1143)
		(layer "In9.Cu")
		(net "CLK_100M_PCH_DP")
	)
	(segment
		(start 63.81115 -98.24085)
		(end 63.144654 -98.907346)
		(width 0.1143)
		(layer "In9.Cu")
		(net "CLK_100M_PCH_DP")
	)
	(segment
		(start 58.048652 -102.396544)
		(end 57.84723 -102.882446)
		(width 0.1143)
		(layer "In9.Cu")
		(net "CLK_100M_PCH_DP")
	)
	(segment
		(start 58.617866 -101.52888)
		(end 58.617866 -101.82733)
		(width 0.1143)
		(layer "In9.Cu")
		(net "CLK_100M_PCH_DP")
	)
	(segment
		(start 62.846204 -98.907346)
		(end 62.607444 -99.146106)
		(width 0.1143)
		(layer "In9.Cu")
		(net "CLK_100M_PCH_DP")
	)
	(segment
		(start 63.81115 -97.66173)
		(end 63.81115 -98.24085)
		(width 0.1143)
		(layer "In9.Cu")
		(net "CLK_100M_PCH_DP")
	)
	(segment
		(start 67.045078 -83.170522)
		(end 66.254122 -83.498182)
		(width 0.1143)
		(layer "In9.Cu")
		(net "CLK_100M_PCH_DP")
	)
	(segment
		(start 60.35167 -58.088784)
		(end 59.78652 -59.453526)
		(width 0.1143)
		(layer "In9.Cu")
		(net "CLK_100M_PCH_DP")
	)
	(segment
		(start 63.81115 -85.647276)
		(end 63.81115 -95.73387)
		(width 0.1143)
		(layer "In9.Cu")
		(net "CLK_100M_PCH_DP")
	)
	(segment
		(start 65.870582 -64.0842)
		(end 68.9864 -67.200018)
		(width 0.1143)
		(layer "In9.Cu")
		(net "CLK_100M_PCH_DP")
	)
	(segment
		(start 67.422522 -82.793332)
		(end 67.045332 -83.170522)
		(width 0.1143)
		(layer "In9.Cu")
		(net "CLK_100M_PCH_DP")
	)
	(segment
		(start 63.60033 -97.45091)
		(end 63.81115 -97.66173)
		(width 0.1143)
		(layer "In9.Cu")
		(net "CLK_100M_PCH_DP")
	)
	(segment
		(start 62.093348 -100.34778)
		(end 61.425328 -101.0158)
		(width 0.1143)
		(layer "In9.Cu")
		(net "CLK_100M_PCH_DP")
	)
	(segment
		(start 55.91429 -104.45496)
		(end 56.19115 -104.1781)
		(width 0.1143)
		(layer "In9.Cu")
		(net "CLK_100M_PCH_DP")
	)
	(segment
		(start 63.60033 -96.28251)
		(end 63.81115 -96.49333)
		(width 0.1143)
		(layer "In9.Cu")
		(net "CLK_100M_PCH_DP")
	)
	(segment
		(start 68.9864 -69.012816)
		(end 68.4276 -70.362064)
		(width 0.1143)
		(layer "In9.Cu")
		(net "CLK_100M_PCH_DP")
	)
	(segment
		(start 63.60033 -97.11309)
		(end 63.60033 -97.45091)
		(width 0.1143)
		(layer "In9.Cu")
		(net "CLK_100M_PCH_DP")
	)
	(segment
		(start 63.60033 -95.94469)
		(end 63.60033 -96.28251)
		(width 0.1143)
		(layer "In9.Cu")
		(net "CLK_100M_PCH_DP")
	)
	(segment
		(start 57.84723 -102.882446)
		(end 57.847484 -102.882446)
		(width 0.1143)
		(layer "In9.Cu")
		(net "CLK_100M_PCH_DP")
	)
	(segment
		(start 57.847484 -102.882446)
		(end 57.57164 -102.996492)
		(width 0.1143)
		(layer "In9.Cu")
		(net "CLK_100M_PCH_DP")
	)
	(segment
		(start 57.427114 -103.896922)
		(end 56.579516 -104.74452)
		(width 0.1143)
		(layer "In9.Cu")
		(net "CLK_100M_PCH_DP")
	)
	(segment
		(start 68.4276 -80.366616)
		(end 67.422522 -82.793332)
		(width 0.1143)
		(layer "In9.Cu")
		(net "CLK_100M_PCH_DP")
	)
	(segment
		(start 58.617866 -101.82733)
		(end 58.048652 -102.396544)
		(width 0.1143)
		(layer "In9.Cu")
		(net "CLK_100M_PCH_DP")
	)
	(segment
		(start 63.144654 -98.907346)
		(end 62.846204 -98.907346)
		(width 0.1143)
		(layer "In9.Cu")
		(net "CLK_100M_PCH_DP")
	)
	(segment
		(start 59.429396 -101.0158)
		(end 59.15533 -101.289866)
		(width 0.1143)
		(layer "In9.Cu")
		(net "CLK_100M_PCH_DP")
	)
	(segment
		(start 57.442354 -103.308912)
		(end 57.556654 -103.584248)
		(width 0.1143)
		(layer "In9.Cu")
		(net "CLK_100M_PCH_DP")
	)
	(segment
		(start 61.022992 -57.65292)
		(end 60.787534 -57.65292)
		(width 0.1143)
		(layer "In9.Cu")
		(net "CLK_100M_PCH_DP")
	)
	(segment
		(start 64.920622 -84.050632)
		(end 64.155574 -84.81568)
		(width 0.1143)
		(layer "In9.Cu")
		(net "CLK_100M_PCH_DP")
	)
	(segment
		(start 60.787534 -57.65292)
		(end 60.35167 -58.088784)
		(width 0.1143)
		(layer "In9.Cu")
		(net "CLK_100M_PCH_DP")
	)
	(segment
		(start 65.978532 -83.384136)
		(end 65.666112 -83.513422)
		(width 0.1143)
		(layer "In9.Cu")
		(net "CLK_100M_PCH_DP")
	)
	(segment
		(start 58.85688 -101.289866)
		(end 58.617866 -101.52888)
		(width 0.1143)
		(layer "In9.Cu")
		(net "CLK_100M_PCH_DP")
	)
	(segment
		(start 62.607444 -99.146106)
		(end 62.607444 -99.444556)
		(width 0.1143)
		(layer "In9.Cu")
		(net "CLK_100M_PCH_DP")
	)
	(segment
		(start 64.0588 -64.0842)
		(end 65.870582 -64.0842)
		(width 0.1143)
		(layer "In9.Cu")
		(net "CLK_100M_PCH_DP")
	)
	(segment
		(start 63.81115 -96.49333)
		(end 63.81115 -96.90227)
		(width 0.1143)
		(layer "In9.Cu")
		(net "CLK_100M_PCH_DP")
	)
	(segment
		(start 61.425328 -101.0158)
		(end 59.429396 -101.0158)
		(width 0.1143)
		(layer "In9.Cu")
		(net "CLK_100M_PCH_DP")
	)
	(segment
		(start 56.02859 -104.74452)
		(end 55.91429 -104.63022)
		(width 0.1143)
		(layer "In9.Cu")
		(net "CLK_100M_PCH_DP")
	)
	(segment
		(start 66.254122 -83.498182)
		(end 65.978532 -83.384136)
		(width 0.1143)
		(layer "In9.Cu")
		(net "CLK_100M_PCH_DP")
	)
	(segment
		(start 60.894976 -57.771284)
		(end 61.2902 -58.166508)
		(width 0.13716)
		(layer "F.Cu")
		(net "CLK_100M_PCH_DN")
	)
	(via
		(at 61.2902 -58.166508)
		(size 0.4572)
		(drill 0.254)
		(layers "F.Cu" "B.Cu")
		(net "CLK_100M_PCH_DN")
	)
	(via
		(at 55.30215 -104.1781)
		(size 0.508)
		(drill 0.254)
		(layers "F.Cu" "B.Cu")
		(net "CLK_100M_PCH_DN")
	)
	(segment
		(start 55.30215 -104.1781)
		(end 55.5752 -104.45115)
		(width 0.14224)
		(layer "B.Cu")
		(net "CLK_100M_PCH_DN")
	)
	(segment
		(start 55.180992 -117.412008)
		(end 55.064914 -117.528086)
		(width 0.14224)
		(layer "B.Cu")
		(net "CLK_100M_PCH_DN")
	)
	(segment
		(start 55.84571 -109.73689)
		(end 55.84571 -115.37569)
		(width 0.14224)
		(layer "B.Cu")
		(net "CLK_100M_PCH_DN")
	)
	(segment
		(start 55.064914 -117.528086)
		(end 55.064914 -118.25986)
		(width 0.14224)
		(layer "B.Cu")
		(net "CLK_100M_PCH_DN")
	)
	(segment
		(start 55.5752 -105.093008)
		(end 56.3245 -105.842308)
		(width 0.14224)
		(layer "B.Cu")
		(net "CLK_100M_PCH_DN")
	)
	(segment
		(start 55.5752 -104.45115)
		(end 55.5752 -105.093008)
		(width 0.14224)
		(layer "B.Cu")
		(net "CLK_100M_PCH_DN")
	)
	(segment
		(start 55.180992 -116.040408)
		(end 55.180992 -117.412008)
		(width 0.14224)
		(layer "B.Cu")
		(net "CLK_100M_PCH_DN")
	)
	(segment
		(start 56.3245 -109.2581)
		(end 55.84571 -109.73689)
		(width 0.14224)
		(layer "B.Cu")
		(net "CLK_100M_PCH_DN")
	)
	(segment
		(start 56.3245 -105.842308)
		(end 56.3245 -109.2581)
		(width 0.14224)
		(layer "B.Cu")
		(net "CLK_100M_PCH_DN")
	)
	(segment
		(start 55.84571 -115.37569)
		(end 55.180992 -116.040408)
		(width 0.14224)
		(layer "B.Cu")
		(net "CLK_100M_PCH_DN")
	)
	(segment
		(start 60.1218 -59.520328)
		(end 60.635896 -58.278776)
		(width 0.1143)
		(layer "In9.Cu")
		(net "CLK_100M_PCH_DN")
	)
	(segment
		(start 63.386462 -64.28232)
		(end 62.546992 -64.28232)
		(width 0.1143)
		(layer "In9.Cu")
		(net "CLK_100M_PCH_DN")
	)
	(segment
		(start 62.377574 -100.537772)
		(end 62.65291 -99.873308)
		(width 0.1143)
		(layer "In9.Cu")
		(net "CLK_100M_PCH_DN")
	)
	(segment
		(start 59.568334 -101.35108)
		(end 61.564266 -101.35108)
		(width 0.1143)
		(layer "In9.Cu")
		(net "CLK_100M_PCH_DN")
	)
	(segment
		(start 61.75883 -63.494158)
		(end 61.516514 -63.251842)
		(width 0.1143)
		(layer "In9.Cu")
		(net "CLK_100M_PCH_DN")
	)
	(segment
		(start 61.564266 -101.35108)
		(end 62.377574 -100.537772)
		(width 0.1143)
		(layer "In9.Cu")
		(net "CLK_100M_PCH_DN")
	)
	(segment
		(start 64.14643 -98.379788)
		(end 64.14643 -85.714078)
		(width 0.1143)
		(layer "In9.Cu")
		(net "CLK_100M_PCH_DN")
	)
	(segment
		(start 65.110614 -84.334858)
		(end 67.235324 -83.454748)
		(width 0.1143)
		(layer "In9.Cu")
		(net "CLK_100M_PCH_DN")
	)
	(segment
		(start 68.76288 -70.428866)
		(end 69.32168 -69.079618)
		(width 0.1143)
		(layer "In9.Cu")
		(net "CLK_100M_PCH_DN")
	)
	(segment
		(start 69.32168 -69.079618)
		(end 69.32168 -68.19773)
		(width 0.1143)
		(layer "In9.Cu")
		(net "CLK_100M_PCH_DN")
	)
	(segment
		(start 62.546992 -64.28232)
		(end 62.27826 -64.013588)
		(width 0.1143)
		(layer "In9.Cu")
		(net "CLK_100M_PCH_DN")
	)
	(segment
		(start 64.4398 -85.005672)
		(end 65.110614 -84.334858)
		(width 0.1143)
		(layer "In9.Cu")
		(net "CLK_100M_PCH_DN")
	)
	(segment
		(start 55.30215 -104.1781)
		(end 55.57901 -104.45496)
		(width 0.1143)
		(layer "In9.Cu")
		(net "CLK_100M_PCH_DN")
	)
	(segment
		(start 60.635896 -58.278776)
		(end 60.926472 -57.9882)
		(width 0.1143)
		(layer "In9.Cu")
		(net "CLK_100M_PCH_DN")
	)
	(segment
		(start 69.5325 -67.98691)
		(end 69.5325 -67.64909)
		(width 0.1143)
		(layer "In9.Cu")
		(net "CLK_100M_PCH_DN")
	)
	(segment
		(start 62.65291 -99.873308)
		(end 64.14643 -98.379788)
		(width 0.1143)
		(layer "In9.Cu")
		(net "CLK_100M_PCH_DN")
	)
	(segment
		(start 63.919862 -63.74892)
		(end 63.386462 -64.28232)
		(width 0.1143)
		(layer "In9.Cu")
		(net "CLK_100M_PCH_DN")
	)
	(segment
		(start 60.612274 -61.069474)
		(end 60.1218 -60.579)
		(width 0.1143)
		(layer "In9.Cu")
		(net "CLK_100M_PCH_DN")
	)
	(segment
		(start 67.235324 -83.454748)
		(end 67.706748 -82.983324)
		(width 0.1143)
		(layer "In9.Cu")
		(net "CLK_100M_PCH_DN")
	)
	(segment
		(start 61.516514 -63.251842)
		(end 60.612274 -61.069474)
		(width 0.1143)
		(layer "In9.Cu")
		(net "CLK_100M_PCH_DN")
	)
	(segment
		(start 61.111892 -57.9882)
		(end 61.2902 -58.166508)
		(width 0.1143)
		(layer "In9.Cu")
		(net "CLK_100M_PCH_DN")
	)
	(segment
		(start 58.332878 -102.586536)
		(end 59.568334 -101.35108)
		(width 0.1143)
		(layer "In9.Cu")
		(net "CLK_100M_PCH_DN")
	)
	(segment
		(start 55.889652 -105.0798)
		(end 56.718454 -105.0798)
		(width 0.1143)
		(layer "In9.Cu")
		(net "CLK_100M_PCH_DN")
	)
	(segment
		(start 55.57901 -104.769158)
		(end 55.889652 -105.0798)
		(width 0.1143)
		(layer "In9.Cu")
		(net "CLK_100M_PCH_DN")
	)
	(segment
		(start 65.11671 -63.5381)
		(end 64.77889 -63.5381)
		(width 0.1143)
		(layer "In9.Cu")
		(net "CLK_100M_PCH_DN")
	)
	(segment
		(start 69.5325 -67.64909)
		(end 69.32168 -67.43827)
		(width 0.1143)
		(layer "In9.Cu")
		(net "CLK_100M_PCH_DN")
	)
	(segment
		(start 60.926472 -57.9882)
		(end 61.111892 -57.9882)
		(width 0.1143)
		(layer "In9.Cu")
		(net "CLK_100M_PCH_DN")
	)
	(segment
		(start 66.00952 -63.74892)
		(end 65.32753 -63.74892)
		(width 0.1143)
		(layer "In9.Cu")
		(net "CLK_100M_PCH_DN")
	)
	(segment
		(start 60.1218 -60.579)
		(end 60.1218 -59.520328)
		(width 0.1143)
		(layer "In9.Cu")
		(net "CLK_100M_PCH_DN")
	)
	(segment
		(start 64.14643 -85.714078)
		(end 64.4398 -85.005672)
		(width 0.1143)
		(layer "In9.Cu")
		(net "CLK_100M_PCH_DN")
	)
	(segment
		(start 69.32168 -67.43827)
		(end 69.32168 -67.06108)
		(width 0.1143)
		(layer "In9.Cu")
		(net "CLK_100M_PCH_DN")
	)
	(segment
		(start 65.32753 -63.74892)
		(end 65.11671 -63.5381)
		(width 0.1143)
		(layer "In9.Cu")
		(net "CLK_100M_PCH_DN")
	)
	(segment
		(start 64.56807 -63.74892)
		(end 63.919862 -63.74892)
		(width 0.1143)
		(layer "In9.Cu")
		(net "CLK_100M_PCH_DN")
	)
	(segment
		(start 64.77889 -63.5381)
		(end 64.56807 -63.74892)
		(width 0.1143)
		(layer "In9.Cu")
		(net "CLK_100M_PCH_DN")
	)
	(segment
		(start 62.03569 -63.494158)
		(end 61.75883 -63.494158)
		(width 0.1143)
		(layer "In9.Cu")
		(net "CLK_100M_PCH_DN")
	)
	(segment
		(start 67.706748 -82.983324)
		(end 68.76288 -80.433418)
		(width 0.1143)
		(layer "In9.Cu")
		(net "CLK_100M_PCH_DN")
	)
	(segment
		(start 68.76288 -80.433418)
		(end 68.76288 -70.428866)
		(width 0.1143)
		(layer "In9.Cu")
		(net "CLK_100M_PCH_DN")
	)
	(segment
		(start 69.32168 -68.19773)
		(end 69.5325 -67.98691)
		(width 0.1143)
		(layer "In9.Cu")
		(net "CLK_100M_PCH_DN")
	)
	(segment
		(start 57.71134 -104.086914)
		(end 58.332878 -102.586536)
		(width 0.1143)
		(layer "In9.Cu")
		(net "CLK_100M_PCH_DN")
	)
	(segment
		(start 55.57901 -104.45496)
		(end 55.57901 -104.769158)
		(width 0.1143)
		(layer "In9.Cu")
		(net "CLK_100M_PCH_DN")
	)
	(segment
		(start 69.32168 -67.06108)
		(end 66.00952 -63.74892)
		(width 0.1143)
		(layer "In9.Cu")
		(net "CLK_100M_PCH_DN")
	)
	(segment
		(start 62.27826 -63.736728)
		(end 62.03569 -63.494158)
		(width 0.1143)
		(layer "In9.Cu")
		(net "CLK_100M_PCH_DN")
	)
	(segment
		(start 56.718454 -105.0798)
		(end 57.71134 -104.086914)
		(width 0.1143)
		(layer "In9.Cu")
		(net "CLK_100M_PCH_DN")
	)
	(segment
		(start 62.27826 -64.013588)
		(end 62.27826 -63.736728)
		(width 0.1143)
		(layer "In9.Cu")
		(net "CLK_100M_PCH_DN")
	)
	(segment
		(start 64.894968 -58.57113)
		(end 65.290192 -58.966354)
		(width 0.1143)
		(layer "F.Cu")
		(net "CLK_100M_GPU_DP")
	)
	(via
		(at 14.346428 -115.149376)
		(size 0.508)
		(drill 0.254)
		(layers "F.Cu" "B.Cu")
		(net "CLK_100M_GPU_DP")
	)
	(via
		(at 65.290192 -58.966354)
		(size 0.4572)
		(drill 0.254)
		(layers "F.Cu" "B.Cu")
		(net "CLK_100M_GPU_DP")
	)
	(segment
		(start 15.07109 -115.409726)
		(end 15.42923 -115.767866)
		(width 0.14224)
		(layer "B.Cu")
		(net "CLK_100M_GPU_DP")
	)
	(segment
		(start 15.42923 -117.410484)
		(end 15.545054 -117.526308)
		(width 0.14224)
		(layer "B.Cu")
		(net "CLK_100M_GPU_DP")
	)
	(segment
		(start 14.346428 -115.149376)
		(end 14.606778 -115.409726)
		(width 0.14224)
		(layer "B.Cu")
		(net "CLK_100M_GPU_DP")
	)
	(segment
		(start 15.42923 -115.767866)
		(end 15.42923 -117.410484)
		(width 0.14224)
		(layer "B.Cu")
		(net "CLK_100M_GPU_DP")
	)
	(segment
		(start 14.606778 -115.409726)
		(end 15.07109 -115.409726)
		(width 0.14224)
		(layer "B.Cu")
		(net "CLK_100M_GPU_DP")
	)
	(segment
		(start 15.545054 -117.526308)
		(end 15.545054 -118.25986)
		(width 0.14224)
		(layer "B.Cu")
		(net "CLK_100M_GPU_DP")
	)
	(segment
		(start 73.192386 -74.534014)
		(end 72.984614 -74.741786)
		(width 0.1143)
		(layer "In9.Cu")
		(net "CLK_100M_GPU_DP")
	)
	(segment
		(start 21.23694 -114.7572)
		(end 20.710906 -114.7572)
		(width 0.1143)
		(layer "In9.Cu")
		(net "CLK_100M_GPU_DP")
	)
	(segment
		(start 75.705462 -68.171314)
		(end 75.458066 -68.666106)
		(width 0.1143)
		(layer "In9.Cu")
		(net "CLK_100M_GPU_DP")
	)
	(segment
		(start 67.676522 -61.442854)
		(end 68.059046 -61.825378)
		(width 0.1143)
		(layer "In9.Cu")
		(net "CLK_100M_GPU_DP")
	)
	(segment
		(start 74.66203 -73.375774)
		(end 74.35469 -73.683114)
		(width 0.1143)
		(layer "In9.Cu")
		(net "CLK_100M_GPU_DP")
	)
	(segment
		(start 22.808692 -115.62842)
		(end 22.432772 -115.2525)
		(width 0.1143)
		(layer "In9.Cu")
		(net "CLK_100M_GPU_DP")
	)
	(segment
		(start 49.112678 -112.612678)
		(end 46.366938 -111.47552)
		(width 0.1143)
		(layer "In9.Cu")
		(net "CLK_100M_GPU_DP")
	)
	(segment
		(start 74.07783 -73.683114)
		(end 73.835514 -73.92543)
		(width 0.1143)
		(layer "In9.Cu")
		(net "CLK_100M_GPU_DP")
	)
	(segment
		(start 46.366938 -111.47552)
		(end 31.06166 -111.47552)
		(width 0.1143)
		(layer "In9.Cu")
		(net "CLK_100M_GPU_DP")
	)
	(segment
		(start 57.6072 -113.1316)
		(end 57.6072 -114.231928)
		(width 0.1143)
		(layer "In9.Cu")
		(net "CLK_100M_GPU_DP")
	)
	(segment
		(start 20.710906 -114.7572)
		(end 17.939004 -113.60912)
		(width 0.1143)
		(layer "In9.Cu")
		(net "CLK_100M_GPU_DP")
	)
	(segment
		(start 74.86015 -70.110096)
		(end 74.86015 -71.28637)
		(width 0.1143)
		(layer "In9.Cu")
		(net "CLK_100M_GPU_DP")
	)
	(segment
		(start 75.038458 -69.16801)
		(end 74.90714 -69.485002)
		(width 0.1143)
		(layer "In9.Cu")
		(net "CLK_100M_GPU_DP")
	)
	(segment
		(start 58.17108 -112.56772)
		(end 57.6072 -113.1316)
		(width 0.1143)
		(layer "In9.Cu")
		(net "CLK_100M_GPU_DP")
	)
	(segment
		(start 73.1774 -63.2206)
		(end 73.5838 -63.627)
		(width 0.1143)
		(layer "In9.Cu")
		(net "CLK_100M_GPU_DP")
	)
	(segment
		(start 74.2315 -65.240154)
		(end 74.544936 -65.240154)
		(width 0.1143)
		(layer "In9.Cu")
		(net "CLK_100M_GPU_DP")
	)
	(segment
		(start 72.10552 -78.40726)
		(end 72.10552 -79.05623)
		(width 0.1143)
		(layer "In9.Cu")
		(net "CLK_100M_GPU_DP")
	)
	(segment
		(start 69.301106 -88.492584)
		(end 68.337176 -89.456768)
		(width 0.1143)
		(layer "In9.Cu")
		(net "CLK_100M_GPU_DP")
	)
	(segment
		(start 73.835514 -74.20229)
		(end 73.50379 -74.534014)
		(width 0.1143)
		(layer "In9.Cu")
		(net "CLK_100M_GPU_DP")
	)
	(segment
		(start 14.9606 -114.079528)
		(end 14.9606 -115.250722)
		(width 0.1143)
		(layer "In9.Cu")
		(net "CLK_100M_GPU_DP")
	)
	(segment
		(start 66.022728 -59.787282)
		(end 66.022728 -59.78906)
		(width 0.1143)
		(layer "In9.Cu")
		(net "CLK_100M_GPU_DP")
	)
	(segment
		(start 71.7804 -84.57946)
		(end 71.559674 -85.112606)
		(width 0.1143)
		(layer "In9.Cu")
		(net "CLK_100M_GPU_DP")
	)
	(segment
		(start 71.628 -77.254354)
		(end 72.10552 -78.40726)
		(width 0.1143)
		(layer "In9.Cu")
		(net "CLK_100M_GPU_DP")
	)
	(segment
		(start 66.445638 -99.468686)
		(end 65.62852 -101.44125)
		(width 0.1143)
		(layer "In9.Cu")
		(net "CLK_100M_GPU_DP")
	)
	(segment
		(start 14.9606 -115.250722)
		(end 14.785086 -115.426236)
		(width 0.1143)
		(layer "In9.Cu")
		(net "CLK_100M_GPU_DP")
	)
	(segment
		(start 71.7804 -79.841598)
		(end 71.7804 -84.57946)
		(width 0.1143)
		(layer "In9.Cu")
		(net "CLK_100M_GPU_DP")
	)
	(segment
		(start 74.818494 -66.069464)
		(end 74.949812 -66.386456)
		(width 0.1143)
		(layer "In9.Cu")
		(net "CLK_100M_GPU_DP")
	)
	(segment
		(start 57.6072 -114.231928)
		(end 57.361328 -114.4778)
		(width 0.1143)
		(layer "In9.Cu")
		(net "CLK_100M_GPU_DP")
	)
	(segment
		(start 68.059046 -61.825378)
		(end 68.059046 -62.102238)
		(width 0.1143)
		(layer "In9.Cu")
		(net "CLK_100M_GPU_DP")
	)
	(segment
		(start 57.361328 -114.4778)
		(end 57.36082 -114.4778)
		(width 0.1143)
		(layer "In9.Cu")
		(net "CLK_100M_GPU_DP")
	)
	(segment
		(start 66.3956 -60.438792)
		(end 66.63817 -60.681362)
		(width 0.1143)
		(layer "In9.Cu")
		(net "CLK_100M_GPU_DP")
	)
	(segment
		(start 73.835514 -73.92543)
		(end 73.835514 -74.20229)
		(width 0.1143)
		(layer "In9.Cu")
		(net "CLK_100M_GPU_DP")
	)
	(segment
		(start 65.62852 -105.117646)
		(end 64.35852 -108.18368)
		(width 0.1143)
		(layer "In9.Cu")
		(net "CLK_100M_GPU_DP")
	)
	(segment
		(start 64.024002 -109.432852)
		(end 61.391546 -112.065308)
		(width 0.1143)
		(layer "In9.Cu")
		(net "CLK_100M_GPU_DP")
	)
	(segment
		(start 72.105266 -79.056484)
		(end 71.7804 -79.841598)
		(width 0.1143)
		(layer "In9.Cu")
		(net "CLK_100M_GPU_DP")
	)
	(segment
		(start 75.705462 -67.699382)
		(end 75.705462 -68.171314)
		(width 0.1143)
		(layer "In9.Cu")
		(net "CLK_100M_GPU_DP")
	)
	(segment
		(start 67.157346 -60.923678)
		(end 67.157346 -61.200538)
		(width 0.1143)
		(layer "In9.Cu")
		(net "CLK_100M_GPU_DP")
	)
	(segment
		(start 67.399662 -61.442854)
		(end 67.676522 -61.442854)
		(width 0.1143)
		(layer "In9.Cu")
		(net "CLK_100M_GPU_DP")
	)
	(segment
		(start 74.90714 -69.485002)
		(end 75.013058 -69.740526)
		(width 0.1143)
		(layer "In9.Cu")
		(net "CLK_100M_GPU_DP")
	)
	(segment
		(start 31.06166 -111.47552)
		(end 29.874972 -111.96701)
		(width 0.1143)
		(layer "In9.Cu")
		(net "CLK_100M_GPU_DP")
	)
	(segment
		(start 15.431008 -113.60912)
		(end 14.9606 -114.079528)
		(width 0.1143)
		(layer "In9.Cu")
		(net "CLK_100M_GPU_DP")
	)
	(segment
		(start 65.595246 -59.271408)
		(end 65.595246 -59.3598)
		(width 0.086106)
		(layer "In9.Cu")
		(net "CLK_100M_GPU_DP")
	)
	(segment
		(start 67.157346 -61.200538)
		(end 67.399662 -61.442854)
		(width 0.1143)
		(layer "In9.Cu")
		(net "CLK_100M_GPU_DP")
	)
	(segment
		(start 66.022728 -59.78906)
		(end 66.3956 -60.161932)
		(width 0.1143)
		(layer "In9.Cu")
		(net "CLK_100M_GPU_DP")
	)
	(segment
		(start 74.949812 -66.386456)
		(end 75.205336 -66.49212)
		(width 0.1143)
		(layer "In9.Cu")
		(net "CLK_100M_GPU_DP")
	)
	(segment
		(start 74.86015 -72.02043)
		(end 74.86015 -72.526906)
		(width 0.1143)
		(layer "In9.Cu")
		(net "CLK_100M_GPU_DP")
	)
	(segment
		(start 73.5838 -64.279018)
		(end 74.025506 -64.720724)
		(width 0.1143)
		(layer "In9.Cu")
		(net "CLK_100M_GPU_DP")
	)
	(segment
		(start 70.046342 -63.2206)
		(end 73.1774 -63.2206)
		(width 0.1143)
		(layer "In9.Cu")
		(net "CLK_100M_GPU_DP")
	)
	(segment
		(start 74.86015 -71.28637)
		(end 74.66457 -71.48195)
		(width 0.1143)
		(layer "In9.Cu")
		(net "CLK_100M_GPU_DP")
	)
	(segment
		(start 74.924412 -65.81394)
		(end 74.818494 -66.069464)
		(width 0.1143)
		(layer "In9.Cu")
		(net "CLK_100M_GPU_DP")
	)
	(segment
		(start 60.179204 -112.56772)
		(end 58.17108 -112.56772)
		(width 0.1143)
		(layer "In9.Cu")
		(net "CLK_100M_GPU_DP")
	)
	(segment
		(start 74.025506 -65.03416)
		(end 74.2315 -65.240154)
		(width 0.1143)
		(layer "In9.Cu")
		(net "CLK_100M_GPU_DP")
	)
	(segment
		(start 74.77252 -73.109074)
		(end 74.66203 -73.375774)
		(width 0.1143)
		(layer "In9.Cu")
		(net "CLK_100M_GPU_DP")
	)
	(segment
		(start 75.458066 -68.666106)
		(end 75.294236 -69.062092)
		(width 0.1143)
		(layer "In9.Cu")
		(net "CLK_100M_GPU_DP")
	)
	(segment
		(start 75.013058 -69.740526)
		(end 74.86015 -70.110096)
		(width 0.1143)
		(layer "In9.Cu")
		(net "CLK_100M_GPU_DP")
	)
	(segment
		(start 29.874972 -111.96701)
		(end 26.768044 -115.073938)
		(width 0.1143)
		(layer "In9.Cu")
		(net "CLK_100M_GPU_DP")
	)
	(segment
		(start 14.623288 -115.426236)
		(end 14.346428 -115.149376)
		(width 0.1143)
		(layer "In9.Cu")
		(net "CLK_100M_GPU_DP")
	)
	(segment
		(start 74.77252 -72.738488)
		(end 74.77252 -73.109074)
		(width 0.1143)
		(layer "In9.Cu")
		(net "CLK_100M_GPU_DP")
	)
	(segment
		(start 72.984614 -75.05319)
		(end 71.854314 -76.18349)
		(width 0.1143)
		(layer "In9.Cu")
		(net "CLK_100M_GPU_DP")
	)
	(segment
		(start 71.559674 -85.112606)
		(end 69.301106 -88.492584)
		(width 0.1143)
		(layer "In9.Cu")
		(net "CLK_100M_GPU_DP")
	)
	(segment
		(start 68.578222 -62.344554)
		(end 69.035676 -62.802008)
		(width 0.1143)
		(layer "In9.Cu")
		(net "CLK_100M_GPU_DP")
	)
	(segment
		(start 26.768044 -115.073938)
		(end 25.429464 -115.62842)
		(width 0.1143)
		(layer "In9.Cu")
		(net "CLK_100M_GPU_DP")
	)
	(segment
		(start 72.10552 -79.05623)
		(end 72.105266 -79.056484)
		(width 0.1143)
		(layer "In9.Cu")
		(net "CLK_100M_GPU_DP")
	)
	(segment
		(start 71.854314 -76.18349)
		(end 71.628 -76.72959)
		(width 0.1143)
		(layer "In9.Cu")
		(net "CLK_100M_GPU_DP")
	)
	(segment
		(start 74.35469 -73.683114)
		(end 74.07783 -73.683114)
		(width 0.1143)
		(layer "In9.Cu")
		(net "CLK_100M_GPU_DP")
	)
	(segment
		(start 57.36082 -114.4778)
		(end 57.15127 -114.68735)
		(width 0.1143)
		(layer "In9.Cu")
		(net "CLK_100M_GPU_DP")
	)
	(segment
		(start 55.521098 -114.4778)
		(end 53.340254 -114.4778)
		(width 0.1143)
		(layer "In9.Cu")
		(net "CLK_100M_GPU_DP")
	)
	(segment
		(start 74.025506 -64.720724)
		(end 74.025506 -65.03416)
		(width 0.1143)
		(layer "In9.Cu")
		(net "CLK_100M_GPU_DP")
	)
	(segment
		(start 73.50379 -74.534014)
		(end 73.192386 -74.534014)
		(width 0.1143)
		(layer "In9.Cu")
		(net "CLK_100M_GPU_DP")
	)
	(segment
		(start 65.62852 -101.44125)
		(end 65.62852 -105.117646)
		(width 0.1143)
		(layer "In9.Cu")
		(net "CLK_100M_GPU_DP")
	)
	(segment
		(start 57.15127 -114.68735)
		(end 56.027066 -114.68735)
		(width 0.1143)
		(layer "In9.Cu")
		(net "CLK_100M_GPU_DP")
	)
	(segment
		(start 53.340254 -114.4778)
		(end 52.636674 -113.77422)
		(width 0.1143)
		(layer "In9.Cu")
		(net "CLK_100M_GPU_DP")
	)
	(segment
		(start 66.4718 -93.95968)
		(end 66.445638 -99.468686)
		(width 0.1143)
		(layer "In9.Cu")
		(net "CLK_100M_GPU_DP")
	)
	(segment
		(start 65.290192 -58.966354)
		(end 65.595246 -59.271408)
		(width 0.086106)
		(layer "In9.Cu")
		(net "CLK_100M_GPU_DP")
	)
	(segment
		(start 74.86015 -72.526906)
		(end 74.77252 -72.738488)
		(width 0.1143)
		(layer "In9.Cu")
		(net "CLK_100M_GPU_DP")
	)
	(segment
		(start 71.628 -76.72959)
		(end 71.628 -77.254354)
		(width 0.1143)
		(layer "In9.Cu")
		(net "CLK_100M_GPU_DP")
	)
	(segment
		(start 74.544936 -65.240154)
		(end 74.787252 -65.48247)
		(width 0.1143)
		(layer "In9.Cu")
		(net "CLK_100M_GPU_DP")
	)
	(segment
		(start 22.432772 -115.2525)
		(end 21.23694 -114.7572)
		(width 0.1143)
		(layer "In9.Cu")
		(net "CLK_100M_GPU_DP")
	)
	(segment
		(start 61.391546 -112.065308)
		(end 60.179204 -112.56772)
		(width 0.1143)
		(layer "In9.Cu")
		(net "CLK_100M_GPU_DP")
	)
	(segment
		(start 68.301362 -62.344554)
		(end 68.578222 -62.344554)
		(width 0.1143)
		(layer "In9.Cu")
		(net "CLK_100M_GPU_DP")
	)
	(segment
		(start 66.91503 -60.681362)
		(end 67.157346 -60.923678)
		(width 0.1143)
		(layer "In9.Cu")
		(net "CLK_100M_GPU_DP")
	)
	(segment
		(start 52.636674 -113.77422)
		(end 50.27422 -113.77422)
		(width 0.1143)
		(layer "In9.Cu")
		(net "CLK_100M_GPU_DP")
	)
	(segment
		(start 64.35852 -108.18368)
		(end 64.35852 -108.625386)
		(width 0.1143)
		(layer "In9.Cu")
		(net "CLK_100M_GPU_DP")
	)
	(segment
		(start 17.939004 -113.60912)
		(end 15.431008 -113.60912)
		(width 0.1143)
		(layer "In9.Cu")
		(net "CLK_100M_GPU_DP")
	)
	(segment
		(start 74.66457 -71.82485)
		(end 74.86015 -72.02043)
		(width 0.1143)
		(layer "In9.Cu")
		(net "CLK_100M_GPU_DP")
	)
	(segment
		(start 66.63817 -60.681362)
		(end 66.91503 -60.681362)
		(width 0.1143)
		(layer "In9.Cu")
		(net "CLK_100M_GPU_DP")
	)
	(segment
		(start 25.429464 -115.62842)
		(end 22.808692 -115.62842)
		(width 0.1143)
		(layer "In9.Cu")
		(net "CLK_100M_GPU_DP")
	)
	(segment
		(start 72.984614 -74.741786)
		(end 72.984614 -75.05319)
		(width 0.1143)
		(layer "In9.Cu")
		(net "CLK_100M_GPU_DP")
	)
	(segment
		(start 74.787252 -65.48247)
		(end 74.924412 -65.81394)
		(width 0.1143)
		(layer "In9.Cu")
		(net "CLK_100M_GPU_DP")
	)
	(segment
		(start 68.337176 -89.456768)
		(end 66.4718 -93.95968)
		(width 0.1143)
		(layer "In9.Cu")
		(net "CLK_100M_GPU_DP")
	)
	(segment
		(start 56.027066 -114.68735)
		(end 55.521098 -114.4778)
		(width 0.1143)
		(layer "In9.Cu")
		(net "CLK_100M_GPU_DP")
	)
	(segment
		(start 73.5838 -63.627)
		(end 73.5838 -64.279018)
		(width 0.1143)
		(layer "In9.Cu")
		(net "CLK_100M_GPU_DP")
	)
	(segment
		(start 50.27422 -113.77422)
		(end 49.112678 -112.612678)
		(width 0.1143)
		(layer "In9.Cu")
		(net "CLK_100M_GPU_DP")
	)
	(segment
		(start 66.3956 -60.161932)
		(end 66.3956 -60.438792)
		(width 0.1143)
		(layer "In9.Cu")
		(net "CLK_100M_GPU_DP")
	)
	(segment
		(start 69.035676 -62.802008)
		(end 70.046342 -63.2206)
		(width 0.1143)
		(layer "In9.Cu")
		(net "CLK_100M_GPU_DP")
	)
	(segment
		(start 14.785086 -115.426236)
		(end 14.623288 -115.426236)
		(width 0.1143)
		(layer "In9.Cu")
		(net "CLK_100M_GPU_DP")
	)
	(segment
		(start 75.205336 -66.49212)
		(end 75.705462 -67.699382)
		(width 0.1143)
		(layer "In9.Cu")
		(net "CLK_100M_GPU_DP")
	)
	(segment
		(start 64.35852 -108.625386)
		(end 64.024002 -109.432852)
		(width 0.1143)
		(layer "In9.Cu")
		(net "CLK_100M_GPU_DP")
	)
	(segment
		(start 74.66457 -71.48195)
		(end 74.66457 -71.82485)
		(width 0.1143)
		(layer "In9.Cu")
		(net "CLK_100M_GPU_DP")
	)
	(segment
		(start 65.595246 -59.3598)
		(end 66.022728 -59.787282)
		(width 0.086106)
		(layer "In9.Cu")
		(net "CLK_100M_GPU_DP")
	)
	(segment
		(start 75.294236 -69.062092)
		(end 75.038458 -69.16801)
		(width 0.1143)
		(layer "In9.Cu")
		(net "CLK_100M_GPU_DP")
	)
	(segment
		(start 68.059046 -62.102238)
		(end 68.301362 -62.344554)
		(width 0.1143)
		(layer "In9.Cu")
		(net "CLK_100M_GPU_DP")
	)
	(segment
		(start 64.094868 -58.57113)
		(end 64.490092 -58.966354)
		(width 0.1143)
		(layer "F.Cu")
		(net "CLK_100M_GPU_DN")
	)
	(via
		(at 14.346428 -116.038376)
		(size 0.508)
		(drill 0.254)
		(layers "F.Cu" "B.Cu")
		(net "CLK_100M_GPU_DN")
	)
	(via
		(at 64.490092 -58.966354)
		(size 0.4572)
		(drill 0.254)
		(layers "F.Cu" "B.Cu")
		(net "CLK_100M_GPU_DN")
	)
	(segment
		(start 14.606778 -115.778026)
		(end 14.918436 -115.778026)
		(width 0.14224)
		(layer "B.Cu")
		(net "CLK_100M_GPU_DN")
	)
	(segment
		(start 15.06093 -117.400324)
		(end 14.945106 -117.516148)
		(width 0.14224)
		(layer "B.Cu")
		(net "CLK_100M_GPU_DN")
	)
	(segment
		(start 14.918436 -115.778026)
		(end 15.06093 -115.92052)
		(width 0.14224)
		(layer "B.Cu")
		(net "CLK_100M_GPU_DN")
	)
	(segment
		(start 15.06093 -115.92052)
		(end 15.06093 -117.400324)
		(width 0.14224)
		(layer "B.Cu")
		(net "CLK_100M_GPU_DN")
	)
	(segment
		(start 14.945106 -117.516148)
		(end 14.945106 -118.25986)
		(width 0.14224)
		(layer "B.Cu")
		(net "CLK_100M_GPU_DN")
	)
	(segment
		(start 14.346428 -116.038376)
		(end 14.606778 -115.778026)
		(width 0.14224)
		(layer "B.Cu")
		(net "CLK_100M_GPU_DN")
	)
	(segment
		(start 73.91908 -64.14008)
		(end 75.071478 -65.292478)
		(width 0.1143)
		(layer "In9.Cu")
		(net "CLK_100M_GPU_DN")
	)
	(segment
		(start 50.135282 -114.1095)
		(end 48.922686 -112.896904)
		(width 0.1143)
		(layer "In9.Cu")
		(net "CLK_100M_GPU_DN")
	)
	(segment
		(start 74.946256 -73.565766)
		(end 72.13854 -76.373482)
		(width 0.1143)
		(layer "In9.Cu")
		(net "CLK_100M_GPU_DN")
	)
	(segment
		(start 20.644104 -115.09248)
		(end 17.872202 -113.9444)
		(width 0.1143)
		(layer "In9.Cu")
		(net "CLK_100M_GPU_DN")
	)
	(segment
		(start 52.497736 -114.1095)
		(end 50.135282 -114.1095)
		(width 0.1143)
		(layer "In9.Cu")
		(net "CLK_100M_GPU_DN")
	)
	(segment
		(start 15.29588 -115.38966)
		(end 14.924024 -115.761516)
		(width 0.1143)
		(layer "In9.Cu")
		(net "CLK_100M_GPU_DN")
	)
	(segment
		(start 57.499758 -114.81308)
		(end 57.290208 -115.02263)
		(width 0.1143)
		(layer "In9.Cu")
		(net "CLK_100M_GPU_DN")
	)
	(segment
		(start 22.24278 -115.536726)
		(end 21.170138 -115.09248)
		(width 0.1143)
		(layer "In9.Cu")
		(net "CLK_100M_GPU_DN")
	)
	(segment
		(start 64.6938 -108.250482)
		(end 64.6938 -108.692188)
		(width 0.1143)
		(layer "In9.Cu")
		(net "CLK_100M_GPU_DN")
	)
	(segment
		(start 31.128462 -111.8108)
		(end 30.064964 -112.251236)
		(width 0.1143)
		(layer "In9.Cu")
		(net "CLK_100M_GPU_DN")
	)
	(segment
		(start 71.96328 -77.187552)
		(end 72.4408 -78.340458)
		(width 0.1143)
		(layer "In9.Cu")
		(net "CLK_100M_GPU_DN")
	)
	(segment
		(start 65.9638 -105.184448)
		(end 64.6938 -108.250482)
		(width 0.1143)
		(layer "In9.Cu")
		(net "CLK_100M_GPU_DN")
	)
	(segment
		(start 70.113144 -62.88532)
		(end 73.316338 -62.88532)
		(width 0.1143)
		(layer "In9.Cu")
		(net "CLK_100M_GPU_DN")
	)
	(segment
		(start 21.170138 -115.09248)
		(end 20.644104 -115.09248)
		(width 0.1143)
		(layer "In9.Cu")
		(net "CLK_100M_GPU_DN")
	)
	(segment
		(start 75.1078 -72.80529)
		(end 75.1078 -73.175876)
		(width 0.1143)
		(layer "In9.Cu")
		(net "CLK_100M_GPU_DN")
	)
	(segment
		(start 68.621402 -89.64676)
		(end 68.621402 -89.647014)
		(width 0.1143)
		(layer "In9.Cu")
		(net "CLK_100M_GPU_DN")
	)
	(segment
		(start 64.863472 -58.592974)
		(end 65.451228 -58.592974)
		(width 0.086106)
		(layer "In9.Cu")
		(net "CLK_100M_GPU_DN")
	)
	(segment
		(start 69.56171 -88.706452)
		(end 68.621402 -89.64676)
		(width 0.1143)
		(layer "In9.Cu")
		(net "CLK_100M_GPU_DN")
	)
	(segment
		(start 26.958036 -115.358164)
		(end 25.496266 -115.9637)
		(width 0.1143)
		(layer "In9.Cu")
		(net "CLK_100M_GPU_DN")
	)
	(segment
		(start 72.4408 -78.340458)
		(end 72.4408 -79.123286)
		(width 0.1143)
		(layer "In9.Cu")
		(net "CLK_100M_GPU_DN")
	)
	(segment
		(start 46.300136 -111.8108)
		(end 31.128462 -111.8108)
		(width 0.1143)
		(layer "In9.Cu")
		(net "CLK_100M_GPU_DN")
	)
	(segment
		(start 65.451228 -58.592974)
		(end 65.8114 -58.953146)
		(width 0.086106)
		(layer "In9.Cu")
		(net "CLK_100M_GPU_DN")
	)
	(segment
		(start 75.19543 -72.593708)
		(end 75.1078 -72.80529)
		(width 0.1143)
		(layer "In9.Cu")
		(net "CLK_100M_GPU_DN")
	)
	(segment
		(start 76.040742 -68.250562)
		(end 75.763374 -68.805298)
		(width 0.1143)
		(layer "In9.Cu")
		(net "CLK_100M_GPU_DN")
	)
	(segment
		(start 48.922686 -112.896904)
		(end 46.300136 -111.8108)
		(width 0.1143)
		(layer "In9.Cu")
		(net "CLK_100M_GPU_DN")
	)
	(segment
		(start 72.11568 -84.646262)
		(end 71.856854 -85.271356)
		(width 0.1143)
		(layer "In9.Cu")
		(net "CLK_100M_GPU_DN")
	)
	(segment
		(start 53.201316 -114.81308)
		(end 52.497736 -114.1095)
		(width 0.1143)
		(layer "In9.Cu")
		(net "CLK_100M_GPU_DN")
	)
	(segment
		(start 72.11568 -79.9084)
		(end 72.11568 -84.646262)
		(width 0.1143)
		(layer "In9.Cu")
		(net "CLK_100M_GPU_DN")
	)
	(segment
		(start 25.496266 -115.9637)
		(end 22.669754 -115.9637)
		(width 0.1143)
		(layer "In9.Cu")
		(net "CLK_100M_GPU_DN")
	)
	(segment
		(start 55.960264 -115.02263)
		(end 55.454296 -114.81308)
		(width 0.1143)
		(layer "In9.Cu")
		(net "CLK_100M_GPU_DN")
	)
	(segment
		(start 58.310018 -112.903)
		(end 57.94248 -113.270538)
		(width 0.1143)
		(layer "In9.Cu")
		(net "CLK_100M_GPU_DN")
	)
	(segment
		(start 64.6938 -108.692188)
		(end 64.308228 -109.622844)
		(width 0.1143)
		(layer "In9.Cu")
		(net "CLK_100M_GPU_DN")
	)
	(segment
		(start 55.454296 -114.81308)
		(end 53.201316 -114.81308)
		(width 0.1143)
		(layer "In9.Cu")
		(net "CLK_100M_GPU_DN")
	)
	(segment
		(start 66.806826 -94.027244)
		(end 66.780664 -99.53625)
		(width 0.1143)
		(layer "In9.Cu")
		(net "CLK_100M_GPU_DN")
	)
	(segment
		(start 65.8114 -58.953146)
		(end 65.8114 -59.103514)
		(width 0.086106)
		(layer "In9.Cu")
		(net "CLK_100M_GPU_DN")
	)
	(segment
		(start 64.490092 -58.966354)
		(end 64.863472 -58.592974)
		(width 0.086106)
		(layer "In9.Cu")
		(net "CLK_100M_GPU_DN")
	)
	(segment
		(start 75.763374 -68.805298)
		(end 75.19543 -70.176898)
		(width 0.1143)
		(layer "In9.Cu")
		(net "CLK_100M_GPU_DN")
	)
	(segment
		(start 57.500266 -114.81308)
		(end 57.499758 -114.81308)
		(width 0.1143)
		(layer "In9.Cu")
		(net "CLK_100M_GPU_DN")
	)
	(segment
		(start 75.19543 -70.176898)
		(end 75.19543 -72.593708)
		(width 0.1143)
		(layer "In9.Cu")
		(net "CLK_100M_GPU_DN")
	)
	(segment
		(start 69.225668 -62.517782)
		(end 70.113144 -62.88532)
		(width 0.1143)
		(layer "In9.Cu")
		(net "CLK_100M_GPU_DN")
	)
	(segment
		(start 71.96328 -76.796392)
		(end 71.96328 -77.187552)
		(width 0.1143)
		(layer "In9.Cu")
		(net "CLK_100M_GPU_DN")
	)
	(segment
		(start 73.91908 -63.488062)
		(end 73.91908 -64.14008)
		(width 0.1143)
		(layer "In9.Cu")
		(net "CLK_100M_GPU_DN")
	)
	(segment
		(start 57.290208 -115.02263)
		(end 55.960264 -115.02263)
		(width 0.1143)
		(layer "In9.Cu")
		(net "CLK_100M_GPU_DN")
	)
	(segment
		(start 75.071478 -65.292478)
		(end 76.040742 -67.63258)
		(width 0.1143)
		(layer "In9.Cu")
		(net "CLK_100M_GPU_DN")
	)
	(segment
		(start 60.246006 -112.903)
		(end 58.310018 -112.903)
		(width 0.1143)
		(layer "In9.Cu")
		(net "CLK_100M_GPU_DN")
	)
	(segment
		(start 15.569946 -113.9444)
		(end 15.29588 -114.218466)
		(width 0.1143)
		(layer "In9.Cu")
		(net "CLK_100M_GPU_DN")
	)
	(segment
		(start 71.856854 -85.271356)
		(end 69.56171 -88.706452)
		(width 0.1143)
		(layer "In9.Cu")
		(net "CLK_100M_GPU_DN")
	)
	(segment
		(start 64.308228 -109.622844)
		(end 61.581538 -112.349534)
		(width 0.1143)
		(layer "In9.Cu")
		(net "CLK_100M_GPU_DN")
	)
	(segment
		(start 75.1078 -73.175876)
		(end 74.946256 -73.565766)
		(width 0.1143)
		(layer "In9.Cu")
		(net "CLK_100M_GPU_DN")
	)
	(segment
		(start 72.4408 -79.123286)
		(end 72.11568 -79.9084)
		(width 0.1143)
		(layer "In9.Cu")
		(net "CLK_100M_GPU_DN")
	)
	(segment
		(start 66.780664 -99.53625)
		(end 65.9638 -101.508052)
		(width 0.1143)
		(layer "In9.Cu")
		(net "CLK_100M_GPU_DN")
	)
	(segment
		(start 76.040742 -67.63258)
		(end 76.040742 -68.250562)
		(width 0.1143)
		(layer "In9.Cu")
		(net "CLK_100M_GPU_DN")
	)
	(segment
		(start 22.669754 -115.9637)
		(end 22.24278 -115.536726)
		(width 0.1143)
		(layer "In9.Cu")
		(net "CLK_100M_GPU_DN")
	)
	(segment
		(start 61.581538 -112.349534)
		(end 60.246006 -112.903)
		(width 0.1143)
		(layer "In9.Cu")
		(net "CLK_100M_GPU_DN")
	)
	(segment
		(start 66.247772 -59.539886)
		(end 69.225668 -62.517782)
		(width 0.1143)
		(layer "In9.Cu")
		(net "CLK_100M_GPU_DN")
	)
	(segment
		(start 57.94248 -114.370866)
		(end 57.500266 -114.81308)
		(width 0.1143)
		(layer "In9.Cu")
		(net "CLK_100M_GPU_DN")
	)
	(segment
		(start 65.8114 -59.103514)
		(end 66.247772 -59.539886)
		(width 0.086106)
		(layer "In9.Cu")
		(net "CLK_100M_GPU_DN")
	)
	(segment
		(start 72.13854 -76.373482)
		(end 71.96328 -76.796392)
		(width 0.1143)
		(layer "In9.Cu")
		(net "CLK_100M_GPU_DN")
	)
	(segment
		(start 57.94248 -113.270538)
		(end 57.94248 -114.370866)
		(width 0.1143)
		(layer "In9.Cu")
		(net "CLK_100M_GPU_DN")
	)
	(segment
		(start 17.872202 -113.9444)
		(end 15.569946 -113.9444)
		(width 0.1143)
		(layer "In9.Cu")
		(net "CLK_100M_GPU_DN")
	)
	(segment
		(start 68.621402 -89.647014)
		(end 66.806826 -94.027244)
		(width 0.1143)
		(layer "In9.Cu")
		(net "CLK_100M_GPU_DN")
	)
	(segment
		(start 73.316338 -62.88532)
		(end 73.91908 -63.488062)
		(width 0.1143)
		(layer "In9.Cu")
		(net "CLK_100M_GPU_DN")
	)
	(segment
		(start 14.623288 -115.761516)
		(end 14.346428 -116.038376)
		(width 0.1143)
		(layer "In9.Cu")
		(net "CLK_100M_GPU_DN")
	)
	(segment
		(start 14.924024 -115.761516)
		(end 14.623288 -115.761516)
		(width 0.1143)
		(layer "In9.Cu")
		(net "CLK_100M_GPU_DN")
	)
	(segment
		(start 15.29588 -114.218466)
		(end 15.29588 -115.38966)
		(width 0.1143)
		(layer "In9.Cu")
		(net "CLK_100M_GPU_DN")
	)
	(segment
		(start 65.9638 -101.508052)
		(end 65.9638 -105.184448)
		(width 0.1143)
		(layer "In9.Cu")
		(net "CLK_100M_GPU_DN")
	)
	(segment
		(start 30.064964 -112.251236)
		(end 26.958036 -115.358164)
		(width 0.1143)
		(layer "In9.Cu")
		(net "CLK_100M_GPU_DN")
	)
	(segment
		(start 47.47895 -66.91376)
		(end 47.6377 -66.75501)
		(width 0.11684)
		(layer "F.Cu")
		(net "BMC_ID_BEEP_SEL")
	)
	(segment
		(start 47.117 -67.818)
		(end 47.47895 -67.818)
		(width 0.11684)
		(layer "F.Cu")
		(net "BMC_ID_BEEP_SEL")
	)
	(segment
		(start 46.99 -68.7578)
		(end 46.99 -67.945)
		(width 0.11684)
		(layer "F.Cu")
		(net "BMC_ID_BEEP_SEL")
	)
	(segment
		(start 47.47895 -67.818)
		(end 47.47895 -66.91376)
		(width 0.11684)
		(layer "F.Cu")
		(net "BMC_ID_BEEP_SEL")
	)
	(segment
		(start 46.99 -67.945)
		(end 47.117 -67.818)
		(width 0.11684)
		(layer "F.Cu")
		(net "BMC_ID_BEEP_SEL")
	)
	(via
		(at 26.924 -23.3426)
		(size 0.508)
		(drill 0.254)
		(layers "F.Cu" "B.Cu")
		(net "BMC_ID_BEEP_SEL")
	)
	(via
		(at 23.4442 -71.6534)
		(size 0.508)
		(drill 0.254)
		(layers "F.Cu" "B.Cu")
		(net "BMC_ID_BEEP_SEL")
	)
	(via
		(at 46.99 -68.7578)
		(size 0.508)
		(drill 0.254)
		(layers "F.Cu" "B.Cu")
		(net "BMC_ID_BEEP_SEL")
	)
	(via
		(at 43.3197 -77.2287)
		(size 0.508)
		(drill 0.254)
		(layers "F.Cu" "B.Cu")
		(net "BMC_ID_BEEP_SEL")
	)
	(segment
		(start 15.847568 -22.340062)
		(end 15.00759 -23.18004)
		(width 0.11684)
		(layer "B.Cu")
		(net "BMC_ID_BEEP_SEL")
	)
	(segment
		(start 25.654 -20.9042)
		(end 24.9682 -20.2184)
		(width 0.11684)
		(layer "B.Cu")
		(net "BMC_ID_BEEP_SEL")
	)
	(segment
		(start 22.176232 -19.809968)
		(end 21.800312 -20.185888)
		(width 0.11684)
		(layer "B.Cu")
		(net "BMC_ID_BEEP_SEL")
	)
	(segment
		(start 24.9682 -20.2184)
		(end 24.9682 -20.0152)
		(width 0.11684)
		(layer "B.Cu")
		(net "BMC_ID_BEEP_SEL")
	)
	(segment
		(start 24.762968 -19.809968)
		(end 22.176232 -19.809968)
		(width 0.11684)
		(layer "B.Cu")
		(net "BMC_ID_BEEP_SEL")
	)
	(segment
		(start 16.882618 -20.185888)
		(end 15.847568 -21.220938)
		(width 0.11684)
		(layer "B.Cu")
		(net "BMC_ID_BEEP_SEL")
	)
	(segment
		(start 25.654 -22.0726)
		(end 25.654 -20.9042)
		(width 0.11684)
		(layer "B.Cu")
		(net "BMC_ID_BEEP_SEL")
	)
	(segment
		(start 21.800312 -20.185888)
		(end 16.882618 -20.185888)
		(width 0.11684)
		(layer "B.Cu")
		(net "BMC_ID_BEEP_SEL")
	)
	(segment
		(start 24.9682 -20.0152)
		(end 24.762968 -19.809968)
		(width 0.11684)
		(layer "B.Cu")
		(net "BMC_ID_BEEP_SEL")
	)
	(segment
		(start 26.924 -23.3426)
		(end 25.654 -22.0726)
		(width 0.11684)
		(layer "B.Cu")
		(net "BMC_ID_BEEP_SEL")
	)
	(segment
		(start 15.00759 -23.18004)
		(end 14.873986 -23.18004)
		(width 0.11684)
		(layer "B.Cu")
		(net "BMC_ID_BEEP_SEL")
	)
	(segment
		(start 15.847568 -21.220938)
		(end 15.847568 -22.340062)
		(width 0.11684)
		(layer "B.Cu")
		(net "BMC_ID_BEEP_SEL")
	)
	(segment
		(start 23.4442 -71.6534)
		(end 25.8826 -74.0918)
		(width 0.08382)
		(layer "In2.Cu")
		(net "BMC_ID_BEEP_SEL")
	)
	(segment
		(start 29.298646 -77.2287)
		(end 32.369252 -77.2287)
		(width 0.08382)
		(layer "In2.Cu")
		(net "BMC_ID_BEEP_SEL")
	)
	(segment
		(start 32.369252 -77.2287)
		(end 32.585152 -77.4446)
		(width 0.08382)
		(layer "In2.Cu")
		(net "BMC_ID_BEEP_SEL")
	)
	(segment
		(start 26.161746 -74.0918)
		(end 29.298646 -77.2287)
		(width 0.08382)
		(layer "In2.Cu")
		(net "BMC_ID_BEEP_SEL")
	)
	(segment
		(start 25.8826 -74.0918)
		(end 26.161746 -74.0918)
		(width 0.08382)
		(layer "In2.Cu")
		(net "BMC_ID_BEEP_SEL")
	)
	(segment
		(start 43.1038 -77.4446)
		(end 43.3197 -77.2287)
		(width 0.08382)
		(layer "In2.Cu")
		(net "BMC_ID_BEEP_SEL")
	)
	(segment
		(start 32.585152 -77.4446)
		(end 43.1038 -77.4446)
		(width 0.08382)
		(layer "In2.Cu")
		(net "BMC_ID_BEEP_SEL")
	)
	(segment
		(start 47.1932 -70.1548)
		(end 47.1932 -68.961)
		(width 0.08382)
		(layer "In9.Cu")
		(net "BMC_ID_BEEP_SEL")
	)
	(segment
		(start 23.61057 -33.19907)
		(end 23.61057 -40.712136)
		(width 0.08382)
		(layer "In9.Cu")
		(net "BMC_ID_BEEP_SEL")
	)
	(segment
		(start 19.4945 -48.854106)
		(end 19.4945 -52.371752)
		(width 0.08382)
		(layer "In9.Cu")
		(net "BMC_ID_BEEP_SEL")
	)
	(segment
		(start 20.04695 -47.3202)
		(end 19.8374 -47.826422)
		(width 0.08382)
		(layer "In9.Cu")
		(net "BMC_ID_BEEP_SEL")
	)
	(segment
		(start 19.76755 -53.95595)
		(end 19.76755 -58.94451)
		(width 0.08382)
		(layer "In9.Cu")
		(net "BMC_ID_BEEP_SEL")
	)
	(segment
		(start 19.76755 -58.94451)
		(end 22.20722 -61.38418)
		(width 0.08382)
		(layer "In9.Cu")
		(net "BMC_ID_BEEP_SEL")
	)
	(segment
		(start 26.924 -23.3426)
		(end 26.797 -23.4696)
		(width 0.08382)
		(layer "In9.Cu")
		(net "BMC_ID_BEEP_SEL")
	)
	(segment
		(start 46.7868 -70.5612)
		(end 47.1932 -70.1548)
		(width 0.08382)
		(layer "In9.Cu")
		(net "BMC_ID_BEEP_SEL")
	)
	(segment
		(start 25.39873 -26.16327)
		(end 25.39873 -29.049218)
		(width 0.08382)
		(layer "In9.Cu")
		(net "BMC_ID_BEEP_SEL")
	)
	(segment
		(start 20.04695 -45.540422)
		(end 20.04695 -47.3202)
		(width 0.08382)
		(layer "In9.Cu")
		(net "BMC_ID_BEEP_SEL")
	)
	(segment
		(start 19.8374 -47.826422)
		(end 19.8374 -48.026066)
		(width 0.08382)
		(layer "In9.Cu")
		(net "BMC_ID_BEEP_SEL")
	)
	(segment
		(start 19.4945 -52.371752)
		(end 19.02587 -52.840382)
		(width 0.08382)
		(layer "In9.Cu")
		(net "BMC_ID_BEEP_SEL")
	)
	(segment
		(start 43.3197 -77.2287)
		(end 43.3197 -77.1779)
		(width 0.08382)
		(layer "In9.Cu")
		(net "BMC_ID_BEEP_SEL")
	)
	(segment
		(start 19.8374 -45.330872)
		(end 20.04695 -45.540422)
		(width 0.08382)
		(layer "In9.Cu")
		(net "BMC_ID_BEEP_SEL")
	)
	(segment
		(start 25.39873 -29.049218)
		(end 25.04313 -29.404818)
		(width 0.08382)
		(layer "In9.Cu")
		(net "BMC_ID_BEEP_SEL")
	)
	(segment
		(start 19.02587 -52.840382)
		(end 19.02587 -53.21427)
		(width 0.08382)
		(layer "In9.Cu")
		(net "BMC_ID_BEEP_SEL")
	)
	(segment
		(start 22.20722 -61.38418)
		(end 22.20722 -69.57822)
		(width 0.08382)
		(layer "In9.Cu")
		(net "BMC_ID_BEEP_SEL")
	)
	(segment
		(start 43.3197 -77.1779)
		(end 43.8912 -76.6064)
		(width 0.08382)
		(layer "In9.Cu")
		(net "BMC_ID_BEEP_SEL")
	)
	(segment
		(start 19.8374 -44.485306)
		(end 19.8374 -45.330872)
		(width 0.08382)
		(layer "In9.Cu")
		(net "BMC_ID_BEEP_SEL")
	)
	(segment
		(start 22.20722 -69.57822)
		(end 23.4442 -70.8152)
		(width 0.08382)
		(layer "In9.Cu")
		(net "BMC_ID_BEEP_SEL")
	)
	(segment
		(start 43.8912 -76.6064)
		(end 43.8912 -75.6158)
		(width 0.08382)
		(layer "In9.Cu")
		(net "BMC_ID_BEEP_SEL")
	)
	(segment
		(start 23.4442 -70.8152)
		(end 23.4442 -71.6534)
		(width 0.08382)
		(layer "In9.Cu")
		(net "BMC_ID_BEEP_SEL")
	)
	(segment
		(start 19.02587 -53.21427)
		(end 19.76755 -53.95595)
		(width 0.08382)
		(layer "In9.Cu")
		(net "BMC_ID_BEEP_SEL")
	)
	(segment
		(start 23.61057 -40.712136)
		(end 19.8374 -44.485306)
		(width 0.08382)
		(layer "In9.Cu")
		(net "BMC_ID_BEEP_SEL")
	)
	(segment
		(start 43.8912 -75.6158)
		(end 46.7868 -72.7202)
		(width 0.08382)
		(layer "In9.Cu")
		(net "BMC_ID_BEEP_SEL")
	)
	(segment
		(start 25.04313 -31.76651)
		(end 23.61057 -33.19907)
		(width 0.08382)
		(layer "In9.Cu")
		(net "BMC_ID_BEEP_SEL")
	)
	(segment
		(start 19.8374 -48.026066)
		(end 19.4945 -48.854106)
		(width 0.08382)
		(layer "In9.Cu")
		(net "BMC_ID_BEEP_SEL")
	)
	(segment
		(start 26.797 -23.4696)
		(end 26.797 -24.765)
		(width 0.08382)
		(layer "In9.Cu")
		(net "BMC_ID_BEEP_SEL")
	)
	(segment
		(start 26.797 -24.765)
		(end 25.39873 -26.16327)
		(width 0.08382)
		(layer "In9.Cu")
		(net "BMC_ID_BEEP_SEL")
	)
	(segment
		(start 46.7868 -72.7202)
		(end 46.7868 -70.5612)
		(width 0.08382)
		(layer "In9.Cu")
		(net "BMC_ID_BEEP_SEL")
	)
	(segment
		(start 25.04313 -29.404818)
		(end 25.04313 -31.76651)
		(width 0.08382)
		(layer "In9.Cu")
		(net "BMC_ID_BEEP_SEL")
	)
	(segment
		(start 47.1932 -68.961)
		(end 46.99 -68.7578)
		(width 0.08382)
		(layer "In9.Cu")
		(net "BMC_ID_BEEP_SEL")
	)
	(segment
		(start 28.41244 -13.941044)
		(end 28.322524 -14.03096)
		(width 0.11684)
		(layer "F.Cu")
		(net "BEEP_LED")
	)
	(segment
		(start 28.6004 -13.4112)
		(end 28.41244 -13.59916)
		(width 0.11684)
		(layer "F.Cu")
		(net "BEEP_LED")
	)
	(segment
		(start 17.19961 -18.01495)
		(end 22.041104 -18.01495)
		(width 0.11684)
		(layer "F.Cu")
		(net "BEEP_LED")
	)
	(segment
		(start 28.322524 -14.03096)
		(end 27.629104 -14.03096)
		(width 0.11684)
		(layer "F.Cu")
		(net "BEEP_LED")
	)
	(segment
		(start 14.494256 -24.166576)
		(end 16.235934 -22.424898)
		(width 0.11684)
		(layer "F.Cu")
		(net "BEEP_LED")
	)
	(segment
		(start 28.41244 -13.59916)
		(end 28.41244 -13.941044)
		(width 0.11684)
		(layer "F.Cu")
		(net "BEEP_LED")
	)
	(segment
		(start 16.235934 -18.978626)
		(end 17.19961 -18.01495)
		(width 0.11684)
		(layer "F.Cu")
		(net "BEEP_LED")
	)
	(segment
		(start 16.235934 -22.424898)
		(end 16.235934 -18.978626)
		(width 0.11684)
		(layer "F.Cu")
		(net "BEEP_LED")
	)
	(segment
		(start 22.041104 -18.01495)
		(end 22.533864 -17.52219)
		(width 0.11684)
		(layer "F.Cu")
		(net "BEEP_LED")
	)
	(segment
		(start 11.430254 -24.166576)
		(end 14.494256 -24.166576)
		(width 0.11684)
		(layer "F.Cu")
		(net "BEEP_LED")
	)
	(segment
		(start 22.533864 -17.52219)
		(end 22.898354 -17.52219)
		(width 0.11684)
		(layer "F.Cu")
		(net "BEEP_LED")
	)
	(via
		(at 28.6004 -13.4112)
		(size 0.508)
		(drill 0.254)
		(layers "F.Cu" "B.Cu")
		(net "BEEP_LED")
	)
	(via
		(at 22.898354 -17.52219)
		(size 0.508)
		(drill 0.254)
		(layers "F.Cu" "B.Cu")
		(net "BEEP_LED")
	)
	(via
		(at 11.430254 -24.166576)
		(size 0.508)
		(drill 0.254)
		(layers "F.Cu" "B.Cu")
		(net "BEEP_LED")
	)
	(segment
		(start 10.975086 -25.23998)
		(end 11.248644 -25.513538)
		(width 0.11684)
		(layer "B.Cu")
		(net "BEEP_LED")
	)
	(segment
		(start 11.61288 -23.98395)
		(end 11.430254 -24.166576)
		(width 0.11684)
		(layer "B.Cu")
		(net "BEEP_LED")
	)
	(segment
		(start 10.975086 -24.621744)
		(end 10.975086 -25.23998)
		(width 0.11684)
		(layer "B.Cu")
		(net "BEEP_LED")
	)
	(segment
		(start 11.430254 -24.166576)
		(end 10.975086 -24.621744)
		(width 0.11684)
		(layer "B.Cu")
		(net "BEEP_LED")
	)
	(segment
		(start 11.248644 -25.513538)
		(end 12.480036 -25.513538)
		(width 0.11684)
		(layer "B.Cu")
		(net "BEEP_LED")
	)
	(segment
		(start 12.913614 -25.07996)
		(end 13.574014 -25.07996)
		(width 0.11684)
		(layer "B.Cu")
		(net "BEEP_LED")
	)
	(segment
		(start 12.480036 -25.513538)
		(end 12.913614 -25.07996)
		(width 0.11684)
		(layer "B.Cu")
		(net "BEEP_LED")
	)
	(segment
		(start 12.192 -23.98395)
		(end 11.61288 -23.98395)
		(width 0.11684)
		(layer "B.Cu")
		(net "BEEP_LED")
	)
	(segment
		(start 26.579322 -13.4112)
		(end 23.819104 -16.171418)
		(width 0.08382)
		(layer "In9.Cu")
		(net "BEEP_LED")
	)
	(segment
		(start 22.814026 -17.437862)
		(end 22.898354 -17.52219)
		(width 0.08382)
		(layer "In9.Cu")
		(net "BEEP_LED")
	)
	(segment
		(start 23.310088 -16.171418)
		(end 22.814026 -16.66748)
		(width 0.08382)
		(layer "In9.Cu")
		(net "BEEP_LED")
	)
	(segment
		(start 28.6004 -13.4112)
		(end 26.579322 -13.4112)
		(width 0.08382)
		(layer "In9.Cu")
		(net "BEEP_LED")
	)
	(segment
		(start 22.814026 -16.66748)
		(end 22.814026 -17.437862)
		(width 0.08382)
		(layer "In9.Cu")
		(net "BEEP_LED")
	)
	(segment
		(start 23.819104 -16.171418)
		(end 23.310088 -16.171418)
		(width 0.08382)
		(layer "In9.Cu")
		(net "BEEP_LED")
	)
	(segment
		(start 19.304 -43.7134)
		(end 18.8722 -43.2816)
		(width 0.11684)
		(layer "F.Cu")
		(net "RST_SPI_FLASH_BUF_R3_N")
	)
	(segment
		(start 19.304 -44.4754)
		(end 18.8976 -44.8818)
		(width 0.11684)
		(layer "F.Cu")
		(net "RST_SPI_FLASH_BUF_R3_N")
	)
	(segment
		(start 18.8722 -43.2816)
		(end 18.4404 -43.2816)
		(width 0.11684)
		(layer "F.Cu")
		(net "RST_SPI_FLASH_BUF_R3_N")
	)
	(segment
		(start 19.304 -44.4754)
		(end 19.304 -43.7134)
		(width 0.11684)
		(layer "F.Cu")
		(net "RST_SPI_FLASH_BUF_R3_N")
	)
	(segment
		(start 17.5768 -45.14088)
		(end 17.5768 -45.90415)
		(width 0.11684)
		(layer "F.Cu")
		(net "RST_SPI_FLASH_BUF_R3_N")
	)
	(segment
		(start 18.8976 -44.8818)
		(end 17.83588 -44.8818)
		(width 0.11684)
		(layer "F.Cu")
		(net "RST_SPI_FLASH_BUF_R3_N")
	)
	(segment
		(start 17.83588 -44.8818)
		(end 17.5768 -45.14088)
		(width 0.11684)
		(layer "F.Cu")
		(net "RST_SPI_FLASH_BUF_R3_N")
	)
	(segment
		(start 18.127726 -43.594274)
		(end 18.127726 -43.825414)
		(width 0.11684)
		(layer "F.Cu")
		(net "RST_SPI_FLASH_BUF_R3_N")
	)
	(segment
		(start 18.4404 -43.2816)
		(end 18.127726 -43.594274)
		(width 0.11684)
		(layer "F.Cu")
		(net "RST_SPI_FLASH_BUF_R3_N")
	)
	(via
		(at 19.304 -44.4754)
		(size 0.762)
		(drill 0.381)
		(layers "F.Cu" "B.Cu")
		(net "RST_SPI_FLASH_BUF_R3_N")
	)
	(segment
		(start 20.66417 -87.99195)
		(end 21.059394 -88.387174)
		(width 0.11684)
		(layer "F.Cu")
		(net "IRQ_PCH_SCI_WHEA_N")
	)
	(via
		(at 52.959 -32.018478)
		(size 0.508)
		(drill 0.254)
		(layers "F.Cu" "B.Cu")
		(net "IRQ_PCH_SCI_WHEA_N")
	)
	(via
		(at 35.814 -91.059)
		(size 0.508)
		(drill 0.254)
		(layers "F.Cu" "B.Cu")
		(net "IRQ_PCH_SCI_WHEA_N")
	)
	(via
		(at 20.66417 -87.99195)
		(size 0.4572)
		(drill 0.254)
		(layers "F.Cu" "B.Cu")
		(net "IRQ_PCH_SCI_WHEA_N")
	)
	(via
		(at 43.053 -45.7708)
		(size 0.508)
		(drill 0.254)
		(layers "F.Cu" "B.Cu")
		(net "IRQ_PCH_SCI_WHEA_N")
	)
	(segment
		(start 52.959 -31.43885)
		(end 52.959 -32.018478)
		(width 0.11684)
		(layer "B.Cu")
		(net "IRQ_PCH_SCI_WHEA_N")
	)
	(segment
		(start 52.7812 -31.26105)
		(end 52.959 -31.43885)
		(width 0.11684)
		(layer "B.Cu")
		(net "IRQ_PCH_SCI_WHEA_N")
	)
	(segment
		(start 53.4924 -32.551878)
		(end 53.4924 -33.773872)
		(width 0.11684)
		(layer "B.Cu")
		(net "IRQ_PCH_SCI_WHEA_N")
	)
	(segment
		(start 53.5432 -33.824672)
		(end 53.5432 -34.237676)
		(width 0.11684)
		(layer "B.Cu")
		(net "IRQ_PCH_SCI_WHEA_N")
	)
	(segment
		(start 53.4924 -33.773872)
		(end 53.5432 -33.824672)
		(width 0.11684)
		(layer "B.Cu")
		(net "IRQ_PCH_SCI_WHEA_N")
	)
	(segment
		(start 52.959 -32.018478)
		(end 53.4924 -32.551878)
		(width 0.11684)
		(layer "B.Cu")
		(net "IRQ_PCH_SCI_WHEA_N")
	)
	(segment
		(start 27.4828 -87.0966)
		(end 27.6352 -87.249)
		(width 0.08382)
		(layer "In2.Cu")
		(net "IRQ_PCH_SCI_WHEA_N")
	)
	(segment
		(start 24.9682 -87.0966)
		(end 27.4828 -87.0966)
		(width 0.08382)
		(layer "In2.Cu")
		(net "IRQ_PCH_SCI_WHEA_N")
	)
	(segment
		(start 33.147 -87.249)
		(end 34.645854 -88.747854)
		(width 0.08382)
		(layer "In2.Cu")
		(net "IRQ_PCH_SCI_WHEA_N")
	)
	(segment
		(start 20.66417 -87.99195)
		(end 21.177504 -87.99195)
		(width 0.08382)
		(layer "In2.Cu")
		(net "IRQ_PCH_SCI_WHEA_N")
	)
	(segment
		(start 21.632164 -87.53729)
		(end 24.52751 -87.53729)
		(width 0.08382)
		(layer "In2.Cu")
		(net "IRQ_PCH_SCI_WHEA_N")
	)
	(segment
		(start 24.52751 -87.53729)
		(end 24.9682 -87.0966)
		(width 0.08382)
		(layer "In2.Cu")
		(net "IRQ_PCH_SCI_WHEA_N")
	)
	(segment
		(start 21.177504 -87.99195)
		(end 21.632164 -87.53729)
		(width 0.08382)
		(layer "In2.Cu")
		(net "IRQ_PCH_SCI_WHEA_N")
	)
	(segment
		(start 27.6352 -87.249)
		(end 33.147 -87.249)
		(width 0.08382)
		(layer "In2.Cu")
		(net "IRQ_PCH_SCI_WHEA_N")
	)
	(segment
		(start 34.645854 -89.890854)
		(end 35.814 -91.059)
		(width 0.08382)
		(layer "In2.Cu")
		(net "IRQ_PCH_SCI_WHEA_N")
	)
	(segment
		(start 34.645854 -88.747854)
		(end 34.645854 -89.890854)
		(width 0.08382)
		(layer "In2.Cu")
		(net "IRQ_PCH_SCI_WHEA_N")
	)
	(segment
		(start 40.202358 -48.406558)
		(end 40.202358 -47.265082)
		(width 0.10668)
		(layer "In4.Cu")
		(net "IRQ_PCH_SCI_WHEA_N")
	)
	(segment
		(start 39.85768 -54.916578)
		(end 39.86022 -54.914038)
		(width 0.10668)
		(layer "In4.Cu")
		(net "IRQ_PCH_SCI_WHEA_N")
	)
	(segment
		(start 40.8686 -51.816254)
		(end 40.8686 -49.0728)
		(width 0.10668)
		(layer "In4.Cu")
		(net "IRQ_PCH_SCI_WHEA_N")
	)
	(segment
		(start 38.89502 -81.017618)
		(end 38.89375 -81.01457)
		(width 0.10668)
		(layer "In4.Cu")
		(net "IRQ_PCH_SCI_WHEA_N")
	)
	(segment
		(start 38.96868 -80.465422)
		(end 38.969442 -80.46466)
		(width 0.10668)
		(layer "In4.Cu")
		(net "IRQ_PCH_SCI_WHEA_N")
	)
	(segment
		(start 40.38854 -60.65774)
		(end 40.03294 -60.30214)
		(width 0.10668)
		(layer "In4.Cu")
		(net "IRQ_PCH_SCI_WHEA_N")
	)
	(segment
		(start 40.03294 -59.423808)
		(end 40.032686 -59.423046)
		(width 0.10668)
		(layer "In4.Cu")
		(net "IRQ_PCH_SCI_WHEA_N")
	)
	(segment
		(start 40.38854 -61.1505)
		(end 40.38854 -60.65774)
		(width 0.10668)
		(layer "In4.Cu")
		(net "IRQ_PCH_SCI_WHEA_N")
	)
	(segment
		(start 39.85768 -54.252622)
		(end 39.85768 -52.827174)
		(width 0.10668)
		(layer "In4.Cu")
		(net "IRQ_PCH_SCI_WHEA_N")
	)
	(segment
		(start 38.89502 -82.1563)
		(end 38.89502 -81.017618)
		(width 0.10668)
		(layer "In4.Cu")
		(net "IRQ_PCH_SCI_WHEA_N")
	)
	(segment
		(start 40.202358 -47.265082)
		(end 40.84701 -46.62043)
		(width 0.10668)
		(layer "In4.Cu")
		(net "IRQ_PCH_SCI_WHEA_N")
	)
	(segment
		(start 40.8686 -49.0728)
		(end 40.202358 -48.406558)
		(width 0.10668)
		(layer "In4.Cu")
		(net "IRQ_PCH_SCI_WHEA_N")
	)
	(segment
		(start 39.15664 -56.247538)
		(end 39.85768 -55.546498)
		(width 0.10668)
		(layer "In4.Cu")
		(net "IRQ_PCH_SCI_WHEA_N")
	)
	(segment
		(start 40.84701 -46.62043)
		(end 42.20337 -46.62043)
		(width 0.10668)
		(layer "In4.Cu")
		(net "IRQ_PCH_SCI_WHEA_N")
	)
	(segment
		(start 39.85768 -55.546498)
		(end 39.85768 -54.916578)
		(width 0.10668)
		(layer "In4.Cu")
		(net "IRQ_PCH_SCI_WHEA_N")
	)
	(segment
		(start 38.969442 -80.46466)
		(end 38.969442 -75.928474)
		(width 0.10668)
		(layer "In4.Cu")
		(net "IRQ_PCH_SCI_WHEA_N")
	)
	(segment
		(start 37.02177 -90.342212)
		(end 37.02177 -86.79307)
		(width 0.10668)
		(layer "In4.Cu")
		(net "IRQ_PCH_SCI_WHEA_N")
	)
	(segment
		(start 37.02177 -86.79307)
		(end 38.20414 -85.6107)
		(width 0.10668)
		(layer "In4.Cu")
		(net "IRQ_PCH_SCI_WHEA_N")
	)
	(segment
		(start 39.32682 -62.21222)
		(end 40.38854 -61.1505)
		(width 0.10668)
		(layer "In4.Cu")
		(net "IRQ_PCH_SCI_WHEA_N")
	)
	(segment
		(start 39.85768 -52.827174)
		(end 40.8686 -51.816254)
		(width 0.10668)
		(layer "In4.Cu")
		(net "IRQ_PCH_SCI_WHEA_N")
	)
	(segment
		(start 39.33698 -67.9323)
		(end 38.81628 -67.4116)
		(width 0.10668)
		(layer "In4.Cu")
		(net "IRQ_PCH_SCI_WHEA_N")
	)
	(segment
		(start 38.969442 -75.928474)
		(end 39.92118 -74.976736)
		(width 0.10668)
		(layer "In4.Cu")
		(net "IRQ_PCH_SCI_WHEA_N")
	)
	(segment
		(start 38.81628 -64.1604)
		(end 39.32682 -63.64986)
		(width 0.10668)
		(layer "In4.Cu")
		(net "IRQ_PCH_SCI_WHEA_N")
	)
	(segment
		(start 40.03294 -60.30214)
		(end 40.03294 -59.423808)
		(width 0.10668)
		(layer "In4.Cu")
		(net "IRQ_PCH_SCI_WHEA_N")
	)
	(segment
		(start 39.32682 -63.64986)
		(end 39.32682 -62.21222)
		(width 0.10668)
		(layer "In4.Cu")
		(net "IRQ_PCH_SCI_WHEA_N")
	)
	(segment
		(start 39.86022 -54.255162)
		(end 39.85768 -54.252622)
		(width 0.10668)
		(layer "In4.Cu")
		(net "IRQ_PCH_SCI_WHEA_N")
	)
	(segment
		(start 38.20414 -82.84718)
		(end 38.89502 -82.1563)
		(width 0.10668)
		(layer "In4.Cu")
		(net "IRQ_PCH_SCI_WHEA_N")
	)
	(segment
		(start 40.032686 -59.423046)
		(end 39.15664 -58.547)
		(width 0.10668)
		(layer "In4.Cu")
		(net "IRQ_PCH_SCI_WHEA_N")
	)
	(segment
		(start 38.81628 -67.4116)
		(end 38.81628 -64.1604)
		(width 0.10668)
		(layer "In4.Cu")
		(net "IRQ_PCH_SCI_WHEA_N")
	)
	(segment
		(start 36.304982 -91.059)
		(end 37.02177 -90.342212)
		(width 0.10668)
		(layer "In4.Cu")
		(net "IRQ_PCH_SCI_WHEA_N")
	)
	(segment
		(start 38.96868 -80.93964)
		(end 38.96868 -80.465422)
		(width 0.10668)
		(layer "In4.Cu")
		(net "IRQ_PCH_SCI_WHEA_N")
	)
	(segment
		(start 38.20414 -85.6107)
		(end 38.20414 -82.84718)
		(width 0.10668)
		(layer "In4.Cu")
		(net "IRQ_PCH_SCI_WHEA_N")
	)
	(segment
		(start 39.92118 -73.46442)
		(end 40.78224 -72.60336)
		(width 0.10668)
		(layer "In4.Cu")
		(net "IRQ_PCH_SCI_WHEA_N")
	)
	(segment
		(start 38.89375 -81.01457)
		(end 38.96868 -80.93964)
		(width 0.10668)
		(layer "In4.Cu")
		(net "IRQ_PCH_SCI_WHEA_N")
	)
	(segment
		(start 42.20337 -46.62043)
		(end 43.053 -45.7708)
		(width 0.10668)
		(layer "In4.Cu")
		(net "IRQ_PCH_SCI_WHEA_N")
	)
	(segment
		(start 39.86022 -54.914038)
		(end 39.86022 -54.255162)
		(width 0.10668)
		(layer "In4.Cu")
		(net "IRQ_PCH_SCI_WHEA_N")
	)
	(segment
		(start 39.92118 -74.976736)
		(end 39.92118 -73.46442)
		(width 0.10668)
		(layer "In4.Cu")
		(net "IRQ_PCH_SCI_WHEA_N")
	)
	(segment
		(start 40.78224 -72.07504)
		(end 39.33698 -70.62978)
		(width 0.10668)
		(layer "In4.Cu")
		(net "IRQ_PCH_SCI_WHEA_N")
	)
	(segment
		(start 40.78224 -72.60336)
		(end 40.78224 -72.07504)
		(width 0.10668)
		(layer "In4.Cu")
		(net "IRQ_PCH_SCI_WHEA_N")
	)
	(segment
		(start 39.33698 -70.62978)
		(end 39.33698 -67.9323)
		(width 0.10668)
		(layer "In4.Cu")
		(net "IRQ_PCH_SCI_WHEA_N")
	)
	(segment
		(start 39.15664 -58.547)
		(end 39.15664 -56.247538)
		(width 0.10668)
		(layer "In4.Cu")
		(net "IRQ_PCH_SCI_WHEA_N")
	)
	(segment
		(start 35.814 -91.059)
		(end 36.304982 -91.059)
		(width 0.10668)
		(layer "In4.Cu")
		(net "IRQ_PCH_SCI_WHEA_N")
	)
	(segment
		(start 36.495228 -30.037532)
		(end 35.70478 -30.037532)
		(width 0.08382)
		(layer "In9.Cu")
		(net "IRQ_PCH_SCI_WHEA_N")
	)
	(segment
		(start 44.22521 -30.645862)
		(end 43.764962 -30.455362)
		(width 0.08382)
		(layer "In9.Cu")
		(net "IRQ_PCH_SCI_WHEA_N")
	)
	(segment
		(start 42.2402 -28.9306)
		(end 37.60216 -28.9306)
		(width 0.08382)
		(layer "In9.Cu")
		(net "IRQ_PCH_SCI_WHEA_N")
	)
	(segment
		(start 39.2938 -41.5544)
		(end 39.2938 -42.0116)
		(width 0.08382)
		(layer "In9.Cu")
		(net "IRQ_PCH_SCI_WHEA_N")
	)
	(segment
		(start 37.7952 -40.7162)
		(end 38.4556 -40.7162)
		(width 0.08382)
		(layer "In9.Cu")
		(net "IRQ_PCH_SCI_WHEA_N")
	)
	(segment
		(start 34.1376 -39.5478)
		(end 35.3314 -39.5478)
		(width 0.08382)
		(layer "In9.Cu")
		(net "IRQ_PCH_SCI_WHEA_N")
	)
	(segment
		(start 35.70478 -30.037532)
		(end 35.18662 -30.555692)
		(width 0.08382)
		(layer "In9.Cu")
		(net "IRQ_PCH_SCI_WHEA_N")
	)
	(segment
		(start 33.3248 -36.8554)
		(end 33.3248 -38.735)
		(width 0.08382)
		(layer "In9.Cu")
		(net "IRQ_PCH_SCI_WHEA_N")
	)
	(segment
		(start 49.562766 -32.2326)
		(end 47.902622 -31.545022)
		(width 0.08382)
		(layer "In9.Cu")
		(net "IRQ_PCH_SCI_WHEA_N")
	)
	(segment
		(start 47.902622 -31.545022)
		(end 47.69358 -31.33598)
		(width 0.08382)
		(layer "In9.Cu")
		(net "IRQ_PCH_SCI_WHEA_N")
	)
	(segment
		(start 37.60216 -28.9306)
		(end 36.495228 -30.037532)
		(width 0.08382)
		(layer "In9.Cu")
		(net "IRQ_PCH_SCI_WHEA_N")
	)
	(segment
		(start 37.4904 -40.4114)
		(end 37.7952 -40.7162)
		(width 0.08382)
		(layer "In9.Cu")
		(net "IRQ_PCH_SCI_WHEA_N")
	)
	(segment
		(start 52.197 -32.4104)
		(end 51.308 -32.4104)
		(width 0.08382)
		(layer "In9.Cu")
		(net "IRQ_PCH_SCI_WHEA_N")
	)
	(segment
		(start 35.18662 -34.99358)
		(end 33.3248 -36.8554)
		(width 0.08382)
		(layer "In9.Cu")
		(net "IRQ_PCH_SCI_WHEA_N")
	)
	(segment
		(start 51.1302 -32.2326)
		(end 49.562766 -32.2326)
		(width 0.08382)
		(layer "In9.Cu")
		(net "IRQ_PCH_SCI_WHEA_N")
	)
	(segment
		(start 36.195 -40.4114)
		(end 37.4904 -40.4114)
		(width 0.08382)
		(layer "In9.Cu")
		(net "IRQ_PCH_SCI_WHEA_N")
	)
	(segment
		(start 35.3314 -39.5478)
		(end 36.195 -40.4114)
		(width 0.08382)
		(layer "In9.Cu")
		(net "IRQ_PCH_SCI_WHEA_N")
	)
	(segment
		(start 35.18662 -30.555692)
		(end 35.18662 -34.99358)
		(width 0.08382)
		(layer "In9.Cu")
		(net "IRQ_PCH_SCI_WHEA_N")
	)
	(segment
		(start 52.959 -32.018478)
		(end 52.588922 -32.018478)
		(width 0.08382)
		(layer "In9.Cu")
		(net "IRQ_PCH_SCI_WHEA_N")
	)
	(segment
		(start 47.69358 -31.33598)
		(end 44.22521 -30.645862)
		(width 0.08382)
		(layer "In9.Cu")
		(net "IRQ_PCH_SCI_WHEA_N")
	)
	(segment
		(start 33.3248 -38.735)
		(end 34.1376 -39.5478)
		(width 0.08382)
		(layer "In9.Cu")
		(net "IRQ_PCH_SCI_WHEA_N")
	)
	(segment
		(start 43.764962 -30.455362)
		(end 42.2402 -28.9306)
		(width 0.08382)
		(layer "In9.Cu")
		(net "IRQ_PCH_SCI_WHEA_N")
	)
	(segment
		(start 39.2938 -42.0116)
		(end 43.053 -45.7708)
		(width 0.08382)
		(layer "In9.Cu")
		(net "IRQ_PCH_SCI_WHEA_N")
	)
	(segment
		(start 38.4556 -40.7162)
		(end 39.2938 -41.5544)
		(width 0.08382)
		(layer "In9.Cu")
		(net "IRQ_PCH_SCI_WHEA_N")
	)
	(segment
		(start 52.588922 -32.018478)
		(end 52.197 -32.4104)
		(width 0.08382)
		(layer "In9.Cu")
		(net "IRQ_PCH_SCI_WHEA_N")
	)
	(segment
		(start 51.308 -32.4104)
		(end 51.1302 -32.2326)
		(width 0.08382)
		(layer "In9.Cu")
		(net "IRQ_PCH_SCI_WHEA_N")
	)
	(segment
		(start 59.78398 -101.71938)
		(end 57.87136 -99.80676)
		(width 0.11684)
		(layer "F.Cu")
		(net "IRQ_PCH_TPM_SPI_N")
	)
	(segment
		(start 59.78398 -102.489)
		(end 59.78398 -101.71938)
		(width 0.11684)
		(layer "F.Cu")
		(net "IRQ_PCH_TPM_SPI_N")
	)
	(segment
		(start 63.11138 -111.4425)
		(end 63.11138 -109.712252)
		(width 0.11684)
		(layer "F.Cu")
		(net "IRQ_PCH_TPM_SPI_N")
	)
	(segment
		(start 59.249564 -103.851456)
		(end 59.249564 -103.023416)
		(width 0.11684)
		(layer "F.Cu")
		(net "IRQ_PCH_TPM_SPI_N")
	)
	(segment
		(start 56.3626 -95.5548)
		(end 56.5912 -95.5548)
		(width 0.11684)
		(layer "F.Cu")
		(net "IRQ_PCH_TPM_SPI_N")
	)
	(segment
		(start 61.324744 -113.229136)
		(end 63.11138 -111.4425)
		(width 0.11684)
		(layer "F.Cu")
		(net "IRQ_PCH_TPM_SPI_N")
	)
	(segment
		(start 44.350432 -55.7784)
		(end 45.287946 -55.7784)
		(width 0.11684)
		(layer "F.Cu")
		(net "IRQ_PCH_TPM_SPI_N")
	)
	(segment
		(start 55.52948 -99.230688)
		(end 55.52948 -96.38792)
		(width 0.11684)
		(layer "F.Cu")
		(net "IRQ_PCH_TPM_SPI_N")
	)
	(segment
		(start 43.85945 -55.5752)
		(end 44.350432 -55.7784)
		(width 0.11684)
		(layer "F.Cu")
		(net "IRQ_PCH_TPM_SPI_N")
	)
	(segment
		(start 58.00471 -95.56369)
		(end 58.492898 -95.075502)
		(width 0.11684)
		(layer "F.Cu")
		(net "IRQ_PCH_TPM_SPI_N")
	)
	(segment
		(start 59.249564 -103.023416)
		(end 59.78398 -102.489)
		(width 0.11684)
		(layer "F.Cu")
		(net "IRQ_PCH_TPM_SPI_N")
	)
	(segment
		(start 22.022816 -103.599234)
		(end 21.966174 -103.599234)
		(width 0.11684)
		(layer "F.Cu")
		(net "IRQ_PCH_TPM_SPI_N")
	)
	(segment
		(start 22.479 -103.14305)
		(end 22.022816 -103.599234)
		(width 0.11684)
		(layer "F.Cu")
		(net "IRQ_PCH_TPM_SPI_N")
	)
	(segment
		(start 43.2816 -54.99735)
		(end 43.85945 -55.5752)
		(width 0.11684)
		(layer "F.Cu")
		(net "IRQ_PCH_TPM_SPI_N")
	)
	(segment
		(start 63.34633 -109.14507)
		(end 63.5508 -108.9406)
		(width 0.11684)
		(layer "F.Cu")
		(net "IRQ_PCH_TPM_SPI_N")
	)
	(segment
		(start 57.56021 -95.5548)
		(end 57.5691 -95.56369)
		(width 0.11684)
		(layer "F.Cu")
		(net "IRQ_PCH_TPM_SPI_N")
	)
	(segment
		(start 63.5508 -108.9406)
		(end 63.5508 -106.31424)
		(width 0.11684)
		(layer "F.Cu")
		(net "IRQ_PCH_TPM_SPI_N")
	)
	(segment
		(start 62.38875 -105.15219)
		(end 59.249564 -103.851456)
		(width 0.11684)
		(layer "F.Cu")
		(net "IRQ_PCH_TPM_SPI_N")
	)
	(segment
		(start 63.5508 -106.31424)
		(end 62.38875 -105.15219)
		(width 0.11684)
		(layer "F.Cu")
		(net "IRQ_PCH_TPM_SPI_N")
	)
	(segment
		(start 56.5912 -95.5548)
		(end 57.56021 -95.5548)
		(width 0.11684)
		(layer "F.Cu")
		(net "IRQ_PCH_TPM_SPI_N")
	)
	(segment
		(start 43.2816 -54.5338)
		(end 43.2816 -54.99735)
		(width 0.11684)
		(layer "F.Cu")
		(net "IRQ_PCH_TPM_SPI_N")
	)
	(segment
		(start 63.11138 -109.712252)
		(end 63.34633 -109.14507)
		(width 0.11684)
		(layer "F.Cu")
		(net "IRQ_PCH_TPM_SPI_N")
	)
	(segment
		(start 55.52948 -96.38792)
		(end 56.3626 -95.5548)
		(width 0.11684)
		(layer "F.Cu")
		(net "IRQ_PCH_TPM_SPI_N")
	)
	(segment
		(start 56.105552 -99.80676)
		(end 55.52948 -99.230688)
		(width 0.11684)
		(layer "F.Cu")
		(net "IRQ_PCH_TPM_SPI_N")
	)
	(segment
		(start 58.492898 -95.075502)
		(end 58.492898 -94.7674)
		(width 0.11684)
		(layer "F.Cu")
		(net "IRQ_PCH_TPM_SPI_N")
	)
	(segment
		(start 57.87136 -99.80676)
		(end 56.105552 -99.80676)
		(width 0.11684)
		(layer "F.Cu")
		(net "IRQ_PCH_TPM_SPI_N")
	)
	(segment
		(start 57.5691 -95.56369)
		(end 58.00471 -95.56369)
		(width 0.11684)
		(layer "F.Cu")
		(net "IRQ_PCH_TPM_SPI_N")
	)
	(segment
		(start 45.287946 -55.7784)
		(end 45.695108 -55.371238)
		(width 0.11684)
		(layer "F.Cu")
		(net "IRQ_PCH_TPM_SPI_N")
	)
	(via
		(at 12.2047 -110.8329)
		(size 0.508)
		(drill 0.254)
		(layers "F.Cu" "B.Cu")
		(net "IRQ_PCH_TPM_SPI_N")
	)
	(via
		(at 21.966174 -103.599234)
		(size 0.508)
		(drill 0.254)
		(layers "F.Cu" "B.Cu")
		(net "IRQ_PCH_TPM_SPI_N")
	)
	(via
		(at 61.324744 -113.229136)
		(size 0.508)
		(drill 0.254)
		(layers "F.Cu" "B.Cu")
		(net "IRQ_PCH_TPM_SPI_N")
	)
	(via
		(at 58.22188 -71.9455)
		(size 0.762)
		(drill 0.254)
		(layers "F.Cu" "B.Cu")
		(net "IRQ_PCH_TPM_SPI_N")
	)
	(via
		(at 43.2816 -54.5338)
		(size 0.508)
		(drill 0.254)
		(layers "F.Cu" "B.Cu")
		(net "IRQ_PCH_TPM_SPI_N")
	)
	(via
		(at 58.492898 -94.7674)
		(size 0.508)
		(drill 0.254)
		(layers "F.Cu" "B.Cu")
		(net "IRQ_PCH_TPM_SPI_N")
	)
	(via
		(at 59.78398 -102.489)
		(size 0.762)
		(drill 0.381)
		(layers "F.Cu" "B.Cu")
		(net "IRQ_PCH_TPM_SPI_N")
	)
	(segment
		(start 48.304196 -113.87709)
		(end 49.678844 -113.87709)
		(width 0.08382)
		(layer "In2.Cu")
		(net "IRQ_PCH_TPM_SPI_N")
	)
	(segment
		(start 12.2047 -110.8329)
		(end 13.1826 -111.8108)
		(width 0.08382)
		(layer "In2.Cu")
		(net "IRQ_PCH_TPM_SPI_N")
	)
	(segment
		(start 35.9537 -112.5093)
		(end 39.05504 -115.61064)
		(width 0.08382)
		(layer "In2.Cu")
		(net "IRQ_PCH_TPM_SPI_N")
	)
	(segment
		(start 55.652162 -114.681)
		(end 56.641746 -113.691416)
		(width 0.08382)
		(layer "In2.Cu")
		(net "IRQ_PCH_TPM_SPI_N")
	)
	(segment
		(start 39.05504 -115.61064)
		(end 40.9194 -115.61064)
		(width 0.08382)
		(layer "In2.Cu")
		(net "IRQ_PCH_TPM_SPI_N")
	)
	(segment
		(start 46.662086 -112.23498)
		(end 48.304196 -113.87709)
		(width 0.08382)
		(layer "In2.Cu")
		(net "IRQ_PCH_TPM_SPI_N")
	)
	(segment
		(start 30.00756 -112.5093)
		(end 35.9537 -112.5093)
		(width 0.08382)
		(layer "In2.Cu")
		(net "IRQ_PCH_TPM_SPI_N")
	)
	(segment
		(start 16.97482 -112.02162)
		(end 17.30502 -112.35182)
		(width 0.08382)
		(layer "In2.Cu")
		(net "IRQ_PCH_TPM_SPI_N")
	)
	(segment
		(start 13.375894 -111.8108)
		(end 13.586714 -112.02162)
		(width 0.08382)
		(layer "In2.Cu")
		(net "IRQ_PCH_TPM_SPI_N")
	)
	(segment
		(start 25.019 -113.6142)
		(end 25.61844 -114.21364)
		(width 0.08382)
		(layer "In2.Cu")
		(net "IRQ_PCH_TPM_SPI_N")
	)
	(segment
		(start 13.586714 -112.02162)
		(end 16.97482 -112.02162)
		(width 0.08382)
		(layer "In2.Cu")
		(net "IRQ_PCH_TPM_SPI_N")
	)
	(segment
		(start 60.18403 -113.08715)
		(end 60.326016 -113.229136)
		(width 0.08382)
		(layer "In2.Cu")
		(net "IRQ_PCH_TPM_SPI_N")
	)
	(segment
		(start 22.168866 -112.35182)
		(end 23.431246 -113.6142)
		(width 0.08382)
		(layer "In2.Cu")
		(net "IRQ_PCH_TPM_SPI_N")
	)
	(segment
		(start 17.30502 -112.35182)
		(end 22.168866 -112.35182)
		(width 0.08382)
		(layer "In2.Cu")
		(net "IRQ_PCH_TPM_SPI_N")
	)
	(segment
		(start 49.678844 -113.87709)
		(end 50.482754 -114.681)
		(width 0.08382)
		(layer "In2.Cu")
		(net "IRQ_PCH_TPM_SPI_N")
	)
	(segment
		(start 56.641746 -113.691416)
		(end 58.094372 -113.08969)
		(width 0.08382)
		(layer "In2.Cu")
		(net "IRQ_PCH_TPM_SPI_N")
	)
	(segment
		(start 44.29506 -112.23498)
		(end 46.662086 -112.23498)
		(width 0.08382)
		(layer "In2.Cu")
		(net "IRQ_PCH_TPM_SPI_N")
	)
	(segment
		(start 59.369452 -113.08969)
		(end 59.371992 -113.08715)
		(width 0.08382)
		(layer "In2.Cu")
		(net "IRQ_PCH_TPM_SPI_N")
	)
	(segment
		(start 50.482754 -114.681)
		(end 55.652162 -114.681)
		(width 0.08382)
		(layer "In2.Cu")
		(net "IRQ_PCH_TPM_SPI_N")
	)
	(segment
		(start 58.094372 -113.08969)
		(end 59.369452 -113.08969)
		(width 0.08382)
		(layer "In2.Cu")
		(net "IRQ_PCH_TPM_SPI_N")
	)
	(segment
		(start 59.371992 -113.08715)
		(end 60.18403 -113.08715)
		(width 0.08382)
		(layer "In2.Cu")
		(net "IRQ_PCH_TPM_SPI_N")
	)
	(segment
		(start 23.431246 -113.6142)
		(end 25.019 -113.6142)
		(width 0.08382)
		(layer "In2.Cu")
		(net "IRQ_PCH_TPM_SPI_N")
	)
	(segment
		(start 28.30322 -114.21364)
		(end 30.00756 -112.5093)
		(width 0.08382)
		(layer "In2.Cu")
		(net "IRQ_PCH_TPM_SPI_N")
	)
	(segment
		(start 13.1826 -111.8108)
		(end 13.375894 -111.8108)
		(width 0.08382)
		(layer "In2.Cu")
		(net "IRQ_PCH_TPM_SPI_N")
	)
	(segment
		(start 60.326016 -113.229136)
		(end 61.324744 -113.229136)
		(width 0.08382)
		(layer "In2.Cu")
		(net "IRQ_PCH_TPM_SPI_N")
	)
	(segment
		(start 25.61844 -114.21364)
		(end 28.30322 -114.21364)
		(width 0.08382)
		(layer "In2.Cu")
		(net "IRQ_PCH_TPM_SPI_N")
	)
	(segment
		(start 40.9194 -115.61064)
		(end 44.29506 -112.23498)
		(width 0.08382)
		(layer "In2.Cu")
		(net "IRQ_PCH_TPM_SPI_N")
	)
	(segment
		(start 55.9054 -84.169504)
		(end 55.9054 -81.025746)
		(width 0.10668)
		(layer "In4.Cu")
		(net "IRQ_PCH_TPM_SPI_N")
	)
	(segment
		(start 56.434482 -80.496664)
		(end 56.434482 -76.890118)
		(width 0.10668)
		(layer "In4.Cu")
		(net "IRQ_PCH_TPM_SPI_N")
	)
	(segment
		(start 56.434482 -76.890118)
		(end 58.0644 -75.2602)
		(width 0.10668)
		(layer "In4.Cu")
		(net "IRQ_PCH_TPM_SPI_N")
	)
	(segment
		(start 58.46318 -91.060524)
		(end 56.6928 -89.290144)
		(width 0.10668)
		(layer "In4.Cu")
		(net "IRQ_PCH_TPM_SPI_N")
	)
	(segment
		(start 56.69534 -87.092536)
		(end 56.6928 -87.089996)
		(width 0.10668)
		(layer "In4.Cu")
		(net "IRQ_PCH_TPM_SPI_N")
	)
	(segment
		(start 56.6928 -87.560404)
		(end 56.69534 -87.557864)
		(width 0.10668)
		(layer "In4.Cu")
		(net "IRQ_PCH_TPM_SPI_N")
	)
	(segment
		(start 58.066178 -72.101202)
		(end 58.22188 -71.9455)
		(width 0.10668)
		(layer "In4.Cu")
		(net "IRQ_PCH_TPM_SPI_N")
	)
	(segment
		(start 58.066432 -75.22464)
		(end 58.066432 -74.947272)
		(width 0.10668)
		(layer "In4.Cu")
		(net "IRQ_PCH_TPM_SPI_N")
	)
	(segment
		(start 58.46318 -94.737682)
		(end 58.46318 -91.060524)
		(width 0.10668)
		(layer "In4.Cu")
		(net "IRQ_PCH_TPM_SPI_N")
	)
	(segment
		(start 55.9054 -81.025746)
		(end 56.434482 -80.496664)
		(width 0.10668)
		(layer "In4.Cu")
		(net "IRQ_PCH_TPM_SPI_N")
	)
	(segment
		(start 58.0644 -75.226672)
		(end 58.066432 -75.22464)
		(width 0.10668)
		(layer "In4.Cu")
		(net "IRQ_PCH_TPM_SPI_N")
	)
	(segment
		(start 58.492898 -94.7674)
		(end 58.46318 -94.737682)
		(width 0.10668)
		(layer "In4.Cu")
		(net "IRQ_PCH_TPM_SPI_N")
	)
	(segment
		(start 56.6928 -89.290144)
		(end 56.6928 -87.560404)
		(width 0.10668)
		(layer "In4.Cu")
		(net "IRQ_PCH_TPM_SPI_N")
	)
	(segment
		(start 56.41848 -86.59368)
		(end 56.41848 -84.682584)
		(width 0.10668)
		(layer "In4.Cu")
		(net "IRQ_PCH_TPM_SPI_N")
	)
	(segment
		(start 56.69534 -87.557864)
		(end 56.69534 -87.092536)
		(width 0.10668)
		(layer "In4.Cu")
		(net "IRQ_PCH_TPM_SPI_N")
	)
	(segment
		(start 56.6928 -87.089996)
		(end 56.6928 -86.868)
		(width 0.10668)
		(layer "In4.Cu")
		(net "IRQ_PCH_TPM_SPI_N")
	)
	(segment
		(start 58.0644 -75.2602)
		(end 58.0644 -75.226672)
		(width 0.10668)
		(layer "In4.Cu")
		(net "IRQ_PCH_TPM_SPI_N")
	)
	(segment
		(start 58.066178 -74.947018)
		(end 58.066178 -72.101202)
		(width 0.10668)
		(layer "In4.Cu")
		(net "IRQ_PCH_TPM_SPI_N")
	)
	(segment
		(start 58.066432 -74.947272)
		(end 58.066178 -74.947018)
		(width 0.10668)
		(layer "In4.Cu")
		(net "IRQ_PCH_TPM_SPI_N")
	)
	(segment
		(start 56.6928 -86.868)
		(end 56.41848 -86.59368)
		(width 0.10668)
		(layer "In4.Cu")
		(net "IRQ_PCH_TPM_SPI_N")
	)
	(segment
		(start 56.41848 -84.682584)
		(end 55.9054 -84.169504)
		(width 0.10668)
		(layer "In4.Cu")
		(net "IRQ_PCH_TPM_SPI_N")
	)
	(segment
		(start 43.32986 -57.753504)
		(end 43.09364 -57.989724)
		(width 0.10668)
		(layer "In7.Cu")
		(net "IRQ_PCH_TPM_SPI_N")
	)
	(segment
		(start 50.40884 -68.806822)
		(end 51.131978 -69.52996)
		(width 0.10668)
		(layer "In7.Cu")
		(net "IRQ_PCH_TPM_SPI_N")
	)
	(segment
		(start 48.471582 -66.845942)
		(end 49.268888 -66.845942)
		(width 0.10668)
		(layer "In7.Cu")
		(net "IRQ_PCH_TPM_SPI_N")
	)
	(segment
		(start 44.86275 -65.89268)
		(end 45.17136 -66.20129)
		(width 0.10668)
		(layer "In7.Cu")
		(net "IRQ_PCH_TPM_SPI_N")
	)
	(segment
		(start 43.286934 -65.89268)
		(end 44.86275 -65.89268)
		(width 0.10668)
		(layer "In7.Cu")
		(net "IRQ_PCH_TPM_SPI_N")
	)
	(segment
		(start 50.40884 -67.985894)
		(end 50.40884 -68.806822)
		(width 0.10668)
		(layer "In7.Cu")
		(net "IRQ_PCH_TPM_SPI_N")
	)
	(segment
		(start 51.131978 -69.52996)
		(end 52.616608 -69.52996)
		(width 0.10668)
		(layer "In7.Cu")
		(net "IRQ_PCH_TPM_SPI_N")
	)
	(segment
		(start 45.17136 -66.20129)
		(end 45.941996 -66.20129)
		(width 0.10668)
		(layer "In7.Cu")
		(net "IRQ_PCH_TPM_SPI_N")
	)
	(segment
		(start 47.58944 -65.9638)
		(end 48.471582 -66.845942)
		(width 0.10668)
		(layer "In7.Cu")
		(net "IRQ_PCH_TPM_SPI_N")
	)
	(segment
		(start 42.7482 -65.353946)
		(end 43.286934 -65.89268)
		(width 0.10668)
		(layer "In7.Cu")
		(net "IRQ_PCH_TPM_SPI_N")
	)
	(segment
		(start 52.616608 -69.52996)
		(end 53.894482 -70.807834)
		(width 0.10668)
		(layer "In7.Cu")
		(net "IRQ_PCH_TPM_SPI_N")
	)
	(segment
		(start 43.09364 -57.989724)
		(end 43.09364 -63.620396)
		(width 0.10668)
		(layer "In7.Cu")
		(net "IRQ_PCH_TPM_SPI_N")
	)
	(segment
		(start 55.669434 -70.807834)
		(end 57.06872 -72.20712)
		(width 0.10668)
		(layer "In7.Cu")
		(net "IRQ_PCH_TPM_SPI_N")
	)
	(segment
		(start 43.32986 -54.58206)
		(end 43.32986 -57.753504)
		(width 0.10668)
		(layer "In7.Cu")
		(net "IRQ_PCH_TPM_SPI_N")
	)
	(segment
		(start 43.2816 -54.5338)
		(end 43.32986 -54.58206)
		(width 0.10668)
		(layer "In7.Cu")
		(net "IRQ_PCH_TPM_SPI_N")
	)
	(segment
		(start 53.894482 -70.807834)
		(end 55.669434 -70.807834)
		(width 0.10668)
		(layer "In7.Cu")
		(net "IRQ_PCH_TPM_SPI_N")
	)
	(segment
		(start 42.7482 -63.965836)
		(end 42.7482 -65.353946)
		(width 0.10668)
		(layer "In7.Cu")
		(net "IRQ_PCH_TPM_SPI_N")
	)
	(segment
		(start 57.06872 -72.20712)
		(end 57.96026 -72.20712)
		(width 0.10668)
		(layer "In7.Cu")
		(net "IRQ_PCH_TPM_SPI_N")
	)
	(segment
		(start 57.96026 -72.20712)
		(end 58.22188 -71.9455)
		(width 0.10668)
		(layer "In7.Cu")
		(net "IRQ_PCH_TPM_SPI_N")
	)
	(segment
		(start 43.09364 -63.620396)
		(end 42.7482 -63.965836)
		(width 0.10668)
		(layer "In7.Cu")
		(net "IRQ_PCH_TPM_SPI_N")
	)
	(segment
		(start 45.941996 -66.20129)
		(end 46.515782 -65.9638)
		(width 0.10668)
		(layer "In7.Cu")
		(net "IRQ_PCH_TPM_SPI_N")
	)
	(segment
		(start 49.268888 -66.845942)
		(end 50.40884 -67.985894)
		(width 0.10668)
		(layer "In7.Cu")
		(net "IRQ_PCH_TPM_SPI_N")
	)
	(segment
		(start 46.515782 -65.9638)
		(end 47.58944 -65.9638)
		(width 0.10668)
		(layer "In7.Cu")
		(net "IRQ_PCH_TPM_SPI_N")
	)
	(segment
		(start 21.966174 -103.599234)
		(end 21.760688 -103.599234)
		(width 0.08382)
		(layer "In9.Cu")
		(net "IRQ_PCH_TPM_SPI_N")
	)
	(segment
		(start 21.514054 -103.3526)
		(end 16.7386 -103.3526)
		(width 0.08382)
		(layer "In9.Cu")
		(net "IRQ_PCH_TPM_SPI_N")
	)
	(segment
		(start 21.760688 -103.599234)
		(end 21.514054 -103.3526)
		(width 0.08382)
		(layer "In9.Cu")
		(net "IRQ_PCH_TPM_SPI_N")
	)
	(segment
		(start 12.5984 -110.4392)
		(end 12.2047 -110.8329)
		(width 0.08382)
		(layer "In9.Cu")
		(net "IRQ_PCH_TPM_SPI_N")
	)
	(segment
		(start 16.56969 -103.52151)
		(end 16.56969 -104.007666)
		(width 0.08382)
		(layer "In9.Cu")
		(net "IRQ_PCH_TPM_SPI_N")
	)
	(segment
		(start 16.56969 -104.007666)
		(end 13.889736 -106.68762)
		(width 0.08382)
		(layer "In9.Cu")
		(net "IRQ_PCH_TPM_SPI_N")
	)
	(segment
		(start 12.5984 -107.137454)
		(end 12.5984 -110.4392)
		(width 0.08382)
		(layer "In9.Cu")
		(net "IRQ_PCH_TPM_SPI_N")
	)
	(segment
		(start 13.048234 -106.68762)
		(end 12.5984 -107.137454)
		(width 0.08382)
		(layer "In9.Cu")
		(net "IRQ_PCH_TPM_SPI_N")
	)
	(segment
		(start 16.7386 -103.3526)
		(end 16.56969 -103.52151)
		(width 0.08382)
		(layer "In9.Cu")
		(net "IRQ_PCH_TPM_SPI_N")
	)
	(segment
		(start 13.889736 -106.68762)
		(end 13.048234 -106.68762)
		(width 0.08382)
		(layer "In9.Cu")
		(net "IRQ_PCH_TPM_SPI_N")
	)
	(segment
		(start 33.16605 -12.33805)
		(end 33.16605 -12.7)
		(width 0.11684)
		(layer "F.Cu")
		(net "FM_ID_LED")
	)
	(segment
		(start 31.9532 -12.02182)
		(end 32.84982 -12.02182)
		(width 0.11684)
		(layer "F.Cu")
		(net "FM_ID_LED")
	)
	(segment
		(start 32.84982 -12.02182)
		(end 33.16605 -12.33805)
		(width 0.11684)
		(layer "F.Cu")
		(net "FM_ID_LED")
	)
	(segment
		(start 44.895008 -44.171362)
		(end 44.499784 -43.776138)
		(width 0.11684)
		(layer "F.Cu")
		(net "FM_ID_LED")
	)
	(via
		(at 44.499784 -43.776138)
		(size 0.4572)
		(drill 0.254)
		(layers "F.Cu" "B.Cu")
		(net "FM_ID_LED")
	)
	(via
		(at 31.9532 -12.02182)
		(size 0.508)
		(drill 0.254)
		(layers "F.Cu" "B.Cu")
		(net "FM_ID_LED")
	)
	(via
		(at 13.5636 -26.108152)
		(size 0.508)
		(drill 0.254)
		(layers "F.Cu" "B.Cu")
		(net "FM_ID_LED")
	)
	(segment
		(start 28.912058 -41.58742)
		(end 31.012638 -43.688)
		(width 0.08382)
		(layer "In2.Cu")
		(net "FM_ID_LED")
	)
	(segment
		(start 25.108154 -41.58742)
		(end 28.912058 -41.58742)
		(width 0.08382)
		(layer "In2.Cu")
		(net "FM_ID_LED")
	)
	(segment
		(start 22.054312 -44.641262)
		(end 25.108154 -41.58742)
		(width 0.08382)
		(layer "In2.Cu")
		(net "FM_ID_LED")
	)
	(segment
		(start 35.606736 -44.98721)
		(end 36.366958 -44.226988)
		(width 0.08382)
		(layer "In2.Cu")
		(net "FM_ID_LED")
	)
	(segment
		(start 20.5486 -49.1998)
		(end 22.054312 -47.694088)
		(width 0.08382)
		(layer "In2.Cu")
		(net "FM_ID_LED")
	)
	(segment
		(start 16.354806 -49.1998)
		(end 20.5486 -49.1998)
		(width 0.08382)
		(layer "In2.Cu")
		(net "FM_ID_LED")
	)
	(segment
		(start 32.7914 -43.688)
		(end 34.09061 -44.98721)
		(width 0.08382)
		(layer "In2.Cu")
		(net "FM_ID_LED")
	)
	(segment
		(start 14.74724 -27.291792)
		(end 14.74724 -47.592234)
		(width 0.08382)
		(layer "In2.Cu")
		(net "FM_ID_LED")
	)
	(segment
		(start 14.74724 -47.592234)
		(end 16.354806 -49.1998)
		(width 0.08382)
		(layer "In2.Cu")
		(net "FM_ID_LED")
	)
	(segment
		(start 44.048934 -44.226988)
		(end 44.499784 -43.776138)
		(width 0.08382)
		(layer "In2.Cu")
		(net "FM_ID_LED")
	)
	(segment
		(start 34.09061 -44.98721)
		(end 35.606736 -44.98721)
		(width 0.08382)
		(layer "In2.Cu")
		(net "FM_ID_LED")
	)
	(segment
		(start 22.054312 -47.694088)
		(end 22.054312 -44.641262)
		(width 0.08382)
		(layer "In2.Cu")
		(net "FM_ID_LED")
	)
	(segment
		(start 31.012638 -43.688)
		(end 32.7914 -43.688)
		(width 0.08382)
		(layer "In2.Cu")
		(net "FM_ID_LED")
	)
	(segment
		(start 36.366958 -44.226988)
		(end 44.048934 -44.226988)
		(width 0.08382)
		(layer "In2.Cu")
		(net "FM_ID_LED")
	)
	(segment
		(start 13.5636 -26.108152)
		(end 14.74724 -27.291792)
		(width 0.08382)
		(layer "In2.Cu")
		(net "FM_ID_LED")
	)
	(segment
		(start 26.02738 -13.632688)
		(end 25.49906 -13.104368)
		(width 0.10668)
		(layer "In7.Cu")
		(net "FM_ID_LED")
	)
	(segment
		(start 14.125702 -17.162526)
		(end 13.177774 -18.110454)
		(width 0.10668)
		(layer "In7.Cu")
		(net "FM_ID_LED")
	)
	(segment
		(start 15.419578 -14.248892)
		(end 14.125702 -15.542768)
		(width 0.10668)
		(layer "In7.Cu")
		(net "FM_ID_LED")
	)
	(segment
		(start 23.597616 -12.197842)
		(end 23.148798 -12.64666)
		(width 0.10668)
		(layer "In7.Cu")
		(net "FM_ID_LED")
	)
	(segment
		(start 13.177774 -19.166586)
		(end 13.912088 -19.9009)
		(width 0.10668)
		(layer "In7.Cu")
		(net "FM_ID_LED")
	)
	(segment
		(start 25.49906 -13.104368)
		(end 25.49906 -12.699492)
		(width 0.10668)
		(layer "In7.Cu")
		(net "FM_ID_LED")
	)
	(segment
		(start 13.177774 -18.110454)
		(end 13.177774 -19.166586)
		(width 0.10668)
		(layer "In7.Cu")
		(net "FM_ID_LED")
	)
	(segment
		(start 25.49906 -12.699492)
		(end 24.99741 -12.197842)
		(width 0.10668)
		(layer "In7.Cu")
		(net "FM_ID_LED")
	)
	(segment
		(start 24.99741 -12.197842)
		(end 23.597616 -12.197842)
		(width 0.10668)
		(layer "In7.Cu")
		(net "FM_ID_LED")
	)
	(segment
		(start 13.5636 -21.05025)
		(end 13.5636 -26.108152)
		(width 0.10668)
		(layer "In7.Cu")
		(net "FM_ID_LED")
	)
	(segment
		(start 13.912088 -19.9009)
		(end 13.912088 -20.701762)
		(width 0.10668)
		(layer "In7.Cu")
		(net "FM_ID_LED")
	)
	(segment
		(start 23.148798 -12.64666)
		(end 23.148798 -13.870432)
		(width 0.10668)
		(layer "In7.Cu")
		(net "FM_ID_LED")
	)
	(segment
		(start 13.912088 -20.701762)
		(end 13.5636 -21.05025)
		(width 0.10668)
		(layer "In7.Cu")
		(net "FM_ID_LED")
	)
	(segment
		(start 31.43377 -12.54125)
		(end 28.253944 -12.54125)
		(width 0.10668)
		(layer "In7.Cu")
		(net "FM_ID_LED")
	)
	(segment
		(start 27.162506 -13.632688)
		(end 26.02738 -13.632688)
		(width 0.10668)
		(layer "In7.Cu")
		(net "FM_ID_LED")
	)
	(segment
		(start 14.125702 -15.542768)
		(end 14.125702 -17.162526)
		(width 0.10668)
		(layer "In7.Cu")
		(net "FM_ID_LED")
	)
	(segment
		(start 31.9532 -12.02182)
		(end 31.43377 -12.54125)
		(width 0.10668)
		(layer "In7.Cu")
		(net "FM_ID_LED")
	)
	(segment
		(start 28.253944 -12.54125)
		(end 27.162506 -13.632688)
		(width 0.10668)
		(layer "In7.Cu")
		(net "FM_ID_LED")
	)
	(segment
		(start 23.148798 -13.870432)
		(end 22.770338 -14.248892)
		(width 0.10668)
		(layer "In7.Cu")
		(net "FM_ID_LED")
	)
	(segment
		(start 22.770338 -14.248892)
		(end 15.419578 -14.248892)
		(width 0.10668)
		(layer "In7.Cu")
		(net "FM_ID_LED")
	)
	(segment
		(start 26.714958 -65.95745)
		(end 26.49982 -65.742312)
		(width 0.11684)
		(layer "F.Cu")
		(net "UART_BMC_5_TXD_BUF1_R")
	)
	(segment
		(start 24.4856 -58.9026)
		(end 22.0218 -56.4388)
		(width 0.11684)
		(layer "F.Cu")
		(net "UART_BMC_5_TXD_BUF1_R")
	)
	(segment
		(start 28.1432 -66.10985)
		(end 27.9908 -65.95745)
		(width 0.11684)
		(layer "F.Cu")
		(net "UART_BMC_5_TXD_BUF1_R")
	)
	(segment
		(start 24.718264 -61.345064)
		(end 24.718264 -60.95619)
		(width 0.11684)
		(layer "F.Cu")
		(net "UART_BMC_5_TXD_BUF1_R")
	)
	(segment
		(start 24.718264 -60.95619)
		(end 24.718264 -60.583318)
		(width 0.11684)
		(layer "F.Cu")
		(net "UART_BMC_5_TXD_BUF1_R")
	)
	(segment
		(start 22.0218 -47.9298)
		(end 21.0566 -46.9646)
		(width 0.11684)
		(layer "F.Cu")
		(net "UART_BMC_5_TXD_BUF1_R")
	)
	(segment
		(start 27.1272 -65.95745)
		(end 26.714958 -65.95745)
		(width 0.11684)
		(layer "F.Cu")
		(net "UART_BMC_5_TXD_BUF1_R")
	)
	(segment
		(start 22.0218 -56.4388)
		(end 22.0218 -47.9298)
		(width 0.11684)
		(layer "F.Cu")
		(net "UART_BMC_5_TXD_BUF1_R")
	)
	(segment
		(start 27.9908 -65.95745)
		(end 27.1272 -65.95745)
		(width 0.11684)
		(layer "F.Cu")
		(net "UART_BMC_5_TXD_BUF1_R")
	)
	(segment
		(start 24.4856 -60.350654)
		(end 24.4856 -58.9026)
		(width 0.11684)
		(layer "F.Cu")
		(net "UART_BMC_5_TXD_BUF1_R")
	)
	(segment
		(start 24.718264 -60.583318)
		(end 24.4856 -60.350654)
		(width 0.11684)
		(layer "F.Cu")
		(net "UART_BMC_5_TXD_BUF1_R")
	)
	(segment
		(start 20.163536 -46.9646)
		(end 19.122136 -45.9232)
		(width 0.11684)
		(layer "F.Cu")
		(net "UART_BMC_5_TXD_BUF1_R")
	)
	(segment
		(start 26.49982 -65.15862)
		(end 26.063702 -64.722502)
		(width 0.11684)
		(layer "F.Cu")
		(net "UART_BMC_5_TXD_BUF1_R")
	)
	(segment
		(start 26.063702 -64.722502)
		(end 26.063702 -62.690502)
		(width 0.11684)
		(layer "F.Cu")
		(net "UART_BMC_5_TXD_BUF1_R")
	)
	(segment
		(start 26.063702 -62.690502)
		(end 24.718264 -61.345064)
		(width 0.11684)
		(layer "F.Cu")
		(net "UART_BMC_5_TXD_BUF1_R")
	)
	(segment
		(start 26.49982 -65.742312)
		(end 26.49982 -65.15862)
		(width 0.11684)
		(layer "F.Cu")
		(net "UART_BMC_5_TXD_BUF1_R")
	)
	(segment
		(start 21.0566 -46.9646)
		(end 20.163536 -46.9646)
		(width 0.11684)
		(layer "F.Cu")
		(net "UART_BMC_5_TXD_BUF1_R")
	)
	(via
		(at 19.122136 -45.9232)
		(size 0.508)
		(drill 0.254)
		(layers "F.Cu" "B.Cu")
		(net "UART_BMC_5_TXD_BUF1_R")
	)
	(via
		(at 13.081 -28.956)
		(size 0.6604)
		(drill 0.3302)
		(layers "F.Cu" "B.Cu")
		(net "UART_BMC_5_TXD_BUF1_R")
	)
	(segment
		(start 14.2494 -30.1244)
		(end 13.081 -28.956)
		(width 0.11684)
		(layer "B.Cu")
		(net "UART_BMC_5_TXD_BUF1_R")
	)
	(segment
		(start 19.122136 -45.9232)
		(end 17.8054 -45.9232)
		(width 0.11684)
		(layer "B.Cu")
		(net "UART_BMC_5_TXD_BUF1_R")
	)
	(segment
		(start 9.109456 -28.386786)
		(end 9.888982 -29.166312)
		(width 0.11684)
		(layer "B.Cu")
		(net "UART_BMC_5_TXD_BUF1_R")
	)
	(segment
		(start 9.888982 -29.166312)
		(end 12.870688 -29.166312)
		(width 0.11684)
		(layer "B.Cu")
		(net "UART_BMC_5_TXD_BUF1_R")
	)
	(segment
		(start 17.8054 -45.9232)
		(end 16.17726 -44.29506)
		(width 0.11684)
		(layer "B.Cu")
		(net "UART_BMC_5_TXD_BUF1_R")
	)
	(segment
		(start 16.17726 -37.33546)
		(end 14.2494 -35.4076)
		(width 0.11684)
		(layer "B.Cu")
		(net "UART_BMC_5_TXD_BUF1_R")
	)
	(segment
		(start 14.2494 -35.4076)
		(end 14.2494 -30.1244)
		(width 0.11684)
		(layer "B.Cu")
		(net "UART_BMC_5_TXD_BUF1_R")
	)
	(segment
		(start 12.870688 -29.166312)
		(end 13.081 -28.956)
		(width 0.11684)
		(layer "B.Cu")
		(net "UART_BMC_5_TXD_BUF1_R")
	)
	(segment
		(start 8.92556 -28.386786)
		(end 9.109456 -28.386786)
		(width 0.11684)
		(layer "B.Cu")
		(net "UART_BMC_5_TXD_BUF1_R")
	)
	(segment
		(start 16.17726 -44.29506)
		(end 16.17726 -37.33546)
		(width 0.11684)
		(layer "B.Cu")
		(net "UART_BMC_5_TXD_BUF1_R")
	)
	(segment
		(start 28.001214 -63.38316)
		(end 27.54122 -63.843154)
		(width 0.11684)
		(layer "F.Cu")
		(net "UART_BMC_5_TXD_BUF1")
	)
	(segment
		(start 27.54122 -64.74333)
		(end 27.1272 -65.15735)
		(width 0.11684)
		(layer "F.Cu")
		(net "UART_BMC_5_TXD_BUF1")
	)
	(segment
		(start 27.432 -62.813946)
		(end 28.001214 -63.38316)
		(width 0.11684)
		(layer "F.Cu")
		(net "UART_BMC_5_TXD_BUF1")
	)
	(segment
		(start 27.54122 -63.843154)
		(end 27.54122 -64.74333)
		(width 0.11684)
		(layer "F.Cu")
		(net "UART_BMC_5_TXD_BUF1")
	)
	(segment
		(start 27.432 -60.2488)
		(end 27.432 -62.813946)
		(width 0.11684)
		(layer "F.Cu")
		(net "UART_BMC_5_TXD_BUF1")
	)
	(via
		(at 27.432 -60.2488)
		(size 0.6604)
		(drill 0.3302)
		(layers "F.Cu" "B.Cu")
		(net "UART_BMC_5_TXD_BUF1")
	)
	(segment
		(start 19.155664 -60.98159)
		(end 19.155664 -60.501276)
		(width 0.11684)
		(layer "F.Cu")
		(net "UART_BMC_5_RXD_BUF1_SW")
	)
	(segment
		(start 19.6215 -60.2107)
		(end 20.3708 -59.4614)
		(width 0.11684)
		(layer "F.Cu")
		(net "UART_BMC_5_RXD_BUF1_SW")
	)
	(segment
		(start 19.44624 -60.2107)
		(end 19.6215 -60.2107)
		(width 0.11684)
		(layer "F.Cu")
		(net "UART_BMC_5_RXD_BUF1_SW")
	)
	(segment
		(start 19.155664 -60.501276)
		(end 19.44624 -60.2107)
		(width 0.11684)
		(layer "F.Cu")
		(net "UART_BMC_5_RXD_BUF1_SW")
	)
	(segment
		(start 20.08505 -59.17565)
		(end 19.1516 -59.17565)
		(width 0.11684)
		(layer "F.Cu")
		(net "UART_BMC_5_RXD_BUF1_SW")
	)
	(segment
		(start 20.3708 -59.4614)
		(end 20.08505 -59.17565)
		(width 0.11684)
		(layer "F.Cu")
		(net "UART_BMC_5_RXD_BUF1_SW")
	)
	(via
		(at 20.3708 -59.4614)
		(size 0.762)
		(drill 0.381)
		(layers "F.Cu" "B.Cu")
		(net "UART_BMC_5_RXD_BUF1_SW")
	)
	(segment
		(start 29.301186 -64.21247)
		(end 29.301186 -63.38316)
		(width 0.11684)
		(layer "F.Cu")
		(net "UART_BMC_5_RXD_BUF1_R")
	)
	(segment
		(start 31.623 -66.32575)
		(end 31.52775 -66.421)
		(width 0.11684)
		(layer "F.Cu")
		(net "UART_BMC_5_RXD_BUF1_R")
	)
	(segment
		(start 30.3784 -66.421)
		(end 30.10154 -66.14414)
		(width 0.11684)
		(layer "F.Cu")
		(net "UART_BMC_5_RXD_BUF1_R")
	)
	(segment
		(start 30.10154 -66.14414)
		(end 29.301186 -64.21247)
		(width 0.11684)
		(layer "F.Cu")
		(net "UART_BMC_5_RXD_BUF1_R")
	)
	(segment
		(start 31.52775 -66.421)
		(end 30.3784 -66.421)
		(width 0.11684)
		(layer "F.Cu")
		(net "UART_BMC_5_RXD_BUF1_R")
	)
	(via
		(at 30.3784 -66.421)
		(size 0.762)
		(drill 0.381)
		(layers "F.Cu" "B.Cu")
		(net "UART_BMC_5_RXD_BUF1_R")
	)
	(segment
		(start 28.7274 -60.7568)
		(end 28.6766 -60.7568)
		(width 0.11684)
		(layer "F.Cu")
		(net "UART_BMC_5_RXD_BUF1")
	)
	(segment
		(start 29.843476 -60.94095)
		(end 29.301186 -61.48324)
		(width 0.11684)
		(layer "F.Cu")
		(net "UART_BMC_5_RXD_BUF1")
	)
	(segment
		(start 29.301186 -61.48324)
		(end 29.301186 -61.330586)
		(width 0.11684)
		(layer "F.Cu")
		(net "UART_BMC_5_RXD_BUF1")
	)
	(segment
		(start 19.1516 -58.37555)
		(end 19.1516 -57.873138)
		(width 0.11684)
		(layer "F.Cu")
		(net "UART_BMC_5_RXD_BUF1")
	)
	(segment
		(start 29.301186 -61.330586)
		(end 28.7274 -60.7568)
		(width 0.11684)
		(layer "F.Cu")
		(net "UART_BMC_5_RXD_BUF1")
	)
	(segment
		(start 19.1516 -57.873138)
		(end 17.895062 -56.6166)
		(width 0.11684)
		(layer "F.Cu")
		(net "UART_BMC_5_RXD_BUF1")
	)
	(segment
		(start 30.564074 -60.94095)
		(end 29.843476 -60.94095)
		(width 0.11684)
		(layer "F.Cu")
		(net "UART_BMC_5_RXD_BUF1")
	)
	(via
		(at 28.6766 -60.7568)
		(size 0.508)
		(drill 0.254)
		(layers "F.Cu" "B.Cu")
		(net "UART_BMC_5_RXD_BUF1")
	)
	(via
		(at 17.895062 -56.6166)
		(size 0.508)
		(drill 0.254)
		(layers "F.Cu" "B.Cu")
		(net "UART_BMC_5_RXD_BUF1")
	)
	(segment
		(start 17.60474 -55.533036)
		(end 17.60474 -53.750972)
		(width 0.11684)
		(layer "B.Cu")
		(net "UART_BMC_5_RXD_BUF1")
	)
	(segment
		(start 19.66976 -43.52544)
		(end 19.881088 -43.314112)
		(width 0.11684)
		(layer "B.Cu")
		(net "UART_BMC_5_RXD_BUF1")
	)
	(segment
		(start 12.769088 -25.9842)
		(end 12.31265 -25.9842)
		(width 0.11684)
		(layer "B.Cu")
		(net "UART_BMC_5_RXD_BUF1")
	)
	(segment
		(start 19.881088 -42.066972)
		(end 19.26209 -40.57269)
		(width 0.11684)
		(layer "B.Cu")
		(net "UART_BMC_5_RXD_BUF1")
	)
	(segment
		(start 19.881088 -43.314112)
		(end 19.881088 -42.066972)
		(width 0.11684)
		(layer "B.Cu")
		(net "UART_BMC_5_RXD_BUF1")
	)
	(segment
		(start 19.26209 -40.57269)
		(end 17.93494 -39.24554)
		(width 0.11684)
		(layer "B.Cu")
		(net "UART_BMC_5_RXD_BUF1")
	)
	(segment
		(start 13.026136 -28.0797)
		(end 13.026136 -26.241248)
		(width 0.11684)
		(layer "B.Cu")
		(net "UART_BMC_5_RXD_BUF1")
	)
	(segment
		(start 16.55699 -37.069522)
		(end 14.59484 -35.107372)
		(width 0.11684)
		(layer "B.Cu")
		(net "UART_BMC_5_RXD_BUF1")
	)
	(segment
		(start 14.59484 -35.107372)
		(end 14.59484 -29.648404)
		(width 0.11684)
		(layer "B.Cu")
		(net "UART_BMC_5_RXD_BUF1")
	)
	(segment
		(start 17.895062 -55.823358)
		(end 17.60474 -55.533036)
		(width 0.11684)
		(layer "B.Cu")
		(net "UART_BMC_5_RXD_BUF1")
	)
	(segment
		(start 17.60474 -53.750972)
		(end 19.66976 -51.685952)
		(width 0.11684)
		(layer "B.Cu")
		(net "UART_BMC_5_RXD_BUF1")
	)
	(segment
		(start 17.171924 -39.24554)
		(end 16.55699 -38.630606)
		(width 0.11684)
		(layer "B.Cu")
		(net "UART_BMC_5_RXD_BUF1")
	)
	(segment
		(start 17.93494 -39.24554)
		(end 17.171924 -39.24554)
		(width 0.11684)
		(layer "B.Cu")
		(net "UART_BMC_5_RXD_BUF1")
	)
	(segment
		(start 17.895062 -56.6166)
		(end 17.895062 -55.823358)
		(width 0.11684)
		(layer "B.Cu")
		(net "UART_BMC_5_RXD_BUF1")
	)
	(segment
		(start 19.66976 -51.685952)
		(end 19.66976 -43.52544)
		(width 0.11684)
		(layer "B.Cu")
		(net "UART_BMC_5_RXD_BUF1")
	)
	(segment
		(start 13.026136 -26.241248)
		(end 12.769088 -25.9842)
		(width 0.11684)
		(layer "B.Cu")
		(net "UART_BMC_5_RXD_BUF1")
	)
	(segment
		(start 16.55699 -38.630606)
		(end 16.55699 -37.069522)
		(width 0.11684)
		(layer "B.Cu")
		(net "UART_BMC_5_RXD_BUF1")
	)
	(segment
		(start 14.59484 -29.648404)
		(end 13.026136 -28.0797)
		(width 0.11684)
		(layer "B.Cu")
		(net "UART_BMC_5_RXD_BUF1")
	)
	(segment
		(start 21.36902 -60.56122)
		(end 19.30654 -60.56122)
		(width 0.08382)
		(layer "In2.Cu")
		(net "UART_BMC_5_RXD_BUF1")
	)
	(segment
		(start 19.30654 -60.56122)
		(end 19.17954 -60.68822)
		(width 0.08382)
		(layer "In2.Cu")
		(net "UART_BMC_5_RXD_BUF1")
	)
	(segment
		(start 14.426692 -52.451)
		(end 17.401794 -55.426102)
		(width 0.08382)
		(layer "In2.Cu")
		(net "UART_BMC_5_RXD_BUF1")
	)
	(segment
		(start 16.46174 -61.12002)
		(end 15.873222 -61.12002)
		(width 0.08382)
		(layer "In2.Cu")
		(net "UART_BMC_5_RXD_BUF1")
	)
	(segment
		(start 28.6766 -60.7568)
		(end 26.723848 -61.565536)
		(width 0.08382)
		(layer "In2.Cu")
		(net "UART_BMC_5_RXD_BUF1")
	)
	(segment
		(start 19.17954 -60.68822)
		(end 16.89354 -60.68822)
		(width 0.08382)
		(layer "In2.Cu")
		(net "UART_BMC_5_RXD_BUF1")
	)
	(segment
		(start 16.89354 -60.68822)
		(end 16.46174 -61.12002)
		(width 0.08382)
		(layer "In2.Cu")
		(net "UART_BMC_5_RXD_BUF1")
	)
	(segment
		(start 12.45743 -59.462162)
		(end 12.45743 -57.984136)
		(width 0.08382)
		(layer "In2.Cu")
		(net "UART_BMC_5_RXD_BUF1")
	)
	(segment
		(start 11.671046 -56.085486)
		(end 11.671046 -53.556154)
		(width 0.08382)
		(layer "In2.Cu")
		(net "UART_BMC_5_RXD_BUF1")
	)
	(segment
		(start 11.671046 -53.556154)
		(end 12.7762 -52.451)
		(width 0.08382)
		(layer "In2.Cu")
		(net "UART_BMC_5_RXD_BUF1")
	)
	(segment
		(start 12.872212 -59.876944)
		(end 12.45743 -59.462162)
		(width 0.08382)
		(layer "In2.Cu")
		(net "UART_BMC_5_RXD_BUF1")
	)
	(segment
		(start 12.45743 -57.984136)
		(end 11.671046 -56.085486)
		(width 0.08382)
		(layer "In2.Cu")
		(net "UART_BMC_5_RXD_BUF1")
	)
	(segment
		(start 26.723848 -61.565536)
		(end 22.373336 -61.565536)
		(width 0.08382)
		(layer "In2.Cu")
		(net "UART_BMC_5_RXD_BUF1")
	)
	(segment
		(start 15.873222 -61.12002)
		(end 12.872212 -59.876944)
		(width 0.08382)
		(layer "In2.Cu")
		(net "UART_BMC_5_RXD_BUF1")
	)
	(segment
		(start 12.7762 -52.451)
		(end 14.426692 -52.451)
		(width 0.08382)
		(layer "In2.Cu")
		(net "UART_BMC_5_RXD_BUF1")
	)
	(segment
		(start 17.401794 -55.426102)
		(end 17.895062 -56.6166)
		(width 0.08382)
		(layer "In2.Cu")
		(net "UART_BMC_5_RXD_BUF1")
	)
	(segment
		(start 22.373336 -61.565536)
		(end 21.36902 -60.56122)
		(width 0.08382)
		(layer "In2.Cu")
		(net "UART_BMC_5_RXD_BUF1")
	)
	(segment
		(start 20.701 -42.50055)
		(end 20.19427 -41.99382)
		(width 0.11684)
		(layer "F.Cu")
		(net "RST_SPI_FLASH_R_N")
	)
	(segment
		(start 18.5928 -41.1226)
		(end 18.4404 -40.9702)
		(width 0.11684)
		(layer "F.Cu")
		(net "RST_SPI_FLASH_R_N")
	)
	(segment
		(start 19.755104 -41.99382)
		(end 19.690842 -41.929558)
		(width 0.11684)
		(layer "F.Cu")
		(net "RST_SPI_FLASH_R_N")
	)
	(segment
		(start 18.5928 -41.5798)
		(end 18.5928 -41.1226)
		(width 0.11684)
		(layer "F.Cu")
		(net "RST_SPI_FLASH_R_N")
	)
	(segment
		(start 20.19427 -41.99382)
		(end 19.755104 -41.99382)
		(width 0.11684)
		(layer "F.Cu")
		(net "RST_SPI_FLASH_R_N")
	)
	(segment
		(start 18.942558 -41.929558)
		(end 18.5928 -41.5798)
		(width 0.11684)
		(layer "F.Cu")
		(net "RST_SPI_FLASH_R_N")
	)
	(segment
		(start 19.690842 -41.929558)
		(end 18.942558 -41.929558)
		(width 0.11684)
		(layer "F.Cu")
		(net "RST_SPI_FLASH_R_N")
	)
	(segment
		(start 18.4404 -40.9702)
		(end 17.78 -40.9702)
		(width 0.11684)
		(layer "F.Cu")
		(net "RST_SPI_FLASH_R_N")
	)
	(segment
		(start 17.47774 -41.27246)
		(end 17.47774 -41.625266)
		(width 0.11684)
		(layer "F.Cu")
		(net "RST_SPI_FLASH_R_N")
	)
	(segment
		(start 17.78 -40.9702)
		(end 17.47774 -41.27246)
		(width 0.11684)
		(layer "F.Cu")
		(net "RST_SPI_FLASH_R_N")
	)
	(segment
		(start 18.264124 -91.191842)
		(end 18.659348 -91.587066)
		(width 0.11684)
		(layer "F.Cu")
		(net "TP_PLD_L3")
	)
	(via
		(at 18.264124 -91.191842)
		(size 0.4572)
		(drill 0.254)
		(layers "F.Cu" "B.Cu")
		(net "TP_PLD_L3")
	)
	(via
		(at 53.4797 -95.32366)
		(size 0.6604)
		(drill 0.3302)
		(layers "F.Cu" "B.Cu")
		(net "SMB_DEBUG_AUX_LVC3_USB_R3_SDA")
	)
	(segment
		(start 53.63464 -94.29496)
		(end 53.4797 -94.4499)
		(width 0.11684)
		(layer "B.Cu")
		(net "SMB_DEBUG_AUX_LVC3_USB_R3_SDA")
	)
	(segment
		(start 51.64455 -94.61119)
		(end 51.64455 -94.1705)
		(width 0.11684)
		(layer "B.Cu")
		(net "SMB_DEBUG_AUX_LVC3_USB_R3_SDA")
	)
	(segment
		(start 52.35702 -95.32366)
		(end 51.64455 -94.61119)
		(width 0.11684)
		(layer "B.Cu")
		(net "SMB_DEBUG_AUX_LVC3_USB_R3_SDA")
	)
	(segment
		(start 53.63464 -93.12656)
		(end 53.63464 -94.29496)
		(width 0.11684)
		(layer "B.Cu")
		(net "SMB_DEBUG_AUX_LVC3_USB_R3_SDA")
	)
	(segment
		(start 54.71668 -92.645484)
		(end 54.115716 -92.645484)
		(width 0.11684)
		(layer "B.Cu")
		(net "SMB_DEBUG_AUX_LVC3_USB_R3_SDA")
	)
	(segment
		(start 53.4797 -94.4499)
		(end 53.4797 -95.32366)
		(width 0.11684)
		(layer "B.Cu")
		(net "SMB_DEBUG_AUX_LVC3_USB_R3_SDA")
	)
	(segment
		(start 54.115716 -92.645484)
		(end 53.63464 -93.12656)
		(width 0.11684)
		(layer "B.Cu")
		(net "SMB_DEBUG_AUX_LVC3_USB_R3_SDA")
	)
	(segment
		(start 53.4797 -95.32366)
		(end 52.35702 -95.32366)
		(width 0.11684)
		(layer "B.Cu")
		(net "SMB_DEBUG_AUX_LVC3_USB_R3_SDA")
	)
	(via
		(at 52.9209 -93.9165)
		(size 0.6604)
		(drill 0.3302)
		(layers "F.Cu" "B.Cu")
		(net "SMB_DEBUG_AUX_LVC3_USB_R3_SCL")
	)
	(segment
		(start 54.71668 -91.995498)
		(end 54.105048 -91.995498)
		(width 0.11684)
		(layer "B.Cu")
		(net "SMB_DEBUG_AUX_LVC3_USB_R3_SCL")
	)
	(segment
		(start 52.9209 -93.9165)
		(end 52.2859 -93.2815)
		(width 0.11684)
		(layer "B.Cu")
		(net "SMB_DEBUG_AUX_LVC3_USB_R3_SCL")
	)
	(segment
		(start 53.23332 -93.60408)
		(end 52.9209 -93.9165)
		(width 0.11684)
		(layer "B.Cu")
		(net "SMB_DEBUG_AUX_LVC3_USB_R3_SCL")
	)
	(segment
		(start 53.23332 -92.867226)
		(end 53.23332 -93.60408)
		(width 0.11684)
		(layer "B.Cu")
		(net "SMB_DEBUG_AUX_LVC3_USB_R3_SCL")
	)
	(segment
		(start 52.2859 -93.2815)
		(end 51.64455 -93.2815)
		(width 0.11684)
		(layer "B.Cu")
		(net "SMB_DEBUG_AUX_LVC3_USB_R3_SCL")
	)
	(segment
		(start 54.105048 -91.995498)
		(end 53.23332 -92.867226)
		(width 0.11684)
		(layer "B.Cu")
		(net "SMB_DEBUG_AUX_LVC3_USB_R3_SCL")
	)
	(segment
		(start 21.209 -68.43395)
		(end 21.209 -67.7926)
		(width 0.11684)
		(layer "F.Cu")
		(net "RST_SPI_FLASH_BUF_N")
	)
	(segment
		(start 18.92935 -45.45838)
		(end 18.4912 -45.89653)
		(width 0.11684)
		(layer "F.Cu")
		(net "RST_SPI_FLASH_BUF_N")
	)
	(segment
		(start 22.41804 -47.765462)
		(end 21.220938 -46.56836)
		(width 0.11684)
		(layer "F.Cu")
		(net "RST_SPI_FLASH_BUF_N")
	)
	(segment
		(start 18.339054 -46.1264)
		(end 18.4912 -45.974254)
		(width 0.11684)
		(layer "F.Cu")
		(net "RST_SPI_FLASH_BUF_N")
	)
	(segment
		(start 22.225 -68.43395)
		(end 21.209 -68.43395)
		(width 0.11684)
		(layer "F.Cu")
		(net "RST_SPI_FLASH_BUF_N")
	)
	(segment
		(start 26.459942 -61.728858)
		(end 26.8732 -61.3156)
		(width 0.11684)
		(layer "F.Cu")
		(net "RST_SPI_FLASH_BUF_N")
	)
	(segment
		(start 17.5768 -46.634146)
		(end 18.084546 -46.1264)
		(width 0.11684)
		(layer "F.Cu")
		(net "RST_SPI_FLASH_BUF_N")
	)
	(segment
		(start 20.482306 -46.56836)
		(end 19.372326 -45.45838)
		(width 0.11684)
		(layer "F.Cu")
		(net "RST_SPI_FLASH_BUF_N")
	)
	(segment
		(start 17.5768 -46.70425)
		(end 17.5768 -46.634146)
		(width 0.11684)
		(layer "F.Cu")
		(net "RST_SPI_FLASH_BUF_N")
	)
	(segment
		(start 26.459942 -63.820548)
		(end 26.459942 -61.728858)
		(width 0.11684)
		(layer "F.Cu")
		(net "RST_SPI_FLASH_BUF_N")
	)
	(segment
		(start 18.084546 -46.1264)
		(end 18.339054 -46.1264)
		(width 0.11684)
		(layer "F.Cu")
		(net "RST_SPI_FLASH_BUF_N")
	)
	(segment
		(start 26.8732 -59.66714)
		(end 22.41804 -55.21198)
		(width 0.11684)
		(layer "F.Cu")
		(net "RST_SPI_FLASH_BUF_N")
	)
	(segment
		(start 18.4912 -45.974254)
		(end 18.4912 -45.90415)
		(width 0.11684)
		(layer "F.Cu")
		(net "RST_SPI_FLASH_BUF_N")
	)
	(segment
		(start 21.220938 -46.56836)
		(end 20.482306 -46.56836)
		(width 0.11684)
		(layer "F.Cu")
		(net "RST_SPI_FLASH_BUF_N")
	)
	(segment
		(start 19.372326 -45.45838)
		(end 18.92935 -45.45838)
		(width 0.11684)
		(layer "F.Cu")
		(net "RST_SPI_FLASH_BUF_N")
	)
	(segment
		(start 22.41804 -55.21198)
		(end 22.41804 -47.765462)
		(width 0.11684)
		(layer "F.Cu")
		(net "RST_SPI_FLASH_BUF_N")
	)
	(segment
		(start 26.8732 -61.3156)
		(end 26.8732 -59.66714)
		(width 0.11684)
		(layer "F.Cu")
		(net "RST_SPI_FLASH_BUF_N")
	)
	(segment
		(start 27.0764 -64.437006)
		(end 26.459942 -63.820548)
		(width 0.11684)
		(layer "F.Cu")
		(net "RST_SPI_FLASH_BUF_N")
	)
	(segment
		(start 18.4912 -45.89653)
		(end 18.4912 -45.90415)
		(width 0.11684)
		(layer "F.Cu")
		(net "RST_SPI_FLASH_BUF_N")
	)
	(via
		(at 27.0764 -64.437006)
		(size 0.508)
		(drill 0.254)
		(layers "F.Cu" "B.Cu")
		(net "RST_SPI_FLASH_BUF_N")
	)
	(via
		(at 21.209 -67.7926)
		(size 0.508)
		(drill 0.254)
		(layers "F.Cu" "B.Cu")
		(net "RST_SPI_FLASH_BUF_N")
	)
	(segment
		(start 27.0764 -64.437006)
		(end 26.175462 -64.437006)
		(width 0.08382)
		(layer "In2.Cu")
		(net "RST_SPI_FLASH_BUF_N")
	)
	(segment
		(start 23.637748 -66.97472)
		(end 22.02688 -66.97472)
		(width 0.08382)
		(layer "In2.Cu")
		(net "RST_SPI_FLASH_BUF_N")
	)
	(segment
		(start 26.175462 -64.437006)
		(end 23.637748 -66.97472)
		(width 0.08382)
		(layer "In2.Cu")
		(net "RST_SPI_FLASH_BUF_N")
	)
	(segment
		(start 22.02688 -66.97472)
		(end 21.209 -67.7926)
		(width 0.08382)
		(layer "In2.Cu")
		(net "RST_SPI_FLASH_BUF_N")
	)
	(segment
		(start 23.854664 -97.582228)
		(end 23.45944 -97.187004)
		(width 0.11684)
		(layer "F.Cu")
		(net "FM_BMC_DEBUG_SW_R2_N")
	)
	(via
		(at 23.854664 -97.582228)
		(size 0.4572)
		(drill 0.254)
		(layers "F.Cu" "B.Cu")
		(net "FM_BMC_DEBUG_SW_R2_N")
	)
	(via
		(at 23.9268 -99.314)
		(size 0.6604)
		(drill 0.3302)
		(layers "F.Cu" "B.Cu")
		(net "FM_BMC_DEBUG_SW_R2_N")
	)
	(segment
		(start 23.68296 -100.584)
		(end 23.9268 -100.34016)
		(width 0.11684)
		(layer "B.Cu")
		(net "FM_BMC_DEBUG_SW_R2_N")
	)
	(segment
		(start 22.4536 -101.09835)
		(end 22.4536 -100.7872)
		(width 0.11684)
		(layer "B.Cu")
		(net "FM_BMC_DEBUG_SW_R2_N")
	)
	(segment
		(start 23.166324 -100.584)
		(end 23.68296 -100.584)
		(width 0.11684)
		(layer "B.Cu")
		(net "FM_BMC_DEBUG_SW_R2_N")
	)
	(segment
		(start 21.971 -101.58095)
		(end 22.4536 -101.09835)
		(width 0.11684)
		(layer "B.Cu")
		(net "FM_BMC_DEBUG_SW_R2_N")
	)
	(segment
		(start 24.257 -97.7646)
		(end 24.074628 -97.582228)
		(width 0.11684)
		(layer "B.Cu")
		(net "FM_BMC_DEBUG_SW_R2_N")
	)
	(segment
		(start 23.9268 -100.34016)
		(end 23.9268 -99.314)
		(width 0.11684)
		(layer "B.Cu")
		(net "FM_BMC_DEBUG_SW_R2_N")
	)
	(segment
		(start 23.9268 -99.314)
		(end 24.257 -98.9838)
		(width 0.11684)
		(layer "B.Cu")
		(net "FM_BMC_DEBUG_SW_R2_N")
	)
	(segment
		(start 23.091394 -100.50907)
		(end 23.166324 -100.584)
		(width 0.11684)
		(layer "B.Cu")
		(net "FM_BMC_DEBUG_SW_R2_N")
	)
	(segment
		(start 22.4536 -100.7872)
		(end 22.73173 -100.50907)
		(width 0.11684)
		(layer "B.Cu")
		(net "FM_BMC_DEBUG_SW_R2_N")
	)
	(segment
		(start 22.73173 -100.50907)
		(end 23.091394 -100.50907)
		(width 0.11684)
		(layer "B.Cu")
		(net "FM_BMC_DEBUG_SW_R2_N")
	)
	(segment
		(start 24.257 -98.9838)
		(end 24.257 -97.7646)
		(width 0.11684)
		(layer "B.Cu")
		(net "FM_BMC_DEBUG_SW_R2_N")
	)
	(segment
		(start 24.074628 -97.582228)
		(end 23.854664 -97.582228)
		(width 0.11684)
		(layer "B.Cu")
		(net "FM_BMC_DEBUG_SW_R2_N")
	)
	(segment
		(start 60.094876 -40.971216)
		(end 60.4901 -40.575992)
		(width 0.11684)
		(layer "F.Cu")
		(net "DP_BMC_HPD_3V3_BUF")
	)
	(via
		(at 60.4901 -40.575992)
		(size 0.4572)
		(drill 0.254)
		(layers "F.Cu" "B.Cu")
		(net "DP_BMC_HPD_3V3_BUF")
	)
	(via
		(at 63.843916 -38.830758)
		(size 0.508)
		(drill 0.254)
		(layers "F.Cu" "B.Cu")
		(net "DP_BMC_HPD_3V3_BUF")
	)
	(segment
		(start 63.843916 -38.830758)
		(end 63.843916 -39.751254)
		(width 0.11684)
		(layer "B.Cu")
		(net "DP_BMC_HPD_3V3_BUF")
	)
	(segment
		(start 64.394334 -40.301672)
		(end 64.394334 -40.322754)
		(width 0.11684)
		(layer "B.Cu")
		(net "DP_BMC_HPD_3V3_BUF")
	)
	(segment
		(start 63.843916 -39.751254)
		(end 64.394334 -40.301672)
		(width 0.11684)
		(layer "B.Cu")
		(net "DP_BMC_HPD_3V3_BUF")
	)
	(segment
		(start 61.484764 -39.512748)
		(end 62.166754 -38.830758)
		(width 0.10668)
		(layer "In7.Cu")
		(net "DP_BMC_HPD_3V3_BUF")
	)
	(segment
		(start 62.166754 -38.830758)
		(end 63.843916 -38.830758)
		(width 0.10668)
		(layer "In7.Cu")
		(net "DP_BMC_HPD_3V3_BUF")
	)
	(segment
		(start 61.484764 -39.754302)
		(end 61.484764 -39.512748)
		(width 0.10668)
		(layer "In7.Cu")
		(net "DP_BMC_HPD_3V3_BUF")
	)
	(segment
		(start 60.663074 -40.575992)
		(end 61.484764 -39.754302)
		(width 0.10668)
		(layer "In7.Cu")
		(net "DP_BMC_HPD_3V3_BUF")
	)
	(segment
		(start 60.4901 -40.575992)
		(end 60.663074 -40.575992)
		(width 0.10668)
		(layer "In7.Cu")
		(net "DP_BMC_HPD_3V3_BUF")
	)
	(segment
		(start -11.6332 -89.672414)
		(end -10.568686 -90.736928)
		(width 0.11684)
		(layer "F.Cu")
		(net "TDR_SE_50_OHM_TOP")
	)
	(segment
		(start -4.1148 -87.195914)
		(end -4.1148 -85.616542)
		(width 0.11684)
		(layer "F.Cu")
		(net "TDR_SE_50_OHM_TOP")
	)
	(segment
		(start -9.8425 -98.509328)
		(end -9.4996 -98.166428)
		(width 0.11684)
		(layer "F.Cu")
		(net "TDR_SE_50_OHM_TOP")
	)
	(segment
		(start -10.0584 -89.505028)
		(end -10.4013 -89.162128)
		(width 0.11684)
		(layer "F.Cu")
		(net "TDR_SE_50_OHM_TOP")
	)
	(segment
		(start -5.179314 -84.552028)
		(end -10.0584 -84.552028)
		(width 0.11684)
		(layer "F.Cu")
		(net "TDR_SE_50_OHM_TOP")
	)
	(segment
		(start -5.3467 -81.732628)
		(end -5.6896 -82.075528)
		(width 0.11684)
		(layer "F.Cu")
		(net "TDR_SE_50_OHM_TOP")
	)
	(segment
		(start -10.0584 -83.307428)
		(end -5.179314 -83.307428)
		(width 0.11684)
		(layer "F.Cu")
		(net "TDR_SE_50_OHM_TOP")
	)
	(segment
		(start -4.1148 -95.522542)
		(end -5.179314 -94.458028)
		(width 0.11684)
		(layer "F.Cu")
		(net "TDR_SE_50_OHM_TOP")
	)
	(segment
		(start -11.6332 -83.140042)
		(end -11.6332 -84.719414)
		(width 0.11684)
		(layer "F.Cu")
		(net "TDR_SE_50_OHM_TOP")
	)
	(segment
		(start -10.0584 -94.458028)
		(end -10.4013 -94.115128)
		(width 0.11684)
		(layer "F.Cu")
		(net "TDR_SE_50_OHM_TOP")
	)
	(segment
		(start -5.3467 -91.079828)
		(end -5.3467 -91.638628)
		(width 0.11684)
		(layer "F.Cu")
		(net "TDR_SE_50_OHM_TOP")
	)
	(segment
		(start -10.4013 -84.209128)
		(end -10.4013 -83.650328)
		(width 0.11684)
		(layer "F.Cu")
		(net "TDR_SE_50_OHM_TOP")
	)
	(segment
		(start -5.179314 -94.458028)
		(end -10.0584 -94.458028)
		(width 0.11684)
		(layer "F.Cu")
		(net "TDR_SE_50_OHM_TOP")
	)
	(segment
		(start -5.179314 -83.307428)
		(end -4.1148 -82.242914)
		(width 0.11684)
		(layer "F.Cu")
		(net "TDR_SE_50_OHM_TOP")
	)
	(segment
		(start -10.568686 -91.981528)
		(end -11.6332 -93.046042)
		(width 0.11684)
		(layer "F.Cu")
		(net "TDR_SE_50_OHM_TOP")
	)
	(segment
		(start -5.6896 -90.736928)
		(end -5.3467 -91.079828)
		(width 0.11684)
		(layer "F.Cu")
		(net "TDR_SE_50_OHM_TOP")
	)
	(segment
		(start -5.6896 -95.689928)
		(end -5.3467 -96.032828)
		(width 0.11684)
		(layer "F.Cu")
		(net "TDR_SE_50_OHM_TOP")
	)
	(segment
		(start -9.4996 -99.411028)
		(end -9.8425 -99.068128)
		(width 0.11684)
		(layer "F.Cu")
		(net "TDR_SE_50_OHM_TOP")
	)
	(segment
		(start -5.3467 -96.032828)
		(end -5.3467 -96.591628)
		(width 0.11684)
		(layer "F.Cu")
		(net "TDR_SE_50_OHM_TOP")
	)
	(segment
		(start -6.604 -103.325676)
		(end -6.397752 -103.119428)
		(width 0.11684)
		(layer "F.Cu")
		(net "TDR_SE_50_OHM_TOP")
	)
	(segment
		(start -6.604 -106.379264)
		(end -6.604 -103.325676)
		(width 0.11684)
		(layer "F.Cu")
		(net "TDR_SE_50_OHM_TOP")
	)
	(segment
		(start -11.6332 -93.046042)
		(end -11.6332 -94.625414)
		(width 0.11684)
		(layer "F.Cu")
		(net "TDR_SE_50_OHM_TOP")
	)
	(segment
		(start -5.3467 -100.985828)
		(end -5.3467 -101.544628)
		(width 0.11684)
		(layer "F.Cu")
		(net "TDR_SE_50_OHM_TOP")
	)
	(segment
		(start -4.1148 -85.616542)
		(end -5.179314 -84.552028)
		(width 0.11684)
		(layer "F.Cu")
		(net "TDR_SE_50_OHM_TOP")
	)
	(segment
		(start -5.3467 -81.173828)
		(end -5.3467 -81.732628)
		(width 0.11684)
		(layer "F.Cu")
		(net "TDR_SE_50_OHM_TOP")
	)
	(segment
		(start -10.4013 -88.603328)
		(end -10.0584 -88.260428)
		(width 0.11684)
		(layer "F.Cu")
		(net "TDR_SE_50_OHM_TOP")
	)
	(segment
		(start -6.397752 -103.119428)
		(end -5.179314 -103.119428)
		(width 0.11684)
		(layer "F.Cu")
		(net "TDR_SE_50_OHM_TOP")
	)
	(segment
		(start -5.6896 -82.075528)
		(end -10.568686 -82.075528)
		(width 0.11684)
		(layer "F.Cu")
		(net "TDR_SE_50_OHM_TOP")
	)
	(segment
		(start -9.144 -102.104444)
		(end -9.144 -106.379264)
		(width 0.11684)
		(layer "F.Cu")
		(net "TDR_SE_50_OHM_TOP")
	)
	(segment
		(start -5.6896 -101.887528)
		(end -8.927084 -101.887528)
		(width 0.11684)
		(layer "F.Cu")
		(net "TDR_SE_50_OHM_TOP")
	)
	(segment
		(start -5.3467 -86.126828)
		(end -5.3467 -86.685628)
		(width 0.11684)
		(layer "F.Cu")
		(net "TDR_SE_50_OHM_TOP")
	)
	(segment
		(start -5.179314 -88.260428)
		(end -4.1148 -87.195914)
		(width 0.11684)
		(layer "F.Cu")
		(net "TDR_SE_50_OHM_TOP")
	)
	(segment
		(start -10.568686 -95.689928)
		(end -5.6896 -95.689928)
		(width 0.11684)
		(layer "F.Cu")
		(net "TDR_SE_50_OHM_TOP")
	)
	(segment
		(start -5.3467 -101.544628)
		(end -5.6896 -101.887528)
		(width 0.11684)
		(layer "F.Cu")
		(net "TDR_SE_50_OHM_TOP")
	)
	(segment
		(start -5.179314 -93.213428)
		(end -4.1148 -92.148914)
		(width 0.11684)
		(layer "F.Cu")
		(net "TDR_SE_50_OHM_TOP")
	)
	(segment
		(start -5.6896 -80.830928)
		(end -5.3467 -81.173828)
		(width 0.11684)
		(layer "F.Cu")
		(net "TDR_SE_50_OHM_TOP")
	)
	(segment
		(start -11.0744 -97.999042)
		(end -11.0744 -99.578414)
		(width 0.11684)
		(layer "F.Cu")
		(net "TDR_SE_50_OHM_TOP")
	)
	(segment
		(start -5.6896 -91.981528)
		(end -10.568686 -91.981528)
		(width 0.11684)
		(layer "F.Cu")
		(net "TDR_SE_50_OHM_TOP")
	)
	(segment
		(start -4.1148 -90.569542)
		(end -5.179314 -89.505028)
		(width 0.11684)
		(layer "F.Cu")
		(net "TDR_SE_50_OHM_TOP")
	)
	(segment
		(start -5.179314 -79.599028)
		(end -9.2583 -79.599028)
		(width 0.11684)
		(layer "F.Cu")
		(net "TDR_SE_50_OHM_TOP")
	)
	(segment
		(start -9.2583 -79.599028)
		(end -9.6012 -79.941928)
		(width 0.11684)
		(layer "F.Cu")
		(net "TDR_SE_50_OHM_TOP")
	)
	(segment
		(start -10.4013 -93.556328)
		(end -10.0584 -93.213428)
		(width 0.11684)
		(layer "F.Cu")
		(net "TDR_SE_50_OHM_TOP")
	)
	(segment
		(start -10.0584 -93.213428)
		(end -5.179314 -93.213428)
		(width 0.11684)
		(layer "F.Cu")
		(net "TDR_SE_50_OHM_TOP")
	)
	(segment
		(start -5.6896 -96.934528)
		(end -10.009886 -96.934528)
		(width 0.11684)
		(layer "F.Cu")
		(net "TDR_SE_50_OHM_TOP")
	)
	(segment
		(start -5.3467 -91.638628)
		(end -5.6896 -91.981528)
		(width 0.11684)
		(layer "F.Cu")
		(net "TDR_SE_50_OHM_TOP")
	)
	(segment
		(start -10.4013 -94.115128)
		(end -10.4013 -93.556328)
		(width 0.11684)
		(layer "F.Cu")
		(net "TDR_SE_50_OHM_TOP")
	)
	(segment
		(start -10.568686 -85.783928)
		(end -5.6896 -85.783928)
		(width 0.11684)
		(layer "F.Cu")
		(net "TDR_SE_50_OHM_TOP")
	)
	(segment
		(start -5.6896 -85.783928)
		(end -5.3467 -86.126828)
		(width 0.11684)
		(layer "F.Cu")
		(net "TDR_SE_50_OHM_TOP")
	)
	(segment
		(start -11.6332 -94.625414)
		(end -10.568686 -95.689928)
		(width 0.11684)
		(layer "F.Cu")
		(net "TDR_SE_50_OHM_TOP")
	)
	(segment
		(start -9.6012 -79.941928)
		(end -9.6012 -80.488028)
		(width 0.11684)
		(layer "F.Cu")
		(net "TDR_SE_50_OHM_TOP")
	)
	(segment
		(start -5.179314 -98.166428)
		(end -4.1148 -97.101914)
		(width 0.11684)
		(layer "F.Cu")
		(net "TDR_SE_50_OHM_TOP")
	)
	(segment
		(start -4.1148 -100.475542)
		(end -5.179314 -99.411028)
		(width 0.11684)
		(layer "F.Cu")
		(net "TDR_SE_50_OHM_TOP")
	)
	(segment
		(start -5.3467 -96.591628)
		(end -5.6896 -96.934528)
		(width 0.11684)
		(layer "F.Cu")
		(net "TDR_SE_50_OHM_TOP")
	)
	(segment
		(start -10.0584 -88.260428)
		(end -5.179314 -88.260428)
		(width 0.11684)
		(layer "F.Cu")
		(net "TDR_SE_50_OHM_TOP")
	)
	(segment
		(start -10.009886 -96.934528)
		(end -11.0744 -97.999042)
		(width 0.11684)
		(layer "F.Cu")
		(net "TDR_SE_50_OHM_TOP")
	)
	(segment
		(start -4.1148 -92.148914)
		(end -4.1148 -90.569542)
		(width 0.11684)
		(layer "F.Cu")
		(net "TDR_SE_50_OHM_TOP")
	)
	(segment
		(start -11.0744 -99.578414)
		(end -10.009886 -100.642928)
		(width 0.11684)
		(layer "F.Cu")
		(net "TDR_SE_50_OHM_TOP")
	)
	(segment
		(start -9.4996 -98.166428)
		(end -5.179314 -98.166428)
		(width 0.11684)
		(layer "F.Cu")
		(net "TDR_SE_50_OHM_TOP")
	)
	(segment
		(start -4.1148 -102.054914)
		(end -4.1148 -100.475542)
		(width 0.11684)
		(layer "F.Cu")
		(net "TDR_SE_50_OHM_TOP")
	)
	(segment
		(start -10.568686 -90.736928)
		(end -5.6896 -90.736928)
		(width 0.11684)
		(layer "F.Cu")
		(net "TDR_SE_50_OHM_TOP")
	)
	(segment
		(start -10.009886 -100.642928)
		(end -5.6896 -100.642928)
		(width 0.11684)
		(layer "F.Cu")
		(net "TDR_SE_50_OHM_TOP")
	)
	(segment
		(start -4.1148 -97.101914)
		(end -4.1148 -95.522542)
		(width 0.11684)
		(layer "F.Cu")
		(net "TDR_SE_50_OHM_TOP")
	)
	(segment
		(start -8.927084 -101.887528)
		(end -9.144 -102.104444)
		(width 0.11684)
		(layer "F.Cu")
		(net "TDR_SE_50_OHM_TOP")
	)
	(segment
		(start -5.179314 -89.505028)
		(end -10.0584 -89.505028)
		(width 0.11684)
		(layer "F.Cu")
		(net "TDR_SE_50_OHM_TOP")
	)
	(segment
		(start -11.6332 -84.719414)
		(end -10.568686 -85.783928)
		(width 0.11684)
		(layer "F.Cu")
		(net "TDR_SE_50_OHM_TOP")
	)
	(segment
		(start -9.2583 -80.830928)
		(end -5.6896 -80.830928)
		(width 0.11684)
		(layer "F.Cu")
		(net "TDR_SE_50_OHM_TOP")
	)
	(segment
		(start -5.179314 -103.119428)
		(end -4.1148 -102.054914)
		(width 0.11684)
		(layer "F.Cu")
		(net "TDR_SE_50_OHM_TOP")
	)
	(segment
		(start -5.3467 -86.685628)
		(end -5.6896 -87.028528)
		(width 0.11684)
		(layer "F.Cu")
		(net "TDR_SE_50_OHM_TOP")
	)
	(segment
		(start -4.1148 -80.663542)
		(end -5.179314 -79.599028)
		(width 0.11684)
		(layer "F.Cu")
		(net "TDR_SE_50_OHM_TOP")
	)
	(segment
		(start -9.6012 -80.488028)
		(end -9.2583 -80.830928)
		(width 0.11684)
		(layer "F.Cu")
		(net "TDR_SE_50_OHM_TOP")
	)
	(segment
		(start -10.0584 -84.552028)
		(end -10.4013 -84.209128)
		(width 0.11684)
		(layer "F.Cu")
		(net "TDR_SE_50_OHM_TOP")
	)
	(segment
		(start -10.4013 -89.162128)
		(end -10.4013 -88.603328)
		(width 0.11684)
		(layer "F.Cu")
		(net "TDR_SE_50_OHM_TOP")
	)
	(segment
		(start -11.6332 -88.093042)
		(end -11.6332 -89.672414)
		(width 0.11684)
		(layer "F.Cu")
		(net "TDR_SE_50_OHM_TOP")
	)
	(segment
		(start -5.179314 -99.411028)
		(end -9.4996 -99.411028)
		(width 0.11684)
		(layer "F.Cu")
		(net "TDR_SE_50_OHM_TOP")
	)
	(segment
		(start -10.568686 -87.028528)
		(end -11.6332 -88.093042)
		(width 0.11684)
		(layer "F.Cu")
		(net "TDR_SE_50_OHM_TOP")
	)
	(segment
		(start -4.1148 -82.242914)
		(end -4.1148 -80.663542)
		(width 0.11684)
		(layer "F.Cu")
		(net "TDR_SE_50_OHM_TOP")
	)
	(segment
		(start -5.6896 -87.028528)
		(end -10.568686 -87.028528)
		(width 0.11684)
		(layer "F.Cu")
		(net "TDR_SE_50_OHM_TOP")
	)
	(segment
		(start -5.6896 -100.642928)
		(end -5.3467 -100.985828)
		(width 0.11684)
		(layer "F.Cu")
		(net "TDR_SE_50_OHM_TOP")
	)
	(segment
		(start -10.568686 -82.075528)
		(end -11.6332 -83.140042)
		(width 0.11684)
		(layer "F.Cu")
		(net "TDR_SE_50_OHM_TOP")
	)
	(segment
		(start -10.4013 -83.650328)
		(end -10.0584 -83.307428)
		(width 0.11684)
		(layer "F.Cu")
		(net "TDR_SE_50_OHM_TOP")
	)
	(segment
		(start -9.8425 -99.068128)
		(end -9.8425 -98.509328)
		(width 0.11684)
		(layer "F.Cu")
		(net "TDR_SE_50_OHM_TOP")
	)
	(segment
		(start -12.51585 -32.763968)
		(end -11.730228 -31.978346)
		(width 0.08382)
		(layer "In9.Cu")
		(net "TDR_SE_50_OHM_IN4")
	)
	(segment
		(start -16.380206 -31.864808)
		(end -17.165828 -32.65043)
		(width 0.08382)
		(layer "In9.Cu")
		(net "TDR_SE_50_OHM_IN4")
	)
	(segment
		(start -17.165828 -25.35555)
		(end -17.165828 -26.507186)
		(width 0.08382)
		(layer "In9.Cu")
		(net "TDR_SE_50_OHM_IN4")
	)
	(segment
		(start -16.007588 -33.688528)
		(end -16.266668 -33.429448)
		(width 0.08382)
		(layer "In9.Cu")
		(net "TDR_SE_50_OHM_IN4")
	)
	(segment
		(start -16.266668 -33.023048)
		(end -16.007588 -32.763968)
		(width 0.08382)
		(layer "In9.Cu")
		(net "TDR_SE_50_OHM_IN4")
	)
	(segment
		(start -16.007588 -26.393648)
		(end -16.266668 -26.134568)
		(width 0.08382)
		(layer "In9.Cu")
		(net "TDR_SE_50_OHM_IN4")
	)
	(segment
		(start -15.674086 -14.272768)
		(end -15.674086 -17.148048)
		(width 0.08382)
		(layer "In9.Cu")
		(net "TDR_SE_50_OHM_IN4")
	)
	(segment
		(start -11.730228 -39.273226)
		(end -11.730228 -38.12159)
		(width 0.08382)
		(layer "In9.Cu")
		(net "TDR_SE_50_OHM_IN4")
	)
	(segment
		(start -16.266668 -22.487128)
		(end -16.266668 -22.080728)
		(width 0.08382)
		(layer "In9.Cu")
		(net "TDR_SE_50_OHM_IN4")
	)
	(segment
		(start -15.674086 -17.148048)
		(end -15.801086 -17.275048)
		(width 0.08382)
		(layer "In9.Cu")
		(net "TDR_SE_50_OHM_IN4")
	)
	(segment
		(start -12.629388 -34.846768)
		(end -12.629388 -35.253168)
		(width 0.08382)
		(layer "In9.Cu")
		(net "TDR_SE_50_OHM_IN4")
	)
	(segment
		(start -12.629388 -23.904448)
		(end -12.629388 -24.310848)
		(width 0.08382)
		(layer "In9.Cu")
		(net "TDR_SE_50_OHM_IN4")
	)
	(segment
		(start -12.629388 -38.494208)
		(end -12.629388 -38.900608)
		(width 0.08382)
		(layer "In9.Cu")
		(net "TDR_SE_50_OHM_IN4")
	)
	(segment
		(start -17.165828 -40.9067)
		(end -16.91132 -41.161208)
		(width 0.08382)
		(layer "In9.Cu")
		(net "TDR_SE_50_OHM_IN4")
	)
	(segment
		(start -12.888468 -19.997928)
		(end -12.629388 -20.257008)
		(width 0.08382)
		(layer "In9.Cu")
		(net "TDR_SE_50_OHM_IN4")
	)
	(segment
		(start -16.007588 -36.411408)
		(end -12.51585 -36.411408)
		(width 0.08382)
		(layer "In9.Cu")
		(net "TDR_SE_50_OHM_IN4")
	)
	(segment
		(start -16.380206 -35.512248)
		(end -17.165828 -36.29787)
		(width 0.08382)
		(layer "In9.Cu")
		(net "TDR_SE_50_OHM_IN4")
	)
	(segment
		(start -16.91132 -41.161208)
		(end -16.53032 -41.161208)
		(width 0.08382)
		(layer "In9.Cu")
		(net "TDR_SE_50_OHM_IN4")
	)
	(segment
		(start -16.266668 -26.134568)
		(end -16.266668 -25.728168)
		(width 0.08382)
		(layer "In9.Cu")
		(net "TDR_SE_50_OHM_IN4")
	)
	(segment
		(start -12.51585 -21.821648)
		(end -11.730228 -21.036026)
		(width 0.08382)
		(layer "In9.Cu")
		(net "TDR_SE_50_OHM_IN4")
	)
	(segment
		(start -17.165828 -37.449506)
		(end -16.380206 -38.235128)
		(width 0.08382)
		(layer "In9.Cu")
		(net "TDR_SE_50_OHM_IN4")
	)
	(segment
		(start -11.730228 -23.53183)
		(end -12.51585 -22.746208)
		(width 0.08382)
		(layer "In9.Cu")
		(net "TDR_SE_50_OHM_IN4")
	)
	(segment
		(start -12.51585 -22.746208)
		(end -16.007588 -22.746208)
		(width 0.08382)
		(layer "In9.Cu")
		(net "TDR_SE_50_OHM_IN4")
	)
	(segment
		(start -16.380206 -30.940248)
		(end -12.888468 -30.940248)
		(width 0.08382)
		(layer "In9.Cu")
		(net "TDR_SE_50_OHM_IN4")
	)
	(segment
		(start -12.51585 -33.688528)
		(end -16.007588 -33.688528)
		(width 0.08382)
		(layer "In9.Cu")
		(net "TDR_SE_50_OHM_IN4")
	)
	(segment
		(start -12.51585 -29.116528)
		(end -11.730228 -28.330906)
		(width 0.08382)
		(layer "In9.Cu")
		(net "TDR_SE_50_OHM_IN4")
	)
	(segment
		(start -11.730228 -35.625786)
		(end -11.730228 -34.47415)
		(width 0.08382)
		(layer "In9.Cu")
		(net "TDR_SE_50_OHM_IN4")
	)
	(segment
		(start -12.888468 -24.569928)
		(end -16.380206 -24.569928)
		(width 0.08382)
		(layer "In9.Cu")
		(net "TDR_SE_50_OHM_IN4")
	)
	(segment
		(start -16.380206 -34.587688)
		(end -12.888468 -34.587688)
		(width 0.08382)
		(layer "In9.Cu")
		(net "TDR_SE_50_OHM_IN4")
	)
	(segment
		(start -12.888468 -38.235128)
		(end -12.629388 -38.494208)
		(width 0.08382)
		(layer "In9.Cu")
		(net "TDR_SE_50_OHM_IN4")
	)
	(segment
		(start -17.165828 -32.65043)
		(end -17.165828 -33.802066)
		(width 0.08382)
		(layer "In9.Cu")
		(net "TDR_SE_50_OHM_IN4")
	)
	(segment
		(start -17.165828 -19.212306)
		(end -16.380206 -19.997928)
		(width 0.08382)
		(layer "In9.Cu")
		(net "TDR_SE_50_OHM_IN4")
	)
	(segment
		(start -12.629388 -38.900608)
		(end -12.888468 -39.159688)
		(width 0.08382)
		(layer "In9.Cu")
		(net "TDR_SE_50_OHM_IN4")
	)
	(segment
		(start -16.380206 -27.292808)
		(end -12.888468 -27.292808)
		(width 0.08382)
		(layer "In9.Cu")
		(net "TDR_SE_50_OHM_IN4")
	)
	(segment
		(start -16.380206 -28.217368)
		(end -17.165828 -29.00299)
		(width 0.08382)
		(layer "In9.Cu")
		(net "TDR_SE_50_OHM_IN4")
	)
	(segment
		(start -15.801086 -17.275048)
		(end -16.380206 -17.275048)
		(width 0.08382)
		(layer "In9.Cu")
		(net "TDR_SE_50_OHM_IN4")
	)
	(segment
		(start -12.51585 -25.469088)
		(end -11.730228 -24.683466)
		(width 0.08382)
		(layer "In9.Cu")
		(net "TDR_SE_50_OHM_IN4")
	)
	(segment
		(start -16.266668 -25.728168)
		(end -16.007588 -25.469088)
		(width 0.08382)
		(layer "In9.Cu")
		(net "TDR_SE_50_OHM_IN4")
	)
	(segment
		(start -17.165828 -29.00299)
		(end -17.165828 -30.154626)
		(width 0.08382)
		(layer "In9.Cu")
		(net "TDR_SE_50_OHM_IN4")
	)
	(segment
		(start -16.266668 -37.076888)
		(end -16.266668 -36.670488)
		(width 0.08382)
		(layer "In9.Cu")
		(net "TDR_SE_50_OHM_IN4")
	)
	(segment
		(start -16.53032 -41.161208)
		(end -16.266668 -40.897556)
		(width 0.08382)
		(layer "In9.Cu")
		(net "TDR_SE_50_OHM_IN4")
	)
	(segment
		(start -12.888468 -39.159688)
		(end -16.380206 -39.159688)
		(width 0.08382)
		(layer "In9.Cu")
		(net "TDR_SE_50_OHM_IN4")
	)
	(segment
		(start -12.629388 -20.257008)
		(end -12.629388 -20.663408)
		(width 0.08382)
		(layer "In9.Cu")
		(net "TDR_SE_50_OHM_IN4")
	)
	(segment
		(start -11.730228 -28.330906)
		(end -11.730228 -27.17927)
		(width 0.08382)
		(layer "In9.Cu")
		(net "TDR_SE_50_OHM_IN4")
	)
	(segment
		(start -12.888468 -30.940248)
		(end -12.629388 -31.199328)
		(width 0.08382)
		(layer "In9.Cu")
		(net "TDR_SE_50_OHM_IN4")
	)
	(segment
		(start -11.730228 -34.47415)
		(end -12.51585 -33.688528)
		(width 0.08382)
		(layer "In9.Cu")
		(net "TDR_SE_50_OHM_IN4")
	)
	(segment
		(start -12.888468 -34.587688)
		(end -12.629388 -34.846768)
		(width 0.08382)
		(layer "In9.Cu")
		(net "TDR_SE_50_OHM_IN4")
	)
	(segment
		(start -16.380206 -19.997928)
		(end -12.888468 -19.997928)
		(width 0.08382)
		(layer "In9.Cu")
		(net "TDR_SE_50_OHM_IN4")
	)
	(segment
		(start -16.266668 -29.782008)
		(end -16.266668 -29.375608)
		(width 0.08382)
		(layer "In9.Cu")
		(net "TDR_SE_50_OHM_IN4")
	)
	(segment
		(start -11.730228 -27.17927)
		(end -12.51585 -26.393648)
		(width 0.08382)
		(layer "In9.Cu")
		(net "TDR_SE_50_OHM_IN4")
	)
	(segment
		(start -17.165828 -36.29787)
		(end -17.165828 -37.449506)
		(width 0.08382)
		(layer "In9.Cu")
		(net "TDR_SE_50_OHM_IN4")
	)
	(segment
		(start -16.007588 -21.821648)
		(end -12.51585 -21.821648)
		(width 0.08382)
		(layer "In9.Cu")
		(net "TDR_SE_50_OHM_IN4")
	)
	(segment
		(start -12.629388 -20.663408)
		(end -12.888468 -20.922488)
		(width 0.08382)
		(layer "In9.Cu")
		(net "TDR_SE_50_OHM_IN4")
	)
	(segment
		(start -12.51585 -36.411408)
		(end -11.730228 -35.625786)
		(width 0.08382)
		(layer "In9.Cu")
		(net "TDR_SE_50_OHM_IN4")
	)
	(segment
		(start -13.261086 -18.174208)
		(end -13.134086 -18.047208)
		(width 0.08382)
		(layer "In9.Cu")
		(net "TDR_SE_50_OHM_IN4")
	)
	(segment
		(start -12.629388 -27.551888)
		(end -12.629388 -27.958288)
		(width 0.08382)
		(layer "In9.Cu")
		(net "TDR_SE_50_OHM_IN4")
	)
	(segment
		(start -13.134086 -18.047208)
		(end -13.134086 -14.272768)
		(width 0.08382)
		(layer "In9.Cu")
		(net "TDR_SE_50_OHM_IN4")
	)
	(segment
		(start -16.007588 -25.469088)
		(end -12.51585 -25.469088)
		(width 0.08382)
		(layer "In9.Cu")
		(net "TDR_SE_50_OHM_IN4")
	)
	(segment
		(start -12.629388 -31.605728)
		(end -12.888468 -31.864808)
		(width 0.08382)
		(layer "In9.Cu")
		(net "TDR_SE_50_OHM_IN4")
	)
	(segment
		(start -12.51585 -30.041088)
		(end -16.007588 -30.041088)
		(width 0.08382)
		(layer "In9.Cu")
		(net "TDR_SE_50_OHM_IN4")
	)
	(segment
		(start -17.165828 -26.507186)
		(end -16.380206 -27.292808)
		(width 0.08382)
		(layer "In9.Cu")
		(net "TDR_SE_50_OHM_IN4")
	)
	(segment
		(start -16.380206 -20.922488)
		(end -17.165828 -21.70811)
		(width 0.08382)
		(layer "In9.Cu")
		(net "TDR_SE_50_OHM_IN4")
	)
	(segment
		(start -12.51585 -19.098768)
		(end -16.007588 -19.098768)
		(width 0.08382)
		(layer "In9.Cu")
		(net "TDR_SE_50_OHM_IN4")
	)
	(segment
		(start -12.888468 -28.217368)
		(end -16.380206 -28.217368)
		(width 0.08382)
		(layer "In9.Cu")
		(net "TDR_SE_50_OHM_IN4")
	)
	(segment
		(start -12.629388 -27.958288)
		(end -12.888468 -28.217368)
		(width 0.08382)
		(layer "In9.Cu")
		(net "TDR_SE_50_OHM_IN4")
	)
	(segment
		(start -16.266668 -22.080728)
		(end -16.007588 -21.821648)
		(width 0.08382)
		(layer "In9.Cu")
		(net "TDR_SE_50_OHM_IN4")
	)
	(segment
		(start -16.380206 -24.569928)
		(end -17.165828 -25.35555)
		(width 0.08382)
		(layer "In9.Cu")
		(net "TDR_SE_50_OHM_IN4")
	)
	(segment
		(start -16.266668 -40.317928)
		(end -16.007588 -40.058848)
		(width 0.08382)
		(layer "In9.Cu")
		(net "TDR_SE_50_OHM_IN4")
	)
	(segment
		(start -11.730228 -30.82671)
		(end -12.51585 -30.041088)
		(width 0.08382)
		(layer "In9.Cu")
		(net "TDR_SE_50_OHM_IN4")
	)
	(segment
		(start -16.266668 -18.839688)
		(end -16.266668 -18.433288)
		(width 0.08382)
		(layer "In9.Cu")
		(net "TDR_SE_50_OHM_IN4")
	)
	(segment
		(start -16.007588 -19.098768)
		(end -16.266668 -18.839688)
		(width 0.08382)
		(layer "In9.Cu")
		(net "TDR_SE_50_OHM_IN4")
	)
	(segment
		(start -17.165828 -18.06067)
		(end -17.165828 -19.212306)
		(width 0.08382)
		(layer "In9.Cu")
		(net "TDR_SE_50_OHM_IN4")
	)
	(segment
		(start -12.888468 -31.864808)
		(end -16.380206 -31.864808)
		(width 0.08382)
		(layer "In9.Cu")
		(net "TDR_SE_50_OHM_IN4")
	)
	(segment
		(start -12.629388 -24.310848)
		(end -12.888468 -24.569928)
		(width 0.08382)
		(layer "In9.Cu")
		(net "TDR_SE_50_OHM_IN4")
	)
	(segment
		(start -16.380206 -38.235128)
		(end -12.888468 -38.235128)
		(width 0.08382)
		(layer "In9.Cu")
		(net "TDR_SE_50_OHM_IN4")
	)
	(segment
		(start -17.165828 -21.70811)
		(end -17.165828 -22.859746)
		(width 0.08382)
		(layer "In9.Cu")
		(net "TDR_SE_50_OHM_IN4")
	)
	(segment
		(start -16.266668 -33.429448)
		(end -16.266668 -33.023048)
		(width 0.08382)
		(layer "In9.Cu")
		(net "TDR_SE_50_OHM_IN4")
	)
	(segment
		(start -12.629388 -35.253168)
		(end -12.888468 -35.512248)
		(width 0.08382)
		(layer "In9.Cu")
		(net "TDR_SE_50_OHM_IN4")
	)
	(segment
		(start -16.266668 -18.433288)
		(end -16.007588 -18.174208)
		(width 0.08382)
		(layer "In9.Cu")
		(net "TDR_SE_50_OHM_IN4")
	)
	(segment
		(start -16.007588 -32.763968)
		(end -12.51585 -32.763968)
		(width 0.08382)
		(layer "In9.Cu")
		(net "TDR_SE_50_OHM_IN4")
	)
	(segment
		(start -16.266668 -40.897556)
		(end -16.266668 -40.317928)
		(width 0.08382)
		(layer "In9.Cu")
		(net "TDR_SE_50_OHM_IN4")
	)
	(segment
		(start -11.730228 -31.978346)
		(end -11.730228 -30.82671)
		(width 0.08382)
		(layer "In9.Cu")
		(net "TDR_SE_50_OHM_IN4")
	)
	(segment
		(start -16.380206 -23.645368)
		(end -12.888468 -23.645368)
		(width 0.08382)
		(layer "In9.Cu")
		(net "TDR_SE_50_OHM_IN4")
	)
	(segment
		(start -16.007588 -29.116528)
		(end -12.51585 -29.116528)
		(width 0.08382)
		(layer "In9.Cu")
		(net "TDR_SE_50_OHM_IN4")
	)
	(segment
		(start -17.165828 -39.94531)
		(end -17.165828 -40.9067)
		(width 0.08382)
		(layer "In9.Cu")
		(net "TDR_SE_50_OHM_IN4")
	)
	(segment
		(start -16.266668 -29.375608)
		(end -16.007588 -29.116528)
		(width 0.08382)
		(layer "In9.Cu")
		(net "TDR_SE_50_OHM_IN4")
	)
	(segment
		(start -11.730228 -21.036026)
		(end -11.730228 -19.88439)
		(width 0.08382)
		(layer "In9.Cu")
		(net "TDR_SE_50_OHM_IN4")
	)
	(segment
		(start -16.266668 -36.670488)
		(end -16.007588 -36.411408)
		(width 0.08382)
		(layer "In9.Cu")
		(net "TDR_SE_50_OHM_IN4")
	)
	(segment
		(start -17.165828 -22.859746)
		(end -16.380206 -23.645368)
		(width 0.08382)
		(layer "In9.Cu")
		(net "TDR_SE_50_OHM_IN4")
	)
	(segment
		(start -16.007588 -22.746208)
		(end -16.266668 -22.487128)
		(width 0.08382)
		(layer "In9.Cu")
		(net "TDR_SE_50_OHM_IN4")
	)
	(segment
		(start -12.51585 -37.335968)
		(end -16.007588 -37.335968)
		(width 0.08382)
		(layer "In9.Cu")
		(net "TDR_SE_50_OHM_IN4")
	)
	(segment
		(start -16.007588 -40.058848)
		(end -12.51585 -40.058848)
		(width 0.08382)
		(layer "In9.Cu")
		(net "TDR_SE_50_OHM_IN4")
	)
	(segment
		(start -16.007588 -37.335968)
		(end -16.266668 -37.076888)
		(width 0.08382)
		(layer "In9.Cu")
		(net "TDR_SE_50_OHM_IN4")
	)
	(segment
		(start -16.007588 -30.041088)
		(end -16.266668 -29.782008)
		(width 0.08382)
		(layer "In9.Cu")
		(net "TDR_SE_50_OHM_IN4")
	)
	(segment
		(start -17.165828 -30.154626)
		(end -16.380206 -30.940248)
		(width 0.08382)
		(layer "In9.Cu")
		(net "TDR_SE_50_OHM_IN4")
	)
	(segment
		(start -16.007588 -18.174208)
		(end -13.261086 -18.174208)
		(width 0.08382)
		(layer "In9.Cu")
		(net "TDR_SE_50_OHM_IN4")
	)
	(segment
		(start -16.380206 -39.159688)
		(end -17.165828 -39.94531)
		(width 0.08382)
		(layer "In9.Cu")
		(net "TDR_SE_50_OHM_IN4")
	)
	(segment
		(start -16.380206 -17.275048)
		(end -17.165828 -18.06067)
		(width 0.08382)
		(layer "In9.Cu")
		(net "TDR_SE_50_OHM_IN4")
	)
	(segment
		(start -12.888468 -20.922488)
		(end -16.380206 -20.922488)
		(width 0.08382)
		(layer "In9.Cu")
		(net "TDR_SE_50_OHM_IN4")
	)
	(segment
		(start -12.888468 -35.512248)
		(end -16.380206 -35.512248)
		(width 0.08382)
		(layer "In9.Cu")
		(net "TDR_SE_50_OHM_IN4")
	)
	(segment
		(start -11.730228 -24.683466)
		(end -11.730228 -23.53183)
		(width 0.08382)
		(layer "In9.Cu")
		(net "TDR_SE_50_OHM_IN4")
	)
	(segment
		(start -11.730228 -19.88439)
		(end -12.51585 -19.098768)
		(width 0.08382)
		(layer "In9.Cu")
		(net "TDR_SE_50_OHM_IN4")
	)
	(segment
		(start -12.51585 -40.058848)
		(end -11.730228 -39.273226)
		(width 0.08382)
		(layer "In9.Cu")
		(net "TDR_SE_50_OHM_IN4")
	)
	(segment
		(start -11.730228 -38.12159)
		(end -12.51585 -37.335968)
		(width 0.08382)
		(layer "In9.Cu")
		(net "TDR_SE_50_OHM_IN4")
	)
	(segment
		(start -12.629388 -31.199328)
		(end -12.629388 -31.605728)
		(width 0.08382)
		(layer "In9.Cu")
		(net "TDR_SE_50_OHM_IN4")
	)
	(segment
		(start -17.165828 -33.802066)
		(end -16.380206 -34.587688)
		(width 0.08382)
		(layer "In9.Cu")
		(net "TDR_SE_50_OHM_IN4")
	)
	(segment
		(start -12.51585 -26.393648)
		(end -16.007588 -26.393648)
		(width 0.08382)
		(layer "In9.Cu")
		(net "TDR_SE_50_OHM_IN4")
	)
	(segment
		(start -12.888468 -23.645368)
		(end -12.629388 -23.904448)
		(width 0.08382)
		(layer "In9.Cu")
		(net "TDR_SE_50_OHM_IN4")
	)
	(segment
		(start -12.888468 -27.292808)
		(end -12.629388 -27.551888)
		(width 0.08382)
		(layer "In9.Cu")
		(net "TDR_SE_50_OHM_IN4")
	)
	(segment
		(start -9.54786 -45.900848)
		(end -5.36194 -45.900848)
		(width 0.10668)
		(layer "In7.Cu")
		(net "TDR_SE_50_OHM_IN3")
	)
	(segment
		(start -9.54786 -43.117008)
		(end -9.82472 -42.840148)
		(width 0.10668)
		(layer "In7.Cu")
		(net "TDR_SE_50_OHM_IN3")
	)
	(segment
		(start -4.5466 -41.356788)
		(end -4.5466 -40.203628)
		(width 0.10668)
		(layer "In7.Cu")
		(net "TDR_SE_50_OHM_IN3")
	)
	(segment
		(start -8.65251 -40.307768)
		(end -5.74294 -40.307768)
		(width 0.10668)
		(layer "In7.Cu")
		(net "TDR_SE_50_OHM_IN3")
	)
	(segment
		(start -10.7442 -58.136028)
		(end -9.92886 -58.951368)
		(width 0.10668)
		(layer "In7.Cu")
		(net "TDR_SE_50_OHM_IN3")
	)
	(segment
		(start -5.74294 -52.438808)
		(end -9.92886 -52.438808)
		(width 0.10668)
		(layer "In7.Cu")
		(net "TDR_SE_50_OHM_IN3")
	)
	(segment
		(start -10.7442 -53.254148)
		(end -10.7442 -54.407308)
		(width 0.10668)
		(layer "In7.Cu")
		(net "TDR_SE_50_OHM_IN3")
	)
	(segment
		(start -10.7442 -50.678588)
		(end -9.92886 -51.493928)
		(width 0.10668)
		(layer "In7.Cu")
		(net "TDR_SE_50_OHM_IN3")
	)
	(segment
		(start -9.54786 -42.172128)
		(end -5.36194 -42.172128)
		(width 0.10668)
		(layer "In7.Cu")
		(net "TDR_SE_50_OHM_IN3")
	)
	(segment
		(start -4.5466 -43.932348)
		(end -5.36194 -43.117008)
		(width 0.10668)
		(layer "In7.Cu")
		(net "TDR_SE_50_OHM_IN3")
	)
	(segment
		(start -5.36194 -60.815728)
		(end -4.5466 -60.000388)
		(width 0.10668)
		(layer "In7.Cu")
		(net "TDR_SE_50_OHM_IN3")
	)
	(segment
		(start -5.36194 -49.629568)
		(end -4.5466 -48.814228)
		(width 0.10668)
		(layer "In7.Cu")
		(net "TDR_SE_50_OHM_IN3")
	)
	(segment
		(start -6.3754 -60.942728)
		(end -6.2484 -60.815728)
		(width 0.10668)
		(layer "In7.Cu")
		(net "TDR_SE_50_OHM_IN3")
	)
	(segment
		(start -9.54786 -57.087008)
		(end -5.36194 -57.087008)
		(width 0.10668)
		(layer "In7.Cu")
		(net "TDR_SE_50_OHM_IN3")
	)
	(segment
		(start -5.74294 -51.493928)
		(end -5.46608 -51.770788)
		(width 0.10668)
		(layer "In7.Cu")
		(net "TDR_SE_50_OHM_IN3")
	)
	(segment
		(start -9.82472 -42.840148)
		(end -9.82472 -42.448988)
		(width 0.10668)
		(layer "In7.Cu")
		(net "TDR_SE_50_OHM_IN3")
	)
	(segment
		(start -9.92886 -48.710088)
		(end -10.7442 -49.525428)
		(width 0.10668)
		(layer "In7.Cu")
		(net "TDR_SE_50_OHM_IN3")
	)
	(segment
		(start -4.5466 -58.847228)
		(end -5.36194 -58.031888)
		(width 0.10668)
		(layer "In7.Cu")
		(net "TDR_SE_50_OHM_IN3")
	)
	(segment
		(start -8.856726 -39.610792)
		(end -8.856726 -40.103552)
		(width 0.10668)
		(layer "In7.Cu")
		(net "TDR_SE_50_OHM_IN3")
	)
	(segment
		(start -9.92886 -55.222648)
		(end -5.74294 -55.222648)
		(width 0.10668)
		(layer "In7.Cu")
		(net "TDR_SE_50_OHM_IN3")
	)
	(segment
		(start -8.7884 -59.896248)
		(end -8.9154 -60.023248)
		(width 0.10668)
		(layer "In7.Cu")
		(net "TDR_SE_50_OHM_IN3")
	)
	(segment
		(start -10.7442 -42.067988)
		(end -10.7442 -43.221148)
		(width 0.10668)
		(layer "In7.Cu")
		(net "TDR_SE_50_OHM_IN3")
	)
	(segment
		(start -10.7442 -45.796708)
		(end -10.7442 -46.949868)
		(width 0.10668)
		(layer "In7.Cu")
		(net "TDR_SE_50_OHM_IN3")
	)
	(segment
		(start -5.36194 -54.303168)
		(end -9.54786 -54.303168)
		(width 0.10668)
		(layer "In7.Cu")
		(net "TDR_SE_50_OHM_IN3")
	)
	(segment
		(start -9.54786 -46.845728)
		(end -9.82472 -46.568868)
		(width 0.10668)
		(layer "In7.Cu")
		(net "TDR_SE_50_OHM_IN3")
	)
	(segment
		(start -4.5466 -60.000388)
		(end -4.5466 -58.847228)
		(width 0.10668)
		(layer "In7.Cu")
		(net "TDR_SE_50_OHM_IN3")
	)
	(segment
		(start -4.5466 -40.203628)
		(end -5.36194 -39.388288)
		(width 0.10668)
		(layer "In7.Cu")
		(net "TDR_SE_50_OHM_IN3")
	)
	(segment
		(start -5.46608 -40.975788)
		(end -5.74294 -41.252648)
		(width 0.10668)
		(layer "In7.Cu")
		(net "TDR_SE_50_OHM_IN3")
	)
	(segment
		(start -10.7442 -56.982868)
		(end -10.7442 -58.136028)
		(width 0.10668)
		(layer "In7.Cu")
		(net "TDR_SE_50_OHM_IN3")
	)
	(segment
		(start -5.46608 -40.584628)
		(end -5.46608 -40.975788)
		(width 0.10668)
		(layer "In7.Cu")
		(net "TDR_SE_50_OHM_IN3")
	)
	(segment
		(start -5.36194 -57.087008)
		(end -4.5466 -56.271668)
		(width 0.10668)
		(layer "In7.Cu")
		(net "TDR_SE_50_OHM_IN3")
	)
	(segment
		(start -9.92886 -58.951368)
		(end -5.74294 -58.951368)
		(width 0.10668)
		(layer "In7.Cu")
		(net "TDR_SE_50_OHM_IN3")
	)
	(segment
		(start -4.5466 -56.271668)
		(end -4.5466 -55.118508)
		(width 0.10668)
		(layer "In7.Cu")
		(net "TDR_SE_50_OHM_IN3")
	)
	(segment
		(start -9.92886 -41.252648)
		(end -10.7442 -42.067988)
		(width 0.10668)
		(layer "In7.Cu")
		(net "TDR_SE_50_OHM_IN3")
	)
	(segment
		(start -4.5466 -45.085508)
		(end -4.5466 -43.932348)
		(width 0.10668)
		(layer "In7.Cu")
		(net "TDR_SE_50_OHM_IN3")
	)
	(segment
		(start -10.7442 -49.525428)
		(end -10.7442 -50.678588)
		(width 0.10668)
		(layer "In7.Cu")
		(net "TDR_SE_50_OHM_IN3")
	)
	(segment
		(start -8.9154 -60.023248)
		(end -8.9154 -63.580264)
		(width 0.10668)
		(layer "In7.Cu")
		(net "TDR_SE_50_OHM_IN3")
	)
	(segment
		(start -9.82472 -49.906428)
		(end -9.54786 -49.629568)
		(width 0.10668)
		(layer "In7.Cu")
		(net "TDR_SE_50_OHM_IN3")
	)
	(segment
		(start -5.74294 -59.896248)
		(end -8.7884 -59.896248)
		(width 0.10668)
		(layer "In7.Cu")
		(net "TDR_SE_50_OHM_IN3")
	)
	(segment
		(start -5.74294 -55.222648)
		(end -5.46608 -55.499508)
		(width 0.10668)
		(layer "In7.Cu")
		(net "TDR_SE_50_OHM_IN3")
	)
	(segment
		(start -9.54786 -54.303168)
		(end -9.82472 -54.026308)
		(width 0.10668)
		(layer "In7.Cu")
		(net "TDR_SE_50_OHM_IN3")
	)
	(segment
		(start -9.82472 -57.755028)
		(end -9.82472 -57.363868)
		(width 0.10668)
		(layer "In7.Cu")
		(net "TDR_SE_50_OHM_IN3")
	)
	(segment
		(start -9.54786 -50.574448)
		(end -9.82472 -50.297588)
		(width 0.10668)
		(layer "In7.Cu")
		(net "TDR_SE_50_OHM_IN3")
	)
	(segment
		(start -8.856726 -40.103552)
		(end -8.65251 -40.307768)
		(width 0.10668)
		(layer "In7.Cu")
		(net "TDR_SE_50_OHM_IN3")
	)
	(segment
		(start -9.82472 -54.026308)
		(end -9.82472 -53.635148)
		(width 0.10668)
		(layer "In7.Cu")
		(net "TDR_SE_50_OHM_IN3")
	)
	(segment
		(start -5.36194 -42.172128)
		(end -4.5466 -41.356788)
		(width 0.10668)
		(layer "In7.Cu")
		(net "TDR_SE_50_OHM_IN3")
	)
	(segment
		(start -5.46608 -48.042068)
		(end -5.46608 -48.433228)
		(width 0.10668)
		(layer "In7.Cu")
		(net "TDR_SE_50_OHM_IN3")
	)
	(segment
		(start -5.36194 -39.388288)
		(end -8.634222 -39.388288)
		(width 0.10668)
		(layer "In7.Cu")
		(net "TDR_SE_50_OHM_IN3")
	)
	(segment
		(start -5.74294 -44.981368)
		(end -9.92886 -44.981368)
		(width 0.10668)
		(layer "In7.Cu")
		(net "TDR_SE_50_OHM_IN3")
	)
	(segment
		(start -6.3754 -63.580264)
		(end -6.3754 -60.942728)
		(width 0.10668)
		(layer "In7.Cu")
		(net "TDR_SE_50_OHM_IN3")
	)
	(segment
		(start -4.5466 -48.814228)
		(end -4.5466 -47.661068)
		(width 0.10668)
		(layer "In7.Cu")
		(net "TDR_SE_50_OHM_IN3")
	)
	(segment
		(start -5.74294 -41.252648)
		(end -9.92886 -41.252648)
		(width 0.10668)
		(layer "In7.Cu")
		(net "TDR_SE_50_OHM_IN3")
	)
	(segment
		(start -9.54786 -58.031888)
		(end -9.82472 -57.755028)
		(width 0.10668)
		(layer "In7.Cu")
		(net "TDR_SE_50_OHM_IN3")
	)
	(segment
		(start -5.36194 -45.900848)
		(end -4.5466 -45.085508)
		(width 0.10668)
		(layer "In7.Cu")
		(net "TDR_SE_50_OHM_IN3")
	)
	(segment
		(start -5.46608 -44.313348)
		(end -5.46608 -44.704508)
		(width 0.10668)
		(layer "In7.Cu")
		(net "TDR_SE_50_OHM_IN3")
	)
	(segment
		(start -9.82472 -46.177708)
		(end -9.54786 -45.900848)
		(width 0.10668)
		(layer "In7.Cu")
		(net "TDR_SE_50_OHM_IN3")
	)
	(segment
		(start -8.634222 -39.388288)
		(end -8.856726 -39.610792)
		(width 0.10668)
		(layer "In7.Cu")
		(net "TDR_SE_50_OHM_IN3")
	)
	(segment
		(start -4.5466 -51.389788)
		(end -5.36194 -50.574448)
		(width 0.10668)
		(layer "In7.Cu")
		(net "TDR_SE_50_OHM_IN3")
	)
	(segment
		(start -9.82472 -46.568868)
		(end -9.82472 -46.177708)
		(width 0.10668)
		(layer "In7.Cu")
		(net "TDR_SE_50_OHM_IN3")
	)
	(segment
		(start -5.74294 -48.710088)
		(end -9.92886 -48.710088)
		(width 0.10668)
		(layer "In7.Cu")
		(net "TDR_SE_50_OHM_IN3")
	)
	(segment
		(start -9.92886 -44.036488)
		(end -5.74294 -44.036488)
		(width 0.10668)
		(layer "In7.Cu")
		(net "TDR_SE_50_OHM_IN3")
	)
	(segment
		(start -5.74294 -47.765208)
		(end -5.46608 -48.042068)
		(width 0.10668)
		(layer "In7.Cu")
		(net "TDR_SE_50_OHM_IN3")
	)
	(segment
		(start -5.74294 -58.951368)
		(end -5.46608 -59.228228)
		(width 0.10668)
		(layer "In7.Cu")
		(net "TDR_SE_50_OHM_IN3")
	)
	(segment
		(start -9.82472 -57.363868)
		(end -9.54786 -57.087008)
		(width 0.10668)
		(layer "In7.Cu")
		(net "TDR_SE_50_OHM_IN3")
	)
	(segment
		(start -9.54786 -53.358288)
		(end -5.36194 -53.358288)
		(width 0.10668)
		(layer "In7.Cu")
		(net "TDR_SE_50_OHM_IN3")
	)
	(segment
		(start -9.92886 -56.167528)
		(end -10.7442 -56.982868)
		(width 0.10668)
		(layer "In7.Cu")
		(net "TDR_SE_50_OHM_IN3")
	)
	(segment
		(start -5.46608 -55.499508)
		(end -5.46608 -55.890668)
		(width 0.10668)
		(layer "In7.Cu")
		(net "TDR_SE_50_OHM_IN3")
	)
	(segment
		(start -9.92886 -44.981368)
		(end -10.7442 -45.796708)
		(width 0.10668)
		(layer "In7.Cu")
		(net "TDR_SE_50_OHM_IN3")
	)
	(segment
		(start -9.82472 -53.635148)
		(end -9.54786 -53.358288)
		(width 0.10668)
		(layer "In7.Cu")
		(net "TDR_SE_50_OHM_IN3")
	)
	(segment
		(start -5.46608 -59.619388)
		(end -5.74294 -59.896248)
		(width 0.10668)
		(layer "In7.Cu")
		(net "TDR_SE_50_OHM_IN3")
	)
	(segment
		(start -9.82472 -50.297588)
		(end -9.82472 -49.906428)
		(width 0.10668)
		(layer "In7.Cu")
		(net "TDR_SE_50_OHM_IN3")
	)
	(segment
		(start -5.46608 -48.433228)
		(end -5.74294 -48.710088)
		(width 0.10668)
		(layer "In7.Cu")
		(net "TDR_SE_50_OHM_IN3")
	)
	(segment
		(start -9.92886 -47.765208)
		(end -5.74294 -47.765208)
		(width 0.10668)
		(layer "In7.Cu")
		(net "TDR_SE_50_OHM_IN3")
	)
	(segment
		(start -5.46608 -52.161948)
		(end -5.74294 -52.438808)
		(width 0.10668)
		(layer "In7.Cu")
		(net "TDR_SE_50_OHM_IN3")
	)
	(segment
		(start -4.5466 -55.118508)
		(end -5.36194 -54.303168)
		(width 0.10668)
		(layer "In7.Cu")
		(net "TDR_SE_50_OHM_IN3")
	)
	(segment
		(start -9.54786 -49.629568)
		(end -5.36194 -49.629568)
		(width 0.10668)
		(layer "In7.Cu")
		(net "TDR_SE_50_OHM_IN3")
	)
	(segment
		(start -5.36194 -43.117008)
		(end -9.54786 -43.117008)
		(width 0.10668)
		(layer "In7.Cu")
		(net "TDR_SE_50_OHM_IN3")
	)
	(segment
		(start -9.82472 -42.448988)
		(end -9.54786 -42.172128)
		(width 0.10668)
		(layer "In7.Cu")
		(net "TDR_SE_50_OHM_IN3")
	)
	(segment
		(start -5.74294 -40.307768)
		(end -5.46608 -40.584628)
		(width 0.10668)
		(layer "In7.Cu")
		(net "TDR_SE_50_OHM_IN3")
	)
	(segment
		(start -10.7442 -43.221148)
		(end -9.92886 -44.036488)
		(width 0.10668)
		(layer "In7.Cu")
		(net "TDR_SE_50_OHM_IN3")
	)
	(segment
		(start -5.36194 -46.845728)
		(end -9.54786 -46.845728)
		(width 0.10668)
		(layer "In7.Cu")
		(net "TDR_SE_50_OHM_IN3")
	)
	(segment
		(start -5.36194 -58.031888)
		(end -9.54786 -58.031888)
		(width 0.10668)
		(layer "In7.Cu")
		(net "TDR_SE_50_OHM_IN3")
	)
	(segment
		(start -5.36194 -53.358288)
		(end -4.5466 -52.542948)
		(width 0.10668)
		(layer "In7.Cu")
		(net "TDR_SE_50_OHM_IN3")
	)
	(segment
		(start -5.46608 -51.770788)
		(end -5.46608 -52.161948)
		(width 0.10668)
		(layer "In7.Cu")
		(net "TDR_SE_50_OHM_IN3")
	)
	(segment
		(start -5.46608 -59.228228)
		(end -5.46608 -59.619388)
		(width 0.10668)
		(layer "In7.Cu")
		(net "TDR_SE_50_OHM_IN3")
	)
	(segment
		(start -5.74294 -56.167528)
		(end -9.92886 -56.167528)
		(width 0.10668)
		(layer "In7.Cu")
		(net "TDR_SE_50_OHM_IN3")
	)
	(segment
		(start -6.2484 -60.815728)
		(end -5.36194 -60.815728)
		(width 0.10668)
		(layer "In7.Cu")
		(net "TDR_SE_50_OHM_IN3")
	)
	(segment
		(start -9.92886 -52.438808)
		(end -10.7442 -53.254148)
		(width 0.10668)
		(layer "In7.Cu")
		(net "TDR_SE_50_OHM_IN3")
	)
	(segment
		(start -5.36194 -50.574448)
		(end -9.54786 -50.574448)
		(width 0.10668)
		(layer "In7.Cu")
		(net "TDR_SE_50_OHM_IN3")
	)
	(segment
		(start -10.7442 -54.407308)
		(end -9.92886 -55.222648)
		(width 0.10668)
		(layer "In7.Cu")
		(net "TDR_SE_50_OHM_IN3")
	)
	(segment
		(start -10.7442 -46.949868)
		(end -9.92886 -47.765208)
		(width 0.10668)
		(layer "In7.Cu")
		(net "TDR_SE_50_OHM_IN3")
	)
	(segment
		(start -9.92886 -51.493928)
		(end -5.74294 -51.493928)
		(width 0.10668)
		(layer "In7.Cu")
		(net "TDR_SE_50_OHM_IN3")
	)
	(segment
		(start -4.5466 -52.542948)
		(end -4.5466 -51.389788)
		(width 0.10668)
		(layer "In7.Cu")
		(net "TDR_SE_50_OHM_IN3")
	)
	(segment
		(start -5.74294 -44.036488)
		(end -5.46608 -44.313348)
		(width 0.10668)
		(layer "In7.Cu")
		(net "TDR_SE_50_OHM_IN3")
	)
	(segment
		(start -5.46608 -55.890668)
		(end -5.74294 -56.167528)
		(width 0.10668)
		(layer "In7.Cu")
		(net "TDR_SE_50_OHM_IN3")
	)
	(segment
		(start -4.5466 -47.661068)
		(end -5.36194 -46.845728)
		(width 0.10668)
		(layer "In7.Cu")
		(net "TDR_SE_50_OHM_IN3")
	)
	(segment
		(start -5.46608 -44.704508)
		(end -5.74294 -44.981368)
		(width 0.10668)
		(layer "In7.Cu")
		(net "TDR_SE_50_OHM_IN3")
	)
	(segment
		(start -17.3482 -45.796708)
		(end -16.53286 -44.981368)
		(width 0.10668)
		(layer "In4.Cu")
		(net "TDR_SE_50_OHM_IN2")
	)
	(segment
		(start -15.215362 -39.388288)
		(end -11.96594 -39.388288)
		(width 0.10668)
		(layer "In4.Cu")
		(net "TDR_SE_50_OHM_IN2")
	)
	(segment
		(start -12.07008 -59.619388)
		(end -12.07008 -59.228228)
		(width 0.10668)
		(layer "In4.Cu")
		(net "TDR_SE_50_OHM_IN2")
	)
	(segment
		(start -12.34694 -41.252648)
		(end -12.07008 -40.975788)
		(width 0.10668)
		(layer "In4.Cu")
		(net "TDR_SE_50_OHM_IN2")
	)
	(segment
		(start -16.15186 -58.031888)
		(end -11.96594 -58.031888)
		(width 0.10668)
		(layer "In4.Cu")
		(net "TDR_SE_50_OHM_IN2")
	)
	(segment
		(start -11.1506 -47.661068)
		(end -11.1506 -48.814228)
		(width 0.10668)
		(layer "In4.Cu")
		(net "TDR_SE_50_OHM_IN2")
	)
	(segment
		(start -16.15186 -57.087008)
		(end -16.42872 -57.363868)
		(width 0.10668)
		(layer "In4.Cu")
		(net "TDR_SE_50_OHM_IN2")
	)
	(segment
		(start -11.1506 -48.814228)
		(end -11.96594 -49.629568)
		(width 0.10668)
		(layer "In4.Cu")
		(net "TDR_SE_50_OHM_IN2")
	)
	(segment
		(start -16.15186 -50.574448)
		(end -11.96594 -50.574448)
		(width 0.10668)
		(layer "In4.Cu")
		(net "TDR_SE_50_OHM_IN2")
	)
	(segment
		(start -11.96594 -53.358288)
		(end -16.15186 -53.358288)
		(width 0.10668)
		(layer "In4.Cu")
		(net "TDR_SE_50_OHM_IN2")
	)
	(segment
		(start -11.1506 -40.203628)
		(end -11.1506 -41.356788)
		(width 0.10668)
		(layer "In4.Cu")
		(net "TDR_SE_50_OHM_IN2")
	)
	(segment
		(start -17.3482 -43.221148)
		(end -17.3482 -42.067988)
		(width 0.10668)
		(layer "In4.Cu")
		(net "TDR_SE_50_OHM_IN2")
	)
	(segment
		(start -11.1506 -43.932348)
		(end -11.1506 -45.085508)
		(width 0.10668)
		(layer "In4.Cu")
		(net "TDR_SE_50_OHM_IN2")
	)
	(segment
		(start -11.1506 -41.356788)
		(end -11.96594 -42.172128)
		(width 0.10668)
		(layer "In4.Cu")
		(net "TDR_SE_50_OHM_IN2")
	)
	(segment
		(start -16.42872 -53.635148)
		(end -16.42872 -54.026308)
		(width 0.10668)
		(layer "In4.Cu")
		(net "TDR_SE_50_OHM_IN2")
	)
	(segment
		(start -16.53286 -56.167528)
		(end -12.34694 -56.167528)
		(width 0.10668)
		(layer "In4.Cu")
		(net "TDR_SE_50_OHM_IN2")
	)
	(segment
		(start -11.96594 -54.303168)
		(end -11.1506 -55.118508)
		(width 0.10668)
		(layer "In4.Cu")
		(net "TDR_SE_50_OHM_IN2")
	)
	(segment
		(start -11.96594 -46.845728)
		(end -11.1506 -47.661068)
		(width 0.10668)
		(layer "In4.Cu")
		(net "TDR_SE_50_OHM_IN2")
	)
	(segment
		(start -11.96594 -43.117008)
		(end -11.1506 -43.932348)
		(width 0.10668)
		(layer "In4.Cu")
		(net "TDR_SE_50_OHM_IN2")
	)
	(segment
		(start -12.34694 -55.222648)
		(end -16.53286 -55.222648)
		(width 0.10668)
		(layer "In4.Cu")
		(net "TDR_SE_50_OHM_IN2")
	)
	(segment
		(start -16.42872 -50.297588)
		(end -16.15186 -50.574448)
		(width 0.10668)
		(layer "In4.Cu")
		(net "TDR_SE_50_OHM_IN2")
	)
	(segment
		(start -11.96594 -50.574448)
		(end -11.1506 -51.389788)
		(width 0.10668)
		(layer "In4.Cu")
		(net "TDR_SE_50_OHM_IN2")
	)
	(segment
		(start -11.1506 -51.389788)
		(end -11.1506 -52.542948)
		(width 0.10668)
		(layer "In4.Cu")
		(net "TDR_SE_50_OHM_IN2")
	)
	(segment
		(start -12.9794 -60.942728)
		(end -12.9794 -63.580264)
		(width 0.10668)
		(layer "In4.Cu")
		(net "TDR_SE_50_OHM_IN2")
	)
	(segment
		(start -15.5194 -63.580264)
		(end -15.5194 -60.023248)
		(width 0.10668)
		(layer "In4.Cu")
		(net "TDR_SE_50_OHM_IN2")
	)
	(segment
		(start -12.07008 -40.975788)
		(end -12.07008 -40.584628)
		(width 0.10668)
		(layer "In4.Cu")
		(net "TDR_SE_50_OHM_IN2")
	)
	(segment
		(start -11.1506 -60.000388)
		(end -11.96594 -60.815728)
		(width 0.10668)
		(layer "In4.Cu")
		(net "TDR_SE_50_OHM_IN2")
	)
	(segment
		(start -16.53286 -44.981368)
		(end -12.34694 -44.981368)
		(width 0.10668)
		(layer "In4.Cu")
		(net "TDR_SE_50_OHM_IN2")
	)
	(segment
		(start -16.15186 -42.172128)
		(end -16.42872 -42.448988)
		(width 0.10668)
		(layer "In4.Cu")
		(net "TDR_SE_50_OHM_IN2")
	)
	(segment
		(start -16.42872 -54.026308)
		(end -16.15186 -54.303168)
		(width 0.10668)
		(layer "In4.Cu")
		(net "TDR_SE_50_OHM_IN2")
	)
	(segment
		(start -11.1506 -55.118508)
		(end -11.1506 -56.271668)
		(width 0.10668)
		(layer "In4.Cu")
		(net "TDR_SE_50_OHM_IN2")
	)
	(segment
		(start -12.07008 -40.584628)
		(end -12.34694 -40.307768)
		(width 0.10668)
		(layer "In4.Cu")
		(net "TDR_SE_50_OHM_IN2")
	)
	(segment
		(start -12.07008 -48.433228)
		(end -12.07008 -48.042068)
		(width 0.10668)
		(layer "In4.Cu")
		(net "TDR_SE_50_OHM_IN2")
	)
	(segment
		(start -15.23365 -40.307768)
		(end -15.437866 -40.103552)
		(width 0.10668)
		(layer "In4.Cu")
		(net "TDR_SE_50_OHM_IN2")
	)
	(segment
		(start -12.07008 -59.228228)
		(end -12.34694 -58.951368)
		(width 0.10668)
		(layer "In4.Cu")
		(net "TDR_SE_50_OHM_IN2")
	)
	(segment
		(start -12.34694 -56.167528)
		(end -12.07008 -55.890668)
		(width 0.10668)
		(layer "In4.Cu")
		(net "TDR_SE_50_OHM_IN2")
	)
	(segment
		(start -16.53286 -47.765208)
		(end -17.3482 -46.949868)
		(width 0.10668)
		(layer "In4.Cu")
		(net "TDR_SE_50_OHM_IN2")
	)
	(segment
		(start -11.96594 -45.900848)
		(end -16.15186 -45.900848)
		(width 0.10668)
		(layer "In4.Cu")
		(net "TDR_SE_50_OHM_IN2")
	)
	(segment
		(start -12.07008 -48.042068)
		(end -12.34694 -47.765208)
		(width 0.10668)
		(layer "In4.Cu")
		(net "TDR_SE_50_OHM_IN2")
	)
	(segment
		(start -11.1506 -45.085508)
		(end -11.96594 -45.900848)
		(width 0.10668)
		(layer "In4.Cu")
		(net "TDR_SE_50_OHM_IN2")
	)
	(segment
		(start -12.07008 -51.770788)
		(end -12.34694 -51.493928)
		(width 0.10668)
		(layer "In4.Cu")
		(net "TDR_SE_50_OHM_IN2")
	)
	(segment
		(start -16.53286 -58.951368)
		(end -17.3482 -58.136028)
		(width 0.10668)
		(layer "In4.Cu")
		(net "TDR_SE_50_OHM_IN2")
	)
	(segment
		(start -12.34694 -40.307768)
		(end -15.23365 -40.307768)
		(width 0.10668)
		(layer "In4.Cu")
		(net "TDR_SE_50_OHM_IN2")
	)
	(segment
		(start -12.34694 -48.710088)
		(end -12.07008 -48.433228)
		(width 0.10668)
		(layer "In4.Cu")
		(net "TDR_SE_50_OHM_IN2")
	)
	(segment
		(start -11.96594 -60.815728)
		(end -12.8524 -60.815728)
		(width 0.10668)
		(layer "In4.Cu")
		(net "TDR_SE_50_OHM_IN2")
	)
	(segment
		(start -16.42872 -46.177708)
		(end -16.42872 -46.568868)
		(width 0.10668)
		(layer "In4.Cu")
		(net "TDR_SE_50_OHM_IN2")
	)
	(segment
		(start -17.3482 -53.254148)
		(end -16.53286 -52.438808)
		(width 0.10668)
		(layer "In4.Cu")
		(net "TDR_SE_50_OHM_IN2")
	)
	(segment
		(start -12.34694 -59.896248)
		(end -12.07008 -59.619388)
		(width 0.10668)
		(layer "In4.Cu")
		(net "TDR_SE_50_OHM_IN2")
	)
	(segment
		(start -12.8524 -60.815728)
		(end -12.9794 -60.942728)
		(width 0.10668)
		(layer "In4.Cu")
		(net "TDR_SE_50_OHM_IN2")
	)
	(segment
		(start -16.53286 -48.710088)
		(end -12.34694 -48.710088)
		(width 0.10668)
		(layer "In4.Cu")
		(net "TDR_SE_50_OHM_IN2")
	)
	(segment
		(start -12.34694 -52.438808)
		(end -12.07008 -52.161948)
		(width 0.10668)
		(layer "In4.Cu")
		(net "TDR_SE_50_OHM_IN2")
	)
	(segment
		(start -11.96594 -57.087008)
		(end -16.15186 -57.087008)
		(width 0.10668)
		(layer "In4.Cu")
		(net "TDR_SE_50_OHM_IN2")
	)
	(segment
		(start -12.34694 -44.036488)
		(end -16.53286 -44.036488)
		(width 0.10668)
		(layer "In4.Cu")
		(net "TDR_SE_50_OHM_IN2")
	)
	(segment
		(start -16.15186 -43.117008)
		(end -11.96594 -43.117008)
		(width 0.10668)
		(layer "In4.Cu")
		(net "TDR_SE_50_OHM_IN2")
	)
	(segment
		(start -11.96594 -39.388288)
		(end -11.1506 -40.203628)
		(width 0.10668)
		(layer "In4.Cu")
		(net "TDR_SE_50_OHM_IN2")
	)
	(segment
		(start -12.34694 -58.951368)
		(end -16.53286 -58.951368)
		(width 0.10668)
		(layer "In4.Cu")
		(net "TDR_SE_50_OHM_IN2")
	)
	(segment
		(start -17.3482 -42.067988)
		(end -16.53286 -41.252648)
		(width 0.10668)
		(layer "In4.Cu")
		(net "TDR_SE_50_OHM_IN2")
	)
	(segment
		(start -15.437866 -40.103552)
		(end -15.437866 -39.610792)
		(width 0.10668)
		(layer "In4.Cu")
		(net "TDR_SE_50_OHM_IN2")
	)
	(segment
		(start -16.15186 -54.303168)
		(end -11.96594 -54.303168)
		(width 0.10668)
		(layer "In4.Cu")
		(net "TDR_SE_50_OHM_IN2")
	)
	(segment
		(start -17.3482 -49.525428)
		(end -16.53286 -48.710088)
		(width 0.10668)
		(layer "In4.Cu")
		(net "TDR_SE_50_OHM_IN2")
	)
	(segment
		(start -12.07008 -52.161948)
		(end -12.07008 -51.770788)
		(width 0.10668)
		(layer "In4.Cu")
		(net "TDR_SE_50_OHM_IN2")
	)
	(segment
		(start -17.3482 -58.136028)
		(end -17.3482 -56.982868)
		(width 0.10668)
		(layer "In4.Cu")
		(net "TDR_SE_50_OHM_IN2")
	)
	(segment
		(start -11.1506 -52.542948)
		(end -11.96594 -53.358288)
		(width 0.10668)
		(layer "In4.Cu")
		(net "TDR_SE_50_OHM_IN2")
	)
	(segment
		(start -16.15186 -46.845728)
		(end -11.96594 -46.845728)
		(width 0.10668)
		(layer "In4.Cu")
		(net "TDR_SE_50_OHM_IN2")
	)
	(segment
		(start -12.07008 -44.704508)
		(end -12.07008 -44.313348)
		(width 0.10668)
		(layer "In4.Cu")
		(net "TDR_SE_50_OHM_IN2")
	)
	(segment
		(start -16.42872 -42.840148)
		(end -16.15186 -43.117008)
		(width 0.10668)
		(layer "In4.Cu")
		(net "TDR_SE_50_OHM_IN2")
	)
	(segment
		(start -16.15186 -53.358288)
		(end -16.42872 -53.635148)
		(width 0.10668)
		(layer "In4.Cu")
		(net "TDR_SE_50_OHM_IN2")
	)
	(segment
		(start -12.34694 -47.765208)
		(end -16.53286 -47.765208)
		(width 0.10668)
		(layer "In4.Cu")
		(net "TDR_SE_50_OHM_IN2")
	)
	(segment
		(start -16.53286 -52.438808)
		(end -12.34694 -52.438808)
		(width 0.10668)
		(layer "In4.Cu")
		(net "TDR_SE_50_OHM_IN2")
	)
	(segment
		(start -16.42872 -49.906428)
		(end -16.42872 -50.297588)
		(width 0.10668)
		(layer "In4.Cu")
		(net "TDR_SE_50_OHM_IN2")
	)
	(segment
		(start -17.3482 -46.949868)
		(end -17.3482 -45.796708)
		(width 0.10668)
		(layer "In4.Cu")
		(net "TDR_SE_50_OHM_IN2")
	)
	(segment
		(start -16.42872 -42.448988)
		(end -16.42872 -42.840148)
		(width 0.10668)
		(layer "In4.Cu")
		(net "TDR_SE_50_OHM_IN2")
	)
	(segment
		(start -17.3482 -54.407308)
		(end -17.3482 -53.254148)
		(width 0.10668)
		(layer "In4.Cu")
		(net "TDR_SE_50_OHM_IN2")
	)
	(segment
		(start -16.53286 -51.493928)
		(end -17.3482 -50.678588)
		(width 0.10668)
		(layer "In4.Cu")
		(net "TDR_SE_50_OHM_IN2")
	)
	(segment
		(start -16.42872 -46.568868)
		(end -16.15186 -46.845728)
		(width 0.10668)
		(layer "In4.Cu")
		(net "TDR_SE_50_OHM_IN2")
	)
	(segment
		(start -16.53286 -55.222648)
		(end -17.3482 -54.407308)
		(width 0.10668)
		(layer "In4.Cu")
		(net "TDR_SE_50_OHM_IN2")
	)
	(segment
		(start -12.34694 -51.493928)
		(end -16.53286 -51.493928)
		(width 0.10668)
		(layer "In4.Cu")
		(net "TDR_SE_50_OHM_IN2")
	)
	(segment
		(start -11.96594 -42.172128)
		(end -16.15186 -42.172128)
		(width 0.10668)
		(layer "In4.Cu")
		(net "TDR_SE_50_OHM_IN2")
	)
	(segment
		(start -17.3482 -56.982868)
		(end -16.53286 -56.167528)
		(width 0.10668)
		(layer "In4.Cu")
		(net "TDR_SE_50_OHM_IN2")
	)
	(segment
		(start -12.07008 -55.890668)
		(end -12.07008 -55.499508)
		(width 0.10668)
		(layer "In4.Cu")
		(net "TDR_SE_50_OHM_IN2")
	)
	(segment
		(start -15.5194 -60.023248)
		(end -15.3924 -59.896248)
		(width 0.10668)
		(layer "In4.Cu")
		(net "TDR_SE_50_OHM_IN2")
	)
	(segment
		(start -11.96594 -58.031888)
		(end -11.1506 -58.847228)
		(width 0.10668)
		(layer "In4.Cu")
		(net "TDR_SE_50_OHM_IN2")
	)
	(segment
		(start -12.07008 -55.499508)
		(end -12.34694 -55.222648)
		(width 0.10668)
		(layer "In4.Cu")
		(net "TDR_SE_50_OHM_IN2")
	)
	(segment
		(start -11.1506 -58.847228)
		(end -11.1506 -60.000388)
		(width 0.10668)
		(layer "In4.Cu")
		(net "TDR_SE_50_OHM_IN2")
	)
	(segment
		(start -11.96594 -49.629568)
		(end -16.15186 -49.629568)
		(width 0.10668)
		(layer "In4.Cu")
		(net "TDR_SE_50_OHM_IN2")
	)
	(segment
		(start -12.34694 -44.981368)
		(end -12.07008 -44.704508)
		(width 0.10668)
		(layer "In4.Cu")
		(net "TDR_SE_50_OHM_IN2")
	)
	(segment
		(start -16.15186 -45.900848)
		(end -16.42872 -46.177708)
		(width 0.10668)
		(layer "In4.Cu")
		(net "TDR_SE_50_OHM_IN2")
	)
	(segment
		(start -15.437866 -39.610792)
		(end -15.215362 -39.388288)
		(width 0.10668)
		(layer "In4.Cu")
		(net "TDR_SE_50_OHM_IN2")
	)
	(segment
		(start -12.07008 -44.313348)
		(end -12.34694 -44.036488)
		(width 0.10668)
		(layer "In4.Cu")
		(net "TDR_SE_50_OHM_IN2")
	)
	(segment
		(start -17.3482 -50.678588)
		(end -17.3482 -49.525428)
		(width 0.10668)
		(layer "In4.Cu")
		(net "TDR_SE_50_OHM_IN2")
	)
	(segment
		(start -16.42872 -57.363868)
		(end -16.42872 -57.755028)
		(width 0.10668)
		(layer "In4.Cu")
		(net "TDR_SE_50_OHM_IN2")
	)
	(segment
		(start -16.15186 -49.629568)
		(end -16.42872 -49.906428)
		(width 0.10668)
		(layer "In4.Cu")
		(net "TDR_SE_50_OHM_IN2")
	)
	(segment
		(start -16.53286 -44.036488)
		(end -17.3482 -43.221148)
		(width 0.10668)
		(layer "In4.Cu")
		(net "TDR_SE_50_OHM_IN2")
	)
	(segment
		(start -15.3924 -59.896248)
		(end -12.34694 -59.896248)
		(width 0.10668)
		(layer "In4.Cu")
		(net "TDR_SE_50_OHM_IN2")
	)
	(segment
		(start -11.1506 -56.271668)
		(end -11.96594 -57.087008)
		(width 0.10668)
		(layer "In4.Cu")
		(net "TDR_SE_50_OHM_IN2")
	)
	(segment
		(start -16.42872 -57.755028)
		(end -16.15186 -58.031888)
		(width 0.10668)
		(layer "In4.Cu")
		(net "TDR_SE_50_OHM_IN2")
	)
	(segment
		(start -16.53286 -41.252648)
		(end -12.34694 -41.252648)
		(width 0.10668)
		(layer "In4.Cu")
		(net "TDR_SE_50_OHM_IN2")
	)
	(segment
		(start -12.24788 -84.215224)
		(end -11.462258 -85.000846)
		(width 0.08382)
		(layer "In2.Cu")
		(net "TDR_SE_50_OHM_IN1")
	)
	(segment
		(start -16.897858 -87.976202)
		(end -16.897858 -86.824566)
		(width 0.08382)
		(layer "In2.Cu")
		(net "TDR_SE_50_OHM_IN1")
	)
	(segment
		(start -12.620498 -74.172064)
		(end -16.112236 -74.172064)
		(width 0.08382)
		(layer "In2.Cu")
		(net "TDR_SE_50_OHM_IN1")
	)
	(segment
		(start -16.897858 -75.882246)
		(end -16.112236 -75.096624)
		(width 0.08382)
		(layer "In2.Cu")
		(net "TDR_SE_50_OHM_IN1")
	)
	(segment
		(start -12.24788 -83.290664)
		(end -15.739618 -83.290664)
		(width 0.08382)
		(layer "In2.Cu")
		(net "TDR_SE_50_OHM_IN1")
	)
	(segment
		(start -11.462258 -71.562722)
		(end -12.24788 -72.348344)
		(width 0.08382)
		(layer "In2.Cu")
		(net "TDR_SE_50_OHM_IN1")
	)
	(segment
		(start -16.897858 -77.033882)
		(end -16.897858 -75.882246)
		(width 0.08382)
		(layer "In2.Cu")
		(net "TDR_SE_50_OHM_IN1")
	)
	(segment
		(start -16.112236 -92.409264)
		(end -16.897858 -91.623642)
		(width 0.08382)
		(layer "In2.Cu")
		(net "TDR_SE_50_OHM_IN1")
	)
	(segment
		(start -15.739618 -75.995784)
		(end -15.998698 -76.254864)
		(width 0.08382)
		(layer "In2.Cu")
		(net "TDR_SE_50_OHM_IN1")
	)
	(segment
		(start -11.462258 -82.505042)
		(end -12.24788 -83.290664)
		(width 0.08382)
		(layer "In2.Cu")
		(net "TDR_SE_50_OHM_IN1")
	)
	(segment
		(start -12.620498 -92.409264)
		(end -16.112236 -92.409264)
		(width 0.08382)
		(layer "In2.Cu")
		(net "TDR_SE_50_OHM_IN1")
	)
	(segment
		(start -16.897858 -79.529686)
		(end -16.112236 -78.744064)
		(width 0.08382)
		(layer "In2.Cu")
		(net "TDR_SE_50_OHM_IN1")
	)
	(segment
		(start -15.739618 -91.510104)
		(end -12.24788 -91.510104)
		(width 0.08382)
		(layer "In2.Cu")
		(net "TDR_SE_50_OHM_IN1")
	)
	(segment
		(start -15.367 -93.333824)
		(end -12.620498 -93.333824)
		(width 0.08382)
		(layer "In2.Cu")
		(net "TDR_SE_50_OHM_IN1")
	)
	(segment
		(start -15.998698 -87.197184)
		(end -15.998698 -87.603584)
		(width 0.08382)
		(layer "In2.Cu")
		(net "TDR_SE_50_OHM_IN1")
	)
	(segment
		(start -12.361418 -78.484984)
		(end -12.361418 -78.078584)
		(width 0.08382)
		(layer "In2.Cu")
		(net "TDR_SE_50_OHM_IN1")
	)
	(segment
		(start -11.462258 -89.799922)
		(end -12.24788 -90.585544)
		(width 0.08382)
		(layer "In2.Cu")
		(net "TDR_SE_50_OHM_IN1")
	)
	(segment
		(start -12.620498 -81.466944)
		(end -16.112236 -81.466944)
		(width 0.08382)
		(layer "In2.Cu")
		(net "TDR_SE_50_OHM_IN1")
	)
	(segment
		(start -12.24788 -80.567784)
		(end -11.462258 -81.353406)
		(width 0.08382)
		(layer "In2.Cu")
		(net "TDR_SE_50_OHM_IN1")
	)
	(segment
		(start -15.739618 -79.643224)
		(end -15.998698 -79.902304)
		(width 0.08382)
		(layer "In2.Cu")
		(net "TDR_SE_50_OHM_IN1")
	)
	(segment
		(start -12.24788 -72.348344)
		(end -15.739618 -72.348344)
		(width 0.08382)
		(layer "In2.Cu")
		(net "TDR_SE_50_OHM_IN1")
	)
	(segment
		(start -15.739618 -76.920344)
		(end -12.24788 -76.920344)
		(width 0.08382)
		(layer "In2.Cu")
		(net "TDR_SE_50_OHM_IN1")
	)
	(segment
		(start -12.361418 -81.726024)
		(end -12.620498 -81.466944)
		(width 0.08382)
		(layer "In2.Cu")
		(net "TDR_SE_50_OHM_IN1")
	)
	(segment
		(start -11.462258 -81.353406)
		(end -11.462258 -82.505042)
		(width 0.08382)
		(layer "In2.Cu")
		(net "TDR_SE_50_OHM_IN1")
	)
	(segment
		(start -12.24788 -86.938104)
		(end -15.739618 -86.938104)
		(width 0.08382)
		(layer "In2.Cu")
		(net "TDR_SE_50_OHM_IN1")
	)
	(segment
		(start -12.620498 -93.333824)
		(end -12.361418 -93.074744)
		(width 0.08382)
		(layer "In2.Cu")
		(net "TDR_SE_50_OHM_IN1")
	)
	(segment
		(start -11.721338 -70.3326)
		(end -11.462258 -70.59168)
		(width 0.08382)
		(layer "In2.Cu")
		(net "TDR_SE_50_OHM_IN1")
	)
	(segment
		(start -16.897858 -91.623642)
		(end -16.897858 -90.472006)
		(width 0.08382)
		(layer "In2.Cu")
		(net "TDR_SE_50_OHM_IN1")
	)
	(segment
		(start -15.739618 -86.938104)
		(end -15.998698 -87.197184)
		(width 0.08382)
		(layer "In2.Cu")
		(net "TDR_SE_50_OHM_IN1")
	)
	(segment
		(start -16.112236 -77.819504)
		(end -16.897858 -77.033882)
		(width 0.08382)
		(layer "In2.Cu")
		(net "TDR_SE_50_OHM_IN1")
	)
	(segment
		(start -11.462258 -74.058526)
		(end -11.462258 -75.210162)
		(width 0.08382)
		(layer "In2.Cu")
		(net "TDR_SE_50_OHM_IN1")
	)
	(segment
		(start -16.112236 -78.744064)
		(end -12.620498 -78.744064)
		(width 0.08382)
		(layer "In2.Cu")
		(net "TDR_SE_50_OHM_IN1")
	)
	(segment
		(start -11.462258 -92.295726)
		(end -11.462258 -93.447362)
		(width 0.08382)
		(layer "In2.Cu")
		(net "TDR_SE_50_OHM_IN1")
	)
	(segment
		(start -15.998698 -83.956144)
		(end -15.739618 -84.215224)
		(width 0.08382)
		(layer "In2.Cu")
		(net "TDR_SE_50_OHM_IN1")
	)
	(segment
		(start -12.24788 -76.920344)
		(end -11.462258 -77.705966)
		(width 0.08382)
		(layer "In2.Cu")
		(net "TDR_SE_50_OHM_IN1")
	)
	(segment
		(start -12.361418 -85.373464)
		(end -12.620498 -85.114384)
		(width 0.08382)
		(layer "In2.Cu")
		(net "TDR_SE_50_OHM_IN1")
	)
	(segment
		(start -16.112236 -85.114384)
		(end -16.897858 -84.328762)
		(width 0.08382)
		(layer "In2.Cu")
		(net "TDR_SE_50_OHM_IN1")
	)
	(segment
		(start -11.462258 -88.648286)
		(end -11.462258 -89.799922)
		(width 0.08382)
		(layer "In2.Cu")
		(net "TDR_SE_50_OHM_IN1")
	)
	(segment
		(start -12.361418 -74.837544)
		(end -12.361418 -74.431144)
		(width 0.08382)
		(layer "In2.Cu")
		(net "TDR_SE_50_OHM_IN1")
	)
	(segment
		(start -15.998698 -90.844624)
		(end -15.998698 -91.251024)
		(width 0.08382)
		(layer "In2.Cu")
		(net "TDR_SE_50_OHM_IN1")
	)
	(segment
		(start -11.462258 -70.59168)
		(end -11.462258 -71.562722)
		(width 0.08382)
		(layer "In2.Cu")
		(net "TDR_SE_50_OHM_IN1")
	)
	(segment
		(start -12.102338 -70.3326)
		(end -11.721338 -70.3326)
		(width 0.08382)
		(layer "In2.Cu")
		(net "TDR_SE_50_OHM_IN1")
	)
	(segment
		(start -16.897858 -83.177126)
		(end -16.112236 -82.391504)
		(width 0.08382)
		(layer "In2.Cu")
		(net "TDR_SE_50_OHM_IN1")
	)
	(segment
		(start -12.361418 -89.020904)
		(end -12.620498 -88.761824)
		(width 0.08382)
		(layer "In2.Cu")
		(net "TDR_SE_50_OHM_IN1")
	)
	(segment
		(start -12.620498 -77.819504)
		(end -16.112236 -77.819504)
		(width 0.08382)
		(layer "In2.Cu")
		(net "TDR_SE_50_OHM_IN1")
	)
	(segment
		(start -15.739618 -90.585544)
		(end -15.998698 -90.844624)
		(width 0.08382)
		(layer "In2.Cu")
		(net "TDR_SE_50_OHM_IN1")
	)
	(segment
		(start -15.998698 -91.251024)
		(end -15.739618 -91.510104)
		(width 0.08382)
		(layer "In2.Cu")
		(net "TDR_SE_50_OHM_IN1")
	)
	(segment
		(start -15.998698 -79.902304)
		(end -15.998698 -80.308704)
		(width 0.08382)
		(layer "In2.Cu")
		(net "TDR_SE_50_OHM_IN1")
	)
	(segment
		(start -16.897858 -80.681322)
		(end -16.897858 -79.529686)
		(width 0.08382)
		(layer "In2.Cu")
		(net "TDR_SE_50_OHM_IN1")
	)
	(segment
		(start -16.112236 -71.449184)
		(end -12.620498 -71.449184)
		(width 0.08382)
		(layer "In2.Cu")
		(net "TDR_SE_50_OHM_IN1")
	)
	(segment
		(start -12.620498 -75.096624)
		(end -12.361418 -74.837544)
		(width 0.08382)
		(layer "In2.Cu")
		(net "TDR_SE_50_OHM_IN1")
	)
	(segment
		(start -12.24788 -94.232984)
		(end -12.827 -94.232984)
		(width 0.08382)
		(layer "In2.Cu")
		(net "TDR_SE_50_OHM_IN1")
	)
	(segment
		(start -15.739618 -72.348344)
		(end -15.998698 -72.607424)
		(width 0.08382)
		(layer "In2.Cu")
		(net "TDR_SE_50_OHM_IN1")
	)
	(segment
		(start -12.361418 -74.431144)
		(end -12.620498 -74.172064)
		(width 0.08382)
		(layer "In2.Cu")
		(net "TDR_SE_50_OHM_IN1")
	)
	(segment
		(start -15.998698 -76.661264)
		(end -15.739618 -76.920344)
		(width 0.08382)
		(layer "In2.Cu")
		(net "TDR_SE_50_OHM_IN1")
	)
	(segment
		(start -12.24788 -79.643224)
		(end -15.739618 -79.643224)
		(width 0.08382)
		(layer "In2.Cu")
		(net "TDR_SE_50_OHM_IN1")
	)
	(segment
		(start -12.361418 -78.078584)
		(end -12.620498 -77.819504)
		(width 0.08382)
		(layer "In2.Cu")
		(net "TDR_SE_50_OHM_IN1")
	)
	(segment
		(start -16.897858 -72.234806)
		(end -16.112236 -71.449184)
		(width 0.08382)
		(layer "In2.Cu")
		(net "TDR_SE_50_OHM_IN1")
	)
	(segment
		(start -15.739618 -84.215224)
		(end -12.24788 -84.215224)
		(width 0.08382)
		(layer "In2.Cu")
		(net "TDR_SE_50_OHM_IN1")
	)
	(segment
		(start -15.494 -93.460824)
		(end -15.367 -93.333824)
		(width 0.08382)
		(layer "In2.Cu")
		(net "TDR_SE_50_OHM_IN1")
	)
	(segment
		(start -16.897858 -90.472006)
		(end -16.112236 -89.686384)
		(width 0.08382)
		(layer "In2.Cu")
		(net "TDR_SE_50_OHM_IN1")
	)
	(segment
		(start -15.739618 -73.272904)
		(end -12.24788 -73.272904)
		(width 0.08382)
		(layer "In2.Cu")
		(net "TDR_SE_50_OHM_IN1")
	)
	(segment
		(start -12.361418 -70.59168)
		(end -12.102338 -70.3326)
		(width 0.08382)
		(layer "In2.Cu")
		(net "TDR_SE_50_OHM_IN1")
	)
	(segment
		(start -16.112236 -75.096624)
		(end -12.620498 -75.096624)
		(width 0.08382)
		(layer "In2.Cu")
		(net "TDR_SE_50_OHM_IN1")
	)
	(segment
		(start -16.112236 -89.686384)
		(end -12.620498 -89.686384)
		(width 0.08382)
		(layer "In2.Cu")
		(net "TDR_SE_50_OHM_IN1")
	)
	(segment
		(start -12.620498 -86.038944)
		(end -12.361418 -85.779864)
		(width 0.08382)
		(layer "In2.Cu")
		(net "TDR_SE_50_OHM_IN1")
	)
	(segment
		(start -16.897858 -73.386442)
		(end -16.897858 -72.234806)
		(width 0.08382)
		(layer "In2.Cu")
		(net "TDR_SE_50_OHM_IN1")
	)
	(segment
		(start -12.361418 -93.074744)
		(end -12.361418 -92.668344)
		(width 0.08382)
		(layer "In2.Cu")
		(net "TDR_SE_50_OHM_IN1")
	)
	(segment
		(start -12.361418 -92.668344)
		(end -12.620498 -92.409264)
		(width 0.08382)
		(layer "In2.Cu")
		(net "TDR_SE_50_OHM_IN1")
	)
	(segment
		(start -12.24788 -75.995784)
		(end -15.739618 -75.995784)
		(width 0.08382)
		(layer "In2.Cu")
		(net "TDR_SE_50_OHM_IN1")
	)
	(segment
		(start -12.361418 -82.132424)
		(end -12.361418 -81.726024)
		(width 0.08382)
		(layer "In2.Cu")
		(net "TDR_SE_50_OHM_IN1")
	)
	(segment
		(start -16.112236 -81.466944)
		(end -16.897858 -80.681322)
		(width 0.08382)
		(layer "In2.Cu")
		(net "TDR_SE_50_OHM_IN1")
	)
	(segment
		(start -11.462258 -75.210162)
		(end -12.24788 -75.995784)
		(width 0.08382)
		(layer "In2.Cu")
		(net "TDR_SE_50_OHM_IN1")
	)
	(segment
		(start -12.954 -94.359984)
		(end -12.954 -97.235264)
		(width 0.08382)
		(layer "In2.Cu")
		(net "TDR_SE_50_OHM_IN1")
	)
	(segment
		(start -12.620498 -71.449184)
		(end -12.361418 -71.190104)
		(width 0.08382)
		(layer "In2.Cu")
		(net "TDR_SE_50_OHM_IN1")
	)
	(segment
		(start -16.112236 -88.761824)
		(end -16.897858 -87.976202)
		(width 0.08382)
		(layer "In2.Cu")
		(net "TDR_SE_50_OHM_IN1")
	)
	(segment
		(start -12.620498 -88.761824)
		(end -16.112236 -88.761824)
		(width 0.08382)
		(layer "In2.Cu")
		(net "TDR_SE_50_OHM_IN1")
	)
	(segment
		(start -11.462258 -93.447362)
		(end -12.24788 -94.232984)
		(width 0.08382)
		(layer "In2.Cu")
		(net "TDR_SE_50_OHM_IN1")
	)
	(segment
		(start -15.998698 -76.254864)
		(end -15.998698 -76.661264)
		(width 0.08382)
		(layer "In2.Cu")
		(net "TDR_SE_50_OHM_IN1")
	)
	(segment
		(start -15.739618 -87.862664)
		(end -12.24788 -87.862664)
		(width 0.08382)
		(layer "In2.Cu")
		(net "TDR_SE_50_OHM_IN1")
	)
	(segment
		(start -15.998698 -83.549744)
		(end -15.998698 -83.956144)
		(width 0.08382)
		(layer "In2.Cu")
		(net "TDR_SE_50_OHM_IN1")
	)
	(segment
		(start -15.739618 -80.567784)
		(end -12.24788 -80.567784)
		(width 0.08382)
		(layer "In2.Cu")
		(net "TDR_SE_50_OHM_IN1")
	)
	(segment
		(start -16.112236 -86.038944)
		(end -12.620498 -86.038944)
		(width 0.08382)
		(layer "In2.Cu")
		(net "TDR_SE_50_OHM_IN1")
	)
	(segment
		(start -15.739618 -83.290664)
		(end -15.998698 -83.549744)
		(width 0.08382)
		(layer "In2.Cu")
		(net "TDR_SE_50_OHM_IN1")
	)
	(segment
		(start -12.620498 -78.744064)
		(end -12.361418 -78.484984)
		(width 0.08382)
		(layer "In2.Cu")
		(net "TDR_SE_50_OHM_IN1")
	)
	(segment
		(start -12.24788 -73.272904)
		(end -11.462258 -74.058526)
		(width 0.08382)
		(layer "In2.Cu")
		(net "TDR_SE_50_OHM_IN1")
	)
	(segment
		(start -12.361418 -89.427304)
		(end -12.361418 -89.020904)
		(width 0.08382)
		(layer "In2.Cu")
		(net "TDR_SE_50_OHM_IN1")
	)
	(segment
		(start -16.897858 -84.328762)
		(end -16.897858 -83.177126)
		(width 0.08382)
		(layer "In2.Cu")
		(net "TDR_SE_50_OHM_IN1")
	)
	(segment
		(start -12.24788 -90.585544)
		(end -15.739618 -90.585544)
		(width 0.08382)
		(layer "In2.Cu")
		(net "TDR_SE_50_OHM_IN1")
	)
	(segment
		(start -12.620498 -89.686384)
		(end -12.361418 -89.427304)
		(width 0.08382)
		(layer "In2.Cu")
		(net "TDR_SE_50_OHM_IN1")
	)
	(segment
		(start -16.897858 -86.824566)
		(end -16.112236 -86.038944)
		(width 0.08382)
		(layer "In2.Cu")
		(net "TDR_SE_50_OHM_IN1")
	)
	(segment
		(start -12.827 -94.232984)
		(end -12.954 -94.359984)
		(width 0.08382)
		(layer "In2.Cu")
		(net "TDR_SE_50_OHM_IN1")
	)
	(segment
		(start -16.112236 -74.172064)
		(end -16.897858 -73.386442)
		(width 0.08382)
		(layer "In2.Cu")
		(net "TDR_SE_50_OHM_IN1")
	)
	(segment
		(start -12.361418 -71.190104)
		(end -12.361418 -70.59168)
		(width 0.08382)
		(layer "In2.Cu")
		(net "TDR_SE_50_OHM_IN1")
	)
	(segment
		(start -11.462258 -86.152482)
		(end -12.24788 -86.938104)
		(width 0.08382)
		(layer "In2.Cu")
		(net "TDR_SE_50_OHM_IN1")
	)
	(segment
		(start -11.462258 -78.857602)
		(end -12.24788 -79.643224)
		(width 0.08382)
		(layer "In2.Cu")
		(net "TDR_SE_50_OHM_IN1")
	)
	(segment
		(start -12.24788 -87.862664)
		(end -11.462258 -88.648286)
		(width 0.08382)
		(layer "In2.Cu")
		(net "TDR_SE_50_OHM_IN1")
	)
	(segment
		(start -12.361418 -85.779864)
		(end -12.361418 -85.373464)
		(width 0.08382)
		(layer "In2.Cu")
		(net "TDR_SE_50_OHM_IN1")
	)
	(segment
		(start -15.494 -97.235264)
		(end -15.494 -93.460824)
		(width 0.08382)
		(layer "In2.Cu")
		(net "TDR_SE_50_OHM_IN1")
	)
	(segment
		(start -15.998698 -80.308704)
		(end -15.739618 -80.567784)
		(width 0.08382)
		(layer "In2.Cu")
		(net "TDR_SE_50_OHM_IN1")
	)
	(segment
		(start -11.462258 -77.705966)
		(end -11.462258 -78.857602)
		(width 0.08382)
		(layer "In2.Cu")
		(net "TDR_SE_50_OHM_IN1")
	)
	(segment
		(start -15.998698 -87.603584)
		(end -15.739618 -87.862664)
		(width 0.08382)
		(layer "In2.Cu")
		(net "TDR_SE_50_OHM_IN1")
	)
	(segment
		(start -16.112236 -82.391504)
		(end -12.620498 -82.391504)
		(width 0.08382)
		(layer "In2.Cu")
		(net "TDR_SE_50_OHM_IN1")
	)
	(segment
		(start -11.462258 -85.000846)
		(end -11.462258 -86.152482)
		(width 0.08382)
		(layer "In2.Cu")
		(net "TDR_SE_50_OHM_IN1")
	)
	(segment
		(start -15.998698 -72.607424)
		(end -15.998698 -73.013824)
		(width 0.08382)
		(layer "In2.Cu")
		(net "TDR_SE_50_OHM_IN1")
	)
	(segment
		(start -15.998698 -73.013824)
		(end -15.739618 -73.272904)
		(width 0.08382)
		(layer "In2.Cu")
		(net "TDR_SE_50_OHM_IN1")
	)
	(segment
		(start -12.24788 -91.510104)
		(end -11.462258 -92.295726)
		(width 0.08382)
		(layer "In2.Cu")
		(net "TDR_SE_50_OHM_IN1")
	)
	(segment
		(start -12.620498 -85.114384)
		(end -16.112236 -85.114384)
		(width 0.08382)
		(layer "In2.Cu")
		(net "TDR_SE_50_OHM_IN1")
	)
	(segment
		(start -12.620498 -82.391504)
		(end -12.361418 -82.132424)
		(width 0.08382)
		(layer "In2.Cu")
		(net "TDR_SE_50_OHM_IN1")
	)
	(segment
		(start -10.7188 -32.097218)
		(end -10.7188 -33.67659)
		(width 0.11684)
		(layer "B.Cu")
		(net "TDR_SE_50_OHM_BOT")
	)
	(segment
		(start -9.4869 -23.260304)
		(end -9.4869 -22.701504)
		(width 0.11684)
		(layer "B.Cu")
		(net "TDR_SE_50_OHM_BOT")
	)
	(segment
		(start -9.654286 -21.126704)
		(end -10.7188 -22.191218)
		(width 0.11684)
		(layer "B.Cu")
		(net "TDR_SE_50_OHM_BOT")
	)
	(segment
		(start -9.4869 -43.072304)
		(end -9.4869 -42.513504)
		(width 0.11684)
		(layer "B.Cu")
		(net "TDR_SE_50_OHM_BOT")
	)
	(segment
		(start -5.585714 -37.217604)
		(end -4.5212 -36.15309)
		(width 0.11684)
		(layer "B.Cu")
		(net "TDR_SE_50_OHM_BOT")
	)
	(segment
		(start -4.5212 -34.573718)
		(end -5.585714 -33.509204)
		(width 0.11684)
		(layer "B.Cu")
		(net "TDR_SE_50_OHM_BOT")
	)
	(segment
		(start -4.5212 -46.05909)
		(end -4.5212 -44.479718)
		(width 0.11684)
		(layer "B.Cu")
		(net "TDR_SE_50_OHM_BOT")
	)
	(segment
		(start -9.144 -43.415204)
		(end -9.4869 -43.072304)
		(width 0.11684)
		(layer "B.Cu")
		(net "TDR_SE_50_OHM_BOT")
	)
	(segment
		(start -9.4869 -27.654504)
		(end -9.144 -27.311604)
		(width 0.11684)
		(layer "B.Cu")
		(net "TDR_SE_50_OHM_BOT")
	)
	(segment
		(start -9.654286 -44.647104)
		(end -6.096 -44.647104)
		(width 0.11684)
		(layer "B.Cu")
		(net "TDR_SE_50_OHM_BOT")
	)
	(segment
		(start -5.7531 -20.783804)
		(end -6.096 -21.126704)
		(width 0.11684)
		(layer "B.Cu")
		(net "TDR_SE_50_OHM_BOT")
	)
	(segment
		(start -9.144 -42.170604)
		(end -5.585714 -42.170604)
		(width 0.11684)
		(layer "B.Cu")
		(net "TDR_SE_50_OHM_BOT")
	)
	(segment
		(start -6.223 -18.650204)
		(end -6.35 -18.523204)
		(width 0.11684)
		(layer "B.Cu")
		(net "TDR_SE_50_OHM_BOT")
	)
	(segment
		(start -9.4869 -37.560504)
		(end -9.144 -37.217604)
		(width 0.11684)
		(layer "B.Cu")
		(net "TDR_SE_50_OHM_BOT")
	)
	(segment
		(start -5.585714 -23.603204)
		(end -9.144 -23.603204)
		(width 0.11684)
		(layer "B.Cu")
		(net "TDR_SE_50_OHM_BOT")
	)
	(segment
		(start -5.7531 -35.642804)
		(end -6.096 -35.985704)
		(width 0.11684)
		(layer "B.Cu")
		(net "TDR_SE_50_OHM_BOT")
	)
	(segment
		(start -9.144 -22.358604)
		(end -5.585714 -22.358604)
		(width 0.11684)
		(layer "B.Cu")
		(net "TDR_SE_50_OHM_BOT")
	)
	(segment
		(start -9.654286 -35.985704)
		(end -10.7188 -37.050218)
		(width 0.11684)
		(layer "B.Cu")
		(net "TDR_SE_50_OHM_BOT")
	)
	(segment
		(start -10.7188 -27.144218)
		(end -10.7188 -28.72359)
		(width 0.11684)
		(layer "B.Cu")
		(net "TDR_SE_50_OHM_BOT")
	)
	(segment
		(start -5.585714 -43.415204)
		(end -9.144 -43.415204)
		(width 0.11684)
		(layer "B.Cu")
		(net "TDR_SE_50_OHM_BOT")
	)
	(segment
		(start -9.144 -23.603204)
		(end -9.4869 -23.260304)
		(width 0.11684)
		(layer "B.Cu")
		(net "TDR_SE_50_OHM_BOT")
	)
	(segment
		(start -6.096 -26.079704)
		(end -9.654286 -26.079704)
		(width 0.11684)
		(layer "B.Cu")
		(net "TDR_SE_50_OHM_BOT")
	)
	(segment
		(start -4.5212 -19.714718)
		(end -5.585714 -18.650204)
		(width 0.11684)
		(layer "B.Cu")
		(net "TDR_SE_50_OHM_BOT")
	)
	(segment
		(start -9.654286 -40.938704)
		(end -10.7188 -42.003218)
		(width 0.11684)
		(layer "B.Cu")
		(net "TDR_SE_50_OHM_BOT")
	)
	(segment
		(start -10.7188 -37.050218)
		(end -10.7188 -38.62959)
		(width 0.11684)
		(layer "B.Cu")
		(net "TDR_SE_50_OHM_BOT")
	)
	(segment
		(start -5.7531 -40.037004)
		(end -5.7531 -40.595804)
		(width 0.11684)
		(layer "B.Cu")
		(net "TDR_SE_50_OHM_BOT")
	)
	(segment
		(start -9.654286 -29.788104)
		(end -6.096 -29.788104)
		(width 0.11684)
		(layer "B.Cu")
		(net "TDR_SE_50_OHM_BOT")
	)
	(segment
		(start -5.6261 -46.67885)
		(end -5.14096 -46.67885)
		(width 0.11684)
		(layer "B.Cu")
		(net "TDR_SE_50_OHM_BOT")
	)
	(segment
		(start -9.654286 -39.694104)
		(end -6.096 -39.694104)
		(width 0.11684)
		(layer "B.Cu")
		(net "TDR_SE_50_OHM_BOT")
	)
	(segment
		(start -9.4869 -38.119304)
		(end -9.4869 -37.560504)
		(width 0.11684)
		(layer "B.Cu")
		(net "TDR_SE_50_OHM_BOT")
	)
	(segment
		(start -9.654286 -31.032704)
		(end -10.7188 -32.097218)
		(width 0.11684)
		(layer "B.Cu")
		(net "TDR_SE_50_OHM_BOT")
	)
	(segment
		(start -9.654286 -24.835104)
		(end -6.096 -24.835104)
		(width 0.11684)
		(layer "B.Cu")
		(net "TDR_SE_50_OHM_BOT")
	)
	(segment
		(start -9.4869 -33.166304)
		(end -9.4869 -32.607504)
		(width 0.11684)
		(layer "B.Cu")
		(net "TDR_SE_50_OHM_BOT")
	)
	(segment
		(start -10.7188 -23.77059)
		(end -9.654286 -24.835104)
		(width 0.11684)
		(layer "B.Cu")
		(net "TDR_SE_50_OHM_BOT")
	)
	(segment
		(start -10.7188 -33.67659)
		(end -9.654286 -34.741104)
		(width 0.11684)
		(layer "B.Cu")
		(net "TDR_SE_50_OHM_BOT")
	)
	(segment
		(start -9.144 -32.264604)
		(end -5.585714 -32.264604)
		(width 0.11684)
		(layer "B.Cu")
		(net "TDR_SE_50_OHM_BOT")
	)
	(segment
		(start -5.7531 -35.084004)
		(end -5.7531 -35.642804)
		(width 0.11684)
		(layer "B.Cu")
		(net "TDR_SE_50_OHM_BOT")
	)
	(segment
		(start -5.585714 -28.556204)
		(end -9.144 -28.556204)
		(width 0.11684)
		(layer "B.Cu")
		(net "TDR_SE_50_OHM_BOT")
	)
	(segment
		(start -8.89 -14.270736)
		(end -8.89 -19.579336)
		(width 0.11684)
		(layer "B.Cu")
		(net "TDR_SE_50_OHM_BOT")
	)
	(segment
		(start -6.096 -29.788104)
		(end -5.7531 -30.131004)
		(width 0.11684)
		(layer "B.Cu")
		(net "TDR_SE_50_OHM_BOT")
	)
	(segment
		(start -8.587232 -19.882104)
		(end -6.096 -19.882104)
		(width 0.11684)
		(layer "B.Cu")
		(net "TDR_SE_50_OHM_BOT")
	)
	(segment
		(start -5.969 -46.33595)
		(end -5.6261 -46.67885)
		(width 0.11684)
		(layer "B.Cu")
		(net "TDR_SE_50_OHM_BOT")
	)
	(segment
		(start -9.144 -27.311604)
		(end -5.585714 -27.311604)
		(width 0.11684)
		(layer "B.Cu")
		(net "TDR_SE_50_OHM_BOT")
	)
	(segment
		(start -4.5212 -21.29409)
		(end -4.5212 -19.714718)
		(width 0.11684)
		(layer "B.Cu")
		(net "TDR_SE_50_OHM_BOT")
	)
	(segment
		(start -6.096 -40.938704)
		(end -9.654286 -40.938704)
		(width 0.11684)
		(layer "B.Cu")
		(net "TDR_SE_50_OHM_BOT")
	)
	(segment
		(start -9.144 -28.556204)
		(end -9.4869 -28.213304)
		(width 0.11684)
		(layer "B.Cu")
		(net "TDR_SE_50_OHM_BOT")
	)
	(segment
		(start -8.89 -19.579336)
		(end -8.587232 -19.882104)
		(width 0.11684)
		(layer "B.Cu")
		(net "TDR_SE_50_OHM_BOT")
	)
	(segment
		(start -9.4869 -28.213304)
		(end -9.4869 -27.654504)
		(width 0.11684)
		(layer "B.Cu")
		(net "TDR_SE_50_OHM_BOT")
	)
	(segment
		(start -4.5212 -31.20009)
		(end -4.5212 -29.620718)
		(width 0.11684)
		(layer "B.Cu")
		(net "TDR_SE_50_OHM_BOT")
	)
	(segment
		(start -4.5212 -26.24709)
		(end -4.5212 -24.667718)
		(width 0.11684)
		(layer "B.Cu")
		(net "TDR_SE_50_OHM_BOT")
	)
	(segment
		(start -10.7188 -28.72359)
		(end -9.654286 -29.788104)
		(width 0.11684)
		(layer "B.Cu")
		(net "TDR_SE_50_OHM_BOT")
	)
	(segment
		(start -5.14096 -46.67885)
		(end -4.5212 -46.05909)
		(width 0.11684)
		(layer "B.Cu")
		(net "TDR_SE_50_OHM_BOT")
	)
	(segment
		(start -5.7531 -45.548804)
		(end -5.969 -45.764704)
		(width 0.11684)
		(layer "B.Cu")
		(net "TDR_SE_50_OHM_BOT")
	)
	(segment
		(start -5.585714 -38.462204)
		(end -9.144 -38.462204)
		(width 0.11684)
		(layer "B.Cu")
		(net "TDR_SE_50_OHM_BOT")
	)
	(segment
		(start -5.7531 -30.689804)
		(end -6.096 -31.032704)
		(width 0.11684)
		(layer "B.Cu")
		(net "TDR_SE_50_OHM_BOT")
	)
	(segment
		(start -6.096 -35.985704)
		(end -9.654286 -35.985704)
		(width 0.11684)
		(layer "B.Cu")
		(net "TDR_SE_50_OHM_BOT")
	)
	(segment
		(start -9.144 -37.217604)
		(end -5.585714 -37.217604)
		(width 0.11684)
		(layer "B.Cu")
		(net "TDR_SE_50_OHM_BOT")
	)
	(segment
		(start -5.969 -45.764704)
		(end -5.969 -46.33595)
		(width 0.11684)
		(layer "B.Cu")
		(net "TDR_SE_50_OHM_BOT")
	)
	(segment
		(start -5.7531 -44.990004)
		(end -5.7531 -45.548804)
		(width 0.11684)
		(layer "B.Cu")
		(net "TDR_SE_50_OHM_BOT")
	)
	(segment
		(start -5.7531 -30.131004)
		(end -5.7531 -30.689804)
		(width 0.11684)
		(layer "B.Cu")
		(net "TDR_SE_50_OHM_BOT")
	)
	(segment
		(start -9.4869 -42.513504)
		(end -9.144 -42.170604)
		(width 0.11684)
		(layer "B.Cu")
		(net "TDR_SE_50_OHM_BOT")
	)
	(segment
		(start -6.096 -34.741104)
		(end -5.7531 -35.084004)
		(width 0.11684)
		(layer "B.Cu")
		(net "TDR_SE_50_OHM_BOT")
	)
	(segment
		(start -9.4869 -22.701504)
		(end -9.144 -22.358604)
		(width 0.11684)
		(layer "B.Cu")
		(net "TDR_SE_50_OHM_BOT")
	)
	(segment
		(start -6.096 -44.647104)
		(end -5.7531 -44.990004)
		(width 0.11684)
		(layer "B.Cu")
		(net "TDR_SE_50_OHM_BOT")
	)
	(segment
		(start -6.096 -31.032704)
		(end -9.654286 -31.032704)
		(width 0.11684)
		(layer "B.Cu")
		(net "TDR_SE_50_OHM_BOT")
	)
	(segment
		(start -9.144 -38.462204)
		(end -9.4869 -38.119304)
		(width 0.11684)
		(layer "B.Cu")
		(net "TDR_SE_50_OHM_BOT")
	)
	(segment
		(start -5.585714 -42.170604)
		(end -4.5212 -41.10609)
		(width 0.11684)
		(layer "B.Cu")
		(net "TDR_SE_50_OHM_BOT")
	)
	(segment
		(start -5.585714 -22.358604)
		(end -4.5212 -21.29409)
		(width 0.11684)
		(layer "B.Cu")
		(net "TDR_SE_50_OHM_BOT")
	)
	(segment
		(start -4.5212 -24.667718)
		(end -5.585714 -23.603204)
		(width 0.11684)
		(layer "B.Cu")
		(net "TDR_SE_50_OHM_BOT")
	)
	(segment
		(start -5.585714 -33.509204)
		(end -9.144 -33.509204)
		(width 0.11684)
		(layer "B.Cu")
		(net "TDR_SE_50_OHM_BOT")
	)
	(segment
		(start -6.096 -19.882104)
		(end -5.7531 -20.225004)
		(width 0.11684)
		(layer "B.Cu")
		(net "TDR_SE_50_OHM_BOT")
	)
	(segment
		(start -5.7531 -25.736804)
		(end -6.096 -26.079704)
		(width 0.11684)
		(layer "B.Cu")
		(net "TDR_SE_50_OHM_BOT")
	)
	(segment
		(start -4.5212 -39.526718)
		(end -5.585714 -38.462204)
		(width 0.11684)
		(layer "B.Cu")
		(net "TDR_SE_50_OHM_BOT")
	)
	(segment
		(start -4.5212 -36.15309)
		(end -4.5212 -34.573718)
		(width 0.11684)
		(layer "B.Cu")
		(net "TDR_SE_50_OHM_BOT")
	)
	(segment
		(start -5.585714 -32.264604)
		(end -4.5212 -31.20009)
		(width 0.11684)
		(layer "B.Cu")
		(net "TDR_SE_50_OHM_BOT")
	)
	(segment
		(start -10.7188 -42.003218)
		(end -10.7188 -43.58259)
		(width 0.11684)
		(layer "B.Cu")
		(net "TDR_SE_50_OHM_BOT")
	)
	(segment
		(start -6.096 -21.126704)
		(end -9.654286 -21.126704)
		(width 0.11684)
		(layer "B.Cu")
		(net "TDR_SE_50_OHM_BOT")
	)
	(segment
		(start -6.096 -24.835104)
		(end -5.7531 -25.178004)
		(width 0.11684)
		(layer "B.Cu")
		(net "TDR_SE_50_OHM_BOT")
	)
	(segment
		(start -9.144 -33.509204)
		(end -9.4869 -33.166304)
		(width 0.11684)
		(layer "B.Cu")
		(net "TDR_SE_50_OHM_BOT")
	)
	(segment
		(start -5.7531 -20.225004)
		(end -5.7531 -20.783804)
		(width 0.11684)
		(layer "B.Cu")
		(net "TDR_SE_50_OHM_BOT")
	)
	(segment
		(start -10.7188 -38.62959)
		(end -9.654286 -39.694104)
		(width 0.11684)
		(layer "B.Cu")
		(net "TDR_SE_50_OHM_BOT")
	)
	(segment
		(start -6.35 -18.523204)
		(end -6.35 -14.270736)
		(width 0.11684)
		(layer "B.Cu")
		(net "TDR_SE_50_OHM_BOT")
	)
	(segment
		(start -9.4869 -32.607504)
		(end -9.144 -32.264604)
		(width 0.11684)
		(layer "B.Cu")
		(net "TDR_SE_50_OHM_BOT")
	)
	(segment
		(start -4.5212 -44.479718)
		(end -5.585714 -43.415204)
		(width 0.11684)
		(layer "B.Cu")
		(net "TDR_SE_50_OHM_BOT")
	)
	(segment
		(start -10.7188 -43.58259)
		(end -9.654286 -44.647104)
		(width 0.11684)
		(layer "B.Cu")
		(net "TDR_SE_50_OHM_BOT")
	)
	(segment
		(start -10.7188 -22.191218)
		(end -10.7188 -23.77059)
		(width 0.11684)
		(layer "B.Cu")
		(net "TDR_SE_50_OHM_BOT")
	)
	(segment
		(start -9.654286 -34.741104)
		(end -6.096 -34.741104)
		(width 0.11684)
		(layer "B.Cu")
		(net "TDR_SE_50_OHM_BOT")
	)
	(segment
		(start -4.5212 -41.10609)
		(end -4.5212 -39.526718)
		(width 0.11684)
		(layer "B.Cu")
		(net "TDR_SE_50_OHM_BOT")
	)
	(segment
		(start -6.096 -39.694104)
		(end -5.7531 -40.037004)
		(width 0.11684)
		(layer "B.Cu")
		(net "TDR_SE_50_OHM_BOT")
	)
	(segment
		(start -9.654286 -26.079704)
		(end -10.7188 -27.144218)
		(width 0.11684)
		(layer "B.Cu")
		(net "TDR_SE_50_OHM_BOT")
	)
	(segment
		(start -5.585714 -18.650204)
		(end -6.223 -18.650204)
		(width 0.11684)
		(layer "B.Cu")
		(net "TDR_SE_50_OHM_BOT")
	)
	(segment
		(start -4.5212 -29.620718)
		(end -5.585714 -28.556204)
		(width 0.11684)
		(layer "B.Cu")
		(net "TDR_SE_50_OHM_BOT")
	)
	(segment
		(start -5.585714 -27.311604)
		(end -4.5212 -26.24709)
		(width 0.11684)
		(layer "B.Cu")
		(net "TDR_SE_50_OHM_BOT")
	)
	(segment
		(start -5.7531 -25.178004)
		(end -5.7531 -25.736804)
		(width 0.11684)
		(layer "B.Cu")
		(net "TDR_SE_50_OHM_BOT")
	)
	(segment
		(start -5.7531 -40.595804)
		(end -6.096 -40.938704)
		(width 0.11684)
		(layer "B.Cu")
		(net "TDR_SE_50_OHM_BOT")
	)
	(segment
		(start 106.882946 -99.15017)
		(end 119.5324 -99.15017)
		(width 0.14224)
		(layer "F.Cu")
		(net "TDR_DIFF_85_TOP_DP")
	)
	(segment
		(start 106.38282 -97.364804)
		(end 106.38282 -96.343216)
		(width 0.14224)
		(layer "F.Cu")
		(net "TDR_DIFF_85_TOP_DP")
	)
	(segment
		(start 106.38282 -90.750644)
		(end 106.38282 -89.729056)
		(width 0.14224)
		(layer "F.Cu")
		(net "TDR_DIFF_85_TOP_DP")
	)
	(segment
		(start 106.38282 -103.978964)
		(end 106.38282 -102.957376)
		(width 0.14224)
		(layer "F.Cu")
		(net "TDR_DIFF_85_TOP_DP")
	)
	(segment
		(start 106.38282 -102.957376)
		(end 106.882946 -102.45725)
		(width 0.14224)
		(layer "F.Cu")
		(net "TDR_DIFF_85_TOP_DP")
	)
	(segment
		(start 112.014 -106.68)
		(end 112.95761 -106.68)
		(width 0.14224)
		(layer "F.Cu")
		(net "TDR_DIFF_85_TOP_DP")
	)
	(segment
		(start 106.882946 -95.84309)
		(end 119.5324 -95.84309)
		(width 0.14224)
		(layer "F.Cu")
		(net "TDR_DIFF_85_TOP_DP")
	)
	(segment
		(start 106.882946 -89.22893)
		(end 119.5324 -89.22893)
		(width 0.14224)
		(layer "F.Cu")
		(net "TDR_DIFF_85_TOP_DP")
	)
	(segment
		(start 119.5324 -92.53601)
		(end 119.81688 -92.25153)
		(width 0.14224)
		(layer "F.Cu")
		(net "TDR_DIFF_85_TOP_DP")
	)
	(segment
		(start 119.7229 -101.45649)
		(end 119.43842 -101.17201)
		(width 0.14224)
		(layer "F.Cu")
		(net "TDR_DIFF_85_TOP_DP")
	)
	(segment
		(start 119.81688 -88.22817)
		(end 119.5324 -87.94369)
		(width 0.14224)
		(layer "F.Cu")
		(net "TDR_DIFF_85_TOP_DP")
	)
	(segment
		(start 119.81688 -91.53525)
		(end 119.5324 -91.25077)
		(width 0.14224)
		(layer "F.Cu")
		(net "TDR_DIFF_85_TOP_DP")
	)
	(segment
		(start 106.38282 -100.671884)
		(end 106.38282 -99.650296)
		(width 0.14224)
		(layer "F.Cu")
		(net "TDR_DIFF_85_TOP_DP")
	)
	(segment
		(start 112.81537 -104.47909)
		(end 106.882946 -104.47909)
		(width 0.14224)
		(layer "F.Cu")
		(net "TDR_DIFF_85_TOP_DP")
	)
	(segment
		(start 106.38282 -94.057724)
		(end 106.38282 -93.036136)
		(width 0.14224)
		(layer "F.Cu")
		(net "TDR_DIFF_85_TOP_DP")
	)
	(segment
		(start 119.81688 -98.86569)
		(end 119.81688 -98.14941)
		(width 0.14224)
		(layer "F.Cu")
		(net "TDR_DIFF_85_TOP_DP")
	)
	(segment
		(start 112.95761 -85.344)
		(end 112.014 -85.344)
		(width 0.14224)
		(layer "F.Cu")
		(net "TDR_DIFF_85_TOP_DP")
	)
	(segment
		(start 106.38282 -96.343216)
		(end 106.882946 -95.84309)
		(width 0.14224)
		(layer "F.Cu")
		(net "TDR_DIFF_85_TOP_DP")
	)
	(segment
		(start 119.5324 -99.15017)
		(end 119.81688 -98.86569)
		(width 0.14224)
		(layer "F.Cu")
		(net "TDR_DIFF_85_TOP_DP")
	)
	(segment
		(start 106.882946 -104.47909)
		(end 106.38282 -103.978964)
		(width 0.14224)
		(layer "F.Cu")
		(net "TDR_DIFF_85_TOP_DP")
	)
	(segment
		(start 119.81688 -98.14941)
		(end 119.5324 -97.86493)
		(width 0.14224)
		(layer "F.Cu")
		(net "TDR_DIFF_85_TOP_DP")
	)
	(segment
		(start 119.81688 -92.25153)
		(end 119.81688 -91.53525)
		(width 0.14224)
		(layer "F.Cu")
		(net "TDR_DIFF_85_TOP_DP")
	)
	(segment
		(start 119.81688 -94.84233)
		(end 119.5324 -94.55785)
		(width 0.14224)
		(layer "F.Cu")
		(net "TDR_DIFF_85_TOP_DP")
	)
	(segment
		(start 119.81688 -95.55861)
		(end 119.81688 -94.84233)
		(width 0.14224)
		(layer "F.Cu")
		(net "TDR_DIFF_85_TOP_DP")
	)
	(segment
		(start 106.38282 -93.036136)
		(end 106.882946 -92.53601)
		(width 0.14224)
		(layer "F.Cu")
		(net "TDR_DIFF_85_TOP_DP")
	)
	(segment
		(start 106.38282 -99.650296)
		(end 106.882946 -99.15017)
		(width 0.14224)
		(layer "F.Cu")
		(net "TDR_DIFF_85_TOP_DP")
	)
	(segment
		(start 119.5324 -91.25077)
		(end 106.882946 -91.25077)
		(width 0.14224)
		(layer "F.Cu")
		(net "TDR_DIFF_85_TOP_DP")
	)
	(segment
		(start 119.5324 -95.84309)
		(end 119.81688 -95.55861)
		(width 0.14224)
		(layer "F.Cu")
		(net "TDR_DIFF_85_TOP_DP")
	)
	(segment
		(start 106.38282 -89.729056)
		(end 106.882946 -89.22893)
		(width 0.14224)
		(layer "F.Cu")
		(net "TDR_DIFF_85_TOP_DP")
	)
	(segment
		(start 113.09985 -106.53776)
		(end 113.09985 -104.76357)
		(width 0.14224)
		(layer "F.Cu")
		(net "TDR_DIFF_85_TOP_DP")
	)
	(segment
		(start 113.09985 -87.443564)
		(end 113.09985 -85.48624)
		(width 0.14224)
		(layer "F.Cu")
		(net "TDR_DIFF_85_TOP_DP")
	)
	(segment
		(start 119.5324 -87.94369)
		(end 113.599976 -87.94369)
		(width 0.14224)
		(layer "F.Cu")
		(net "TDR_DIFF_85_TOP_DP")
	)
	(segment
		(start 119.81688 -88.94445)
		(end 119.81688 -88.22817)
		(width 0.14224)
		(layer "F.Cu")
		(net "TDR_DIFF_85_TOP_DP")
	)
	(segment
		(start 119.43842 -101.17201)
		(end 106.882946 -101.17201)
		(width 0.14224)
		(layer "F.Cu")
		(net "TDR_DIFF_85_TOP_DP")
	)
	(segment
		(start 112.95761 -106.68)
		(end 113.09985 -106.53776)
		(width 0.14224)
		(layer "F.Cu")
		(net "TDR_DIFF_85_TOP_DP")
	)
	(segment
		(start 106.882946 -101.17201)
		(end 106.38282 -100.671884)
		(width 0.14224)
		(layer "F.Cu")
		(net "TDR_DIFF_85_TOP_DP")
	)
	(segment
		(start 113.09985 -85.48624)
		(end 112.95761 -85.344)
		(width 0.14224)
		(layer "F.Cu")
		(net "TDR_DIFF_85_TOP_DP")
	)
	(segment
		(start 119.5324 -94.55785)
		(end 106.882946 -94.55785)
		(width 0.14224)
		(layer "F.Cu")
		(net "TDR_DIFF_85_TOP_DP")
	)
	(segment
		(start 119.43842 -102.45725)
		(end 119.7229 -102.17277)
		(width 0.14224)
		(layer "F.Cu")
		(net "TDR_DIFF_85_TOP_DP")
	)
	(segment
		(start 113.599976 -87.94369)
		(end 113.09985 -87.443564)
		(width 0.14224)
		(layer "F.Cu")
		(net "TDR_DIFF_85_TOP_DP")
	)
	(segment
		(start 119.5324 -89.22893)
		(end 119.81688 -88.94445)
		(width 0.14224)
		(layer "F.Cu")
		(net "TDR_DIFF_85_TOP_DP")
	)
	(segment
		(start 113.09985 -104.76357)
		(end 112.81537 -104.47909)
		(width 0.14224)
		(layer "F.Cu")
		(net "TDR_DIFF_85_TOP_DP")
	)
	(segment
		(start 106.882946 -94.55785)
		(end 106.38282 -94.057724)
		(width 0.14224)
		(layer "F.Cu")
		(net "TDR_DIFF_85_TOP_DP")
	)
	(segment
		(start 106.882946 -97.86493)
		(end 106.38282 -97.364804)
		(width 0.14224)
		(layer "F.Cu")
		(net "TDR_DIFF_85_TOP_DP")
	)
	(segment
		(start 119.7229 -102.17277)
		(end 119.7229 -101.45649)
		(width 0.14224)
		(layer "F.Cu")
		(net "TDR_DIFF_85_TOP_DP")
	)
	(segment
		(start 119.5324 -97.86493)
		(end 106.882946 -97.86493)
		(width 0.14224)
		(layer "F.Cu")
		(net "TDR_DIFF_85_TOP_DP")
	)
	(segment
		(start 106.882946 -92.53601)
		(end 119.5324 -92.53601)
		(width 0.14224)
		(layer "F.Cu")
		(net "TDR_DIFF_85_TOP_DP")
	)
	(segment
		(start 106.882946 -102.45725)
		(end 119.43842 -102.45725)
		(width 0.14224)
		(layer "F.Cu")
		(net "TDR_DIFF_85_TOP_DP")
	)
	(segment
		(start 106.882946 -91.25077)
		(end 106.38282 -90.750644)
		(width 0.14224)
		(layer "F.Cu")
		(net "TDR_DIFF_85_TOP_DP")
	)
	(segment
		(start 119.685054 -96.21139)
		(end 120.18518 -95.711264)
		(width 0.14224)
		(layer "F.Cu")
		(net "TDR_DIFF_85_TOP_DN")
	)
	(segment
		(start 113.75263 -87.57539)
		(end 113.46815 -87.29091)
		(width 0.14224)
		(layer "F.Cu")
		(net "TDR_DIFF_85_TOP_DN")
	)
	(segment
		(start 106.75112 -103.11003)
		(end 107.0356 -102.82555)
		(width 0.14224)
		(layer "F.Cu")
		(net "TDR_DIFF_85_TOP_DN")
	)
	(segment
		(start 107.0356 -92.90431)
		(end 119.685054 -92.90431)
		(width 0.14224)
		(layer "F.Cu")
		(net "TDR_DIFF_85_TOP_DN")
	)
	(segment
		(start 113.61039 -106.68)
		(end 113.46815 -106.53776)
		(width 0.14224)
		(layer "F.Cu")
		(net "TDR_DIFF_85_TOP_DN")
	)
	(segment
		(start 106.75112 -103.82631)
		(end 106.75112 -103.11003)
		(width 0.14224)
		(layer "F.Cu")
		(net "TDR_DIFF_85_TOP_DN")
	)
	(segment
		(start 120.18518 -97.996756)
		(end 119.685054 -97.49663)
		(width 0.14224)
		(layer "F.Cu")
		(net "TDR_DIFF_85_TOP_DN")
	)
	(segment
		(start 119.685054 -90.88247)
		(end 107.0356 -90.88247)
		(width 0.14224)
		(layer "F.Cu")
		(net "TDR_DIFF_85_TOP_DN")
	)
	(segment
		(start 119.685054 -99.51847)
		(end 120.18518 -99.018344)
		(width 0.14224)
		(layer "F.Cu")
		(net "TDR_DIFF_85_TOP_DN")
	)
	(segment
		(start 113.46815 -87.29091)
		(end 113.46815 -85.48624)
		(width 0.14224)
		(layer "F.Cu")
		(net "TDR_DIFF_85_TOP_DN")
	)
	(segment
		(start 113.46815 -85.48624)
		(end 113.61039 -85.344)
		(width 0.14224)
		(layer "F.Cu")
		(net "TDR_DIFF_85_TOP_DN")
	)
	(segment
		(start 107.0356 -89.59723)
		(end 119.685054 -89.59723)
		(width 0.14224)
		(layer "F.Cu")
		(net "TDR_DIFF_85_TOP_DN")
	)
	(segment
		(start 119.685054 -89.59723)
		(end 120.18518 -89.097104)
		(width 0.14224)
		(layer "F.Cu")
		(net "TDR_DIFF_85_TOP_DN")
	)
	(segment
		(start 114.554 -106.68)
		(end 113.61039 -106.68)
		(width 0.14224)
		(layer "F.Cu")
		(net "TDR_DIFF_85_TOP_DN")
	)
	(segment
		(start 113.46815 -104.610916)
		(end 112.968024 -104.11079)
		(width 0.14224)
		(layer "F.Cu")
		(net "TDR_DIFF_85_TOP_DN")
	)
	(segment
		(start 107.0356 -96.21139)
		(end 119.685054 -96.21139)
		(width 0.14224)
		(layer "F.Cu")
		(net "TDR_DIFF_85_TOP_DN")
	)
	(segment
		(start 107.0356 -104.11079)
		(end 106.75112 -103.82631)
		(width 0.14224)
		(layer "F.Cu")
		(net "TDR_DIFF_85_TOP_DN")
	)
	(segment
		(start 107.0356 -90.88247)
		(end 106.75112 -90.59799)
		(width 0.14224)
		(layer "F.Cu")
		(net "TDR_DIFF_85_TOP_DN")
	)
	(segment
		(start 119.685054 -87.57539)
		(end 113.75263 -87.57539)
		(width 0.14224)
		(layer "F.Cu")
		(net "TDR_DIFF_85_TOP_DN")
	)
	(segment
		(start 107.0356 -94.18955)
		(end 106.75112 -93.90507)
		(width 0.14224)
		(layer "F.Cu")
		(net "TDR_DIFF_85_TOP_DN")
	)
	(segment
		(start 106.75112 -90.59799)
		(end 106.75112 -89.88171)
		(width 0.14224)
		(layer "F.Cu")
		(net "TDR_DIFF_85_TOP_DN")
	)
	(segment
		(start 120.18518 -88.075516)
		(end 119.685054 -87.57539)
		(width 0.14224)
		(layer "F.Cu")
		(net "TDR_DIFF_85_TOP_DN")
	)
	(segment
		(start 106.75112 -100.51923)
		(end 106.75112 -99.80295)
		(width 0.14224)
		(layer "F.Cu")
		(net "TDR_DIFF_85_TOP_DN")
	)
	(segment
		(start 120.18518 -92.404184)
		(end 120.18518 -91.382596)
		(width 0.14224)
		(layer "F.Cu")
		(net "TDR_DIFF_85_TOP_DN")
	)
	(segment
		(start 107.0356 -100.80371)
		(end 106.75112 -100.51923)
		(width 0.14224)
		(layer "F.Cu")
		(net "TDR_DIFF_85_TOP_DN")
	)
	(segment
		(start 120.18518 -91.382596)
		(end 119.685054 -90.88247)
		(width 0.14224)
		(layer "F.Cu")
		(net "TDR_DIFF_85_TOP_DN")
	)
	(segment
		(start 107.0356 -102.82555)
		(end 119.591074 -102.82555)
		(width 0.14224)
		(layer "F.Cu")
		(net "TDR_DIFF_85_TOP_DN")
	)
	(segment
		(start 106.75112 -89.88171)
		(end 107.0356 -89.59723)
		(width 0.14224)
		(layer "F.Cu")
		(net "TDR_DIFF_85_TOP_DN")
	)
	(segment
		(start 120.18518 -95.711264)
		(end 120.18518 -94.689676)
		(width 0.14224)
		(layer "F.Cu")
		(net "TDR_DIFF_85_TOP_DN")
	)
	(segment
		(start 107.0356 -99.51847)
		(end 119.685054 -99.51847)
		(width 0.14224)
		(layer "F.Cu")
		(net "TDR_DIFF_85_TOP_DN")
	)
	(segment
		(start 120.18518 -94.689676)
		(end 119.685054 -94.18955)
		(width 0.14224)
		(layer "F.Cu")
		(net "TDR_DIFF_85_TOP_DN")
	)
	(segment
		(start 119.591074 -102.82555)
		(end 120.0912 -102.325424)
		(width 0.14224)
		(layer "F.Cu")
		(net "TDR_DIFF_85_TOP_DN")
	)
	(segment
		(start 106.75112 -97.21215)
		(end 106.75112 -96.49587)
		(width 0.14224)
		(layer "F.Cu")
		(net "TDR_DIFF_85_TOP_DN")
	)
	(segment
		(start 107.0356 -97.49663)
		(end 106.75112 -97.21215)
		(width 0.14224)
		(layer "F.Cu")
		(net "TDR_DIFF_85_TOP_DN")
	)
	(segment
		(start 120.0912 -101.303836)
		(end 119.591074 -100.80371)
		(width 0.14224)
		(layer "F.Cu")
		(net "TDR_DIFF_85_TOP_DN")
	)
	(segment
		(start 119.685054 -94.18955)
		(end 107.0356 -94.18955)
		(width 0.14224)
		(layer "F.Cu")
		(net "TDR_DIFF_85_TOP_DN")
	)
	(segment
		(start 113.46815 -106.53776)
		(end 113.46815 -104.610916)
		(width 0.14224)
		(layer "F.Cu")
		(net "TDR_DIFF_85_TOP_DN")
	)
	(segment
		(start 106.75112 -93.90507)
		(end 106.75112 -93.18879)
		(width 0.14224)
		(layer "F.Cu")
		(net "TDR_DIFF_85_TOP_DN")
	)
	(segment
		(start 112.968024 -104.11079)
		(end 107.0356 -104.11079)
		(width 0.14224)
		(layer "F.Cu")
		(net "TDR_DIFF_85_TOP_DN")
	)
	(segment
		(start 119.591074 -100.80371)
		(end 107.0356 -100.80371)
		(width 0.14224)
		(layer "F.Cu")
		(net "TDR_DIFF_85_TOP_DN")
	)
	(segment
		(start 120.18518 -99.018344)
		(end 120.18518 -97.996756)
		(width 0.14224)
		(layer "F.Cu")
		(net "TDR_DIFF_85_TOP_DN")
	)
	(segment
		(start 119.685054 -97.49663)
		(end 107.0356 -97.49663)
		(width 0.14224)
		(layer "F.Cu")
		(net "TDR_DIFF_85_TOP_DN")
	)
	(segment
		(start 106.75112 -93.18879)
		(end 107.0356 -92.90431)
		(width 0.14224)
		(layer "F.Cu")
		(net "TDR_DIFF_85_TOP_DN")
	)
	(segment
		(start 113.61039 -85.344)
		(end 114.554 -85.344)
		(width 0.14224)
		(layer "F.Cu")
		(net "TDR_DIFF_85_TOP_DN")
	)
	(segment
		(start 119.685054 -92.90431)
		(end 120.18518 -92.404184)
		(width 0.14224)
		(layer "F.Cu")
		(net "TDR_DIFF_85_TOP_DN")
	)
	(segment
		(start 106.75112 -96.49587)
		(end 107.0356 -96.21139)
		(width 0.14224)
		(layer "F.Cu")
		(net "TDR_DIFF_85_TOP_DN")
	)
	(segment
		(start 120.18518 -89.097104)
		(end 120.18518 -88.075516)
		(width 0.14224)
		(layer "F.Cu")
		(net "TDR_DIFF_85_TOP_DN")
	)
	(segment
		(start 120.0912 -102.325424)
		(end 120.0912 -101.303836)
		(width 0.14224)
		(layer "F.Cu")
		(net "TDR_DIFF_85_TOP_DN")
	)
	(segment
		(start 106.75112 -99.80295)
		(end 107.0356 -99.51847)
		(width 0.14224)
		(layer "F.Cu")
		(net "TDR_DIFF_85_TOP_DN")
	)
	(segment
		(start 105.761282 -48.888904)
		(end 112.88776 -48.888904)
		(width 0.1143)
		(layer "In9.Cu")
		(net "TDR_DIFF_85_IN4_DP")
	)
	(segment
		(start 105.5243 -34.645346)
		(end 105.5243 -35.723322)
		(width 0.1143)
		(layer "In9.Cu")
		(net "TDR_DIFF_85_IN4_DP")
	)
	(segment
		(start 105.33634 -48.463962)
		(end 105.761282 -48.888904)
		(width 0.1143)
		(layer "In9.Cu")
		(net "TDR_DIFF_85_IN4_DP")
	)
	(segment
		(start 120.38838 -45.932344)
		(end 120.38838 -46.732444)
		(width 0.1143)
		(layer "In9.Cu")
		(net "TDR_DIFF_85_IN4_DP")
	)
	(segment
		(start 120.38838 -46.732444)
		(end 120.15978 -46.961044)
		(width 0.1143)
		(layer "In9.Cu")
		(net "TDR_DIFF_85_IN4_DP")
	)
	(segment
		(start 105.746042 -45.703744)
		(end 120.15978 -45.703744)
		(width 0.1143)
		(layer "In9.Cu")
		(net "TDR_DIFF_85_IN4_DP")
	)
	(segment
		(start 105.761282 -46.961044)
		(end 105.33634 -47.385986)
		(width 0.1143)
		(layer "In9.Cu")
		(net "TDR_DIFF_85_IN4_DP")
	)
	(segment
		(start 105.789222 -42.518584)
		(end 120.15978 -42.518584)
		(width 0.1143)
		(layer "In9.Cu")
		(net "TDR_DIFF_85_IN4_DP")
	)
	(segment
		(start 105.4354 -37.830506)
		(end 105.4354 -38.908482)
		(width 0.1143)
		(layer "In9.Cu")
		(net "TDR_DIFF_85_IN4_DP")
	)
	(segment
		(start 105.860342 -39.333424)
		(end 120.15978 -39.333424)
		(width 0.1143)
		(layer "In9.Cu")
		(net "TDR_DIFF_85_IN4_DP")
	)
	(segment
		(start 105.3211 -44.200826)
		(end 105.3211 -45.278802)
		(width 0.1143)
		(layer "In9.Cu")
		(net "TDR_DIFF_85_IN4_DP")
	)
	(segment
		(start 113.11636 -32.1183)
		(end 113.11636 -33.991804)
		(width 0.1143)
		(layer "In9.Cu")
		(net "TDR_DIFF_85_IN4_DP")
	)
	(segment
		(start 105.4354 -38.908482)
		(end 105.860342 -39.333424)
		(width 0.1143)
		(layer "In9.Cu")
		(net "TDR_DIFF_85_IN4_DP")
	)
	(segment
		(start 105.33634 -47.385986)
		(end 105.33634 -48.463962)
		(width 0.1143)
		(layer "In9.Cu")
		(net "TDR_DIFF_85_IN4_DP")
	)
	(segment
		(start 105.746042 -43.775884)
		(end 105.3211 -44.200826)
		(width 0.1143)
		(layer "In9.Cu")
		(net "TDR_DIFF_85_IN4_DP")
	)
	(segment
		(start 120.15978 -43.775884)
		(end 105.746042 -43.775884)
		(width 0.1143)
		(layer "In9.Cu")
		(net "TDR_DIFF_85_IN4_DP")
	)
	(segment
		(start 112.014 -32.004)
		(end 113.00206 -32.004)
		(width 0.1143)
		(layer "In9.Cu")
		(net "TDR_DIFF_85_IN4_DP")
	)
	(segment
		(start 120.38838 -43.547284)
		(end 120.15978 -43.775884)
		(width 0.1143)
		(layer "In9.Cu")
		(net "TDR_DIFF_85_IN4_DP")
	)
	(segment
		(start 120.15978 -36.148264)
		(end 120.38838 -36.376864)
		(width 0.1143)
		(layer "In9.Cu")
		(net "TDR_DIFF_85_IN4_DP")
	)
	(segment
		(start 120.38838 -37.176964)
		(end 120.15978 -37.405564)
		(width 0.1143)
		(layer "In9.Cu")
		(net "TDR_DIFF_85_IN4_DP")
	)
	(segment
		(start 105.789222 -40.590724)
		(end 105.36428 -41.015666)
		(width 0.1143)
		(layer "In9.Cu")
		(net "TDR_DIFF_85_IN4_DP")
	)
	(segment
		(start 120.15978 -45.703744)
		(end 120.38838 -45.932344)
		(width 0.1143)
		(layer "In9.Cu")
		(net "TDR_DIFF_85_IN4_DP")
	)
	(segment
		(start 113.11636 -50.6857)
		(end 113.00206 -50.8)
		(width 0.1143)
		(layer "In9.Cu")
		(net "TDR_DIFF_85_IN4_DP")
	)
	(segment
		(start 120.15978 -37.405564)
		(end 105.860342 -37.405564)
		(width 0.1143)
		(layer "In9.Cu")
		(net "TDR_DIFF_85_IN4_DP")
	)
	(segment
		(start 112.88776 -34.220404)
		(end 105.949242 -34.220404)
		(width 0.1143)
		(layer "In9.Cu")
		(net "TDR_DIFF_85_IN4_DP")
	)
	(segment
		(start 113.11636 -49.117504)
		(end 113.11636 -50.6857)
		(width 0.1143)
		(layer "In9.Cu")
		(net "TDR_DIFF_85_IN4_DP")
	)
	(segment
		(start 105.5243 -35.723322)
		(end 105.949242 -36.148264)
		(width 0.1143)
		(layer "In9.Cu")
		(net "TDR_DIFF_85_IN4_DP")
	)
	(segment
		(start 120.15978 -40.590724)
		(end 105.789222 -40.590724)
		(width 0.1143)
		(layer "In9.Cu")
		(net "TDR_DIFF_85_IN4_DP")
	)
	(segment
		(start 112.88776 -48.888904)
		(end 113.11636 -49.117504)
		(width 0.1143)
		(layer "In9.Cu")
		(net "TDR_DIFF_85_IN4_DP")
	)
	(segment
		(start 120.15978 -42.518584)
		(end 120.38838 -42.747184)
		(width 0.1143)
		(layer "In9.Cu")
		(net "TDR_DIFF_85_IN4_DP")
	)
	(segment
		(start 113.00206 -50.8)
		(end 112.014 -50.8)
		(width 0.1143)
		(layer "In9.Cu")
		(net "TDR_DIFF_85_IN4_DP")
	)
	(segment
		(start 105.860342 -37.405564)
		(end 105.4354 -37.830506)
		(width 0.1143)
		(layer "In9.Cu")
		(net "TDR_DIFF_85_IN4_DP")
	)
	(segment
		(start 120.38838 -42.747184)
		(end 120.38838 -43.547284)
		(width 0.1143)
		(layer "In9.Cu")
		(net "TDR_DIFF_85_IN4_DP")
	)
	(segment
		(start 120.15978 -39.333424)
		(end 120.38838 -39.562024)
		(width 0.1143)
		(layer "In9.Cu")
		(net "TDR_DIFF_85_IN4_DP")
	)
	(segment
		(start 105.949242 -34.220404)
		(end 105.5243 -34.645346)
		(width 0.1143)
		(layer "In9.Cu")
		(net "TDR_DIFF_85_IN4_DP")
	)
	(segment
		(start 120.15978 -46.961044)
		(end 105.761282 -46.961044)
		(width 0.1143)
		(layer "In9.Cu")
		(net "TDR_DIFF_85_IN4_DP")
	)
	(segment
		(start 120.38838 -40.362124)
		(end 120.15978 -40.590724)
		(width 0.1143)
		(layer "In9.Cu")
		(net "TDR_DIFF_85_IN4_DP")
	)
	(segment
		(start 105.36428 -41.015666)
		(end 105.36428 -42.093642)
		(width 0.1143)
		(layer "In9.Cu")
		(net "TDR_DIFF_85_IN4_DP")
	)
	(segment
		(start 113.00206 -32.004)
		(end 113.11636 -32.1183)
		(width 0.1143)
		(layer "In9.Cu")
		(net "TDR_DIFF_85_IN4_DP")
	)
	(segment
		(start 105.949242 -36.148264)
		(end 120.15978 -36.148264)
		(width 0.1143)
		(layer "In9.Cu")
		(net "TDR_DIFF_85_IN4_DP")
	)
	(segment
		(start 105.36428 -42.093642)
		(end 105.789222 -42.518584)
		(width 0.1143)
		(layer "In9.Cu")
		(net "TDR_DIFF_85_IN4_DP")
	)
	(segment
		(start 105.3211 -45.278802)
		(end 105.746042 -45.703744)
		(width 0.1143)
		(layer "In9.Cu")
		(net "TDR_DIFF_85_IN4_DP")
	)
	(segment
		(start 120.38838 -36.376864)
		(end 120.38838 -37.176964)
		(width 0.1143)
		(layer "In9.Cu")
		(net "TDR_DIFF_85_IN4_DP")
	)
	(segment
		(start 113.11636 -33.991804)
		(end 112.88776 -34.220404)
		(width 0.1143)
		(layer "In9.Cu")
		(net "TDR_DIFF_85_IN4_DP")
	)
	(segment
		(start 120.38838 -39.562024)
		(end 120.38838 -40.362124)
		(width 0.1143)
		(layer "In9.Cu")
		(net "TDR_DIFF_85_IN4_DP")
	)
	(segment
		(start 105.77068 -37.969444)
		(end 105.77068 -38.769544)
		(width 0.1143)
		(layer "In9.Cu")
		(net "TDR_DIFF_85_IN4_DN")
	)
	(segment
		(start 113.56594 -32.004)
		(end 113.45164 -32.1183)
		(width 0.1143)
		(layer "In9.Cu")
		(net "TDR_DIFF_85_IN4_DN")
	)
	(segment
		(start 113.45164 -50.6857)
		(end 113.56594 -50.8)
		(width 0.1143)
		(layer "In9.Cu")
		(net "TDR_DIFF_85_IN4_DN")
	)
	(segment
		(start 113.026698 -34.555684)
		(end 106.08818 -34.555684)
		(width 0.1143)
		(layer "In9.Cu")
		(net "TDR_DIFF_85_IN4_DN")
	)
	(segment
		(start 105.65638 -44.339764)
		(end 105.65638 -45.139864)
		(width 0.1143)
		(layer "In9.Cu")
		(net "TDR_DIFF_85_IN4_DN")
	)
	(segment
		(start 120.72366 -40.501062)
		(end 120.298718 -40.926004)
		(width 0.1143)
		(layer "In9.Cu")
		(net "TDR_DIFF_85_IN4_DN")
	)
	(segment
		(start 105.88498 -44.111164)
		(end 105.65638 -44.339764)
		(width 0.1143)
		(layer "In9.Cu")
		(net "TDR_DIFF_85_IN4_DN")
	)
	(segment
		(start 120.298718 -40.926004)
		(end 105.92816 -40.926004)
		(width 0.1143)
		(layer "In9.Cu")
		(net "TDR_DIFF_85_IN4_DN")
	)
	(segment
		(start 120.298718 -38.998144)
		(end 120.72366 -39.423086)
		(width 0.1143)
		(layer "In9.Cu")
		(net "TDR_DIFF_85_IN4_DN")
	)
	(segment
		(start 113.45164 -34.130742)
		(end 113.026698 -34.555684)
		(width 0.1143)
		(layer "In9.Cu")
		(net "TDR_DIFF_85_IN4_DN")
	)
	(segment
		(start 105.85958 -35.584384)
		(end 106.08818 -35.812984)
		(width 0.1143)
		(layer "In9.Cu")
		(net "TDR_DIFF_85_IN4_DN")
	)
	(segment
		(start 105.65638 -45.139864)
		(end 105.88498 -45.368464)
		(width 0.1143)
		(layer "In9.Cu")
		(net "TDR_DIFF_85_IN4_DN")
	)
	(segment
		(start 113.026698 -48.553624)
		(end 113.45164 -48.978566)
		(width 0.1143)
		(layer "In9.Cu")
		(net "TDR_DIFF_85_IN4_DN")
	)
	(segment
		(start 113.45164 -32.1183)
		(end 113.45164 -34.130742)
		(width 0.1143)
		(layer "In9.Cu")
		(net "TDR_DIFF_85_IN4_DN")
	)
	(segment
		(start 113.56594 -50.8)
		(end 114.554 -50.8)
		(width 0.1143)
		(layer "In9.Cu")
		(net "TDR_DIFF_85_IN4_DN")
	)
	(segment
		(start 120.72366 -36.237926)
		(end 120.72366 -37.315902)
		(width 0.1143)
		(layer "In9.Cu")
		(net "TDR_DIFF_85_IN4_DN")
	)
	(segment
		(start 120.298718 -45.368464)
		(end 120.72366 -45.793406)
		(width 0.1143)
		(layer "In9.Cu")
		(net "TDR_DIFF_85_IN4_DN")
	)
	(segment
		(start 120.298718 -35.812984)
		(end 120.72366 -36.237926)
		(width 0.1143)
		(layer "In9.Cu")
		(net "TDR_DIFF_85_IN4_DN")
	)
	(segment
		(start 105.88498 -45.368464)
		(end 120.298718 -45.368464)
		(width 0.1143)
		(layer "In9.Cu")
		(net "TDR_DIFF_85_IN4_DN")
	)
	(segment
		(start 105.90022 -48.553624)
		(end 113.026698 -48.553624)
		(width 0.1143)
		(layer "In9.Cu")
		(net "TDR_DIFF_85_IN4_DN")
	)
	(segment
		(start 105.69956 -41.954704)
		(end 105.92816 -42.183304)
		(width 0.1143)
		(layer "In9.Cu")
		(net "TDR_DIFF_85_IN4_DN")
	)
	(segment
		(start 120.72366 -37.315902)
		(end 120.298718 -37.740844)
		(width 0.1143)
		(layer "In9.Cu")
		(net "TDR_DIFF_85_IN4_DN")
	)
	(segment
		(start 120.298718 -44.111164)
		(end 105.88498 -44.111164)
		(width 0.1143)
		(layer "In9.Cu")
		(net "TDR_DIFF_85_IN4_DN")
	)
	(segment
		(start 120.72366 -42.608246)
		(end 120.72366 -43.686222)
		(width 0.1143)
		(layer "In9.Cu")
		(net "TDR_DIFF_85_IN4_DN")
	)
	(segment
		(start 120.72366 -43.686222)
		(end 120.298718 -44.111164)
		(width 0.1143)
		(layer "In9.Cu")
		(net "TDR_DIFF_85_IN4_DN")
	)
	(segment
		(start 114.554 -32.004)
		(end 113.56594 -32.004)
		(width 0.1143)
		(layer "In9.Cu")
		(net "TDR_DIFF_85_IN4_DN")
	)
	(segment
		(start 120.72366 -46.871382)
		(end 120.298718 -47.296324)
		(width 0.1143)
		(layer "In9.Cu")
		(net "TDR_DIFF_85_IN4_DN")
	)
	(segment
		(start 105.67162 -48.325024)
		(end 105.90022 -48.553624)
		(width 0.1143)
		(layer "In9.Cu")
		(net "TDR_DIFF_85_IN4_DN")
	)
	(segment
		(start 120.72366 -39.423086)
		(end 120.72366 -40.501062)
		(width 0.1143)
		(layer "In9.Cu")
		(net "TDR_DIFF_85_IN4_DN")
	)
	(segment
		(start 105.77068 -38.769544)
		(end 105.99928 -38.998144)
		(width 0.1143)
		(layer "In9.Cu")
		(net "TDR_DIFF_85_IN4_DN")
	)
	(segment
		(start 106.08818 -34.555684)
		(end 105.85958 -34.784284)
		(width 0.1143)
		(layer "In9.Cu")
		(net "TDR_DIFF_85_IN4_DN")
	)
	(segment
		(start 120.72366 -45.793406)
		(end 120.72366 -46.871382)
		(width 0.1143)
		(layer "In9.Cu")
		(net "TDR_DIFF_85_IN4_DN")
	)
	(segment
		(start 105.92816 -40.926004)
		(end 105.69956 -41.154604)
		(width 0.1143)
		(layer "In9.Cu")
		(net "TDR_DIFF_85_IN4_DN")
	)
	(segment
		(start 105.99928 -37.740844)
		(end 105.77068 -37.969444)
		(width 0.1143)
		(layer "In9.Cu")
		(net "TDR_DIFF_85_IN4_DN")
	)
	(segment
		(start 105.85958 -34.784284)
		(end 105.85958 -35.584384)
		(width 0.1143)
		(layer "In9.Cu")
		(net "TDR_DIFF_85_IN4_DN")
	)
	(segment
		(start 105.92816 -42.183304)
		(end 120.298718 -42.183304)
		(width 0.1143)
		(layer "In9.Cu")
		(net "TDR_DIFF_85_IN4_DN")
	)
	(segment
		(start 120.298718 -37.740844)
		(end 105.99928 -37.740844)
		(width 0.1143)
		(layer "In9.Cu")
		(net "TDR_DIFF_85_IN4_DN")
	)
	(segment
		(start 120.298718 -42.183304)
		(end 120.72366 -42.608246)
		(width 0.1143)
		(layer "In9.Cu")
		(net "TDR_DIFF_85_IN4_DN")
	)
	(segment
		(start 105.99928 -38.998144)
		(end 120.298718 -38.998144)
		(width 0.1143)
		(layer "In9.Cu")
		(net "TDR_DIFF_85_IN4_DN")
	)
	(segment
		(start 105.90022 -47.296324)
		(end 105.67162 -47.524924)
		(width 0.1143)
		(layer "In9.Cu")
		(net "TDR_DIFF_85_IN4_DN")
	)
	(segment
		(start 113.45164 -48.978566)
		(end 113.45164 -50.6857)
		(width 0.1143)
		(layer "In9.Cu")
		(net "TDR_DIFF_85_IN4_DN")
	)
	(segment
		(start 105.69956 -41.154604)
		(end 105.69956 -41.954704)
		(width 0.1143)
		(layer "In9.Cu")
		(net "TDR_DIFF_85_IN4_DN")
	)
	(segment
		(start 120.298718 -47.296324)
		(end 105.90022 -47.296324)
		(width 0.1143)
		(layer "In9.Cu")
		(net "TDR_DIFF_85_IN4_DN")
	)
	(segment
		(start 105.67162 -47.524924)
		(end 105.67162 -48.325024)
		(width 0.1143)
		(layer "In9.Cu")
		(net "TDR_DIFF_85_IN4_DN")
	)
	(segment
		(start 106.08818 -35.812984)
		(end 120.298718 -35.812984)
		(width 0.1143)
		(layer "In9.Cu")
		(net "TDR_DIFF_85_IN4_DN")
	)
	(segment
		(start 105.296462 -73.217786)
		(end 121.03862 -73.217786)
		(width 0.1143)
		(layer "In2.Cu")
		(net "TDR_DIFF_85_IN1_DP")
	)
	(segment
		(start 104.87152 -74.720704)
		(end 104.87152 -73.642728)
		(width 0.1143)
		(layer "In2.Cu")
		(net "TDR_DIFF_85_IN1_DP")
	)
	(segment
		(start 121.26722 -66.618866)
		(end 121.26722 -65.818766)
		(width 0.1143)
		(layer "In2.Cu")
		(net "TDR_DIFF_85_IN1_DP")
	)
	(segment
		(start 121.26722 -69.804026)
		(end 121.26722 -69.003926)
		(width 0.1143)
		(layer "In2.Cu")
		(net "TDR_DIFF_85_IN1_DP")
	)
	(segment
		(start 106.950002 -62.405006)
		(end 106.52506 -61.980064)
		(width 0.1143)
		(layer "In2.Cu")
		(net "TDR_DIFF_85_IN1_DP")
	)
	(segment
		(start 106.426762 -70.032626)
		(end 121.03862 -70.032626)
		(width 0.1143)
		(layer "In2.Cu")
		(net "TDR_DIFF_85_IN1_DP")
	)
	(segment
		(start 112.88776 -75.145646)
		(end 105.296462 -75.145646)
		(width 0.1143)
		(layer "In2.Cu")
		(net "TDR_DIFF_85_IN1_DP")
	)
	(segment
		(start 121.26722 -65.818766)
		(end 121.03862 -65.590166)
		(width 0.1143)
		(layer "In2.Cu")
		(net "TDR_DIFF_85_IN1_DP")
	)
	(segment
		(start 106.52506 -67.272408)
		(end 106.950002 -66.847466)
		(width 0.1143)
		(layer "In2.Cu")
		(net "TDR_DIFF_85_IN1_DP")
	)
	(segment
		(start 106.00182 -71.535544)
		(end 106.00182 -70.457568)
		(width 0.1143)
		(layer "In2.Cu")
		(net "TDR_DIFF_85_IN1_DP")
	)
	(segment
		(start 106.52506 -68.350384)
		(end 106.52506 -67.272408)
		(width 0.1143)
		(layer "In2.Cu")
		(net "TDR_DIFF_85_IN1_DP")
	)
	(segment
		(start 113.11636 -60.248546)
		(end 113.11636 -58.5343)
		(width 0.1143)
		(layer "In2.Cu")
		(net "TDR_DIFF_85_IN1_DP")
	)
	(segment
		(start 121.26722 -62.633606)
		(end 121.03862 -62.405006)
		(width 0.1143)
		(layer "In2.Cu")
		(net "TDR_DIFF_85_IN1_DP")
	)
	(segment
		(start 106.950002 -66.847466)
		(end 121.03862 -66.847466)
		(width 0.1143)
		(layer "In2.Cu")
		(net "TDR_DIFF_85_IN1_DP")
	)
	(segment
		(start 106.5403 -64.087248)
		(end 106.965242 -63.662306)
		(width 0.1143)
		(layer "In2.Cu")
		(net "TDR_DIFF_85_IN1_DP")
	)
	(segment
		(start 113.11636 -58.5343)
		(end 113.00206 -58.42)
		(width 0.1143)
		(layer "In2.Cu")
		(net "TDR_DIFF_85_IN1_DP")
	)
	(segment
		(start 106.00182 -70.457568)
		(end 106.426762 -70.032626)
		(width 0.1143)
		(layer "In2.Cu")
		(net "TDR_DIFF_85_IN1_DP")
	)
	(segment
		(start 113.11636 -77.1017)
		(end 113.11636 -75.374246)
		(width 0.1143)
		(layer "In2.Cu")
		(net "TDR_DIFF_85_IN1_DP")
	)
	(segment
		(start 121.03862 -66.847466)
		(end 121.26722 -66.618866)
		(width 0.1143)
		(layer "In2.Cu")
		(net "TDR_DIFF_85_IN1_DP")
	)
	(segment
		(start 121.26722 -72.989186)
		(end 121.26722 -72.189086)
		(width 0.1143)
		(layer "In2.Cu")
		(net "TDR_DIFF_85_IN1_DP")
	)
	(segment
		(start 121.26722 -72.189086)
		(end 121.03862 -71.960486)
		(width 0.1143)
		(layer "In2.Cu")
		(net "TDR_DIFF_85_IN1_DP")
	)
	(segment
		(start 106.52506 -60.902088)
		(end 106.950002 -60.477146)
		(width 0.1143)
		(layer "In2.Cu")
		(net "TDR_DIFF_85_IN1_DP")
	)
	(segment
		(start 113.11636 -75.374246)
		(end 112.88776 -75.145646)
		(width 0.1143)
		(layer "In2.Cu")
		(net "TDR_DIFF_85_IN1_DP")
	)
	(segment
		(start 106.950002 -68.775326)
		(end 106.52506 -68.350384)
		(width 0.1143)
		(layer "In2.Cu")
		(net "TDR_DIFF_85_IN1_DP")
	)
	(segment
		(start 106.52506 -61.980064)
		(end 106.52506 -60.902088)
		(width 0.1143)
		(layer "In2.Cu")
		(net "TDR_DIFF_85_IN1_DP")
	)
	(segment
		(start 121.03862 -62.405006)
		(end 106.950002 -62.405006)
		(width 0.1143)
		(layer "In2.Cu")
		(net "TDR_DIFF_85_IN1_DP")
	)
	(segment
		(start 121.03862 -68.775326)
		(end 106.950002 -68.775326)
		(width 0.1143)
		(layer "In2.Cu")
		(net "TDR_DIFF_85_IN1_DP")
	)
	(segment
		(start 104.87152 -73.642728)
		(end 105.296462 -73.217786)
		(width 0.1143)
		(layer "In2.Cu")
		(net "TDR_DIFF_85_IN1_DP")
	)
	(segment
		(start 106.950002 -60.477146)
		(end 112.88776 -60.477146)
		(width 0.1143)
		(layer "In2.Cu")
		(net "TDR_DIFF_85_IN1_DP")
	)
	(segment
		(start 112.88776 -60.477146)
		(end 113.11636 -60.248546)
		(width 0.1143)
		(layer "In2.Cu")
		(net "TDR_DIFF_85_IN1_DP")
	)
	(segment
		(start 121.03862 -71.960486)
		(end 106.426762 -71.960486)
		(width 0.1143)
		(layer "In2.Cu")
		(net "TDR_DIFF_85_IN1_DP")
	)
	(segment
		(start 105.296462 -75.145646)
		(end 104.87152 -74.720704)
		(width 0.1143)
		(layer "In2.Cu")
		(net "TDR_DIFF_85_IN1_DP")
	)
	(segment
		(start 121.03862 -65.590166)
		(end 106.965242 -65.590166)
		(width 0.1143)
		(layer "In2.Cu")
		(net "TDR_DIFF_85_IN1_DP")
	)
	(segment
		(start 113.00206 -77.216)
		(end 113.11636 -77.1017)
		(width 0.1143)
		(layer "In2.Cu")
		(net "TDR_DIFF_85_IN1_DP")
	)
	(segment
		(start 121.26722 -63.433706)
		(end 121.26722 -62.633606)
		(width 0.1143)
		(layer "In2.Cu")
		(net "TDR_DIFF_85_IN1_DP")
	)
	(segment
		(start 121.03862 -70.032626)
		(end 121.26722 -69.804026)
		(width 0.1143)
		(layer "In2.Cu")
		(net "TDR_DIFF_85_IN1_DP")
	)
	(segment
		(start 113.00206 -58.42)
		(end 112.014 -58.42)
		(width 0.1143)
		(layer "In2.Cu")
		(net "TDR_DIFF_85_IN1_DP")
	)
	(segment
		(start 106.965242 -65.590166)
		(end 106.5403 -65.165224)
		(width 0.1143)
		(layer "In2.Cu")
		(net "TDR_DIFF_85_IN1_DP")
	)
	(segment
		(start 121.03862 -63.662306)
		(end 121.26722 -63.433706)
		(width 0.1143)
		(layer "In2.Cu")
		(net "TDR_DIFF_85_IN1_DP")
	)
	(segment
		(start 121.26722 -69.003926)
		(end 121.03862 -68.775326)
		(width 0.1143)
		(layer "In2.Cu")
		(net "TDR_DIFF_85_IN1_DP")
	)
	(segment
		(start 106.5403 -65.165224)
		(end 106.5403 -64.087248)
		(width 0.1143)
		(layer "In2.Cu")
		(net "TDR_DIFF_85_IN1_DP")
	)
	(segment
		(start 106.965242 -63.662306)
		(end 121.03862 -63.662306)
		(width 0.1143)
		(layer "In2.Cu")
		(net "TDR_DIFF_85_IN1_DP")
	)
	(segment
		(start 121.03862 -73.217786)
		(end 121.26722 -72.989186)
		(width 0.1143)
		(layer "In2.Cu")
		(net "TDR_DIFF_85_IN1_DP")
	)
	(segment
		(start 112.014 -77.216)
		(end 113.00206 -77.216)
		(width 0.1143)
		(layer "In2.Cu")
		(net "TDR_DIFF_85_IN1_DP")
	)
	(segment
		(start 106.426762 -71.960486)
		(end 106.00182 -71.535544)
		(width 0.1143)
		(layer "In2.Cu")
		(net "TDR_DIFF_85_IN1_DP")
	)
	(segment
		(start 121.177558 -65.254886)
		(end 107.10418 -65.254886)
		(width 0.1143)
		(layer "In2.Cu")
		(net "TDR_DIFF_85_IN1_DN")
	)
	(segment
		(start 121.6025 -66.757804)
		(end 121.6025 -65.679828)
		(width 0.1143)
		(layer "In2.Cu")
		(net "TDR_DIFF_85_IN1_DN")
	)
	(segment
		(start 121.6025 -73.128124)
		(end 121.6025 -72.050148)
		(width 0.1143)
		(layer "In2.Cu")
		(net "TDR_DIFF_85_IN1_DN")
	)
	(segment
		(start 106.86034 -61.841126)
		(end 106.86034 -61.041026)
		(width 0.1143)
		(layer "In2.Cu")
		(net "TDR_DIFF_85_IN1_DN")
	)
	(segment
		(start 106.87558 -64.226186)
		(end 107.10418 -63.997586)
		(width 0.1143)
		(layer "In2.Cu")
		(net "TDR_DIFF_85_IN1_DN")
	)
	(segment
		(start 106.5657 -71.625206)
		(end 106.3371 -71.396606)
		(width 0.1143)
		(layer "In2.Cu")
		(net "TDR_DIFF_85_IN1_DN")
	)
	(segment
		(start 107.08894 -68.440046)
		(end 106.86034 -68.211446)
		(width 0.1143)
		(layer "In2.Cu")
		(net "TDR_DIFF_85_IN1_DN")
	)
	(segment
		(start 121.177558 -63.997586)
		(end 121.6025 -63.572644)
		(width 0.1143)
		(layer "In2.Cu")
		(net "TDR_DIFF_85_IN1_DN")
	)
	(segment
		(start 106.86034 -67.411346)
		(end 107.08894 -67.182746)
		(width 0.1143)
		(layer "In2.Cu")
		(net "TDR_DIFF_85_IN1_DN")
	)
	(segment
		(start 121.177558 -62.069726)
		(end 107.08894 -62.069726)
		(width 0.1143)
		(layer "In2.Cu")
		(net "TDR_DIFF_85_IN1_DN")
	)
	(segment
		(start 121.177558 -73.553066)
		(end 121.6025 -73.128124)
		(width 0.1143)
		(layer "In2.Cu")
		(net "TDR_DIFF_85_IN1_DN")
	)
	(segment
		(start 106.5657 -70.367906)
		(end 121.177558 -70.367906)
		(width 0.1143)
		(layer "In2.Cu")
		(net "TDR_DIFF_85_IN1_DN")
	)
	(segment
		(start 121.6025 -63.572644)
		(end 121.6025 -62.494668)
		(width 0.1143)
		(layer "In2.Cu")
		(net "TDR_DIFF_85_IN1_DN")
	)
	(segment
		(start 121.6025 -69.942964)
		(end 121.6025 -68.864988)
		(width 0.1143)
		(layer "In2.Cu")
		(net "TDR_DIFF_85_IN1_DN")
	)
	(segment
		(start 113.45164 -75.235308)
		(end 113.026698 -74.810366)
		(width 0.1143)
		(layer "In2.Cu")
		(net "TDR_DIFF_85_IN1_DN")
	)
	(segment
		(start 113.45164 -60.387484)
		(end 113.45164 -58.5343)
		(width 0.1143)
		(layer "In2.Cu")
		(net "TDR_DIFF_85_IN1_DN")
	)
	(segment
		(start 107.10418 -63.997586)
		(end 121.177558 -63.997586)
		(width 0.1143)
		(layer "In2.Cu")
		(net "TDR_DIFF_85_IN1_DN")
	)
	(segment
		(start 113.56594 -58.42)
		(end 114.554 -58.42)
		(width 0.1143)
		(layer "In2.Cu")
		(net "TDR_DIFF_85_IN1_DN")
	)
	(segment
		(start 113.56594 -77.216)
		(end 113.45164 -77.1017)
		(width 0.1143)
		(layer "In2.Cu")
		(net "TDR_DIFF_85_IN1_DN")
	)
	(segment
		(start 121.6025 -65.679828)
		(end 121.177558 -65.254886)
		(width 0.1143)
		(layer "In2.Cu")
		(net "TDR_DIFF_85_IN1_DN")
	)
	(segment
		(start 121.6025 -72.050148)
		(end 121.177558 -71.625206)
		(width 0.1143)
		(layer "In2.Cu")
		(net "TDR_DIFF_85_IN1_DN")
	)
	(segment
		(start 105.4354 -73.553066)
		(end 121.177558 -73.553066)
		(width 0.1143)
		(layer "In2.Cu")
		(net "TDR_DIFF_85_IN1_DN")
	)
	(segment
		(start 121.6025 -62.494668)
		(end 121.177558 -62.069726)
		(width 0.1143)
		(layer "In2.Cu")
		(net "TDR_DIFF_85_IN1_DN")
	)
	(segment
		(start 121.177558 -67.182746)
		(end 121.6025 -66.757804)
		(width 0.1143)
		(layer "In2.Cu")
		(net "TDR_DIFF_85_IN1_DN")
	)
	(segment
		(start 113.026698 -60.812426)
		(end 113.45164 -60.387484)
		(width 0.1143)
		(layer "In2.Cu")
		(net "TDR_DIFF_85_IN1_DN")
	)
	(segment
		(start 114.554 -77.216)
		(end 113.56594 -77.216)
		(width 0.1143)
		(layer "In2.Cu")
		(net "TDR_DIFF_85_IN1_DN")
	)
	(segment
		(start 113.45164 -77.1017)
		(end 113.45164 -75.235308)
		(width 0.1143)
		(layer "In2.Cu")
		(net "TDR_DIFF_85_IN1_DN")
	)
	(segment
		(start 106.87558 -65.026286)
		(end 106.87558 -64.226186)
		(width 0.1143)
		(layer "In2.Cu")
		(net "TDR_DIFF_85_IN1_DN")
	)
	(segment
		(start 121.177558 -68.440046)
		(end 107.08894 -68.440046)
		(width 0.1143)
		(layer "In2.Cu")
		(net "TDR_DIFF_85_IN1_DN")
	)
	(segment
		(start 107.08894 -62.069726)
		(end 106.86034 -61.841126)
		(width 0.1143)
		(layer "In2.Cu")
		(net "TDR_DIFF_85_IN1_DN")
	)
	(segment
		(start 105.2068 -74.581766)
		(end 105.2068 -73.781666)
		(width 0.1143)
		(layer "In2.Cu")
		(net "TDR_DIFF_85_IN1_DN")
	)
	(segment
		(start 107.08894 -60.812426)
		(end 113.026698 -60.812426)
		(width 0.1143)
		(layer "In2.Cu")
		(net "TDR_DIFF_85_IN1_DN")
	)
	(segment
		(start 106.3371 -70.596506)
		(end 106.5657 -70.367906)
		(width 0.1143)
		(layer "In2.Cu")
		(net "TDR_DIFF_85_IN1_DN")
	)
	(segment
		(start 107.10418 -65.254886)
		(end 106.87558 -65.026286)
		(width 0.1143)
		(layer "In2.Cu")
		(net "TDR_DIFF_85_IN1_DN")
	)
	(segment
		(start 105.2068 -73.781666)
		(end 105.4354 -73.553066)
		(width 0.1143)
		(layer "In2.Cu")
		(net "TDR_DIFF_85_IN1_DN")
	)
	(segment
		(start 121.177558 -71.625206)
		(end 106.5657 -71.625206)
		(width 0.1143)
		(layer "In2.Cu")
		(net "TDR_DIFF_85_IN1_DN")
	)
	(segment
		(start 121.177558 -70.367906)
		(end 121.6025 -69.942964)
		(width 0.1143)
		(layer "In2.Cu")
		(net "TDR_DIFF_85_IN1_DN")
	)
	(segment
		(start 106.86034 -68.211446)
		(end 106.86034 -67.411346)
		(width 0.1143)
		(layer "In2.Cu")
		(net "TDR_DIFF_85_IN1_DN")
	)
	(segment
		(start 107.08894 -67.182746)
		(end 121.177558 -67.182746)
		(width 0.1143)
		(layer "In2.Cu")
		(net "TDR_DIFF_85_IN1_DN")
	)
	(segment
		(start 105.4354 -74.810366)
		(end 105.2068 -74.581766)
		(width 0.1143)
		(layer "In2.Cu")
		(net "TDR_DIFF_85_IN1_DN")
	)
	(segment
		(start 106.3371 -71.396606)
		(end 106.3371 -70.596506)
		(width 0.1143)
		(layer "In2.Cu")
		(net "TDR_DIFF_85_IN1_DN")
	)
	(segment
		(start 106.86034 -61.041026)
		(end 107.08894 -60.812426)
		(width 0.1143)
		(layer "In2.Cu")
		(net "TDR_DIFF_85_IN1_DN")
	)
	(segment
		(start 113.026698 -74.810366)
		(end 105.4354 -74.810366)
		(width 0.1143)
		(layer "In2.Cu")
		(net "TDR_DIFF_85_IN1_DN")
	)
	(segment
		(start 121.6025 -68.864988)
		(end 121.177558 -68.440046)
		(width 0.1143)
		(layer "In2.Cu")
		(net "TDR_DIFF_85_IN1_DN")
	)
	(segment
		(start 113.45164 -58.5343)
		(end 113.56594 -58.42)
		(width 0.1143)
		(layer "In2.Cu")
		(net "TDR_DIFF_85_IN1_DN")
	)
	(segment
		(start 119.685054 -10.60831)
		(end 120.18518 -10.108184)
		(width 0.14224)
		(layer "B.Cu")
		(net "TDR_DIFF_85_BOT_DP")
	)
	(segment
		(start 106.75112 -17.50695)
		(end 107.0356 -17.22247)
		(width 0.14224)
		(layer "B.Cu")
		(net "TDR_DIFF_85_BOT_DP")
	)
	(segment
		(start 119.685054 -13.91539)
		(end 120.18518 -13.415264)
		(width 0.14224)
		(layer "B.Cu")
		(net "TDR_DIFF_85_BOT_DP")
	)
	(segment
		(start 107.0356 -20.52955)
		(end 119.591074 -20.52955)
		(width 0.14224)
		(layer "B.Cu")
		(net "TDR_DIFF_85_BOT_DP")
	)
	(segment
		(start 106.75112 -10.89279)
		(end 107.0356 -10.60831)
		(width 0.14224)
		(layer "B.Cu")
		(net "TDR_DIFF_85_BOT_DP")
	)
	(segment
		(start 113.61039 -24.384)
		(end 113.46815 -24.24176)
		(width 0.14224)
		(layer "B.Cu")
		(net "TDR_DIFF_85_BOT_DP")
	)
	(segment
		(start 119.685054 -15.20063)
		(end 107.0356 -15.20063)
		(width 0.14224)
		(layer "B.Cu")
		(net "TDR_DIFF_85_BOT_DP")
	)
	(segment
		(start 113.75263 -5.27939)
		(end 113.46815 -4.99491)
		(width 0.14224)
		(layer "B.Cu")
		(net "TDR_DIFF_85_BOT_DP")
	)
	(segment
		(start 120.0912 -20.029424)
		(end 120.0912 -19.007836)
		(width 0.14224)
		(layer "B.Cu")
		(net "TDR_DIFF_85_BOT_DP")
	)
	(segment
		(start 113.46815 -22.314916)
		(end 112.968024 -21.81479)
		(width 0.14224)
		(layer "B.Cu")
		(net "TDR_DIFF_85_BOT_DP")
	)
	(segment
		(start 120.18518 -9.086596)
		(end 119.685054 -8.58647)
		(width 0.14224)
		(layer "B.Cu")
		(net "TDR_DIFF_85_BOT_DP")
	)
	(segment
		(start 107.0356 -13.91539)
		(end 119.685054 -13.91539)
		(width 0.14224)
		(layer "B.Cu")
		(net "TDR_DIFF_85_BOT_DP")
	)
	(segment
		(start 106.75112 -18.22323)
		(end 106.75112 -17.50695)
		(width 0.14224)
		(layer "B.Cu")
		(net "TDR_DIFF_85_BOT_DP")
	)
	(segment
		(start 120.18518 -12.393676)
		(end 119.685054 -11.89355)
		(width 0.14224)
		(layer "B.Cu")
		(net "TDR_DIFF_85_BOT_DP")
	)
	(segment
		(start 120.18518 -15.700756)
		(end 119.685054 -15.20063)
		(width 0.14224)
		(layer "B.Cu")
		(net "TDR_DIFF_85_BOT_DP")
	)
	(segment
		(start 112.968024 -21.81479)
		(end 107.0356 -21.81479)
		(width 0.14224)
		(layer "B.Cu")
		(net "TDR_DIFF_85_BOT_DP")
	)
	(segment
		(start 106.75112 -20.81403)
		(end 107.0356 -20.52955)
		(width 0.14224)
		(layer "B.Cu")
		(net "TDR_DIFF_85_BOT_DP")
	)
	(segment
		(start 107.0356 -8.58647)
		(end 106.75112 -8.30199)
		(width 0.14224)
		(layer "B.Cu")
		(net "TDR_DIFF_85_BOT_DP")
	)
	(segment
		(start 106.75112 -21.53031)
		(end 106.75112 -20.81403)
		(width 0.14224)
		(layer "B.Cu")
		(net "TDR_DIFF_85_BOT_DP")
	)
	(segment
		(start 119.591074 -18.50771)
		(end 107.0356 -18.50771)
		(width 0.14224)
		(layer "B.Cu")
		(net "TDR_DIFF_85_BOT_DP")
	)
	(segment
		(start 107.0356 -10.60831)
		(end 119.685054 -10.60831)
		(width 0.14224)
		(layer "B.Cu")
		(net "TDR_DIFF_85_BOT_DP")
	)
	(segment
		(start 120.18518 -6.801104)
		(end 120.18518 -5.779516)
		(width 0.14224)
		(layer "B.Cu")
		(net "TDR_DIFF_85_BOT_DP")
	)
	(segment
		(start 120.0912 -19.007836)
		(end 119.591074 -18.50771)
		(width 0.14224)
		(layer "B.Cu")
		(net "TDR_DIFF_85_BOT_DP")
	)
	(segment
		(start 106.75112 -11.60907)
		(end 106.75112 -10.89279)
		(width 0.14224)
		(layer "B.Cu")
		(net "TDR_DIFF_85_BOT_DP")
	)
	(segment
		(start 106.75112 -8.30199)
		(end 106.75112 -7.58571)
		(width 0.14224)
		(layer "B.Cu")
		(net "TDR_DIFF_85_BOT_DP")
	)
	(segment
		(start 114.554 -24.384)
		(end 113.61039 -24.384)
		(width 0.14224)
		(layer "B.Cu")
		(net "TDR_DIFF_85_BOT_DP")
	)
	(segment
		(start 106.75112 -7.58571)
		(end 107.0356 -7.30123)
		(width 0.14224)
		(layer "B.Cu")
		(net "TDR_DIFF_85_BOT_DP")
	)
	(segment
		(start 120.18518 -10.108184)
		(end 120.18518 -9.086596)
		(width 0.14224)
		(layer "B.Cu")
		(net "TDR_DIFF_85_BOT_DP")
	)
	(segment
		(start 113.46815 -3.19024)
		(end 113.61039 -3.048)
		(width 0.14224)
		(layer "B.Cu")
		(net "TDR_DIFF_85_BOT_DP")
	)
	(segment
		(start 107.0356 -21.81479)
		(end 106.75112 -21.53031)
		(width 0.14224)
		(layer "B.Cu")
		(net "TDR_DIFF_85_BOT_DP")
	)
	(segment
		(start 120.18518 -16.722344)
		(end 120.18518 -15.700756)
		(width 0.14224)
		(layer "B.Cu")
		(net "TDR_DIFF_85_BOT_DP")
	)
	(segment
		(start 107.0356 -7.30123)
		(end 119.685054 -7.30123)
		(width 0.14224)
		(layer "B.Cu")
		(net "TDR_DIFF_85_BOT_DP")
	)
	(segment
		(start 120.18518 -5.779516)
		(end 119.685054 -5.27939)
		(width 0.14224)
		(layer "B.Cu")
		(net "TDR_DIFF_85_BOT_DP")
	)
	(segment
		(start 119.685054 -8.58647)
		(end 107.0356 -8.58647)
		(width 0.14224)
		(layer "B.Cu")
		(net "TDR_DIFF_85_BOT_DP")
	)
	(segment
		(start 120.18518 -13.415264)
		(end 120.18518 -12.393676)
		(width 0.14224)
		(layer "B.Cu")
		(net "TDR_DIFF_85_BOT_DP")
	)
	(segment
		(start 107.0356 -11.89355)
		(end 106.75112 -11.60907)
		(width 0.14224)
		(layer "B.Cu")
		(net "TDR_DIFF_85_BOT_DP")
	)
	(segment
		(start 113.46815 -24.24176)
		(end 113.46815 -22.314916)
		(width 0.14224)
		(layer "B.Cu")
		(net "TDR_DIFF_85_BOT_DP")
	)
	(segment
		(start 106.75112 -14.19987)
		(end 107.0356 -13.91539)
		(width 0.14224)
		(layer "B.Cu")
		(net "TDR_DIFF_85_BOT_DP")
	)
	(segment
		(start 107.0356 -15.20063)
		(end 106.75112 -14.91615)
		(width 0.14224)
		(layer "B.Cu")
		(net "TDR_DIFF_85_BOT_DP")
	)
	(segment
		(start 107.0356 -17.22247)
		(end 119.685054 -17.22247)
		(width 0.14224)
		(layer "B.Cu")
		(net "TDR_DIFF_85_BOT_DP")
	)
	(segment
		(start 113.46815 -4.99491)
		(end 113.46815 -3.19024)
		(width 0.14224)
		(layer "B.Cu")
		(net "TDR_DIFF_85_BOT_DP")
	)
	(segment
		(start 119.685054 -5.27939)
		(end 113.75263 -5.27939)
		(width 0.14224)
		(layer "B.Cu")
		(net "TDR_DIFF_85_BOT_DP")
	)
	(segment
		(start 113.61039 -3.048)
		(end 114.554 -3.048)
		(width 0.14224)
		(layer "B.Cu")
		(net "TDR_DIFF_85_BOT_DP")
	)
	(segment
		(start 119.685054 -17.22247)
		(end 120.18518 -16.722344)
		(width 0.14224)
		(layer "B.Cu")
		(net "TDR_DIFF_85_BOT_DP")
	)
	(segment
		(start 119.591074 -20.52955)
		(end 120.0912 -20.029424)
		(width 0.14224)
		(layer "B.Cu")
		(net "TDR_DIFF_85_BOT_DP")
	)
	(segment
		(start 106.75112 -14.91615)
		(end 106.75112 -14.19987)
		(width 0.14224)
		(layer "B.Cu")
		(net "TDR_DIFF_85_BOT_DP")
	)
	(segment
		(start 107.0356 -18.50771)
		(end 106.75112 -18.22323)
		(width 0.14224)
		(layer "B.Cu")
		(net "TDR_DIFF_85_BOT_DP")
	)
	(segment
		(start 119.685054 -11.89355)
		(end 107.0356 -11.89355)
		(width 0.14224)
		(layer "B.Cu")
		(net "TDR_DIFF_85_BOT_DP")
	)
	(segment
		(start 119.685054 -7.30123)
		(end 120.18518 -6.801104)
		(width 0.14224)
		(layer "B.Cu")
		(net "TDR_DIFF_85_BOT_DP")
	)
	(segment
		(start 106.38282 -20.661376)
		(end 106.882946 -20.16125)
		(width 0.14224)
		(layer "B.Cu")
		(net "TDR_DIFF_85_BOT_DN")
	)
	(segment
		(start 119.5324 -13.54709)
		(end 119.81688 -13.26261)
		(width 0.14224)
		(layer "B.Cu")
		(net "TDR_DIFF_85_BOT_DN")
	)
	(segment
		(start 106.38282 -8.454644)
		(end 106.38282 -7.433056)
		(width 0.14224)
		(layer "B.Cu")
		(net "TDR_DIFF_85_BOT_DN")
	)
	(segment
		(start 119.81688 -16.56969)
		(end 119.81688 -15.85341)
		(width 0.14224)
		(layer "B.Cu")
		(net "TDR_DIFF_85_BOT_DN")
	)
	(segment
		(start 106.882946 -12.26185)
		(end 106.38282 -11.761724)
		(width 0.14224)
		(layer "B.Cu")
		(net "TDR_DIFF_85_BOT_DN")
	)
	(segment
		(start 113.09985 -5.147564)
		(end 113.09985 -3.19024)
		(width 0.14224)
		(layer "B.Cu")
		(net "TDR_DIFF_85_BOT_DN")
	)
	(segment
		(start 106.38282 -21.682964)
		(end 106.38282 -20.661376)
		(width 0.14224)
		(layer "B.Cu")
		(net "TDR_DIFF_85_BOT_DN")
	)
	(segment
		(start 106.882946 -22.18309)
		(end 106.38282 -21.682964)
		(width 0.14224)
		(layer "B.Cu")
		(net "TDR_DIFF_85_BOT_DN")
	)
	(segment
		(start 119.5324 -5.64769)
		(end 113.599976 -5.64769)
		(width 0.14224)
		(layer "B.Cu")
		(net "TDR_DIFF_85_BOT_DN")
	)
	(segment
		(start 106.882946 -6.93293)
		(end 119.5324 -6.93293)
		(width 0.14224)
		(layer "B.Cu")
		(net "TDR_DIFF_85_BOT_DN")
	)
	(segment
		(start 119.5324 -10.24001)
		(end 119.81688 -9.95553)
		(width 0.14224)
		(layer "B.Cu")
		(net "TDR_DIFF_85_BOT_DN")
	)
	(segment
		(start 119.81688 -6.64845)
		(end 119.81688 -5.93217)
		(width 0.14224)
		(layer "B.Cu")
		(net "TDR_DIFF_85_BOT_DN")
	)
	(segment
		(start 106.882946 -20.16125)
		(end 119.43842 -20.16125)
		(width 0.14224)
		(layer "B.Cu")
		(net "TDR_DIFF_85_BOT_DN")
	)
	(segment
		(start 113.09985 -3.19024)
		(end 112.95761 -3.048)
		(width 0.14224)
		(layer "B.Cu")
		(net "TDR_DIFF_85_BOT_DN")
	)
	(segment
		(start 106.882946 -13.54709)
		(end 119.5324 -13.54709)
		(width 0.14224)
		(layer "B.Cu")
		(net "TDR_DIFF_85_BOT_DN")
	)
	(segment
		(start 112.81537 -22.18309)
		(end 106.882946 -22.18309)
		(width 0.14224)
		(layer "B.Cu")
		(net "TDR_DIFF_85_BOT_DN")
	)
	(segment
		(start 106.38282 -14.047216)
		(end 106.882946 -13.54709)
		(width 0.14224)
		(layer "B.Cu")
		(net "TDR_DIFF_85_BOT_DN")
	)
	(segment
		(start 106.38282 -18.375884)
		(end 106.38282 -17.354296)
		(width 0.14224)
		(layer "B.Cu")
		(net "TDR_DIFF_85_BOT_DN")
	)
	(segment
		(start 119.81688 -9.95553)
		(end 119.81688 -9.23925)
		(width 0.14224)
		(layer "B.Cu")
		(net "TDR_DIFF_85_BOT_DN")
	)
	(segment
		(start 119.5324 -6.93293)
		(end 119.81688 -6.64845)
		(width 0.14224)
		(layer "B.Cu")
		(net "TDR_DIFF_85_BOT_DN")
	)
	(segment
		(start 119.5324 -16.85417)
		(end 119.81688 -16.56969)
		(width 0.14224)
		(layer "B.Cu")
		(net "TDR_DIFF_85_BOT_DN")
	)
	(segment
		(start 106.38282 -7.433056)
		(end 106.882946 -6.93293)
		(width 0.14224)
		(layer "B.Cu")
		(net "TDR_DIFF_85_BOT_DN")
	)
	(segment
		(start 106.38282 -17.354296)
		(end 106.882946 -16.85417)
		(width 0.14224)
		(layer "B.Cu")
		(net "TDR_DIFF_85_BOT_DN")
	)
	(segment
		(start 119.5324 -8.95477)
		(end 106.882946 -8.95477)
		(width 0.14224)
		(layer "B.Cu")
		(net "TDR_DIFF_85_BOT_DN")
	)
	(segment
		(start 106.882946 -10.24001)
		(end 119.5324 -10.24001)
		(width 0.14224)
		(layer "B.Cu")
		(net "TDR_DIFF_85_BOT_DN")
	)
	(segment
		(start 106.38282 -11.761724)
		(end 106.38282 -10.740136)
		(width 0.14224)
		(layer "B.Cu")
		(net "TDR_DIFF_85_BOT_DN")
	)
	(segment
		(start 112.95761 -24.384)
		(end 113.09985 -24.24176)
		(width 0.14224)
		(layer "B.Cu")
		(net "TDR_DIFF_85_BOT_DN")
	)
	(segment
		(start 113.599976 -5.64769)
		(end 113.09985 -5.147564)
		(width 0.14224)
		(layer "B.Cu")
		(net "TDR_DIFF_85_BOT_DN")
	)
	(segment
		(start 119.5324 -15.56893)
		(end 106.882946 -15.56893)
		(width 0.14224)
		(layer "B.Cu")
		(net "TDR_DIFF_85_BOT_DN")
	)
	(segment
		(start 106.882946 -8.95477)
		(end 106.38282 -8.454644)
		(width 0.14224)
		(layer "B.Cu")
		(net "TDR_DIFF_85_BOT_DN")
	)
	(segment
		(start 119.81688 -9.23925)
		(end 119.5324 -8.95477)
		(width 0.14224)
		(layer "B.Cu")
		(net "TDR_DIFF_85_BOT_DN")
	)
	(segment
		(start 112.014 -24.384)
		(end 112.95761 -24.384)
		(width 0.14224)
		(layer "B.Cu")
		(net "TDR_DIFF_85_BOT_DN")
	)
	(segment
		(start 113.09985 -22.46757)
		(end 112.81537 -22.18309)
		(width 0.14224)
		(layer "B.Cu")
		(net "TDR_DIFF_85_BOT_DN")
	)
	(segment
		(start 106.882946 -16.85417)
		(end 119.5324 -16.85417)
		(width 0.14224)
		(layer "B.Cu")
		(net "TDR_DIFF_85_BOT_DN")
	)
	(segment
		(start 106.882946 -15.56893)
		(end 106.38282 -15.068804)
		(width 0.14224)
		(layer "B.Cu")
		(net "TDR_DIFF_85_BOT_DN")
	)
	(segment
		(start 119.81688 -15.85341)
		(end 119.5324 -15.56893)
		(width 0.14224)
		(layer "B.Cu")
		(net "TDR_DIFF_85_BOT_DN")
	)
	(segment
		(start 113.09985 -24.24176)
		(end 113.09985 -22.46757)
		(width 0.14224)
		(layer "B.Cu")
		(net "TDR_DIFF_85_BOT_DN")
	)
	(segment
		(start 119.81688 -5.93217)
		(end 119.5324 -5.64769)
		(width 0.14224)
		(layer "B.Cu")
		(net "TDR_DIFF_85_BOT_DN")
	)
	(segment
		(start 106.38282 -15.068804)
		(end 106.38282 -14.047216)
		(width 0.14224)
		(layer "B.Cu")
		(net "TDR_DIFF_85_BOT_DN")
	)
	(segment
		(start 112.95761 -3.048)
		(end 112.014 -3.048)
		(width 0.14224)
		(layer "B.Cu")
		(net "TDR_DIFF_85_BOT_DN")
	)
	(segment
		(start 119.43842 -18.87601)
		(end 106.882946 -18.87601)
		(width 0.14224)
		(layer "B.Cu")
		(net "TDR_DIFF_85_BOT_DN")
	)
	(segment
		(start 119.81688 -12.54633)
		(end 119.5324 -12.26185)
		(width 0.14224)
		(layer "B.Cu")
		(net "TDR_DIFF_85_BOT_DN")
	)
	(segment
		(start 106.882946 -18.87601)
		(end 106.38282 -18.375884)
		(width 0.14224)
		(layer "B.Cu")
		(net "TDR_DIFF_85_BOT_DN")
	)
	(segment
		(start 119.7229 -19.16049)
		(end 119.43842 -18.87601)
		(width 0.14224)
		(layer "B.Cu")
		(net "TDR_DIFF_85_BOT_DN")
	)
	(segment
		(start 119.81688 -13.26261)
		(end 119.81688 -12.54633)
		(width 0.14224)
		(layer "B.Cu")
		(net "TDR_DIFF_85_BOT_DN")
	)
	(segment
		(start 106.38282 -10.740136)
		(end 106.882946 -10.24001)
		(width 0.14224)
		(layer "B.Cu")
		(net "TDR_DIFF_85_BOT_DN")
	)
	(segment
		(start 119.43842 -20.16125)
		(end 119.7229 -19.87677)
		(width 0.14224)
		(layer "B.Cu")
		(net "TDR_DIFF_85_BOT_DN")
	)
	(segment
		(start 119.5324 -12.26185)
		(end 106.882946 -12.26185)
		(width 0.14224)
		(layer "B.Cu")
		(net "TDR_DIFF_85_BOT_DN")
	)
	(segment
		(start 119.7229 -19.87677)
		(end 119.7229 -19.16049)
		(width 0.14224)
		(layer "B.Cu")
		(net "TDR_DIFF_85_BOT_DN")
	)
	(segment
		(start 118.872 22.799802)
		(end 107.538012 22.799802)
		(width 0.1016)
		(layer "F.Cu")
		(net "TDR_DIFF_100_TOP_DP")
	)
	(segment
		(start 107.538012 18.380202)
		(end 118.872 18.380202)
		(width 0.1016)
		(layer "F.Cu")
		(net "TDR_DIFF_100_TOP_DP")
	)
	(segment
		(start 119.6848 12.284202)
		(end 119.6848 12.893802)
		(width 0.1016)
		(layer "F.Cu")
		(net "TDR_DIFF_100_TOP_DP")
	)
	(segment
		(start 107.0102 21.05279)
		(end 107.538012 21.580602)
		(width 0.1016)
		(layer "F.Cu")
		(net "TDR_DIFF_100_TOP_DP")
	)
	(segment
		(start 119.6594 9.083802)
		(end 119.6594 9.693402)
		(width 0.1016)
		(layer "F.Cu")
		(net "TDR_DIFF_100_TOP_DP")
	)
	(segment
		(start 119.6594 9.693402)
		(end 119.3546 9.998202)
		(width 0.1016)
		(layer "F.Cu")
		(net "TDR_DIFF_100_TOP_DP")
	)
	(segment
		(start 119.1768 16.094202)
		(end 118.872 16.399002)
		(width 0.1016)
		(layer "F.Cu")
		(net "TDR_DIFF_100_TOP_DP")
	)
	(segment
		(start 119.3546 9.998202)
		(end 108.046012 9.998202)
		(width 0.1016)
		(layer "F.Cu")
		(net "TDR_DIFF_100_TOP_DP")
	)
	(segment
		(start 107.5182 11.45159)
		(end 108.046012 11.979402)
		(width 0.1016)
		(layer "F.Cu")
		(net "TDR_DIFF_100_TOP_DP")
	)
	(segment
		(start 107.0102 13.726414)
		(end 107.0102 14.65199)
		(width 0.1016)
		(layer "F.Cu")
		(net "TDR_DIFF_100_TOP_DP")
	)
	(segment
		(start 107.0102 14.65199)
		(end 107.538012 15.179802)
		(width 0.1016)
		(layer "F.Cu")
		(net "TDR_DIFF_100_TOP_DP")
	)
	(segment
		(start 113.0935 6.493002)
		(end 112.7887 6.797802)
		(width 0.1016)
		(layer "F.Cu")
		(net "TDR_DIFF_100_TOP_DP")
	)
	(segment
		(start 118.872 16.399002)
		(end 107.538012 16.399002)
		(width 0.1016)
		(layer "F.Cu")
		(net "TDR_DIFF_100_TOP_DP")
	)
	(segment
		(start 107.5436 8.25119)
		(end 108.071412 8.779002)
		(width 0.1016)
		(layer "F.Cu")
		(net "TDR_DIFF_100_TOP_DP")
	)
	(segment
		(start 113.0935 25.085802)
		(end 113.0935 26.9748)
		(width 0.1016)
		(layer "F.Cu")
		(net "TDR_DIFF_100_TOP_DP")
	)
	(segment
		(start 108.046012 11.979402)
		(end 119.38 11.979402)
		(width 0.1016)
		(layer "F.Cu")
		(net "TDR_DIFF_100_TOP_DP")
	)
	(segment
		(start 107.538012 24.781002)
		(end 112.7887 24.781002)
		(width 0.1016)
		(layer "F.Cu")
		(net "TDR_DIFF_100_TOP_DP")
	)
	(segment
		(start 107.0102 17.85239)
		(end 107.538012 18.380202)
		(width 0.1016)
		(layer "F.Cu")
		(net "TDR_DIFF_100_TOP_DP")
	)
	(segment
		(start 119.3546 8.779002)
		(end 119.6594 9.083802)
		(width 0.1016)
		(layer "F.Cu")
		(net "TDR_DIFF_100_TOP_DP")
	)
	(segment
		(start 118.872 19.599402)
		(end 107.538012 19.599402)
		(width 0.1016)
		(layer "F.Cu")
		(net "TDR_DIFF_100_TOP_DP")
	)
	(segment
		(start 107.538012 15.179802)
		(end 118.872 15.179802)
		(width 0.1016)
		(layer "F.Cu")
		(net "TDR_DIFF_100_TOP_DP")
	)
	(segment
		(start 107.538012 22.799802)
		(end 107.0102 23.327614)
		(width 0.1016)
		(layer "F.Cu")
		(net "TDR_DIFF_100_TOP_DP")
	)
	(segment
		(start 119.6848 12.893802)
		(end 119.38 13.198602)
		(width 0.1016)
		(layer "F.Cu")
		(net "TDR_DIFF_100_TOP_DP")
	)
	(segment
		(start 118.872 18.380202)
		(end 119.1768 18.685002)
		(width 0.1016)
		(layer "F.Cu")
		(net "TDR_DIFF_100_TOP_DP")
	)
	(segment
		(start 119.1768 18.685002)
		(end 119.1768 19.294602)
		(width 0.1016)
		(layer "F.Cu")
		(net "TDR_DIFF_100_TOP_DP")
	)
	(segment
		(start 112.014 4.572)
		(end 112.8903 4.572)
		(width 0.1016)
		(layer "F.Cu")
		(net "TDR_DIFF_100_TOP_DP")
	)
	(segment
		(start 113.0935 4.7752)
		(end 113.0935 6.493002)
		(width 0.1016)
		(layer "F.Cu")
		(net "TDR_DIFF_100_TOP_DP")
	)
	(segment
		(start 107.538012 21.580602)
		(end 118.872 21.580602)
		(width 0.1016)
		(layer "F.Cu")
		(net "TDR_DIFF_100_TOP_DP")
	)
	(segment
		(start 107.0102 24.25319)
		(end 107.538012 24.781002)
		(width 0.1016)
		(layer "F.Cu")
		(net "TDR_DIFF_100_TOP_DP")
	)
	(segment
		(start 119.1768 21.885402)
		(end 119.1768 22.495002)
		(width 0.1016)
		(layer "F.Cu")
		(net "TDR_DIFF_100_TOP_DP")
	)
	(segment
		(start 107.538012 13.198602)
		(end 107.0102 13.726414)
		(width 0.1016)
		(layer "F.Cu")
		(net "TDR_DIFF_100_TOP_DP")
	)
	(segment
		(start 107.538012 16.399002)
		(end 107.0102 16.926814)
		(width 0.1016)
		(layer "F.Cu")
		(net "TDR_DIFF_100_TOP_DP")
	)
	(segment
		(start 119.38 13.198602)
		(end 107.538012 13.198602)
		(width 0.1016)
		(layer "F.Cu")
		(net "TDR_DIFF_100_TOP_DP")
	)
	(segment
		(start 113.0935 26.9748)
		(end 112.8903 27.178)
		(width 0.1016)
		(layer "F.Cu")
		(net "TDR_DIFF_100_TOP_DP")
	)
	(segment
		(start 108.071412 6.797802)
		(end 107.5436 7.325614)
		(width 0.1016)
		(layer "F.Cu")
		(net "TDR_DIFF_100_TOP_DP")
	)
	(segment
		(start 112.8903 27.178)
		(end 112.014 27.178)
		(width 0.1016)
		(layer "F.Cu")
		(net "TDR_DIFF_100_TOP_DP")
	)
	(segment
		(start 118.872 21.580602)
		(end 119.1768 21.885402)
		(width 0.1016)
		(layer "F.Cu")
		(net "TDR_DIFF_100_TOP_DP")
	)
	(segment
		(start 119.38 11.979402)
		(end 119.6848 12.284202)
		(width 0.1016)
		(layer "F.Cu")
		(net "TDR_DIFF_100_TOP_DP")
	)
	(segment
		(start 118.872 15.179802)
		(end 119.1768 15.484602)
		(width 0.1016)
		(layer "F.Cu")
		(net "TDR_DIFF_100_TOP_DP")
	)
	(segment
		(start 119.1768 22.495002)
		(end 118.872 22.799802)
		(width 0.1016)
		(layer "F.Cu")
		(net "TDR_DIFF_100_TOP_DP")
	)
	(segment
		(start 112.7887 24.781002)
		(end 113.0935 25.085802)
		(width 0.1016)
		(layer "F.Cu")
		(net "TDR_DIFF_100_TOP_DP")
	)
	(segment
		(start 119.1768 15.484602)
		(end 119.1768 16.094202)
		(width 0.1016)
		(layer "F.Cu")
		(net "TDR_DIFF_100_TOP_DP")
	)
	(segment
		(start 112.7887 6.797802)
		(end 108.071412 6.797802)
		(width 0.1016)
		(layer "F.Cu")
		(net "TDR_DIFF_100_TOP_DP")
	)
	(segment
		(start 119.1768 19.294602)
		(end 118.872 19.599402)
		(width 0.1016)
		(layer "F.Cu")
		(net "TDR_DIFF_100_TOP_DP")
	)
	(segment
		(start 112.8903 4.572)
		(end 113.0935 4.7752)
		(width 0.1016)
		(layer "F.Cu")
		(net "TDR_DIFF_100_TOP_DP")
	)
	(segment
		(start 107.0102 16.926814)
		(end 107.0102 17.85239)
		(width 0.1016)
		(layer "F.Cu")
		(net "TDR_DIFF_100_TOP_DP")
	)
	(segment
		(start 107.0102 20.127214)
		(end 107.0102 21.05279)
		(width 0.1016)
		(layer "F.Cu")
		(net "TDR_DIFF_100_TOP_DP")
	)
	(segment
		(start 107.0102 23.327614)
		(end 107.0102 24.25319)
		(width 0.1016)
		(layer "F.Cu")
		(net "TDR_DIFF_100_TOP_DP")
	)
	(segment
		(start 108.071412 8.779002)
		(end 119.3546 8.779002)
		(width 0.1016)
		(layer "F.Cu")
		(net "TDR_DIFF_100_TOP_DP")
	)
	(segment
		(start 107.5182 10.526014)
		(end 107.5182 11.45159)
		(width 0.1016)
		(layer "F.Cu")
		(net "TDR_DIFF_100_TOP_DP")
	)
	(segment
		(start 108.046012 9.998202)
		(end 107.5182 10.526014)
		(width 0.1016)
		(layer "F.Cu")
		(net "TDR_DIFF_100_TOP_DP")
	)
	(segment
		(start 107.538012 19.599402)
		(end 107.0102 20.127214)
		(width 0.1016)
		(layer "F.Cu")
		(net "TDR_DIFF_100_TOP_DP")
	)
	(segment
		(start 107.5436 7.325614)
		(end 107.5436 8.25119)
		(width 0.1016)
		(layer "F.Cu")
		(net "TDR_DIFF_100_TOP_DP")
	)
	(segment
		(start 107.696 21.199602)
		(end 119.029988 21.199602)
		(width 0.1016)
		(layer "F.Cu")
		(net "TDR_DIFF_100_TOP_DN")
	)
	(segment
		(start 119.512588 10.379202)
		(end 108.204 10.379202)
		(width 0.1016)
		(layer "F.Cu")
		(net "TDR_DIFF_100_TOP_DN")
	)
	(segment
		(start 107.9246 7.483602)
		(end 107.9246 8.093202)
		(width 0.1016)
		(layer "F.Cu")
		(net "TDR_DIFF_100_TOP_DN")
	)
	(segment
		(start 108.204 10.379202)
		(end 107.8992 10.684002)
		(width 0.1016)
		(layer "F.Cu")
		(net "TDR_DIFF_100_TOP_DN")
	)
	(segment
		(start 107.3912 17.694402)
		(end 107.696 17.999202)
		(width 0.1016)
		(layer "F.Cu")
		(net "TDR_DIFF_100_TOP_DN")
	)
	(segment
		(start 119.5578 16.25219)
		(end 119.029988 16.780002)
		(width 0.1016)
		(layer "F.Cu")
		(net "TDR_DIFF_100_TOP_DN")
	)
	(segment
		(start 113.4745 6.65099)
		(end 112.946688 7.178802)
		(width 0.1016)
		(layer "F.Cu")
		(net "TDR_DIFF_100_TOP_DN")
	)
	(segment
		(start 119.029988 17.999202)
		(end 119.5578 18.527014)
		(width 0.1016)
		(layer "F.Cu")
		(net "TDR_DIFF_100_TOP_DN")
	)
	(segment
		(start 107.3912 20.285202)
		(end 107.3912 20.894802)
		(width 0.1016)
		(layer "F.Cu")
		(net "TDR_DIFF_100_TOP_DN")
	)
	(segment
		(start 119.5578 18.527014)
		(end 119.5578 19.45259)
		(width 0.1016)
		(layer "F.Cu")
		(net "TDR_DIFF_100_TOP_DN")
	)
	(segment
		(start 119.5578 15.326614)
		(end 119.5578 16.25219)
		(width 0.1016)
		(layer "F.Cu")
		(net "TDR_DIFF_100_TOP_DN")
	)
	(segment
		(start 119.512588 8.398002)
		(end 120.0404 8.925814)
		(width 0.1016)
		(layer "F.Cu")
		(net "TDR_DIFF_100_TOP_DN")
	)
	(segment
		(start 120.0404 8.925814)
		(end 120.0404 9.85139)
		(width 0.1016)
		(layer "F.Cu")
		(net "TDR_DIFF_100_TOP_DN")
	)
	(segment
		(start 107.696 13.579602)
		(end 107.3912 13.884402)
		(width 0.1016)
		(layer "F.Cu")
		(net "TDR_DIFF_100_TOP_DN")
	)
	(segment
		(start 107.3912 13.884402)
		(end 107.3912 14.494002)
		(width 0.1016)
		(layer "F.Cu")
		(net "TDR_DIFF_100_TOP_DN")
	)
	(segment
		(start 112.946688 7.178802)
		(end 108.2294 7.178802)
		(width 0.1016)
		(layer "F.Cu")
		(net "TDR_DIFF_100_TOP_DN")
	)
	(segment
		(start 107.3912 17.084802)
		(end 107.3912 17.694402)
		(width 0.1016)
		(layer "F.Cu")
		(net "TDR_DIFF_100_TOP_DN")
	)
	(segment
		(start 113.4745 26.9748)
		(end 113.6777 27.178)
		(width 0.1016)
		(layer "F.Cu")
		(net "TDR_DIFF_100_TOP_DN")
	)
	(segment
		(start 119.029988 21.199602)
		(end 119.5578 21.727414)
		(width 0.1016)
		(layer "F.Cu")
		(net "TDR_DIFF_100_TOP_DN")
	)
	(segment
		(start 120.0404 9.85139)
		(end 119.512588 10.379202)
		(width 0.1016)
		(layer "F.Cu")
		(net "TDR_DIFF_100_TOP_DN")
	)
	(segment
		(start 107.3912 14.494002)
		(end 107.696 14.798802)
		(width 0.1016)
		(layer "F.Cu")
		(net "TDR_DIFF_100_TOP_DN")
	)
	(segment
		(start 119.5578 22.65299)
		(end 119.029988 23.180802)
		(width 0.1016)
		(layer "F.Cu")
		(net "TDR_DIFF_100_TOP_DN")
	)
	(segment
		(start 107.8992 10.684002)
		(end 107.8992 11.293602)
		(width 0.1016)
		(layer "F.Cu")
		(net "TDR_DIFF_100_TOP_DN")
	)
	(segment
		(start 114.554 4.572)
		(end 113.6777 4.572)
		(width 0.1016)
		(layer "F.Cu")
		(net "TDR_DIFF_100_TOP_DN")
	)
	(segment
		(start 107.3912 20.894802)
		(end 107.696 21.199602)
		(width 0.1016)
		(layer "F.Cu")
		(net "TDR_DIFF_100_TOP_DN")
	)
	(segment
		(start 107.696 14.798802)
		(end 119.029988 14.798802)
		(width 0.1016)
		(layer "F.Cu")
		(net "TDR_DIFF_100_TOP_DN")
	)
	(segment
		(start 107.9246 8.093202)
		(end 108.2294 8.398002)
		(width 0.1016)
		(layer "F.Cu")
		(net "TDR_DIFF_100_TOP_DN")
	)
	(segment
		(start 119.537988 11.598402)
		(end 120.0658 12.126214)
		(width 0.1016)
		(layer "F.Cu")
		(net "TDR_DIFF_100_TOP_DN")
	)
	(segment
		(start 107.696 24.400002)
		(end 112.946688 24.400002)
		(width 0.1016)
		(layer "F.Cu")
		(net "TDR_DIFF_100_TOP_DN")
	)
	(segment
		(start 120.0658 13.05179)
		(end 119.537988 13.579602)
		(width 0.1016)
		(layer "F.Cu")
		(net "TDR_DIFF_100_TOP_DN")
	)
	(segment
		(start 120.0658 12.126214)
		(end 120.0658 13.05179)
		(width 0.1016)
		(layer "F.Cu")
		(net "TDR_DIFF_100_TOP_DN")
	)
	(segment
		(start 113.4745 4.7752)
		(end 113.4745 6.65099)
		(width 0.1016)
		(layer "F.Cu")
		(net "TDR_DIFF_100_TOP_DN")
	)
	(segment
		(start 112.946688 24.400002)
		(end 113.4745 24.927814)
		(width 0.1016)
		(layer "F.Cu")
		(net "TDR_DIFF_100_TOP_DN")
	)
	(segment
		(start 119.5578 21.727414)
		(end 119.5578 22.65299)
		(width 0.1016)
		(layer "F.Cu")
		(net "TDR_DIFF_100_TOP_DN")
	)
	(segment
		(start 119.029988 16.780002)
		(end 107.696 16.780002)
		(width 0.1016)
		(layer "F.Cu")
		(net "TDR_DIFF_100_TOP_DN")
	)
	(segment
		(start 119.5578 19.45259)
		(end 119.029988 19.980402)
		(width 0.1016)
		(layer "F.Cu")
		(net "TDR_DIFF_100_TOP_DN")
	)
	(segment
		(start 107.696 23.180802)
		(end 107.3912 23.485602)
		(width 0.1016)
		(layer "F.Cu")
		(net "TDR_DIFF_100_TOP_DN")
	)
	(segment
		(start 107.696 19.980402)
		(end 107.3912 20.285202)
		(width 0.1016)
		(layer "F.Cu")
		(net "TDR_DIFF_100_TOP_DN")
	)
	(segment
		(start 119.537988 13.579602)
		(end 107.696 13.579602)
		(width 0.1016)
		(layer "F.Cu")
		(net "TDR_DIFF_100_TOP_DN")
	)
	(segment
		(start 107.8992 11.293602)
		(end 108.204 11.598402)
		(width 0.1016)
		(layer "F.Cu")
		(net "TDR_DIFF_100_TOP_DN")
	)
	(segment
		(start 108.204 11.598402)
		(end 119.537988 11.598402)
		(width 0.1016)
		(layer "F.Cu")
		(net "TDR_DIFF_100_TOP_DN")
	)
	(segment
		(start 119.029988 23.180802)
		(end 107.696 23.180802)
		(width 0.1016)
		(layer "F.Cu")
		(net "TDR_DIFF_100_TOP_DN")
	)
	(segment
		(start 113.6777 4.572)
		(end 113.4745 4.7752)
		(width 0.1016)
		(layer "F.Cu")
		(net "TDR_DIFF_100_TOP_DN")
	)
	(segment
		(start 119.029988 14.798802)
		(end 119.5578 15.326614)
		(width 0.1016)
		(layer "F.Cu")
		(net "TDR_DIFF_100_TOP_DN")
	)
	(segment
		(start 119.029988 19.980402)
		(end 107.696 19.980402)
		(width 0.1016)
		(layer "F.Cu")
		(net "TDR_DIFF_100_TOP_DN")
	)
	(segment
		(start 107.3912 23.485602)
		(end 107.3912 24.095202)
		(width 0.1016)
		(layer "F.Cu")
		(net "TDR_DIFF_100_TOP_DN")
	)
	(segment
		(start 107.696 16.780002)
		(end 107.3912 17.084802)
		(width 0.1016)
		(layer "F.Cu")
		(net "TDR_DIFF_100_TOP_DN")
	)
	(segment
		(start 113.4745 24.927814)
		(end 113.4745 26.9748)
		(width 0.1016)
		(layer "F.Cu")
		(net "TDR_DIFF_100_TOP_DN")
	)
	(segment
		(start 107.696 17.999202)
		(end 119.029988 17.999202)
		(width 0.1016)
		(layer "F.Cu")
		(net "TDR_DIFF_100_TOP_DN")
	)
	(segment
		(start 113.6777 27.178)
		(end 114.554 27.178)
		(width 0.1016)
		(layer "F.Cu")
		(net "TDR_DIFF_100_TOP_DN")
	)
	(segment
		(start 108.2294 7.178802)
		(end 107.9246 7.483602)
		(width 0.1016)
		(layer "F.Cu")
		(net "TDR_DIFF_100_TOP_DN")
	)
	(segment
		(start 107.3912 24.095202)
		(end 107.696 24.400002)
		(width 0.1016)
		(layer "F.Cu")
		(net "TDR_DIFF_100_TOP_DN")
	)
	(segment
		(start 108.2294 8.398002)
		(end 119.512588 8.398002)
		(width 0.1016)
		(layer "F.Cu")
		(net "TDR_DIFF_100_TOP_DN")
	)
	(segment
		(start 105.41254 71.251572)
		(end 105.832148 70.831964)
		(width 0.08636)
		(layer "In9.Cu")
		(net "TDR_DIFF_100_IN4_DP")
	)
	(segment
		(start 120.41378 73.961244)
		(end 120.41378 73.077324)
		(width 0.08636)
		(layer "In9.Cu")
		(net "TDR_DIFF_100_IN4_DP")
	)
	(segment
		(start 105.43286 67.949572)
		(end 105.852468 67.529964)
		(width 0.08636)
		(layer "In9.Cu")
		(net "TDR_DIFF_100_IN4_DP")
	)
	(segment
		(start 120.24106 74.133964)
		(end 120.41378 73.961244)
		(width 0.08636)
		(layer "In9.Cu")
		(net "TDR_DIFF_100_IN4_DP")
	)
	(segment
		(start 120.24106 67.529964)
		(end 120.41378 67.357244)
		(width 0.08636)
		(layer "In9.Cu")
		(net "TDR_DIFF_100_IN4_DP")
	)
	(segment
		(start 106.152188 79.508604)
		(end 105.73258 79.088996)
		(width 0.08636)
		(layer "In9.Cu")
		(net "TDR_DIFF_100_IN4_DP")
	)
	(segment
		(start 113.07318 64.055244)
		(end 113.07318 62.31636)
		(width 0.08636)
		(layer "In9.Cu")
		(net "TDR_DIFF_100_IN4_DP")
	)
	(segment
		(start 105.69194 74.553572)
		(end 106.111548 74.133964)
		(width 0.08636)
		(layer "In9.Cu")
		(net "TDR_DIFF_100_IN4_DP")
	)
	(segment
		(start 105.832148 70.831964)
		(end 120.24106 70.831964)
		(width 0.08636)
		(layer "In9.Cu")
		(net "TDR_DIFF_100_IN4_DP")
	)
	(segment
		(start 105.45318 65.880996)
		(end 105.45318 64.647572)
		(width 0.08636)
		(layer "In9.Cu")
		(net "TDR_DIFF_100_IN4_DP")
	)
	(segment
		(start 112.98682 82.1436)
		(end 113.07318 82.05724)
		(width 0.08636)
		(layer "In9.Cu")
		(net "TDR_DIFF_100_IN4_DP")
	)
	(segment
		(start 112.014 82.1436)
		(end 112.98682 82.1436)
		(width 0.08636)
		(layer "In9.Cu")
		(net "TDR_DIFF_100_IN4_DP")
	)
	(segment
		(start 120.41378 77.263244)
		(end 120.41378 76.379324)
		(width 0.08636)
		(layer "In9.Cu")
		(net "TDR_DIFF_100_IN4_DP")
	)
	(segment
		(start 105.41254 72.484996)
		(end 105.41254 71.251572)
		(width 0.08636)
		(layer "In9.Cu")
		(net "TDR_DIFF_100_IN4_DP")
	)
	(segment
		(start 105.852468 67.529964)
		(end 120.24106 67.529964)
		(width 0.08636)
		(layer "In9.Cu")
		(net "TDR_DIFF_100_IN4_DP")
	)
	(segment
		(start 120.24106 76.206604)
		(end 106.111548 76.206604)
		(width 0.08636)
		(layer "In9.Cu")
		(net "TDR_DIFF_100_IN4_DP")
	)
	(segment
		(start 120.41378 67.357244)
		(end 120.41378 66.473324)
		(width 0.08636)
		(layer "In9.Cu")
		(net "TDR_DIFF_100_IN4_DP")
	)
	(segment
		(start 120.41378 66.473324)
		(end 120.24106 66.300604)
		(width 0.08636)
		(layer "In9.Cu")
		(net "TDR_DIFF_100_IN4_DP")
	)
	(segment
		(start 105.73258 77.855572)
		(end 106.152188 77.435964)
		(width 0.08636)
		(layer "In9.Cu")
		(net "TDR_DIFF_100_IN4_DP")
	)
	(segment
		(start 113.07318 62.31636)
		(end 112.98682 62.23)
		(width 0.08636)
		(layer "In9.Cu")
		(net "TDR_DIFF_100_IN4_DP")
	)
	(segment
		(start 112.90046 64.227964)
		(end 113.07318 64.055244)
		(width 0.08636)
		(layer "In9.Cu")
		(net "TDR_DIFF_100_IN4_DP")
	)
	(segment
		(start 105.872788 66.300604)
		(end 105.45318 65.880996)
		(width 0.08636)
		(layer "In9.Cu")
		(net "TDR_DIFF_100_IN4_DP")
	)
	(segment
		(start 106.111548 76.206604)
		(end 105.69194 75.786996)
		(width 0.08636)
		(layer "In9.Cu")
		(net "TDR_DIFF_100_IN4_DP")
	)
	(segment
		(start 105.45318 64.647572)
		(end 105.872788 64.227964)
		(width 0.08636)
		(layer "In9.Cu")
		(net "TDR_DIFF_100_IN4_DP")
	)
	(segment
		(start 120.41378 70.659244)
		(end 120.41378 69.775324)
		(width 0.08636)
		(layer "In9.Cu")
		(net "TDR_DIFF_100_IN4_DP")
	)
	(segment
		(start 105.73258 79.088996)
		(end 105.73258 77.855572)
		(width 0.08636)
		(layer "In9.Cu")
		(net "TDR_DIFF_100_IN4_DP")
	)
	(segment
		(start 120.41378 73.077324)
		(end 120.24106 72.904604)
		(width 0.08636)
		(layer "In9.Cu")
		(net "TDR_DIFF_100_IN4_DP")
	)
	(segment
		(start 106.152188 77.435964)
		(end 120.24106 77.435964)
		(width 0.08636)
		(layer "In9.Cu")
		(net "TDR_DIFF_100_IN4_DP")
	)
	(segment
		(start 112.98682 62.23)
		(end 112.014 62.23)
		(width 0.08636)
		(layer "In9.Cu")
		(net "TDR_DIFF_100_IN4_DP")
	)
	(segment
		(start 120.24106 69.602604)
		(end 105.852468 69.602604)
		(width 0.08636)
		(layer "In9.Cu")
		(net "TDR_DIFF_100_IN4_DP")
	)
	(segment
		(start 105.43286 69.182996)
		(end 105.43286 67.949572)
		(width 0.08636)
		(layer "In9.Cu")
		(net "TDR_DIFF_100_IN4_DP")
	)
	(segment
		(start 120.24106 72.904604)
		(end 105.832148 72.904604)
		(width 0.08636)
		(layer "In9.Cu")
		(net "TDR_DIFF_100_IN4_DP")
	)
	(segment
		(start 120.24106 66.300604)
		(end 105.872788 66.300604)
		(width 0.08636)
		(layer "In9.Cu")
		(net "TDR_DIFF_100_IN4_DP")
	)
	(segment
		(start 120.41378 69.775324)
		(end 120.24106 69.602604)
		(width 0.08636)
		(layer "In9.Cu")
		(net "TDR_DIFF_100_IN4_DP")
	)
	(segment
		(start 105.832148 72.904604)
		(end 105.41254 72.484996)
		(width 0.08636)
		(layer "In9.Cu")
		(net "TDR_DIFF_100_IN4_DP")
	)
	(segment
		(start 120.24106 70.831964)
		(end 120.41378 70.659244)
		(width 0.08636)
		(layer "In9.Cu")
		(net "TDR_DIFF_100_IN4_DP")
	)
	(segment
		(start 113.07318 82.05724)
		(end 113.07318 79.681324)
		(width 0.08636)
		(layer "In9.Cu")
		(net "TDR_DIFF_100_IN4_DP")
	)
	(segment
		(start 105.852468 69.602604)
		(end 105.43286 69.182996)
		(width 0.08636)
		(layer "In9.Cu")
		(net "TDR_DIFF_100_IN4_DP")
	)
	(segment
		(start 106.111548 74.133964)
		(end 120.24106 74.133964)
		(width 0.08636)
		(layer "In9.Cu")
		(net "TDR_DIFF_100_IN4_DP")
	)
	(segment
		(start 113.07318 79.681324)
		(end 112.90046 79.508604)
		(width 0.08636)
		(layer "In9.Cu")
		(net "TDR_DIFF_100_IN4_DP")
	)
	(segment
		(start 120.24106 77.435964)
		(end 120.41378 77.263244)
		(width 0.08636)
		(layer "In9.Cu")
		(net "TDR_DIFF_100_IN4_DP")
	)
	(segment
		(start 112.90046 79.508604)
		(end 106.152188 79.508604)
		(width 0.08636)
		(layer "In9.Cu")
		(net "TDR_DIFF_100_IN4_DP")
	)
	(segment
		(start 120.41378 76.379324)
		(end 120.24106 76.206604)
		(width 0.08636)
		(layer "In9.Cu")
		(net "TDR_DIFF_100_IN4_DP")
	)
	(segment
		(start 105.872788 64.227964)
		(end 112.90046 64.227964)
		(width 0.08636)
		(layer "In9.Cu")
		(net "TDR_DIFF_100_IN4_DP")
	)
	(segment
		(start 105.69194 75.786996)
		(end 105.69194 74.553572)
		(width 0.08636)
		(layer "In9.Cu")
		(net "TDR_DIFF_100_IN4_DP")
	)
	(segment
		(start 120.83542 74.135996)
		(end 120.83542 72.902572)
		(width 0.08636)
		(layer "In9.Cu")
		(net "TDR_DIFF_100_IN4_DN")
	)
	(segment
		(start 120.83542 67.531996)
		(end 120.83542 66.298572)
		(width 0.08636)
		(layer "In9.Cu")
		(net "TDR_DIFF_100_IN4_DN")
	)
	(segment
		(start 120.83542 72.902572)
		(end 120.415812 72.482964)
		(width 0.08636)
		(layer "In9.Cu")
		(net "TDR_DIFF_100_IN4_DN")
	)
	(segment
		(start 113.075212 64.649604)
		(end 113.49482 64.229996)
		(width 0.08636)
		(layer "In9.Cu")
		(net "TDR_DIFF_100_IN4_DN")
	)
	(segment
		(start 120.415812 74.555604)
		(end 120.83542 74.135996)
		(width 0.08636)
		(layer "In9.Cu")
		(net "TDR_DIFF_100_IN4_DN")
	)
	(segment
		(start 113.075212 79.086964)
		(end 106.32694 79.086964)
		(width 0.08636)
		(layer "In9.Cu")
		(net "TDR_DIFF_100_IN4_DN")
	)
	(segment
		(start 105.87482 64.822324)
		(end 106.04754 64.649604)
		(width 0.08636)
		(layer "In9.Cu")
		(net "TDR_DIFF_100_IN4_DN")
	)
	(segment
		(start 114.554 82.1436)
		(end 113.58118 82.1436)
		(width 0.08636)
		(layer "In9.Cu")
		(net "TDR_DIFF_100_IN4_DN")
	)
	(segment
		(start 106.02722 67.951604)
		(end 120.415812 67.951604)
		(width 0.08636)
		(layer "In9.Cu")
		(net "TDR_DIFF_100_IN4_DN")
	)
	(segment
		(start 106.15422 78.030324)
		(end 106.32694 77.857604)
		(width 0.08636)
		(layer "In9.Cu")
		(net "TDR_DIFF_100_IN4_DN")
	)
	(segment
		(start 106.32694 79.086964)
		(end 106.15422 78.914244)
		(width 0.08636)
		(layer "In9.Cu")
		(net "TDR_DIFF_100_IN4_DN")
	)
	(segment
		(start 120.83542 77.437996)
		(end 120.83542 76.204572)
		(width 0.08636)
		(layer "In9.Cu")
		(net "TDR_DIFF_100_IN4_DN")
	)
	(segment
		(start 106.0069 71.253604)
		(end 120.415812 71.253604)
		(width 0.08636)
		(layer "In9.Cu")
		(net "TDR_DIFF_100_IN4_DN")
	)
	(segment
		(start 120.415812 72.482964)
		(end 106.0069 72.482964)
		(width 0.08636)
		(layer "In9.Cu")
		(net "TDR_DIFF_100_IN4_DN")
	)
	(segment
		(start 106.15422 78.914244)
		(end 106.15422 78.030324)
		(width 0.08636)
		(layer "In9.Cu")
		(net "TDR_DIFF_100_IN4_DN")
	)
	(segment
		(start 120.83542 66.298572)
		(end 120.415812 65.878964)
		(width 0.08636)
		(layer "In9.Cu")
		(net "TDR_DIFF_100_IN4_DN")
	)
	(segment
		(start 113.58118 62.23)
		(end 114.554 62.23)
		(width 0.08636)
		(layer "In9.Cu")
		(net "TDR_DIFF_100_IN4_DN")
	)
	(segment
		(start 113.49482 64.229996)
		(end 113.49482 62.31636)
		(width 0.08636)
		(layer "In9.Cu")
		(net "TDR_DIFF_100_IN4_DN")
	)
	(segment
		(start 106.2863 75.784964)
		(end 106.11358 75.612244)
		(width 0.08636)
		(layer "In9.Cu")
		(net "TDR_DIFF_100_IN4_DN")
	)
	(segment
		(start 105.8545 68.124324)
		(end 106.02722 67.951604)
		(width 0.08636)
		(layer "In9.Cu")
		(net "TDR_DIFF_100_IN4_DN")
	)
	(segment
		(start 106.11358 75.612244)
		(end 106.11358 74.728324)
		(width 0.08636)
		(layer "In9.Cu")
		(net "TDR_DIFF_100_IN4_DN")
	)
	(segment
		(start 105.83418 71.426324)
		(end 106.0069 71.253604)
		(width 0.08636)
		(layer "In9.Cu")
		(net "TDR_DIFF_100_IN4_DN")
	)
	(segment
		(start 105.83418 72.310244)
		(end 105.83418 71.426324)
		(width 0.08636)
		(layer "In9.Cu")
		(net "TDR_DIFF_100_IN4_DN")
	)
	(segment
		(start 106.02722 69.180964)
		(end 105.8545 69.008244)
		(width 0.08636)
		(layer "In9.Cu")
		(net "TDR_DIFF_100_IN4_DN")
	)
	(segment
		(start 120.83542 76.204572)
		(end 120.415812 75.784964)
		(width 0.08636)
		(layer "In9.Cu")
		(net "TDR_DIFF_100_IN4_DN")
	)
	(segment
		(start 120.415812 71.253604)
		(end 120.83542 70.833996)
		(width 0.08636)
		(layer "In9.Cu")
		(net "TDR_DIFF_100_IN4_DN")
	)
	(segment
		(start 113.49482 82.05724)
		(end 113.49482 79.506572)
		(width 0.08636)
		(layer "In9.Cu")
		(net "TDR_DIFF_100_IN4_DN")
	)
	(segment
		(start 113.49482 79.506572)
		(end 113.075212 79.086964)
		(width 0.08636)
		(layer "In9.Cu")
		(net "TDR_DIFF_100_IN4_DN")
	)
	(segment
		(start 120.415812 75.784964)
		(end 106.2863 75.784964)
		(width 0.08636)
		(layer "In9.Cu")
		(net "TDR_DIFF_100_IN4_DN")
	)
	(segment
		(start 120.415812 77.857604)
		(end 120.83542 77.437996)
		(width 0.08636)
		(layer "In9.Cu")
		(net "TDR_DIFF_100_IN4_DN")
	)
	(segment
		(start 120.415812 67.951604)
		(end 120.83542 67.531996)
		(width 0.08636)
		(layer "In9.Cu")
		(net "TDR_DIFF_100_IN4_DN")
	)
	(segment
		(start 106.2863 74.555604)
		(end 120.415812 74.555604)
		(width 0.08636)
		(layer "In9.Cu")
		(net "TDR_DIFF_100_IN4_DN")
	)
	(segment
		(start 106.32694 77.857604)
		(end 120.415812 77.857604)
		(width 0.08636)
		(layer "In9.Cu")
		(net "TDR_DIFF_100_IN4_DN")
	)
	(segment
		(start 105.87482 65.706244)
		(end 105.87482 64.822324)
		(width 0.08636)
		(layer "In9.Cu")
		(net "TDR_DIFF_100_IN4_DN")
	)
	(segment
		(start 120.83542 70.833996)
		(end 120.83542 69.600572)
		(width 0.08636)
		(layer "In9.Cu")
		(net "TDR_DIFF_100_IN4_DN")
	)
	(segment
		(start 106.11358 74.728324)
		(end 106.2863 74.555604)
		(width 0.08636)
		(layer "In9.Cu")
		(net "TDR_DIFF_100_IN4_DN")
	)
	(segment
		(start 106.04754 64.649604)
		(end 113.075212 64.649604)
		(width 0.08636)
		(layer "In9.Cu")
		(net "TDR_DIFF_100_IN4_DN")
	)
	(segment
		(start 106.0069 72.482964)
		(end 105.83418 72.310244)
		(width 0.08636)
		(layer "In9.Cu")
		(net "TDR_DIFF_100_IN4_DN")
	)
	(segment
		(start 106.04754 65.878964)
		(end 105.87482 65.706244)
		(width 0.08636)
		(layer "In9.Cu")
		(net "TDR_DIFF_100_IN4_DN")
	)
	(segment
		(start 113.49482 62.31636)
		(end 113.58118 62.23)
		(width 0.08636)
		(layer "In9.Cu")
		(net "TDR_DIFF_100_IN4_DN")
	)
	(segment
		(start 120.83542 69.600572)
		(end 120.415812 69.180964)
		(width 0.08636)
		(layer "In9.Cu")
		(net "TDR_DIFF_100_IN4_DN")
	)
	(segment
		(start 120.415812 65.878964)
		(end 106.04754 65.878964)
		(width 0.08636)
		(layer "In9.Cu")
		(net "TDR_DIFF_100_IN4_DN")
	)
	(segment
		(start 105.8545 69.008244)
		(end 105.8545 68.124324)
		(width 0.08636)
		(layer "In9.Cu")
		(net "TDR_DIFF_100_IN4_DN")
	)
	(segment
		(start 113.58118 82.1436)
		(end 113.49482 82.05724)
		(width 0.08636)
		(layer "In9.Cu")
		(net "TDR_DIFF_100_IN4_DN")
	)
	(segment
		(start 120.415812 69.180964)
		(end 106.02722 69.180964)
		(width 0.08636)
		(layer "In9.Cu")
		(net "TDR_DIFF_100_IN4_DN")
	)
	(segment
		(start 112.90046 51.975004)
		(end 106.152188 51.975004)
		(width 0.08636)
		(layer "In2.Cu")
		(net "TDR_DIFF_100_IN1_DP")
	)
	(segment
		(start 120.24106 45.371004)
		(end 105.832148 45.371004)
		(width 0.08636)
		(layer "In2.Cu")
		(net "TDR_DIFF_100_IN1_DP")
	)
	(segment
		(start 120.41378 48.845724)
		(end 120.24106 48.673004)
		(width 0.08636)
		(layer "In2.Cu")
		(net "TDR_DIFF_100_IN1_DP")
	)
	(segment
		(start 105.832148 45.371004)
		(end 105.41254 44.951396)
		(width 0.08636)
		(layer "In2.Cu")
		(net "TDR_DIFF_100_IN1_DP")
	)
	(segment
		(start 120.24106 42.069004)
		(end 105.852468 42.069004)
		(width 0.08636)
		(layer "In2.Cu")
		(net "TDR_DIFF_100_IN1_DP")
	)
	(segment
		(start 113.07318 34.78276)
		(end 112.98682 34.6964)
		(width 0.08636)
		(layer "In2.Cu")
		(net "TDR_DIFF_100_IN1_DP")
	)
	(segment
		(start 105.73258 50.321972)
		(end 106.152188 49.902364)
		(width 0.08636)
		(layer "In2.Cu")
		(net "TDR_DIFF_100_IN1_DP")
	)
	(segment
		(start 120.24106 48.673004)
		(end 106.111548 48.673004)
		(width 0.08636)
		(layer "In2.Cu")
		(net "TDR_DIFF_100_IN1_DP")
	)
	(segment
		(start 120.24106 49.902364)
		(end 120.41378 49.729644)
		(width 0.08636)
		(layer "In2.Cu")
		(net "TDR_DIFF_100_IN1_DP")
	)
	(segment
		(start 105.69194 47.019972)
		(end 106.111548 46.600364)
		(width 0.08636)
		(layer "In2.Cu")
		(net "TDR_DIFF_100_IN1_DP")
	)
	(segment
		(start 106.111548 48.673004)
		(end 105.69194 48.253396)
		(width 0.08636)
		(layer "In2.Cu")
		(net "TDR_DIFF_100_IN1_DP")
	)
	(segment
		(start 120.24106 38.767004)
		(end 105.872788 38.767004)
		(width 0.08636)
		(layer "In2.Cu")
		(net "TDR_DIFF_100_IN1_DP")
	)
	(segment
		(start 105.73258 51.555396)
		(end 105.73258 50.321972)
		(width 0.08636)
		(layer "In2.Cu")
		(net "TDR_DIFF_100_IN1_DP")
	)
	(segment
		(start 120.41378 38.939724)
		(end 120.24106 38.767004)
		(width 0.08636)
		(layer "In2.Cu")
		(net "TDR_DIFF_100_IN1_DP")
	)
	(segment
		(start 105.832148 43.298364)
		(end 120.24106 43.298364)
		(width 0.08636)
		(layer "In2.Cu")
		(net "TDR_DIFF_100_IN1_DP")
	)
	(segment
		(start 112.90046 36.694364)
		(end 113.07318 36.521644)
		(width 0.08636)
		(layer "In2.Cu")
		(net "TDR_DIFF_100_IN1_DP")
	)
	(segment
		(start 106.152188 49.902364)
		(end 120.24106 49.902364)
		(width 0.08636)
		(layer "In2.Cu")
		(net "TDR_DIFF_100_IN1_DP")
	)
	(segment
		(start 105.872788 38.767004)
		(end 105.45318 38.347396)
		(width 0.08636)
		(layer "In2.Cu")
		(net "TDR_DIFF_100_IN1_DP")
	)
	(segment
		(start 120.41378 45.543724)
		(end 120.24106 45.371004)
		(width 0.08636)
		(layer "In2.Cu")
		(net "TDR_DIFF_100_IN1_DP")
	)
	(segment
		(start 105.41254 44.951396)
		(end 105.41254 43.717972)
		(width 0.08636)
		(layer "In2.Cu")
		(net "TDR_DIFF_100_IN1_DP")
	)
	(segment
		(start 113.07318 52.147724)
		(end 112.90046 51.975004)
		(width 0.08636)
		(layer "In2.Cu")
		(net "TDR_DIFF_100_IN1_DP")
	)
	(segment
		(start 105.852468 42.069004)
		(end 105.43286 41.649396)
		(width 0.08636)
		(layer "In2.Cu")
		(net "TDR_DIFF_100_IN1_DP")
	)
	(segment
		(start 105.43286 41.649396)
		(end 105.43286 40.415972)
		(width 0.08636)
		(layer "In2.Cu")
		(net "TDR_DIFF_100_IN1_DP")
	)
	(segment
		(start 105.41254 43.717972)
		(end 105.832148 43.298364)
		(width 0.08636)
		(layer "In2.Cu")
		(net "TDR_DIFF_100_IN1_DP")
	)
	(segment
		(start 120.24106 39.996364)
		(end 120.41378 39.823644)
		(width 0.08636)
		(layer "In2.Cu")
		(net "TDR_DIFF_100_IN1_DP")
	)
	(segment
		(start 105.872788 36.694364)
		(end 112.90046 36.694364)
		(width 0.08636)
		(layer "In2.Cu")
		(net "TDR_DIFF_100_IN1_DP")
	)
	(segment
		(start 105.45318 37.113972)
		(end 105.872788 36.694364)
		(width 0.08636)
		(layer "In2.Cu")
		(net "TDR_DIFF_100_IN1_DP")
	)
	(segment
		(start 113.07318 36.521644)
		(end 113.07318 34.78276)
		(width 0.08636)
		(layer "In2.Cu")
		(net "TDR_DIFF_100_IN1_DP")
	)
	(segment
		(start 120.41378 46.427644)
		(end 120.41378 45.543724)
		(width 0.08636)
		(layer "In2.Cu")
		(net "TDR_DIFF_100_IN1_DP")
	)
	(segment
		(start 105.852468 39.996364)
		(end 120.24106 39.996364)
		(width 0.08636)
		(layer "In2.Cu")
		(net "TDR_DIFF_100_IN1_DP")
	)
	(segment
		(start 120.24106 43.298364)
		(end 120.41378 43.125644)
		(width 0.08636)
		(layer "In2.Cu")
		(net "TDR_DIFF_100_IN1_DP")
	)
	(segment
		(start 105.45318 38.347396)
		(end 105.45318 37.113972)
		(width 0.08636)
		(layer "In2.Cu")
		(net "TDR_DIFF_100_IN1_DP")
	)
	(segment
		(start 105.69194 48.253396)
		(end 105.69194 47.019972)
		(width 0.08636)
		(layer "In2.Cu")
		(net "TDR_DIFF_100_IN1_DP")
	)
	(segment
		(start 112.98682 54.61)
		(end 113.07318 54.52364)
		(width 0.08636)
		(layer "In2.Cu")
		(net "TDR_DIFF_100_IN1_DP")
	)
	(segment
		(start 105.43286 40.415972)
		(end 105.852468 39.996364)
		(width 0.08636)
		(layer "In2.Cu")
		(net "TDR_DIFF_100_IN1_DP")
	)
	(segment
		(start 106.111548 46.600364)
		(end 120.24106 46.600364)
		(width 0.08636)
		(layer "In2.Cu")
		(net "TDR_DIFF_100_IN1_DP")
	)
	(segment
		(start 112.014 54.61)
		(end 112.98682 54.61)
		(width 0.08636)
		(layer "In2.Cu")
		(net "TDR_DIFF_100_IN1_DP")
	)
	(segment
		(start 113.07318 54.52364)
		(end 113.07318 52.147724)
		(width 0.08636)
		(layer "In2.Cu")
		(net "TDR_DIFF_100_IN1_DP")
	)
	(segment
		(start 120.41378 43.125644)
		(end 120.41378 42.241724)
		(width 0.08636)
		(layer "In2.Cu")
		(net "TDR_DIFF_100_IN1_DP")
	)
	(segment
		(start 112.98682 34.6964)
		(end 112.014 34.6964)
		(width 0.08636)
		(layer "In2.Cu")
		(net "TDR_DIFF_100_IN1_DP")
	)
	(segment
		(start 120.41378 42.241724)
		(end 120.24106 42.069004)
		(width 0.08636)
		(layer "In2.Cu")
		(net "TDR_DIFF_100_IN1_DP")
	)
	(segment
		(start 120.41378 39.823644)
		(end 120.41378 38.939724)
		(width 0.08636)
		(layer "In2.Cu")
		(net "TDR_DIFF_100_IN1_DP")
	)
	(segment
		(start 120.24106 46.600364)
		(end 120.41378 46.427644)
		(width 0.08636)
		(layer "In2.Cu")
		(net "TDR_DIFF_100_IN1_DP")
	)
	(segment
		(start 120.41378 49.729644)
		(end 120.41378 48.845724)
		(width 0.08636)
		(layer "In2.Cu")
		(net "TDR_DIFF_100_IN1_DP")
	)
	(segment
		(start 106.152188 51.975004)
		(end 105.73258 51.555396)
		(width 0.08636)
		(layer "In2.Cu")
		(net "TDR_DIFF_100_IN1_DP")
	)
	(segment
		(start 106.11358 48.078644)
		(end 106.11358 47.194724)
		(width 0.08636)
		(layer "In2.Cu")
		(net "TDR_DIFF_100_IN1_DN")
	)
	(segment
		(start 106.32694 51.553364)
		(end 106.15422 51.380644)
		(width 0.08636)
		(layer "In2.Cu")
		(net "TDR_DIFF_100_IN1_DN")
	)
	(segment
		(start 113.49482 34.78276)
		(end 113.58118 34.6964)
		(width 0.08636)
		(layer "In2.Cu")
		(net "TDR_DIFF_100_IN1_DN")
	)
	(segment
		(start 105.87482 38.172644)
		(end 105.87482 37.288724)
		(width 0.08636)
		(layer "In2.Cu")
		(net "TDR_DIFF_100_IN1_DN")
	)
	(segment
		(start 113.075212 51.553364)
		(end 106.32694 51.553364)
		(width 0.08636)
		(layer "In2.Cu")
		(net "TDR_DIFF_100_IN1_DN")
	)
	(segment
		(start 105.83418 44.776644)
		(end 105.83418 43.892724)
		(width 0.08636)
		(layer "In2.Cu")
		(net "TDR_DIFF_100_IN1_DN")
	)
	(segment
		(start 105.87482 37.288724)
		(end 106.04754 37.116004)
		(width 0.08636)
		(layer "In2.Cu")
		(net "TDR_DIFF_100_IN1_DN")
	)
	(segment
		(start 106.04754 37.116004)
		(end 113.075212 37.116004)
		(width 0.08636)
		(layer "In2.Cu")
		(net "TDR_DIFF_100_IN1_DN")
	)
	(segment
		(start 120.415812 44.949364)
		(end 106.0069 44.949364)
		(width 0.08636)
		(layer "In2.Cu")
		(net "TDR_DIFF_100_IN1_DN")
	)
	(segment
		(start 120.83542 46.602396)
		(end 120.83542 45.368972)
		(width 0.08636)
		(layer "In2.Cu")
		(net "TDR_DIFF_100_IN1_DN")
	)
	(segment
		(start 113.49482 36.696396)
		(end 113.49482 34.78276)
		(width 0.08636)
		(layer "In2.Cu")
		(net "TDR_DIFF_100_IN1_DN")
	)
	(segment
		(start 120.415812 43.720004)
		(end 120.83542 43.300396)
		(width 0.08636)
		(layer "In2.Cu")
		(net "TDR_DIFF_100_IN1_DN")
	)
	(segment
		(start 120.415812 48.251364)
		(end 106.2863 48.251364)
		(width 0.08636)
		(layer "In2.Cu")
		(net "TDR_DIFF_100_IN1_DN")
	)
	(segment
		(start 106.32694 50.324004)
		(end 120.415812 50.324004)
		(width 0.08636)
		(layer "In2.Cu")
		(net "TDR_DIFF_100_IN1_DN")
	)
	(segment
		(start 120.83542 49.904396)
		(end 120.83542 48.670972)
		(width 0.08636)
		(layer "In2.Cu")
		(net "TDR_DIFF_100_IN1_DN")
	)
	(segment
		(start 106.15422 50.496724)
		(end 106.32694 50.324004)
		(width 0.08636)
		(layer "In2.Cu")
		(net "TDR_DIFF_100_IN1_DN")
	)
	(segment
		(start 120.83542 43.300396)
		(end 120.83542 42.066972)
		(width 0.08636)
		(layer "In2.Cu")
		(net "TDR_DIFF_100_IN1_DN")
	)
	(segment
		(start 120.415812 50.324004)
		(end 120.83542 49.904396)
		(width 0.08636)
		(layer "In2.Cu")
		(net "TDR_DIFF_100_IN1_DN")
	)
	(segment
		(start 120.415812 41.647364)
		(end 106.02722 41.647364)
		(width 0.08636)
		(layer "In2.Cu")
		(net "TDR_DIFF_100_IN1_DN")
	)
	(segment
		(start 106.02722 40.418004)
		(end 120.415812 40.418004)
		(width 0.08636)
		(layer "In2.Cu")
		(net "TDR_DIFF_100_IN1_DN")
	)
	(segment
		(start 113.58118 34.6964)
		(end 114.554 34.6964)
		(width 0.08636)
		(layer "In2.Cu")
		(net "TDR_DIFF_100_IN1_DN")
	)
	(segment
		(start 105.83418 43.892724)
		(end 106.0069 43.720004)
		(width 0.08636)
		(layer "In2.Cu")
		(net "TDR_DIFF_100_IN1_DN")
	)
	(segment
		(start 120.415812 40.418004)
		(end 120.83542 39.998396)
		(width 0.08636)
		(layer "In2.Cu")
		(net "TDR_DIFF_100_IN1_DN")
	)
	(segment
		(start 106.2863 48.251364)
		(end 106.11358 48.078644)
		(width 0.08636)
		(layer "In2.Cu")
		(net "TDR_DIFF_100_IN1_DN")
	)
	(segment
		(start 106.2863 47.022004)
		(end 120.415812 47.022004)
		(width 0.08636)
		(layer "In2.Cu")
		(net "TDR_DIFF_100_IN1_DN")
	)
	(segment
		(start 114.554 54.61)
		(end 113.58118 54.61)
		(width 0.08636)
		(layer "In2.Cu")
		(net "TDR_DIFF_100_IN1_DN")
	)
	(segment
		(start 120.83542 38.764972)
		(end 120.415812 38.345364)
		(width 0.08636)
		(layer "In2.Cu")
		(net "TDR_DIFF_100_IN1_DN")
	)
	(segment
		(start 106.11358 47.194724)
		(end 106.2863 47.022004)
		(width 0.08636)
		(layer "In2.Cu")
		(net "TDR_DIFF_100_IN1_DN")
	)
	(segment
		(start 106.04754 38.345364)
		(end 105.87482 38.172644)
		(width 0.08636)
		(layer "In2.Cu")
		(net "TDR_DIFF_100_IN1_DN")
	)
	(segment
		(start 106.0069 43.720004)
		(end 120.415812 43.720004)
		(width 0.08636)
		(layer "In2.Cu")
		(net "TDR_DIFF_100_IN1_DN")
	)
	(segment
		(start 120.83542 39.998396)
		(end 120.83542 38.764972)
		(width 0.08636)
		(layer "In2.Cu")
		(net "TDR_DIFF_100_IN1_DN")
	)
	(segment
		(start 106.0069 44.949364)
		(end 105.83418 44.776644)
		(width 0.08636)
		(layer "In2.Cu")
		(net "TDR_DIFF_100_IN1_DN")
	)
	(segment
		(start 105.8545 40.590724)
		(end 106.02722 40.418004)
		(width 0.08636)
		(layer "In2.Cu")
		(net "TDR_DIFF_100_IN1_DN")
	)
	(segment
		(start 113.075212 37.116004)
		(end 113.49482 36.696396)
		(width 0.08636)
		(layer "In2.Cu")
		(net "TDR_DIFF_100_IN1_DN")
	)
	(segment
		(start 120.83542 45.368972)
		(end 120.415812 44.949364)
		(width 0.08636)
		(layer "In2.Cu")
		(net "TDR_DIFF_100_IN1_DN")
	)
	(segment
		(start 120.415812 47.022004)
		(end 120.83542 46.602396)
		(width 0.08636)
		(layer "In2.Cu")
		(net "TDR_DIFF_100_IN1_DN")
	)
	(segment
		(start 106.02722 41.647364)
		(end 105.8545 41.474644)
		(width 0.08636)
		(layer "In2.Cu")
		(net "TDR_DIFF_100_IN1_DN")
	)
	(segment
		(start 105.8545 41.474644)
		(end 105.8545 40.590724)
		(width 0.08636)
		(layer "In2.Cu")
		(net "TDR_DIFF_100_IN1_DN")
	)
	(segment
		(start 113.58118 54.61)
		(end 113.49482 54.52364)
		(width 0.08636)
		(layer "In2.Cu")
		(net "TDR_DIFF_100_IN1_DN")
	)
	(segment
		(start 120.83542 42.066972)
		(end 120.415812 41.647364)
		(width 0.08636)
		(layer "In2.Cu")
		(net "TDR_DIFF_100_IN1_DN")
	)
	(segment
		(start 113.49482 51.972972)
		(end 113.075212 51.553364)
		(width 0.08636)
		(layer "In2.Cu")
		(net "TDR_DIFF_100_IN1_DN")
	)
	(segment
		(start 113.49482 54.52364)
		(end 113.49482 51.972972)
		(width 0.08636)
		(layer "In2.Cu")
		(net "TDR_DIFF_100_IN1_DN")
	)
	(segment
		(start 120.415812 38.345364)
		(end 106.04754 38.345364)
		(width 0.08636)
		(layer "In2.Cu")
		(net "TDR_DIFF_100_IN1_DN")
	)
	(segment
		(start 120.83542 48.670972)
		(end 120.415812 48.251364)
		(width 0.08636)
		(layer "In2.Cu")
		(net "TDR_DIFF_100_IN1_DN")
	)
	(segment
		(start 106.15422 51.380644)
		(end 106.15422 50.496724)
		(width 0.08636)
		(layer "In2.Cu")
		(net "TDR_DIFF_100_IN1_DN")
	)
	(segment
		(start 107.538012 110.379002)
		(end 112.7887 110.379002)
		(width 0.1016)
		(layer "B.Cu")
		(net "TDR_DIFF_100_BOT_DP")
	)
	(segment
		(start 107.538012 105.197402)
		(end 107.0102 105.725214)
		(width 0.1016)
		(layer "B.Cu")
		(net "TDR_DIFF_100_BOT_DP")
	)
	(segment
		(start 119.6848 98.491802)
		(end 119.38 98.796602)
		(width 0.1016)
		(layer "B.Cu")
		(net "TDR_DIFF_100_BOT_DP")
	)
	(segment
		(start 113.0935 112.5728)
		(end 112.8903 112.776)
		(width 0.1016)
		(layer "B.Cu")
		(net "TDR_DIFF_100_BOT_DP")
	)
	(segment
		(start 118.872 101.997002)
		(end 107.538012 101.997002)
		(width 0.1016)
		(layer "B.Cu")
		(net "TDR_DIFF_100_BOT_DP")
	)
	(segment
		(start 107.538012 98.796602)
		(end 107.0102 99.324414)
		(width 0.1016)
		(layer "B.Cu")
		(net "TDR_DIFF_100_BOT_DP")
	)
	(segment
		(start 119.6594 94.681802)
		(end 119.6594 95.291402)
		(width 0.1016)
		(layer "B.Cu")
		(net "TDR_DIFF_100_BOT_DP")
	)
	(segment
		(start 107.0102 106.65079)
		(end 107.538012 107.178602)
		(width 0.1016)
		(layer "B.Cu")
		(net "TDR_DIFF_100_BOT_DP")
	)
	(segment
		(start 107.5182 96.124014)
		(end 107.5182 97.04959)
		(width 0.1016)
		(layer "B.Cu")
		(net "TDR_DIFF_100_BOT_DP")
	)
	(segment
		(start 112.7887 92.395802)
		(end 108.071412 92.395802)
		(width 0.1016)
		(layer "B.Cu")
		(net "TDR_DIFF_100_BOT_DP")
	)
	(segment
		(start 107.538012 108.397802)
		(end 107.0102 108.925614)
		(width 0.1016)
		(layer "B.Cu")
		(net "TDR_DIFF_100_BOT_DP")
	)
	(segment
		(start 118.872 100.777802)
		(end 119.1768 101.082602)
		(width 0.1016)
		(layer "B.Cu")
		(net "TDR_DIFF_100_BOT_DP")
	)
	(segment
		(start 112.8903 112.776)
		(end 112.014 112.776)
		(width 0.1016)
		(layer "B.Cu")
		(net "TDR_DIFF_100_BOT_DP")
	)
	(segment
		(start 107.0102 105.725214)
		(end 107.0102 106.65079)
		(width 0.1016)
		(layer "B.Cu")
		(net "TDR_DIFF_100_BOT_DP")
	)
	(segment
		(start 119.3546 94.377002)
		(end 119.6594 94.681802)
		(width 0.1016)
		(layer "B.Cu")
		(net "TDR_DIFF_100_BOT_DP")
	)
	(segment
		(start 108.046012 95.596202)
		(end 107.5182 96.124014)
		(width 0.1016)
		(layer "B.Cu")
		(net "TDR_DIFF_100_BOT_DP")
	)
	(segment
		(start 119.6848 97.882202)
		(end 119.6848 98.491802)
		(width 0.1016)
		(layer "B.Cu")
		(net "TDR_DIFF_100_BOT_DP")
	)
	(segment
		(start 112.7887 110.379002)
		(end 113.0935 110.683802)
		(width 0.1016)
		(layer "B.Cu")
		(net "TDR_DIFF_100_BOT_DP")
	)
	(segment
		(start 112.014 90.17)
		(end 112.8903 90.17)
		(width 0.1016)
		(layer "B.Cu")
		(net "TDR_DIFF_100_BOT_DP")
	)
	(segment
		(start 118.872 103.978202)
		(end 119.1768 104.283002)
		(width 0.1016)
		(layer "B.Cu")
		(net "TDR_DIFF_100_BOT_DP")
	)
	(segment
		(start 107.5436 92.923614)
		(end 107.5436 93.84919)
		(width 0.1016)
		(layer "B.Cu")
		(net "TDR_DIFF_100_BOT_DP")
	)
	(segment
		(start 107.5436 93.84919)
		(end 108.071412 94.377002)
		(width 0.1016)
		(layer "B.Cu")
		(net "TDR_DIFF_100_BOT_DP")
	)
	(segment
		(start 107.0102 100.24999)
		(end 107.538012 100.777802)
		(width 0.1016)
		(layer "B.Cu")
		(net "TDR_DIFF_100_BOT_DP")
	)
	(segment
		(start 113.0935 110.683802)
		(end 113.0935 112.5728)
		(width 0.1016)
		(layer "B.Cu")
		(net "TDR_DIFF_100_BOT_DP")
	)
	(segment
		(start 119.1768 107.483402)
		(end 119.1768 108.093002)
		(width 0.1016)
		(layer "B.Cu")
		(net "TDR_DIFF_100_BOT_DP")
	)
	(segment
		(start 107.538012 103.978202)
		(end 118.872 103.978202)
		(width 0.1016)
		(layer "B.Cu")
		(net "TDR_DIFF_100_BOT_DP")
	)
	(segment
		(start 119.1768 104.283002)
		(end 119.1768 104.892602)
		(width 0.1016)
		(layer "B.Cu")
		(net "TDR_DIFF_100_BOT_DP")
	)
	(segment
		(start 119.1768 101.692202)
		(end 118.872 101.997002)
		(width 0.1016)
		(layer "B.Cu")
		(net "TDR_DIFF_100_BOT_DP")
	)
	(segment
		(start 113.0935 90.3732)
		(end 113.0935 92.091002)
		(width 0.1016)
		(layer "B.Cu")
		(net "TDR_DIFF_100_BOT_DP")
	)
	(segment
		(start 119.1768 104.892602)
		(end 118.872 105.197402)
		(width 0.1016)
		(layer "B.Cu")
		(net "TDR_DIFF_100_BOT_DP")
	)
	(segment
		(start 119.38 98.796602)
		(end 107.538012 98.796602)
		(width 0.1016)
		(layer "B.Cu")
		(net "TDR_DIFF_100_BOT_DP")
	)
	(segment
		(start 112.8903 90.17)
		(end 113.0935 90.3732)
		(width 0.1016)
		(layer "B.Cu")
		(net "TDR_DIFF_100_BOT_DP")
	)
	(segment
		(start 107.0102 108.925614)
		(end 107.0102 109.85119)
		(width 0.1016)
		(layer "B.Cu")
		(net "TDR_DIFF_100_BOT_DP")
	)
	(segment
		(start 108.071412 92.395802)
		(end 107.5436 92.923614)
		(width 0.1016)
		(layer "B.Cu")
		(net "TDR_DIFF_100_BOT_DP")
	)
	(segment
		(start 107.538012 101.997002)
		(end 107.0102 102.524814)
		(width 0.1016)
		(layer "B.Cu")
		(net "TDR_DIFF_100_BOT_DP")
	)
	(segment
		(start 113.0935 92.091002)
		(end 112.7887 92.395802)
		(width 0.1016)
		(layer "B.Cu")
		(net "TDR_DIFF_100_BOT_DP")
	)
	(segment
		(start 119.38 97.577402)
		(end 119.6848 97.882202)
		(width 0.1016)
		(layer "B.Cu")
		(net "TDR_DIFF_100_BOT_DP")
	)
	(segment
		(start 108.046012 97.577402)
		(end 119.38 97.577402)
		(width 0.1016)
		(layer "B.Cu")
		(net "TDR_DIFF_100_BOT_DP")
	)
	(segment
		(start 118.872 105.197402)
		(end 107.538012 105.197402)
		(width 0.1016)
		(layer "B.Cu")
		(net "TDR_DIFF_100_BOT_DP")
	)
	(segment
		(start 107.5182 97.04959)
		(end 108.046012 97.577402)
		(width 0.1016)
		(layer "B.Cu")
		(net "TDR_DIFF_100_BOT_DP")
	)
	(segment
		(start 107.0102 99.324414)
		(end 107.0102 100.24999)
		(width 0.1016)
		(layer "B.Cu")
		(net "TDR_DIFF_100_BOT_DP")
	)
	(segment
		(start 118.872 108.397802)
		(end 107.538012 108.397802)
		(width 0.1016)
		(layer "B.Cu")
		(net "TDR_DIFF_100_BOT_DP")
	)
	(segment
		(start 108.071412 94.377002)
		(end 119.3546 94.377002)
		(width 0.1016)
		(layer "B.Cu")
		(net "TDR_DIFF_100_BOT_DP")
	)
	(segment
		(start 119.1768 101.082602)
		(end 119.1768 101.692202)
		(width 0.1016)
		(layer "B.Cu")
		(net "TDR_DIFF_100_BOT_DP")
	)
	(segment
		(start 118.872 107.178602)
		(end 119.1768 107.483402)
		(width 0.1016)
		(layer "B.Cu")
		(net "TDR_DIFF_100_BOT_DP")
	)
	(segment
		(start 107.0102 109.85119)
		(end 107.538012 110.379002)
		(width 0.1016)
		(layer "B.Cu")
		(net "TDR_DIFF_100_BOT_DP")
	)
	(segment
		(start 107.0102 103.45039)
		(end 107.538012 103.978202)
		(width 0.1016)
		(layer "B.Cu")
		(net "TDR_DIFF_100_BOT_DP")
	)
	(segment
		(start 107.0102 102.524814)
		(end 107.0102 103.45039)
		(width 0.1016)
		(layer "B.Cu")
		(net "TDR_DIFF_100_BOT_DP")
	)
	(segment
		(start 107.538012 107.178602)
		(end 118.872 107.178602)
		(width 0.1016)
		(layer "B.Cu")
		(net "TDR_DIFF_100_BOT_DP")
	)
	(segment
		(start 107.538012 100.777802)
		(end 118.872 100.777802)
		(width 0.1016)
		(layer "B.Cu")
		(net "TDR_DIFF_100_BOT_DP")
	)
	(segment
		(start 119.3546 95.596202)
		(end 108.046012 95.596202)
		(width 0.1016)
		(layer "B.Cu")
		(net "TDR_DIFF_100_BOT_DP")
	)
	(segment
		(start 119.6594 95.291402)
		(end 119.3546 95.596202)
		(width 0.1016)
		(layer "B.Cu")
		(net "TDR_DIFF_100_BOT_DP")
	)
	(segment
		(start 119.1768 108.093002)
		(end 118.872 108.397802)
		(width 0.1016)
		(layer "B.Cu")
		(net "TDR_DIFF_100_BOT_DP")
	)
	(segment
		(start 107.3912 100.092002)
		(end 107.696 100.396802)
		(width 0.1016)
		(layer "B.Cu")
		(net "TDR_DIFF_100_BOT_DN")
	)
	(segment
		(start 107.696 105.578402)
		(end 107.3912 105.883202)
		(width 0.1016)
		(layer "B.Cu")
		(net "TDR_DIFF_100_BOT_DN")
	)
	(segment
		(start 112.946688 92.776802)
		(end 108.2294 92.776802)
		(width 0.1016)
		(layer "B.Cu")
		(net "TDR_DIFF_100_BOT_DN")
	)
	(segment
		(start 119.029988 106.797602)
		(end 119.5578 107.325414)
		(width 0.1016)
		(layer "B.Cu")
		(net "TDR_DIFF_100_BOT_DN")
	)
	(segment
		(start 107.696 108.778802)
		(end 107.3912 109.083602)
		(width 0.1016)
		(layer "B.Cu")
		(net "TDR_DIFF_100_BOT_DN")
	)
	(segment
		(start 119.512588 93.996002)
		(end 120.0404 94.523814)
		(width 0.1016)
		(layer "B.Cu")
		(net "TDR_DIFF_100_BOT_DN")
	)
	(segment
		(start 119.512588 95.977202)
		(end 108.204 95.977202)
		(width 0.1016)
		(layer "B.Cu")
		(net "TDR_DIFF_100_BOT_DN")
	)
	(segment
		(start 107.8992 96.891602)
		(end 108.204 97.196402)
		(width 0.1016)
		(layer "B.Cu")
		(net "TDR_DIFF_100_BOT_DN")
	)
	(segment
		(start 107.3912 105.883202)
		(end 107.3912 106.492802)
		(width 0.1016)
		(layer "B.Cu")
		(net "TDR_DIFF_100_BOT_DN")
	)
	(segment
		(start 107.3912 102.682802)
		(end 107.3912 103.292402)
		(width 0.1016)
		(layer "B.Cu")
		(net "TDR_DIFF_100_BOT_DN")
	)
	(segment
		(start 119.5578 107.325414)
		(end 119.5578 108.25099)
		(width 0.1016)
		(layer "B.Cu")
		(net "TDR_DIFF_100_BOT_DN")
	)
	(segment
		(start 114.554 90.17)
		(end 113.6777 90.17)
		(width 0.1016)
		(layer "B.Cu")
		(net "TDR_DIFF_100_BOT_DN")
	)
	(segment
		(start 108.204 95.977202)
		(end 107.8992 96.282002)
		(width 0.1016)
		(layer "B.Cu")
		(net "TDR_DIFF_100_BOT_DN")
	)
	(segment
		(start 107.696 100.396802)
		(end 119.029988 100.396802)
		(width 0.1016)
		(layer "B.Cu")
		(net "TDR_DIFF_100_BOT_DN")
	)
	(segment
		(start 113.4745 90.3732)
		(end 113.4745 92.24899)
		(width 0.1016)
		(layer "B.Cu")
		(net "TDR_DIFF_100_BOT_DN")
	)
	(segment
		(start 120.0658 98.64979)
		(end 119.537988 99.177602)
		(width 0.1016)
		(layer "B.Cu")
		(net "TDR_DIFF_100_BOT_DN")
	)
	(segment
		(start 119.029988 108.778802)
		(end 107.696 108.778802)
		(width 0.1016)
		(layer "B.Cu")
		(net "TDR_DIFF_100_BOT_DN")
	)
	(segment
		(start 119.029988 105.578402)
		(end 107.696 105.578402)
		(width 0.1016)
		(layer "B.Cu")
		(net "TDR_DIFF_100_BOT_DN")
	)
	(segment
		(start 107.696 103.597202)
		(end 119.029988 103.597202)
		(width 0.1016)
		(layer "B.Cu")
		(net "TDR_DIFF_100_BOT_DN")
	)
	(segment
		(start 120.0404 94.523814)
		(end 120.0404 95.44939)
		(width 0.1016)
		(layer "B.Cu")
		(net "TDR_DIFF_100_BOT_DN")
	)
	(segment
		(start 112.946688 109.998002)
		(end 113.4745 110.525814)
		(width 0.1016)
		(layer "B.Cu")
		(net "TDR_DIFF_100_BOT_DN")
	)
	(segment
		(start 119.5578 105.05059)
		(end 119.029988 105.578402)
		(width 0.1016)
		(layer "B.Cu")
		(net "TDR_DIFF_100_BOT_DN")
	)
	(segment
		(start 119.537988 99.177602)
		(end 107.696 99.177602)
		(width 0.1016)
		(layer "B.Cu")
		(net "TDR_DIFF_100_BOT_DN")
	)
	(segment
		(start 119.5578 108.25099)
		(end 119.029988 108.778802)
		(width 0.1016)
		(layer "B.Cu")
		(net "TDR_DIFF_100_BOT_DN")
	)
	(segment
		(start 113.6777 112.776)
		(end 114.554 112.776)
		(width 0.1016)
		(layer "B.Cu")
		(net "TDR_DIFF_100_BOT_DN")
	)
	(segment
		(start 107.3912 106.492802)
		(end 107.696 106.797602)
		(width 0.1016)
		(layer "B.Cu")
		(net "TDR_DIFF_100_BOT_DN")
	)
	(segment
		(start 108.204 97.196402)
		(end 119.537988 97.196402)
		(width 0.1016)
		(layer "B.Cu")
		(net "TDR_DIFF_100_BOT_DN")
	)
	(segment
		(start 107.3912 109.083602)
		(end 107.3912 109.693202)
		(width 0.1016)
		(layer "B.Cu")
		(net "TDR_DIFF_100_BOT_DN")
	)
	(segment
		(start 107.8992 96.282002)
		(end 107.8992 96.891602)
		(width 0.1016)
		(layer "B.Cu")
		(net "TDR_DIFF_100_BOT_DN")
	)
	(segment
		(start 120.0404 95.44939)
		(end 119.512588 95.977202)
		(width 0.1016)
		(layer "B.Cu")
		(net "TDR_DIFF_100_BOT_DN")
	)
	(segment
		(start 119.029988 103.597202)
		(end 119.5578 104.125014)
		(width 0.1016)
		(layer "B.Cu")
		(net "TDR_DIFF_100_BOT_DN")
	)
	(segment
		(start 119.537988 97.196402)
		(end 120.0658 97.724214)
		(width 0.1016)
		(layer "B.Cu")
		(net "TDR_DIFF_100_BOT_DN")
	)
	(segment
		(start 107.3912 99.482402)
		(end 107.3912 100.092002)
		(width 0.1016)
		(layer "B.Cu")
		(net "TDR_DIFF_100_BOT_DN")
	)
	(segment
		(start 107.9246 93.691202)
		(end 108.2294 93.996002)
		(width 0.1016)
		(layer "B.Cu")
		(net "TDR_DIFF_100_BOT_DN")
	)
	(segment
		(start 107.9246 93.081602)
		(end 107.9246 93.691202)
		(width 0.1016)
		(layer "B.Cu")
		(net "TDR_DIFF_100_BOT_DN")
	)
	(segment
		(start 119.5578 100.924614)
		(end 119.5578 101.85019)
		(width 0.1016)
		(layer "B.Cu")
		(net "TDR_DIFF_100_BOT_DN")
	)
	(segment
		(start 113.4745 112.5728)
		(end 113.6777 112.776)
		(width 0.1016)
		(layer "B.Cu")
		(net "TDR_DIFF_100_BOT_DN")
	)
	(segment
		(start 119.029988 100.396802)
		(end 119.5578 100.924614)
		(width 0.1016)
		(layer "B.Cu")
		(net "TDR_DIFF_100_BOT_DN")
	)
	(segment
		(start 108.2294 92.776802)
		(end 107.9246 93.081602)
		(width 0.1016)
		(layer "B.Cu")
		(net "TDR_DIFF_100_BOT_DN")
	)
	(segment
		(start 107.696 109.998002)
		(end 112.946688 109.998002)
		(width 0.1016)
		(layer "B.Cu")
		(net "TDR_DIFF_100_BOT_DN")
	)
	(segment
		(start 107.696 102.378002)
		(end 107.3912 102.682802)
		(width 0.1016)
		(layer "B.Cu")
		(net "TDR_DIFF_100_BOT_DN")
	)
	(segment
		(start 119.029988 102.378002)
		(end 107.696 102.378002)
		(width 0.1016)
		(layer "B.Cu")
		(net "TDR_DIFF_100_BOT_DN")
	)
	(segment
		(start 113.4745 110.525814)
		(end 113.4745 112.5728)
		(width 0.1016)
		(layer "B.Cu")
		(net "TDR_DIFF_100_BOT_DN")
	)
	(segment
		(start 119.5578 101.85019)
		(end 119.029988 102.378002)
		(width 0.1016)
		(layer "B.Cu")
		(net "TDR_DIFF_100_BOT_DN")
	)
	(segment
		(start 113.4745 92.24899)
		(end 112.946688 92.776802)
		(width 0.1016)
		(layer "B.Cu")
		(net "TDR_DIFF_100_BOT_DN")
	)
	(segment
		(start 107.3912 109.693202)
		(end 107.696 109.998002)
		(width 0.1016)
		(layer "B.Cu")
		(net "TDR_DIFF_100_BOT_DN")
	)
	(segment
		(start 107.696 99.177602)
		(end 107.3912 99.482402)
		(width 0.1016)
		(layer "B.Cu")
		(net "TDR_DIFF_100_BOT_DN")
	)
	(segment
		(start 107.696 106.797602)
		(end 119.029988 106.797602)
		(width 0.1016)
		(layer "B.Cu")
		(net "TDR_DIFF_100_BOT_DN")
	)
	(segment
		(start 119.5578 104.125014)
		(end 119.5578 105.05059)
		(width 0.1016)
		(layer "B.Cu")
		(net "TDR_DIFF_100_BOT_DN")
	)
	(segment
		(start 108.2294 93.996002)
		(end 119.512588 93.996002)
		(width 0.1016)
		(layer "B.Cu")
		(net "TDR_DIFF_100_BOT_DN")
	)
	(segment
		(start 107.3912 103.292402)
		(end 107.696 103.597202)
		(width 0.1016)
		(layer "B.Cu")
		(net "TDR_DIFF_100_BOT_DN")
	)
	(segment
		(start 120.0658 97.724214)
		(end 120.0658 98.64979)
		(width 0.1016)
		(layer "B.Cu")
		(net "TDR_DIFF_100_BOT_DN")
	)
	(segment
		(start 113.6777 90.17)
		(end 113.4745 90.3732)
		(width 0.1016)
		(layer "B.Cu")
		(net "TDR_DIFF_100_BOT_DN")
	)
	(via
		(at 37.71646 -95.061786)
		(size 0.6604)
		(drill 0.3302)
		(layers "F.Cu" "B.Cu")
		(net "SMB_DEBUG_AUX_LVC3_USB_R2_SDA")
	)
	(segment
		(start 38.645846 -94.1324)
		(end 39.903654 -94.1324)
		(width 0.11684)
		(layer "B.Cu")
		(net "SMB_DEBUG_AUX_LVC3_USB_R2_SDA")
	)
	(segment
		(start 37.71646 -95.061786)
		(end 38.645846 -94.1324)
		(width 0.11684)
		(layer "B.Cu")
		(net "SMB_DEBUG_AUX_LVC3_USB_R2_SDA")
	)
	(segment
		(start 39.903654 -94.1324)
		(end 40.180006 -93.856048)
		(width 0.11684)
		(layer "B.Cu")
		(net "SMB_DEBUG_AUX_LVC3_USB_R2_SDA")
	)
	(segment
		(start 37.71646 -96.67875)
		(end 37.71646 -95.061786)
		(width 0.11684)
		(layer "B.Cu")
		(net "SMB_DEBUG_AUX_LVC3_USB_R2_SDA")
	)
	(segment
		(start 40.180006 -93.856048)
		(end 40.180006 -93.599)
		(width 0.11684)
		(layer "B.Cu")
		(net "SMB_DEBUG_AUX_LVC3_USB_R2_SDA")
	)
	(segment
		(start 37.17417 -97.22104)
		(end 37.71646 -96.67875)
		(width 0.11684)
		(layer "B.Cu")
		(net "SMB_DEBUG_AUX_LVC3_USB_R2_SDA")
	)
	(via
		(at 38.15334 -93.7895)
		(size 0.6604)
		(drill 0.3302)
		(layers "F.Cu" "B.Cu")
		(net "SMB_DEBUG_AUX_LVC3_USB_R2_SCL")
	)
	(segment
		(start 37.17417 -94.76867)
		(end 37.17417 -96.20504)
		(width 0.11684)
		(layer "B.Cu")
		(net "SMB_DEBUG_AUX_LVC3_USB_R2_SCL")
	)
	(segment
		(start 38.15334 -93.7895)
		(end 37.17417 -94.76867)
		(width 0.11684)
		(layer "B.Cu")
		(net "SMB_DEBUG_AUX_LVC3_USB_R2_SCL")
	)
	(segment
		(start 39.67988 -93.599)
		(end 39.67988 -93.43644)
		(width 0.11684)
		(layer "B.Cu")
		(net "SMB_DEBUG_AUX_LVC3_USB_R2_SCL")
	)
	(segment
		(start 39.56304 -93.3196)
		(end 38.62324 -93.3196)
		(width 0.11684)
		(layer "B.Cu")
		(net "SMB_DEBUG_AUX_LVC3_USB_R2_SCL")
	)
	(segment
		(start 38.62324 -93.3196)
		(end 38.15334 -93.7895)
		(width 0.11684)
		(layer "B.Cu")
		(net "SMB_DEBUG_AUX_LVC3_USB_R2_SCL")
	)
	(segment
		(start 39.67988 -93.43644)
		(end 39.56304 -93.3196)
		(width 0.11684)
		(layer "B.Cu")
		(net "SMB_DEBUG_AUX_LVC3_USB_R2_SCL")
	)
	(via
		(at 52.91201 -87.18169)
		(size 0.6604)
		(drill 0.3302)
		(layers "F.Cu" "B.Cu")
		(net "RST_PLTRST_R2_N")
	)
	(segment
		(start 53.825648 -88.095328)
		(end 52.91201 -87.18169)
		(width 0.11684)
		(layer "B.Cu")
		(net "RST_PLTRST_R2_N")
	)
	(segment
		(start 54.71668 -88.095328)
		(end 53.825648 -88.095328)
		(width 0.11684)
		(layer "B.Cu")
		(net "RST_PLTRST_R2_N")
	)
	(segment
		(start 52.91201 -87.18169)
		(end 52.66182 -86.9315)
		(width 0.11684)
		(layer "B.Cu")
		(net "RST_PLTRST_R2_N")
	)
	(segment
		(start 52.66182 -86.9315)
		(end 51.77155 -86.9315)
		(width 0.11684)
		(layer "B.Cu")
		(net "RST_PLTRST_R2_N")
	)
	(via
		(at 52.9082 -85.9028)
		(size 0.6604)
		(drill 0.3302)
		(layers "F.Cu" "B.Cu")
		(net "PWRGD_SYS_PWROK_R1")
	)
	(segment
		(start 53.594 -86.5886)
		(end 53.594 -87.223346)
		(width 0.11684)
		(layer "B.Cu")
		(net "PWRGD_SYS_PWROK_R1")
	)
	(segment
		(start 53.594 -87.223346)
		(end 53.815996 -87.445342)
		(width 0.11684)
		(layer "B.Cu")
		(net "PWRGD_SYS_PWROK_R1")
	)
	(segment
		(start 51.91125 -85.9028)
		(end 52.9082 -85.9028)
		(width 0.11684)
		(layer "B.Cu")
		(net "PWRGD_SYS_PWROK_R1")
	)
	(segment
		(start 51.77155 -86.0425)
		(end 51.91125 -85.9028)
		(width 0.11684)
		(layer "B.Cu")
		(net "PWRGD_SYS_PWROK_R1")
	)
	(segment
		(start 53.815996 -87.445342)
		(end 54.71668 -87.445342)
		(width 0.11684)
		(layer "B.Cu")
		(net "PWRGD_SYS_PWROK_R1")
	)
	(segment
		(start 52.9082 -85.9028)
		(end 53.594 -86.5886)
		(width 0.11684)
		(layer "B.Cu")
		(net "PWRGD_SYS_PWROK_R1")
	)
	(via
		(at 52.91328 -88.465914)
		(size 0.6604)
		(drill 0.3302)
		(layers "F.Cu" "B.Cu")
		(net "PWRGD_DSW_PWROK_R3")
	)
	(segment
		(start 52.300632 -88.465914)
		(end 52.91328 -88.465914)
		(width 0.11684)
		(layer "B.Cu")
		(net "PWRGD_DSW_PWROK_R3")
	)
	(segment
		(start 51.64455 -87.8205)
		(end 51.64455 -88.7095)
		(width 0.11684)
		(layer "B.Cu")
		(net "PWRGD_DSW_PWROK_R3")
	)
	(segment
		(start 53.490368 -88.465914)
		(end 53.769768 -88.745314)
		(width 0.11684)
		(layer "B.Cu")
		(net "PWRGD_DSW_PWROK_R3")
	)
	(segment
		(start 52.057046 -88.7095)
		(end 52.300632 -88.465914)
		(width 0.11684)
		(layer "B.Cu")
		(net "PWRGD_DSW_PWROK_R3")
	)
	(segment
		(start 51.64455 -88.7095)
		(end 52.057046 -88.7095)
		(width 0.11684)
		(layer "B.Cu")
		(net "PWRGD_DSW_PWROK_R3")
	)
	(segment
		(start 52.91328 -88.465914)
		(end 53.490368 -88.465914)
		(width 0.11684)
		(layer "B.Cu")
		(net "PWRGD_DSW_PWROK_R3")
	)
	(segment
		(start 53.769768 -88.745314)
		(end 54.71668 -88.745314)
		(width 0.11684)
		(layer "B.Cu")
		(net "PWRGD_DSW_PWROK_R3")
	)
	(segment
		(start 65.65265 -64.737488)
		(end 65.620138 -64.77)
		(width 0.11684)
		(layer "F.Cu")
		(net "PWRGD_DSW_PWROK")
	)
	(segment
		(start 65.205864 -64.77)
		(end 65.056512 -64.620648)
		(width 0.11684)
		(layer "F.Cu")
		(net "PWRGD_DSW_PWROK")
	)
	(segment
		(start 27.559 -103.14305)
		(end 27.559 -103.80472)
		(width 0.11684)
		(layer "F.Cu")
		(net "PWRGD_DSW_PWROK")
	)
	(segment
		(start 65.056512 -64.620648)
		(end 65.056512 -64.326516)
		(width 0.11684)
		(layer "F.Cu")
		(net "PWRGD_DSW_PWROK")
	)
	(segment
		(start 65.620138 -64.77)
		(end 65.205864 -64.77)
		(width 0.11684)
		(layer "F.Cu")
		(net "PWRGD_DSW_PWROK")
	)
	(via
		(at 65.65265 -64.737488)
		(size 0.508)
		(drill 0.254)
		(layers "F.Cu" "B.Cu")
		(net "PWRGD_DSW_PWROK")
	)
	(via
		(at 50.731166 -79.89951)
		(size 0.508)
		(drill 0.254)
		(layers "F.Cu" "B.Cu")
		(net "PWRGD_DSW_PWROK")
	)
	(via
		(at 27.559 -103.80472)
		(size 0.508)
		(drill 0.254)
		(layers "F.Cu" "B.Cu")
		(net "PWRGD_DSW_PWROK")
	)
	(via
		(at 67.12331 -80.217518)
		(size 0.508)
		(drill 0.254)
		(layers "F.Cu" "B.Cu")
		(net "PWRGD_DSW_PWROK")
	)
	(via
		(at 50.218594 -88.7095)
		(size 0.508)
		(drill 0.254)
		(layers "F.Cu" "B.Cu")
		(net "PWRGD_DSW_PWROK")
	)
	(via
		(at 49.7332 -100.78212)
		(size 0.508)
		(drill 0.254)
		(layers "F.Cu" "B.Cu")
		(net "PWRGD_DSW_PWROK")
	)
	(segment
		(start 27.559 -103.80472)
		(end 27.121866 -103.80472)
		(width 0.11684)
		(layer "B.Cu")
		(net "PWRGD_DSW_PWROK")
	)
	(segment
		(start 50.218594 -88.7095)
		(end 50.84445 -88.7095)
		(width 0.11684)
		(layer "B.Cu")
		(net "PWRGD_DSW_PWROK")
	)
	(segment
		(start 26.035 -102.717854)
		(end 26.035 -102.38105)
		(width 0.11684)
		(layer "B.Cu")
		(net "PWRGD_DSW_PWROK")
	)
	(segment
		(start 27.121866 -103.80472)
		(end 26.035 -102.717854)
		(width 0.11684)
		(layer "B.Cu")
		(net "PWRGD_DSW_PWROK")
	)
	(segment
		(start 35.3314 -102.95763)
		(end 46.81601 -102.95763)
		(width 0.08382)
		(layer "In2.Cu")
		(net "PWRGD_DSW_PWROK")
	)
	(segment
		(start 50.731166 -79.89951)
		(end 50.731166 -78.935834)
		(width 0.08382)
		(layer "In2.Cu")
		(net "PWRGD_DSW_PWROK")
	)
	(segment
		(start 35.13582 -103.15321)
		(end 35.3314 -102.95763)
		(width 0.08382)
		(layer "In2.Cu")
		(net "PWRGD_DSW_PWROK")
	)
	(segment
		(start 62.656974 -79.60487)
		(end 63.68923 -79.60487)
		(width 0.08382)
		(layer "In2.Cu")
		(net "PWRGD_DSW_PWROK")
	)
	(segment
		(start 59.70524 -80.53324)
		(end 60.24245 -81.07045)
		(width 0.08382)
		(layer "In2.Cu")
		(net "PWRGD_DSW_PWROK")
	)
	(segment
		(start 57.44464 -80.53324)
		(end 59.70524 -80.53324)
		(width 0.08382)
		(layer "In2.Cu")
		(net "PWRGD_DSW_PWROK")
	)
	(segment
		(start 51.04384 -78.62316)
		(end 53.431186 -78.62316)
		(width 0.08382)
		(layer "In2.Cu")
		(net "PWRGD_DSW_PWROK")
	)
	(segment
		(start 50.731166 -78.935834)
		(end 51.04384 -78.62316)
		(width 0.08382)
		(layer "In2.Cu")
		(net "PWRGD_DSW_PWROK")
	)
	(segment
		(start 27.559 -103.80472)
		(end 27.68346 -103.92918)
		(width 0.08382)
		(layer "In2.Cu")
		(net "PWRGD_DSW_PWROK")
	)
	(segment
		(start 30.9626 -103.92283)
		(end 31.670244 -103.92283)
		(width 0.08382)
		(layer "In2.Cu")
		(net "PWRGD_DSW_PWROK")
	)
	(segment
		(start 54.887368 -77.975968)
		(end 57.44464 -80.53324)
		(width 0.08382)
		(layer "In2.Cu")
		(net "PWRGD_DSW_PWROK")
	)
	(segment
		(start 64.301878 -80.217518)
		(end 67.12331 -80.217518)
		(width 0.08382)
		(layer "In2.Cu")
		(net "PWRGD_DSW_PWROK")
	)
	(segment
		(start 63.68923 -79.60487)
		(end 64.301878 -80.217518)
		(width 0.08382)
		(layer "In2.Cu")
		(net "PWRGD_DSW_PWROK")
	)
	(segment
		(start 31.670244 -103.92283)
		(end 32.439864 -103.15321)
		(width 0.08382)
		(layer "In2.Cu")
		(net "PWRGD_DSW_PWROK")
	)
	(segment
		(start 46.81601 -102.95763)
		(end 48.99152 -100.78212)
		(width 0.08382)
		(layer "In2.Cu")
		(net "PWRGD_DSW_PWROK")
	)
	(segment
		(start 54.078378 -77.975968)
		(end 54.887368 -77.975968)
		(width 0.08382)
		(layer "In2.Cu")
		(net "PWRGD_DSW_PWROK")
	)
	(segment
		(start 62.211712 -80.805528)
		(end 62.211712 -80.050132)
		(width 0.08382)
		(layer "In2.Cu")
		(net "PWRGD_DSW_PWROK")
	)
	(segment
		(start 60.24245 -81.07045)
		(end 61.94679 -81.07045)
		(width 0.08382)
		(layer "In2.Cu")
		(net "PWRGD_DSW_PWROK")
	)
	(segment
		(start 61.94679 -81.07045)
		(end 62.211712 -80.805528)
		(width 0.08382)
		(layer "In2.Cu")
		(net "PWRGD_DSW_PWROK")
	)
	(segment
		(start 48.99152 -100.78212)
		(end 49.7332 -100.78212)
		(width 0.08382)
		(layer "In2.Cu")
		(net "PWRGD_DSW_PWROK")
	)
	(segment
		(start 30.95625 -103.92918)
		(end 30.9626 -103.92283)
		(width 0.08382)
		(layer "In2.Cu")
		(net "PWRGD_DSW_PWROK")
	)
	(segment
		(start 27.68346 -103.92918)
		(end 30.95625 -103.92918)
		(width 0.08382)
		(layer "In2.Cu")
		(net "PWRGD_DSW_PWROK")
	)
	(segment
		(start 32.439864 -103.15321)
		(end 35.13582 -103.15321)
		(width 0.08382)
		(layer "In2.Cu")
		(net "PWRGD_DSW_PWROK")
	)
	(segment
		(start 62.211712 -80.050132)
		(end 62.656974 -79.60487)
		(width 0.08382)
		(layer "In2.Cu")
		(net "PWRGD_DSW_PWROK")
	)
	(segment
		(start 53.431186 -78.62316)
		(end 54.078378 -77.975968)
		(width 0.08382)
		(layer "In2.Cu")
		(net "PWRGD_DSW_PWROK")
	)
	(segment
		(start 51.32578 -86.29142)
		(end 49.7586 -87.8586)
		(width 0.10668)
		(layer "In4.Cu")
		(net "PWRGD_DSW_PWROK")
	)
	(segment
		(start 49.7586 -88.249506)
		(end 50.218594 -88.7095)
		(width 0.10668)
		(layer "In4.Cu")
		(net "PWRGD_DSW_PWROK")
	)
	(segment
		(start 50.41646 -84.30006)
		(end 51.32578 -85.20938)
		(width 0.10668)
		(layer "In4.Cu")
		(net "PWRGD_DSW_PWROK")
	)
	(segment
		(start 50.731166 -79.89951)
		(end 51.19878 -79.89951)
		(width 0.10668)
		(layer "In4.Cu")
		(net "PWRGD_DSW_PWROK")
	)
	(segment
		(start 50.41646 -82.12074)
		(end 50.41646 -84.30006)
		(width 0.10668)
		(layer "In4.Cu")
		(net "PWRGD_DSW_PWROK")
	)
	(segment
		(start 51.32578 -85.20938)
		(end 51.32578 -86.29142)
		(width 0.10668)
		(layer "In4.Cu")
		(net "PWRGD_DSW_PWROK")
	)
	(segment
		(start 51.32578 -81.21142)
		(end 50.41646 -82.12074)
		(width 0.10668)
		(layer "In4.Cu")
		(net "PWRGD_DSW_PWROK")
	)
	(segment
		(start 49.7586 -87.8586)
		(end 49.7586 -88.249506)
		(width 0.10668)
		(layer "In4.Cu")
		(net "PWRGD_DSW_PWROK")
	)
	(segment
		(start 51.19878 -79.89951)
		(end 51.32578 -80.02651)
		(width 0.10668)
		(layer "In4.Cu")
		(net "PWRGD_DSW_PWROK")
	)
	(segment
		(start 51.32578 -80.02651)
		(end 51.32578 -81.21142)
		(width 0.10668)
		(layer "In4.Cu")
		(net "PWRGD_DSW_PWROK")
	)
	(segment
		(start 68.0974 -69.459348)
		(end 67.2338 -68.595748)
		(width 0.08382)
		(layer "In9.Cu")
		(net "PWRGD_DSW_PWROK")
	)
	(segment
		(start 67.32651 -67.58432)
		(end 67.32651 -66.13271)
		(width 0.08382)
		(layer "In9.Cu")
		(net "PWRGD_DSW_PWROK")
	)
	(segment
		(start 50.218594 -88.724994)
		(end 50.218594 -88.7095)
		(width 0.08382)
		(layer "In9.Cu")
		(net "PWRGD_DSW_PWROK")
	)
	(segment
		(start 52.1716 -98.34372)
		(end 52.1716 -90.678)
		(width 0.08382)
		(layer "In9.Cu")
		(net "PWRGD_DSW_PWROK")
	)
	(segment
		(start 49.7332 -100.78212)
		(end 52.1716 -98.34372)
		(width 0.08382)
		(layer "In9.Cu")
		(net "PWRGD_DSW_PWROK")
	)
	(segment
		(start 67.437508 -79.90332)
		(end 68.0974 -78.309978)
		(width 0.08382)
		(layer "In9.Cu")
		(net "PWRGD_DSW_PWROK")
	)
	(segment
		(start 65.931288 -64.737488)
		(end 65.65265 -64.737488)
		(width 0.08382)
		(layer "In9.Cu")
		(net "PWRGD_DSW_PWROK")
	)
	(segment
		(start 68.0974 -78.309978)
		(end 68.0974 -69.459348)
		(width 0.08382)
		(layer "In9.Cu")
		(net "PWRGD_DSW_PWROK")
	)
	(segment
		(start 67.12331 -80.217518)
		(end 67.437508 -79.90332)
		(width 0.08382)
		(layer "In9.Cu")
		(net "PWRGD_DSW_PWROK")
	)
	(segment
		(start 52.1716 -90.678)
		(end 50.218594 -88.724994)
		(width 0.08382)
		(layer "In9.Cu")
		(net "PWRGD_DSW_PWROK")
	)
	(segment
		(start 67.2338 -67.67703)
		(end 67.32651 -67.58432)
		(width 0.08382)
		(layer "In9.Cu")
		(net "PWRGD_DSW_PWROK")
	)
	(segment
		(start 67.32651 -66.13271)
		(end 65.931288 -64.737488)
		(width 0.08382)
		(layer "In9.Cu")
		(net "PWRGD_DSW_PWROK")
	)
	(segment
		(start 67.2338 -68.595748)
		(end 67.2338 -67.67703)
		(width 0.08382)
		(layer "In9.Cu")
		(net "PWRGD_DSW_PWROK")
	)
	(via
		(at 62.33922 -93.29547)
		(size 0.6604)
		(drill 0.3302)
		(layers "F.Cu" "B.Cu")
		(net "LED_POSTCODE_INT")
	)
	(segment
		(start 63.46952 -93.29547)
		(end 62.33922 -93.29547)
		(width 0.11684)
		(layer "B.Cu")
		(net "LED_POSTCODE_INT")
	)
	(segment
		(start 63.5762 -93.40215)
		(end 63.46952 -93.29547)
		(width 0.11684)
		(layer "B.Cu")
		(net "LED_POSTCODE_INT")
	)
	(segment
		(start 62.33922 -93.29547)
		(end 60.55868 -93.29547)
		(width 0.11684)
		(layer "B.Cu")
		(net "LED_POSTCODE_INT")
	)
	(via
		(at 62.3316 -90.3732)
		(size 0.6604)
		(drill 0.3302)
		(layers "F.Cu" "B.Cu")
		(net "LED_POSTCODE_A2")
	)
	(segment
		(start 61.446156 -91.995498)
		(end 60.55868 -91.995498)
		(width 0.11684)
		(layer "B.Cu")
		(net "LED_POSTCODE_A2")
	)
	(segment
		(start 61.6712 -91.3638)
		(end 61.6712 -91.770454)
		(width 0.11684)
		(layer "B.Cu")
		(net "LED_POSTCODE_A2")
	)
	(segment
		(start 62.3316 -90.7034)
		(end 61.6712 -91.3638)
		(width 0.11684)
		(layer "B.Cu")
		(net "LED_POSTCODE_A2")
	)
	(segment
		(start 63.55715 -90.2208)
		(end 63.55715 -89.2048)
		(width 0.11684)
		(layer "B.Cu")
		(net "LED_POSTCODE_A2")
	)
	(segment
		(start 63.40475 -90.3732)
		(end 62.3316 -90.3732)
		(width 0.11684)
		(layer "B.Cu")
		(net "LED_POSTCODE_A2")
	)
	(segment
		(start 61.6712 -91.770454)
		(end 61.446156 -91.995498)
		(width 0.11684)
		(layer "B.Cu")
		(net "LED_POSTCODE_A2")
	)
	(segment
		(start 62.3316 -90.3732)
		(end 62.3316 -90.7034)
		(width 0.11684)
		(layer "B.Cu")
		(net "LED_POSTCODE_A2")
	)
	(segment
		(start 63.55715 -90.2208)
		(end 63.40475 -90.3732)
		(width 0.11684)
		(layer "B.Cu")
		(net "LED_POSTCODE_A2")
	)
	(via
		(at 62.3062 -91.7194)
		(size 0.6604)
		(drill 0.3302)
		(layers "F.Cu" "B.Cu")
		(net "LED_POSTCODE_A1")
	)
	(segment
		(start 63.55715 -92.2274)
		(end 62.8142 -92.2274)
		(width 0.11684)
		(layer "B.Cu")
		(net "LED_POSTCODE_A1")
	)
	(segment
		(start 63.55715 -91.2114)
		(end 63.55715 -92.2274)
		(width 0.11684)
		(layer "B.Cu")
		(net "LED_POSTCODE_A1")
	)
	(segment
		(start 61.913516 -92.645484)
		(end 60.55868 -92.645484)
		(width 0.11684)
		(layer "B.Cu")
		(net "LED_POSTCODE_A1")
	)
	(segment
		(start 62.3062 -92.2528)
		(end 61.913516 -92.645484)
		(width 0.11684)
		(layer "B.Cu")
		(net "LED_POSTCODE_A1")
	)
	(segment
		(start 62.8142 -92.2274)
		(end 62.3062 -91.7194)
		(width 0.11684)
		(layer "B.Cu")
		(net "LED_POSTCODE_A1")
	)
	(segment
		(start 62.3062 -91.7194)
		(end 62.3062 -92.2528)
		(width 0.11684)
		(layer "B.Cu")
		(net "LED_POSTCODE_A1")
	)
	(via
		(at 58.08472 -95.66529)
		(size 0.6604)
		(drill 0.3302)
		(layers "F.Cu" "B.Cu")
		(net "LED_POSTCODE_A0")
	)
	(segment
		(start 54.71668 -91.345512)
		(end 57.360312 -91.345512)
		(width 0.11684)
		(layer "B.Cu")
		(net "LED_POSTCODE_A0")
	)
	(segment
		(start 58.04916 -94.09684)
		(end 57.35701 -94.78899)
		(width 0.11684)
		(layer "B.Cu")
		(net "LED_POSTCODE_A0")
	)
	(segment
		(start 58.04916 -92.03436)
		(end 58.04916 -94.09684)
		(width 0.11684)
		(layer "B.Cu")
		(net "LED_POSTCODE_A0")
	)
	(segment
		(start 56.87568 -95.620586)
		(end 56.87568 -95.66529)
		(width 0.11684)
		(layer "B.Cu")
		(net "LED_POSTCODE_A0")
	)
	(segment
		(start 58.74766 -95.66529)
		(end 59.39155 -95.0214)
		(width 0.11684)
		(layer "B.Cu")
		(net "LED_POSTCODE_A0")
	)
	(segment
		(start 58.08472 -95.66529)
		(end 58.74766 -95.66529)
		(width 0.11684)
		(layer "B.Cu")
		(net "LED_POSTCODE_A0")
	)
	(segment
		(start 57.35701 -95.139256)
		(end 56.87568 -95.620586)
		(width 0.11684)
		(layer "B.Cu")
		(net "LED_POSTCODE_A0")
	)
	(segment
		(start 57.360312 -91.345512)
		(end 58.04916 -92.03436)
		(width 0.11684)
		(layer "B.Cu")
		(net "LED_POSTCODE_A0")
	)
	(segment
		(start 57.35701 -94.78899)
		(end 57.35701 -95.139256)
		(width 0.11684)
		(layer "B.Cu")
		(net "LED_POSTCODE_A0")
	)
	(segment
		(start 58.08472 -95.66529)
		(end 56.87568 -95.66529)
		(width 0.11684)
		(layer "B.Cu")
		(net "LED_POSTCODE_A0")
	)
	(via
		(at 59.309 -87.353394)
		(size 0.508)
		(drill 0.254)
		(layers "F.Cu" "B.Cu")
		(net "LED_POSTCODE_7_R1")
	)
	(via
		(at 74.94905 -30.2514)
		(size 0.508)
		(drill 0.254)
		(layers "F.Cu" "B.Cu")
		(net "LED_POSTCODE_7_R1")
	)
	(via
		(at 75.20305 -30.988)
		(size 0.6604)
		(drill 0.3302)
		(layers "F.Cu" "B.Cu")
		(net "LED_POSTCODE_7_R1")
	)
	(segment
		(start 59.38012 -87.353394)
		(end 59.309 -87.353394)
		(width 0.11684)
		(layer "B.Cu")
		(net "LED_POSTCODE_7_R1")
	)
	(segment
		(start 60.55868 -86.795356)
		(end 59.938158 -86.795356)
		(width 0.11684)
		(layer "B.Cu")
		(net "LED_POSTCODE_7_R1")
	)
	(segment
		(start 59.938158 -86.795356)
		(end 59.38012 -87.353394)
		(width 0.11684)
		(layer "B.Cu")
		(net "LED_POSTCODE_7_R1")
	)
	(segment
		(start 75.20305 -30.988)
		(end 74.94905 -30.734)
		(width 0.254)
		(layer "B.Cu")
		(net "LED_POSTCODE_7_R1")
	)
	(segment
		(start 75.20305 -32.131)
		(end 75.20305 -30.988)
		(width 0.254)
		(layer "B.Cu")
		(net "LED_POSTCODE_7_R1")
	)
	(segment
		(start 74.94905 -30.734)
		(end 74.94905 -30.2514)
		(width 0.254)
		(layer "B.Cu")
		(net "LED_POSTCODE_7_R1")
	)
	(segment
		(start 77.37856 -33.5026)
		(end 78.989936 -35.113976)
		(width 0.08382)
		(layer "In2.Cu")
		(net "LED_POSTCODE_7_R1")
	)
	(segment
		(start 87.00008 -77.76718)
		(end 84.285074 -80.482186)
		(width 0.08382)
		(layer "In2.Cu")
		(net "LED_POSTCODE_7_R1")
	)
	(segment
		(start 79.51978 -87.63508)
		(end 74.116184 -87.63508)
		(width 0.08382)
		(layer "In2.Cu")
		(net "LED_POSTCODE_7_R1")
	)
	(segment
		(start 78.989936 -35.113976)
		(end 81.843626 -35.113976)
		(width 0.08382)
		(layer "In2.Cu")
		(net "LED_POSTCODE_7_R1")
	)
	(segment
		(start 74.116184 -87.63508)
		(end 72.785224 -86.30412)
		(width 0.08382)
		(layer "In2.Cu")
		(net "LED_POSTCODE_7_R1")
	)
	(segment
		(start 86.594442 -36.691062)
		(end 87.00008 -37.0967)
		(width 0.08382)
		(layer "In2.Cu")
		(net "LED_POSTCODE_7_R1")
	)
	(segment
		(start 61.715142 -87.353394)
		(end 59.309 -87.353394)
		(width 0.08382)
		(layer "In2.Cu")
		(net "LED_POSTCODE_7_R1")
	)
	(segment
		(start 84.285074 -80.482186)
		(end 84.285074 -85.308186)
		(width 0.08382)
		(layer "In2.Cu")
		(net "LED_POSTCODE_7_R1")
	)
	(segment
		(start 64.666876 -84.40166)
		(end 61.715142 -87.353394)
		(width 0.08382)
		(layer "In2.Cu")
		(net "LED_POSTCODE_7_R1")
	)
	(segment
		(start 87.00008 -37.0967)
		(end 87.00008 -77.76718)
		(width 0.08382)
		(layer "In2.Cu")
		(net "LED_POSTCODE_7_R1")
	)
	(segment
		(start 75.7936 -31.09595)
		(end 75.7936 -32.970216)
		(width 0.08382)
		(layer "In2.Cu")
		(net "LED_POSTCODE_7_R1")
	)
	(segment
		(start 72.785224 -86.30412)
		(end 69.43852 -86.30412)
		(width 0.08382)
		(layer "In2.Cu")
		(net "LED_POSTCODE_7_R1")
	)
	(segment
		(start 67.53606 -84.40166)
		(end 64.666876 -84.40166)
		(width 0.08382)
		(layer "In2.Cu")
		(net "LED_POSTCODE_7_R1")
	)
	(segment
		(start 76.325984 -33.5026)
		(end 77.37856 -33.5026)
		(width 0.08382)
		(layer "In2.Cu")
		(net "LED_POSTCODE_7_R1")
	)
	(segment
		(start 80.15478 -87.00008)
		(end 79.51978 -87.63508)
		(width 0.08382)
		(layer "In2.Cu")
		(net "LED_POSTCODE_7_R1")
	)
	(segment
		(start 69.43852 -86.30412)
		(end 67.53606 -84.40166)
		(width 0.08382)
		(layer "In2.Cu")
		(net "LED_POSTCODE_7_R1")
	)
	(segment
		(start 75.7936 -32.970216)
		(end 76.325984 -33.5026)
		(width 0.08382)
		(layer "In2.Cu")
		(net "LED_POSTCODE_7_R1")
	)
	(segment
		(start 84.285074 -85.308186)
		(end 82.59318 -87.00008)
		(width 0.08382)
		(layer "In2.Cu")
		(net "LED_POSTCODE_7_R1")
	)
	(segment
		(start 82.59318 -87.00008)
		(end 80.15478 -87.00008)
		(width 0.08382)
		(layer "In2.Cu")
		(net "LED_POSTCODE_7_R1")
	)
	(segment
		(start 83.420712 -36.691062)
		(end 86.594442 -36.691062)
		(width 0.08382)
		(layer "In2.Cu")
		(net "LED_POSTCODE_7_R1")
	)
	(segment
		(start 74.94905 -30.2514)
		(end 75.7936 -31.09595)
		(width 0.08382)
		(layer "In2.Cu")
		(net "LED_POSTCODE_7_R1")
	)
	(segment
		(start 81.843626 -35.113976)
		(end 83.420712 -36.691062)
		(width 0.08382)
		(layer "In2.Cu")
		(net "LED_POSTCODE_7_R1")
	)
	(segment
		(start 72.93737 -31.357824)
		(end 72.46493 -31.357824)
		(width 0.254)
		(layer "F.Cu")
		(net "LED_POSTCODE_7")
	)
	(segment
		(start 44.603162 -48.4632)
		(end 44.895008 -48.171354)
		(width 0.254)
		(layer "F.Cu")
		(net "LED_POSTCODE_7")
	)
	(segment
		(start 73.22312 -32.057848)
		(end 73.22312 -31.643574)
		(width 0.254)
		(layer "F.Cu")
		(net "LED_POSTCODE_7")
	)
	(segment
		(start 73.22312 -31.643574)
		(end 72.93737 -31.357824)
		(width 0.254)
		(layer "F.Cu")
		(net "LED_POSTCODE_7")
	)
	(segment
		(start 43.3832 -49.0474)
		(end 43.3832 -48.7426)
		(width 0.254)
		(layer "F.Cu")
		(net "LED_POSTCODE_7")
	)
	(segment
		(start 43.6626 -48.4632)
		(end 44.603162 -48.4632)
		(width 0.254)
		(layer "F.Cu")
		(net "LED_POSTCODE_7")
	)
	(segment
		(start 43.3832 -48.7426)
		(end 43.6626 -48.4632)
		(width 0.254)
		(layer "F.Cu")
		(net "LED_POSTCODE_7")
	)
	(via
		(at 43.3832 -49.0474)
		(size 0.508)
		(drill 0.254)
		(layers "F.Cu" "B.Cu")
		(net "LED_POSTCODE_7")
	)
	(via
		(at 73.22312 -32.057848)
		(size 0.508)
		(drill 0.254)
		(layers "F.Cu" "B.Cu")
		(net "LED_POSTCODE_7")
	)
	(segment
		(start 73.847198 -32.057848)
		(end 73.22312 -32.057848)
		(width 0.254)
		(layer "B.Cu")
		(net "LED_POSTCODE_7")
	)
	(segment
		(start 74.40295 -32.131)
		(end 73.92035 -32.131)
		(width 0.254)
		(layer "B.Cu")
		(net "LED_POSTCODE_7")
	)
	(segment
		(start 73.92035 -32.131)
		(end 73.847198 -32.057848)
		(width 0.254)
		(layer "B.Cu")
		(net "LED_POSTCODE_7")
	)
	(segment
		(start 61.846714 -40.159686)
		(end 62.557914 -40.159686)
		(width 0.10668)
		(layer "In7.Cu")
		(net "LED_POSTCODE_7")
	)
	(segment
		(start 65.1764 -36.91636)
		(end 65.54216 -36.5506)
		(width 0.10668)
		(layer "In7.Cu")
		(net "LED_POSTCODE_7")
	)
	(segment
		(start 47.866808 -45.782992)
		(end 48.116236 -45.533564)
		(width 0.10668)
		(layer "In7.Cu")
		(net "LED_POSTCODE_7")
	)
	(segment
		(start 52.10556 -42.716196)
		(end 52.251102 -42.570654)
		(width 0.10668)
		(layer "In7.Cu")
		(net "LED_POSTCODE_7")
	)
	(segment
		(start 43.3832 -49.0474)
		(end 43.9674 -47.637192)
		(width 0.10668)
		(layer "In7.Cu")
		(net "LED_POSTCODE_7")
	)
	(segment
		(start 73.22312 -32.49168)
		(end 73.22312 -32.057848)
		(width 0.254)
		(layer "In7.Cu")
		(net "LED_POSTCODE_7")
	)
	(segment
		(start 65.009776 -39.28872)
		(end 65.3034 -38.995096)
		(width 0.10668)
		(layer "In7.Cu")
		(net "LED_POSTCODE_7")
	)
	(segment
		(start 61.675518 -40.733218)
		(end 61.675518 -40.330882)
		(width 0.10668)
		(layer "In7.Cu")
		(net "LED_POSTCODE_7")
	)
	(segment
		(start 60.649104 -41.759632)
		(end 61.675518 -40.733218)
		(width 0.10668)
		(layer "In7.Cu")
		(net "LED_POSTCODE_7")
	)
	(segment
		(start 45.783754 -45.782992)
		(end 47.866808 -45.782992)
		(width 0.10668)
		(layer "In7.Cu")
		(net "LED_POSTCODE_7")
	)
	(segment
		(start 52.10556 -43.192954)
		(end 52.10556 -42.716196)
		(width 0.10668)
		(layer "In7.Cu")
		(net "LED_POSTCODE_7")
	)
	(segment
		(start 48.883316 -44.734988)
		(end 48.883316 -44.563284)
		(width 0.10668)
		(layer "In7.Cu")
		(net "LED_POSTCODE_7")
	)
	(segment
		(start 68.93433 -34.672016)
		(end 68.986146 -34.6202)
		(width 0.254)
		(layer "In7.Cu")
		(net "LED_POSTCODE_7")
	)
	(segment
		(start 48.283876 -44.959524)
		(end 48.65878 -44.959524)
		(width 0.10668)
		(layer "In7.Cu")
		(net "LED_POSTCODE_7")
	)
	(segment
		(start 49.8094 -43.6372)
		(end 51.661314 -43.6372)
		(width 0.10668)
		(layer "In7.Cu")
		(net "LED_POSTCODE_7")
	)
	(segment
		(start 48.65878 -44.959524)
		(end 48.883316 -44.734988)
		(width 0.10668)
		(layer "In7.Cu")
		(net "LED_POSTCODE_7")
	)
	(segment
		(start 61.675518 -40.330882)
		(end 61.846714 -40.159686)
		(width 0.10668)
		(layer "In7.Cu")
		(net "LED_POSTCODE_7")
	)
	(segment
		(start 52.251102 -42.570654)
		(end 59.892946 -42.570654)
		(width 0.10668)
		(layer "In7.Cu")
		(net "LED_POSTCODE_7")
	)
	(segment
		(start 48.883316 -44.563284)
		(end 49.8094 -43.6372)
		(width 0.10668)
		(layer "In7.Cu")
		(net "LED_POSTCODE_7")
	)
	(segment
		(start 65.3034 -38.995096)
		(end 65.3034 -37.6428)
		(width 0.10668)
		(layer "In7.Cu")
		(net "LED_POSTCODE_7")
	)
	(segment
		(start 70.519798 -34.29)
		(end 71.4248 -34.29)
		(width 0.254)
		(layer "In7.Cu")
		(net "LED_POSTCODE_7")
	)
	(segment
		(start 48.116236 -45.533564)
		(end 48.116236 -45.127164)
		(width 0.10668)
		(layer "In7.Cu")
		(net "LED_POSTCODE_7")
	)
	(segment
		(start 71.4248 -34.29)
		(end 73.22312 -32.49168)
		(width 0.254)
		(layer "In7.Cu")
		(net "LED_POSTCODE_7")
	)
	(segment
		(start 45.158152 -46.154848)
		(end 45.411898 -46.154848)
		(width 0.10668)
		(layer "In7.Cu")
		(net "LED_POSTCODE_7")
	)
	(segment
		(start 60.073794 -42.389806)
		(end 60.073794 -41.983406)
		(width 0.10668)
		(layer "In7.Cu")
		(net "LED_POSTCODE_7")
	)
	(segment
		(start 43.9674 -47.3456)
		(end 45.158152 -46.154848)
		(width 0.10668)
		(layer "In7.Cu")
		(net "LED_POSTCODE_7")
	)
	(segment
		(start 68.230242 -34.672016)
		(end 68.93433 -34.672016)
		(width 0.254)
		(layer "In7.Cu")
		(net "LED_POSTCODE_7")
	)
	(segment
		(start 59.892946 -42.570654)
		(end 60.073794 -42.389806)
		(width 0.10668)
		(layer "In7.Cu")
		(net "LED_POSTCODE_7")
	)
	(segment
		(start 67.917822 -34.984436)
		(end 68.230242 -34.672016)
		(width 0.254)
		(layer "In7.Cu")
		(net "LED_POSTCODE_7")
	)
	(segment
		(start 51.661314 -43.6372)
		(end 52.10556 -43.192954)
		(width 0.10668)
		(layer "In7.Cu")
		(net "LED_POSTCODE_7")
	)
	(segment
		(start 63.42888 -39.28872)
		(end 65.009776 -39.28872)
		(width 0.10668)
		(layer "In7.Cu")
		(net "LED_POSTCODE_7")
	)
	(segment
		(start 60.073794 -41.983406)
		(end 60.297568 -41.759632)
		(width 0.10668)
		(layer "In7.Cu")
		(net "LED_POSTCODE_7")
	)
	(segment
		(start 67.055746 -36.5506)
		(end 67.917822 -35.688524)
		(width 0.254)
		(layer "In7.Cu")
		(net "LED_POSTCODE_7")
	)
	(segment
		(start 67.917822 -35.688524)
		(end 67.917822 -34.984436)
		(width 0.254)
		(layer "In7.Cu")
		(net "LED_POSTCODE_7")
	)
	(segment
		(start 65.3034 -37.6428)
		(end 65.1764 -37.5158)
		(width 0.10668)
		(layer "In7.Cu")
		(net "LED_POSTCODE_7")
	)
	(segment
		(start 43.9674 -47.637192)
		(end 43.9674 -47.3456)
		(width 0.10668)
		(layer "In7.Cu")
		(net "LED_POSTCODE_7")
	)
	(segment
		(start 48.116236 -45.127164)
		(end 48.283876 -44.959524)
		(width 0.10668)
		(layer "In7.Cu")
		(net "LED_POSTCODE_7")
	)
	(segment
		(start 65.1764 -37.5158)
		(end 65.1764 -36.91636)
		(width 0.10668)
		(layer "In7.Cu")
		(net "LED_POSTCODE_7")
	)
	(segment
		(start 65.54216 -36.5506)
		(end 67.055746 -36.5506)
		(width 0.254)
		(layer "In7.Cu")
		(net "LED_POSTCODE_7")
	)
	(segment
		(start 60.297568 -41.759632)
		(end 60.649104 -41.759632)
		(width 0.10668)
		(layer "In7.Cu")
		(net "LED_POSTCODE_7")
	)
	(segment
		(start 68.986146 -34.6202)
		(end 70.189598 -34.6202)
		(width 0.254)
		(layer "In7.Cu")
		(net "LED_POSTCODE_7")
	)
	(segment
		(start 45.411898 -46.154848)
		(end 45.783754 -45.782992)
		(width 0.10668)
		(layer "In7.Cu")
		(net "LED_POSTCODE_7")
	)
	(segment
		(start 62.557914 -40.159686)
		(end 63.42888 -39.28872)
		(width 0.10668)
		(layer "In7.Cu")
		(net "LED_POSTCODE_7")
	)
	(segment
		(start 70.189598 -34.6202)
		(end 70.519798 -34.29)
		(width 0.254)
		(layer "In7.Cu")
		(net "LED_POSTCODE_7")
	)
	(via
		(at 76.327 -31.75)
		(size 0.508)
		(drill 0.254)
		(layers "F.Cu" "B.Cu")
		(net "LED_POSTCODE_6_R1")
	)
	(via
		(at 59.309 -88.115394)
		(size 0.508)
		(drill 0.254)
		(layers "F.Cu" "B.Cu")
		(net "LED_POSTCODE_6_R1")
	)
	(segment
		(start 59.979052 -87.445342)
		(end 59.309 -88.115394)
		(width 0.11684)
		(layer "B.Cu")
		(net "LED_POSTCODE_6_R1")
	)
	(segment
		(start 75.7936 -32.2834)
		(end 76.327 -31.75)
		(width 0.254)
		(layer "B.Cu")
		(net "LED_POSTCODE_6_R1")
	)
	(segment
		(start 60.55868 -87.445342)
		(end 59.979052 -87.445342)
		(width 0.11684)
		(layer "B.Cu")
		(net "LED_POSTCODE_6_R1")
	)
	(segment
		(start 75.7936 -32.91205)
		(end 75.7936 -32.2834)
		(width 0.254)
		(layer "B.Cu")
		(net "LED_POSTCODE_6_R1")
	)
	(segment
		(start 75.25385 -33.4518)
		(end 75.7936 -32.91205)
		(width 0.254)
		(layer "B.Cu")
		(net "LED_POSTCODE_6_R1")
	)
	(segment
		(start 82.7913 -87.4776)
		(end 80.3529 -87.4776)
		(width 0.08382)
		(layer "In2.Cu")
		(net "LED_POSTCODE_6_R1")
	)
	(segment
		(start 66.414904 -85.46084)
		(end 66.05524 -85.46084)
		(width 0.08382)
		(layer "In2.Cu")
		(net "LED_POSTCODE_6_R1")
	)
	(segment
		(start 83.827874 -34.636456)
		(end 84.1756 -34.28873)
		(width 0.08382)
		(layer "In2.Cu")
		(net "LED_POSTCODE_6_R1")
	)
	(segment
		(start 72.582024 -86.77656)
		(end 67.730624 -86.77656)
		(width 0.08382)
		(layer "In2.Cu")
		(net "LED_POSTCODE_6_R1")
	)
	(segment
		(start 67.730624 -86.77656)
		(end 66.414904 -85.46084)
		(width 0.08382)
		(layer "In2.Cu")
		(net "LED_POSTCODE_6_R1")
	)
	(segment
		(start 79.7179 -88.1126)
		(end 73.918064 -88.1126)
		(width 0.08382)
		(layer "In2.Cu")
		(net "LED_POSTCODE_6_R1")
	)
	(segment
		(start 87.4776 -35.6616)
		(end 87.4776 -77.9653)
		(width 0.08382)
		(layer "In2.Cu")
		(net "LED_POSTCODE_6_R1")
	)
	(segment
		(start 61.287406 -88.115394)
		(end 59.309 -88.115394)
		(width 0.08382)
		(layer "In2.Cu")
		(net "LED_POSTCODE_6_R1")
	)
	(segment
		(start 64.5414 -84.8614)
		(end 61.287406 -88.115394)
		(width 0.08382)
		(layer "In2.Cu")
		(net "LED_POSTCODE_6_R1")
	)
	(segment
		(start 66.05524 -85.46084)
		(end 65.4558 -84.8614)
		(width 0.08382)
		(layer "In2.Cu")
		(net "LED_POSTCODE_6_R1")
	)
	(segment
		(start 84.757514 -80.685386)
		(end 84.757514 -85.511386)
		(width 0.08382)
		(layer "In2.Cu")
		(net "LED_POSTCODE_6_R1")
	)
	(segment
		(start 84.1756 -34.28873)
		(end 86.10473 -34.28873)
		(width 0.08382)
		(layer "In2.Cu")
		(net "LED_POSTCODE_6_R1")
	)
	(segment
		(start 86.10473 -34.28873)
		(end 87.4776 -35.6616)
		(width 0.08382)
		(layer "In2.Cu")
		(net "LED_POSTCODE_6_R1")
	)
	(segment
		(start 79.213456 -34.636456)
		(end 83.827874 -34.636456)
		(width 0.08382)
		(layer "In2.Cu")
		(net "LED_POSTCODE_6_R1")
	)
	(segment
		(start 76.327 -31.75)
		(end 79.213456 -34.636456)
		(width 0.08382)
		(layer "In2.Cu")
		(net "LED_POSTCODE_6_R1")
	)
	(segment
		(start 87.4776 -77.9653)
		(end 84.757514 -80.685386)
		(width 0.08382)
		(layer "In2.Cu")
		(net "LED_POSTCODE_6_R1")
	)
	(segment
		(start 65.4558 -84.8614)
		(end 64.5414 -84.8614)
		(width 0.08382)
		(layer "In2.Cu")
		(net "LED_POSTCODE_6_R1")
	)
	(segment
		(start 80.3529 -87.4776)
		(end 79.7179 -88.1126)
		(width 0.08382)
		(layer "In2.Cu")
		(net "LED_POSTCODE_6_R1")
	)
	(segment
		(start 73.918064 -88.1126)
		(end 72.582024 -86.77656)
		(width 0.08382)
		(layer "In2.Cu")
		(net "LED_POSTCODE_6_R1")
	)
	(segment
		(start 84.757514 -85.511386)
		(end 82.7913 -87.4776)
		(width 0.08382)
		(layer "In2.Cu")
		(net "LED_POSTCODE_6_R1")
	)
	(segment
		(start 44.895008 -48.9712)
		(end 44.281344 -48.9712)
		(width 0.254)
		(layer "F.Cu")
		(net "LED_POSTCODE_6")
	)
	(segment
		(start 73.7108 -32.893)
		(end 73.227946 -32.893)
		(width 0.254)
		(layer "F.Cu")
		(net "LED_POSTCODE_6")
	)
	(segment
		(start 72.946514 -32.611568)
		(end 72.46493 -32.611568)
		(width 0.254)
		(layer "F.Cu")
		(net "LED_POSTCODE_6")
	)
	(segment
		(start 73.227946 -32.893)
		(end 72.946514 -32.611568)
		(width 0.254)
		(layer "F.Cu")
		(net "LED_POSTCODE_6")
	)
	(via
		(at 44.281344 -48.9712)
		(size 0.4572)
		(drill 0.254)
		(layers "F.Cu" "B.Cu")
		(net "LED_POSTCODE_6")
	)
	(via
		(at 73.7108 -32.893)
		(size 0.508)
		(drill 0.254)
		(layers "F.Cu" "B.Cu")
		(net "LED_POSTCODE_6")
	)
	(segment
		(start 73.9394 -33.4518)
		(end 73.7108 -33.2232)
		(width 0.254)
		(layer "B.Cu")
		(net "LED_POSTCODE_6")
	)
	(segment
		(start 74.45375 -33.4518)
		(end 73.9394 -33.4518)
		(width 0.254)
		(layer "B.Cu")
		(net "LED_POSTCODE_6")
	)
	(segment
		(start 73.7108 -33.2232)
		(end 73.7108 -32.893)
		(width 0.254)
		(layer "B.Cu")
		(net "LED_POSTCODE_6")
	)
	(segment
		(start 66.01714 -38.870636)
		(end 66.01714 -37.694362)
		(width 0.10668)
		(layer "In7.Cu")
		(net "LED_POSTCODE_6")
	)
	(segment
		(start 49.276 -44.729146)
		(end 50.088546 -43.9166)
		(width 0.10668)
		(layer "In7.Cu")
		(net "LED_POSTCODE_6")
	)
	(segment
		(start 66.153284 -37.558218)
		(end 66.40576 -37.305742)
		(width 0.254)
		(layer "In7.Cu")
		(net "LED_POSTCODE_6")
	)
	(segment
		(start 73.4568 -33.958022)
		(end 73.7108 -33.704022)
		(width 0.254)
		(layer "In7.Cu")
		(net "LED_POSTCODE_6")
	)
	(segment
		(start 47.879 -46.5836)
		(end 48.116236 -46.346364)
		(width 0.10668)
		(layer "In7.Cu")
		(net "LED_POSTCODE_6")
	)
	(segment
		(start 49.276 -45.1866)
		(end 49.276 -44.729146)
		(width 0.10668)
		(layer "In7.Cu")
		(net "LED_POSTCODE_6")
	)
	(segment
		(start 48.67021 -45.79239)
		(end 49.276 -45.1866)
		(width 0.10668)
		(layer "In7.Cu")
		(net "LED_POSTCODE_6")
	)
	(segment
		(start 71.933054 -34.6964)
		(end 72.671432 -33.958022)
		(width 0.254)
		(layer "In7.Cu")
		(net "LED_POSTCODE_6")
	)
	(segment
		(start 44.281344 -47.438056)
		(end 45.1358 -46.5836)
		(width 0.10668)
		(layer "In7.Cu")
		(net "LED_POSTCODE_6")
	)
	(segment
		(start 68.488052 -37.305742)
		(end 69.23405 -36.559744)
		(width 0.254)
		(layer "In7.Cu")
		(net "LED_POSTCODE_6")
	)
	(segment
		(start 65.009776 -39.878)
		(end 66.01714 -38.870636)
		(width 0.10668)
		(layer "In7.Cu")
		(net "LED_POSTCODE_6")
	)
	(segment
		(start 66.01714 -37.694362)
		(end 66.153284 -37.558218)
		(width 0.10668)
		(layer "In7.Cu")
		(net "LED_POSTCODE_6")
	)
	(segment
		(start 50.088546 -43.9166)
		(end 52.272438 -43.9166)
		(width 0.10668)
		(layer "In7.Cu")
		(net "LED_POSTCODE_6")
	)
	(segment
		(start 70.6882 -34.6964)
		(end 71.933054 -34.6964)
		(width 0.254)
		(layer "In7.Cu")
		(net "LED_POSTCODE_6")
	)
	(segment
		(start 69.23405 -36.559744)
		(end 69.23405 -36.15055)
		(width 0.254)
		(layer "In7.Cu")
		(net "LED_POSTCODE_6")
	)
	(segment
		(start 48.116236 -46.346364)
		(end 48.116236 -46.016926)
		(width 0.10668)
		(layer "In7.Cu")
		(net "LED_POSTCODE_6")
	)
	(segment
		(start 52.810918 -43.37812)
		(end 55.57012 -43.37812)
		(width 0.10668)
		(layer "In7.Cu")
		(net "LED_POSTCODE_6")
	)
	(segment
		(start 48.340772 -45.79239)
		(end 48.67021 -45.79239)
		(width 0.10668)
		(layer "In7.Cu")
		(net "LED_POSTCODE_6")
	)
	(segment
		(start 52.272438 -43.9166)
		(end 52.810918 -43.37812)
		(width 0.10668)
		(layer "In7.Cu")
		(net "LED_POSTCODE_6")
	)
	(segment
		(start 48.116236 -46.016926)
		(end 48.340772 -45.79239)
		(width 0.10668)
		(layer "In7.Cu")
		(net "LED_POSTCODE_6")
	)
	(segment
		(start 60.4012 -43.6626)
		(end 61.6966 -42.3672)
		(width 0.10668)
		(layer "In7.Cu")
		(net "LED_POSTCODE_6")
	)
	(segment
		(start 55.8546 -43.6626)
		(end 60.4012 -43.6626)
		(width 0.10668)
		(layer "In7.Cu")
		(net "LED_POSTCODE_6")
	)
	(segment
		(start 61.6966 -42.3672)
		(end 61.6966 -42.0116)
		(width 0.10668)
		(layer "In7.Cu")
		(net "LED_POSTCODE_6")
	)
	(segment
		(start 73.7108 -33.704022)
		(end 73.7108 -32.893)
		(width 0.254)
		(layer "In7.Cu")
		(net "LED_POSTCODE_6")
	)
	(segment
		(start 45.1358 -46.5836)
		(end 47.879 -46.5836)
		(width 0.10668)
		(layer "In7.Cu")
		(net "LED_POSTCODE_6")
	)
	(segment
		(start 69.23405 -36.15055)
		(end 70.6882 -34.6964)
		(width 0.254)
		(layer "In7.Cu")
		(net "LED_POSTCODE_6")
	)
	(segment
		(start 72.671432 -33.958022)
		(end 73.4568 -33.958022)
		(width 0.254)
		(layer "In7.Cu")
		(net "LED_POSTCODE_6")
	)
	(segment
		(start 55.57012 -43.37812)
		(end 55.8546 -43.6626)
		(width 0.10668)
		(layer "In7.Cu")
		(net "LED_POSTCODE_6")
	)
	(segment
		(start 63.8302 -39.878)
		(end 65.009776 -39.878)
		(width 0.10668)
		(layer "In7.Cu")
		(net "LED_POSTCODE_6")
	)
	(segment
		(start 44.281344 -48.9712)
		(end 44.281344 -47.438056)
		(width 0.10668)
		(layer "In7.Cu")
		(net "LED_POSTCODE_6")
	)
	(segment
		(start 61.6966 -42.0116)
		(end 63.8302 -39.878)
		(width 0.10668)
		(layer "In7.Cu")
		(net "LED_POSTCODE_6")
	)
	(segment
		(start 66.40576 -37.305742)
		(end 68.488052 -37.305742)
		(width 0.254)
		(layer "In7.Cu")
		(net "LED_POSTCODE_6")
	)
	(via
		(at 76.454 -30.738064)
		(size 0.508)
		(drill 0.254)
		(layers "F.Cu" "B.Cu")
		(net "LED_POSTCODE_5_R1")
	)
	(via
		(at 65.055496 -85.43417)
		(size 0.508)
		(drill 0.254)
		(layers "F.Cu" "B.Cu")
		(net "LED_POSTCODE_5_R1")
	)
	(segment
		(start 76.454 -30.738064)
		(end 77.446886 -30.738064)
		(width 0.254)
		(layer "B.Cu")
		(net "LED_POSTCODE_5_R1")
	)
	(segment
		(start 62.394338 -88.095328)
		(end 60.55868 -88.095328)
		(width 0.11684)
		(layer "B.Cu")
		(net "LED_POSTCODE_5_R1")
	)
	(segment
		(start 77.446886 -30.738064)
		(end 77.47 -30.71495)
		(width 0.254)
		(layer "B.Cu")
		(net "LED_POSTCODE_5_R1")
	)
	(segment
		(start 65.055496 -85.43417)
		(end 62.394338 -88.095328)
		(width 0.11684)
		(layer "B.Cu")
		(net "LED_POSTCODE_5_R1")
	)
	(segment
		(start 72.480424 -87.01278)
		(end 67.63258 -87.01278)
		(width 0.08382)
		(layer "In2.Cu")
		(net "LED_POSTCODE_5_R1")
	)
	(segment
		(start 87.71636 -78.06436)
		(end 84.993734 -80.786986)
		(width 0.08382)
		(layer "In2.Cu")
		(net "LED_POSTCODE_5_R1")
	)
	(segment
		(start 80.87868 -33.719516)
		(end 85.992716 -33.719516)
		(width 0.08382)
		(layer "In2.Cu")
		(net "LED_POSTCODE_5_R1")
	)
	(segment
		(start 73.819004 -88.35136)
		(end 72.480424 -87.01278)
		(width 0.08382)
		(layer "In2.Cu")
		(net "LED_POSTCODE_5_R1")
	)
	(segment
		(start 84.993734 -80.786986)
		(end 84.993734 -85.612986)
		(width 0.08382)
		(layer "In2.Cu")
		(net "LED_POSTCODE_5_R1")
	)
	(segment
		(start 65.666366 -86.04504)
		(end 65.055496 -85.43417)
		(width 0.08382)
		(layer "In2.Cu")
		(net "LED_POSTCODE_5_R1")
	)
	(segment
		(start 84.993734 -85.612986)
		(end 82.89036 -87.71636)
		(width 0.08382)
		(layer "In2.Cu")
		(net "LED_POSTCODE_5_R1")
	)
	(segment
		(start 76.932536 -30.738064)
		(end 77.05598 -30.61462)
		(width 0.08382)
		(layer "In2.Cu")
		(net "LED_POSTCODE_5_R1")
	)
	(segment
		(start 76.454 -30.738064)
		(end 76.932536 -30.738064)
		(width 0.08382)
		(layer "In2.Cu")
		(net "LED_POSTCODE_5_R1")
	)
	(segment
		(start 67.63258 -87.01278)
		(end 66.66484 -86.04504)
		(width 0.08382)
		(layer "In2.Cu")
		(net "LED_POSTCODE_5_R1")
	)
	(segment
		(start 77.05598 -30.61462)
		(end 78.266036 -30.61462)
		(width 0.08382)
		(layer "In2.Cu")
		(net "LED_POSTCODE_5_R1")
	)
	(segment
		(start 87.71636 -35.44316)
		(end 87.71636 -78.06436)
		(width 0.08382)
		(layer "In2.Cu")
		(net "LED_POSTCODE_5_R1")
	)
	(segment
		(start 78.266036 -30.61462)
		(end 78.680564 -31.029148)
		(width 0.08382)
		(layer "In2.Cu")
		(net "LED_POSTCODE_5_R1")
	)
	(segment
		(start 82.89036 -87.71636)
		(end 80.45196 -87.71636)
		(width 0.08382)
		(layer "In2.Cu")
		(net "LED_POSTCODE_5_R1")
	)
	(segment
		(start 80.45196 -87.71636)
		(end 79.81696 -88.35136)
		(width 0.08382)
		(layer "In2.Cu")
		(net "LED_POSTCODE_5_R1")
	)
	(segment
		(start 78.680564 -31.029148)
		(end 78.680564 -31.5214)
		(width 0.08382)
		(layer "In2.Cu")
		(net "LED_POSTCODE_5_R1")
	)
	(segment
		(start 79.81696 -88.35136)
		(end 73.819004 -88.35136)
		(width 0.08382)
		(layer "In2.Cu")
		(net "LED_POSTCODE_5_R1")
	)
	(segment
		(start 85.992716 -33.719516)
		(end 87.71636 -35.44316)
		(width 0.08382)
		(layer "In2.Cu")
		(net "LED_POSTCODE_5_R1")
	)
	(segment
		(start 66.66484 -86.04504)
		(end 65.666366 -86.04504)
		(width 0.08382)
		(layer "In2.Cu")
		(net "LED_POSTCODE_5_R1")
	)
	(segment
		(start 78.680564 -31.5214)
		(end 80.87868 -33.719516)
		(width 0.08382)
		(layer "In2.Cu")
		(net "LED_POSTCODE_5_R1")
	)
	(segment
		(start 47.295054 -48.171354)
		(end 46.89983 -47.77613)
		(width 0.254)
		(layer "F.Cu")
		(net "LED_POSTCODE_5")
	)
	(segment
		(start 78.3844 -30.2006)
		(end 79.172054 -30.2006)
		(width 0.11684)
		(layer "F.Cu")
		(net "LED_POSTCODE_5")
	)
	(segment
		(start 78.0796 -30.5054)
		(end 78.3844 -30.2006)
		(width 0.11684)
		(layer "F.Cu")
		(net "LED_POSTCODE_5")
	)
	(segment
		(start 80.207104 -31.23565)
		(end 80.4418 -31.23565)
		(width 0.11684)
		(layer "F.Cu")
		(net "LED_POSTCODE_5")
	)
	(segment
		(start 78.0796 -31.0642)
		(end 78.0796 -30.5054)
		(width 0.11684)
		(layer "F.Cu")
		(net "LED_POSTCODE_5")
	)
	(segment
		(start 79.172054 -30.2006)
		(end 80.207104 -31.23565)
		(width 0.11684)
		(layer "F.Cu")
		(net "LED_POSTCODE_5")
	)
	(via
		(at 78.0796 -31.0642)
		(size 0.508)
		(drill 0.254)
		(layers "F.Cu" "B.Cu")
		(net "LED_POSTCODE_5")
	)
	(via
		(at 46.89983 -47.77613)
		(size 0.4572)
		(drill 0.254)
		(layers "F.Cu" "B.Cu")
		(net "LED_POSTCODE_5")
	)
	(segment
		(start 77.47 -31.51505)
		(end 77.62875 -31.51505)
		(width 0.254)
		(layer "B.Cu")
		(net "LED_POSTCODE_5")
	)
	(segment
		(start 77.62875 -31.51505)
		(end 78.0796 -31.0642)
		(width 0.254)
		(layer "B.Cu")
		(net "LED_POSTCODE_5")
	)
	(segment
		(start 66.326004 -39.515796)
		(end 64.882014 -40.959786)
		(width 0.10668)
		(layer "In7.Cu")
		(net "LED_POSTCODE_5")
	)
	(segment
		(start 75.61326 -34.20745)
		(end 74.716894 -34.20745)
		(width 0.254)
		(layer "In7.Cu")
		(net "LED_POSTCODE_5")
	)
	(segment
		(start 78.0796 -31.0642)
		(end 78.7654 -31.75)
		(width 0.254)
		(layer "In7.Cu")
		(net "LED_POSTCODE_5")
	)
	(segment
		(start 68.845938 -39.049198)
		(end 68.37934 -39.515796)
		(width 0.254)
		(layer "In7.Cu")
		(net "LED_POSTCODE_5")
	)
	(segment
		(start 74.11339 -34.810954)
		(end 72.971406 -34.810954)
		(width 0.254)
		(layer "In7.Cu")
		(net "LED_POSTCODE_5")
	)
	(segment
		(start 72.22998 -35.55238)
		(end 72.172068 -35.55238)
		(width 0.254)
		(layer "In7.Cu")
		(net "LED_POSTCODE_5")
	)
	(segment
		(start 61.67374 -43.935142)
		(end 61.438282 -44.1706)
		(width 0.10668)
		(layer "In7.Cu")
		(net "LED_POSTCODE_5")
	)
	(segment
		(start 78.7654 -31.75)
		(end 78.7654 -32.9946)
		(width 0.254)
		(layer "In7.Cu")
		(net "LED_POSTCODE_5")
	)
	(segment
		(start 48.33112 -47.37608)
		(end 47.93107 -47.77613)
		(width 0.10668)
		(layer "In7.Cu")
		(net "LED_POSTCODE_5")
	)
	(segment
		(start 72.165972 -35.546284)
		(end 71.094092 -35.546284)
		(width 0.254)
		(layer "In7.Cu")
		(net "LED_POSTCODE_5")
	)
	(segment
		(start 72.172068 -35.55238)
		(end 72.165972 -35.546284)
		(width 0.254)
		(layer "In7.Cu")
		(net "LED_POSTCODE_5")
	)
	(segment
		(start 62.253622 -43.359578)
		(end 61.872622 -43.359578)
		(width 0.10668)
		(layer "In7.Cu")
		(net "LED_POSTCODE_5")
	)
	(segment
		(start 64.882014 -40.959786)
		(end 64.653414 -40.959786)
		(width 0.10668)
		(layer "In7.Cu")
		(net "LED_POSTCODE_5")
	)
	(segment
		(start 74.716894 -34.20745)
		(end 74.11339 -34.810954)
		(width 0.254)
		(layer "In7.Cu")
		(net "LED_POSTCODE_5")
	)
	(segment
		(start 55.417974 -43.9928)
		(end 54.239922 -43.9928)
		(width 0.10668)
		(layer "In7.Cu")
		(net "LED_POSTCODE_5")
	)
	(segment
		(start 55.595774 -44.1706)
		(end 55.417974 -43.9928)
		(width 0.10668)
		(layer "In7.Cu")
		(net "LED_POSTCODE_5")
	)
	(segment
		(start 53.637434 -44.970954)
		(end 51.047396 -44.970954)
		(width 0.10668)
		(layer "In7.Cu")
		(net "LED_POSTCODE_5")
	)
	(segment
		(start 47.93107 -47.77613)
		(end 46.89983 -47.77613)
		(width 0.10668)
		(layer "In7.Cu")
		(net "LED_POSTCODE_5")
	)
	(segment
		(start 78.7654 -32.9946)
		(end 78.212696 -33.547304)
		(width 0.254)
		(layer "In7.Cu")
		(net "LED_POSTCODE_5")
	)
	(segment
		(start 61.67374 -43.55846)
		(end 61.67374 -43.935142)
		(width 0.10668)
		(layer "In7.Cu")
		(net "LED_POSTCODE_5")
	)
	(segment
		(start 64.653414 -40.959786)
		(end 62.253622 -43.359578)
		(width 0.10668)
		(layer "In7.Cu")
		(net "LED_POSTCODE_5")
	)
	(segment
		(start 76.273406 -33.547304)
		(end 75.61326 -34.20745)
		(width 0.254)
		(layer "In7.Cu")
		(net "LED_POSTCODE_5")
	)
	(segment
		(start 68.845938 -38.408102)
		(end 68.845938 -39.049198)
		(width 0.254)
		(layer "In7.Cu")
		(net "LED_POSTCODE_5")
	)
	(segment
		(start 53.828188 -44.7802)
		(end 53.637434 -44.970954)
		(width 0.10668)
		(layer "In7.Cu")
		(net "LED_POSTCODE_5")
	)
	(segment
		(start 70.460108 -36.180268)
		(end 70.460108 -36.793932)
		(width 0.254)
		(layer "In7.Cu")
		(net "LED_POSTCODE_5")
	)
	(segment
		(start 54.239922 -43.9928)
		(end 53.828188 -44.404534)
		(width 0.10668)
		(layer "In7.Cu")
		(net "LED_POSTCODE_5")
	)
	(segment
		(start 68.37934 -39.515796)
		(end 66.326004 -39.515796)
		(width 0.254)
		(layer "In7.Cu")
		(net "LED_POSTCODE_5")
	)
	(segment
		(start 53.828188 -44.404534)
		(end 53.828188 -44.7802)
		(width 0.10668)
		(layer "In7.Cu")
		(net "LED_POSTCODE_5")
	)
	(segment
		(start 78.212696 -33.547304)
		(end 76.273406 -33.547304)
		(width 0.254)
		(layer "In7.Cu")
		(net "LED_POSTCODE_5")
	)
	(segment
		(start 71.094092 -35.546284)
		(end 70.460108 -36.180268)
		(width 0.254)
		(layer "In7.Cu")
		(net "LED_POSTCODE_5")
	)
	(segment
		(start 72.971406 -34.810954)
		(end 72.22998 -35.55238)
		(width 0.254)
		(layer "In7.Cu")
		(net "LED_POSTCODE_5")
	)
	(segment
		(start 61.438282 -44.1706)
		(end 55.595774 -44.1706)
		(width 0.10668)
		(layer "In7.Cu")
		(net "LED_POSTCODE_5")
	)
	(segment
		(start 70.460108 -36.793932)
		(end 68.845938 -38.408102)
		(width 0.254)
		(layer "In7.Cu")
		(net "LED_POSTCODE_5")
	)
	(segment
		(start 48.64227 -47.37608)
		(end 48.33112 -47.37608)
		(width 0.10668)
		(layer "In7.Cu")
		(net "LED_POSTCODE_5")
	)
	(segment
		(start 51.047396 -44.970954)
		(end 48.64227 -47.37608)
		(width 0.10668)
		(layer "In7.Cu")
		(net "LED_POSTCODE_5")
	)
	(segment
		(start 61.872622 -43.359578)
		(end 61.67374 -43.55846)
		(width 0.10668)
		(layer "In7.Cu")
		(net "LED_POSTCODE_5")
	)
	(via
		(at 66.3702 -84.8614)
		(size 0.508)
		(drill 0.254)
		(layers "F.Cu" "B.Cu")
		(net "LED_POSTCODE_4_R1")
	)
	(via
		(at 76.454 -32.9946)
		(size 0.508)
		(drill 0.254)
		(layers "F.Cu" "B.Cu")
		(net "LED_POSTCODE_4_R1")
	)
	(segment
		(start 62.125352 -88.745314)
		(end 60.55868 -88.745314)
		(width 0.11684)
		(layer "B.Cu")
		(net "LED_POSTCODE_4_R1")
	)
	(segment
		(start 64.744346 -86.12632)
		(end 62.125352 -88.745314)
		(width 0.11684)
		(layer "B.Cu")
		(net "LED_POSTCODE_4_R1")
	)
	(segment
		(start 66.3702 -85.384894)
		(end 65.628774 -86.12632)
		(width 0.11684)
		(layer "B.Cu")
		(net "LED_POSTCODE_4_R1")
	)
	(segment
		(start 76.71689 -32.9946)
		(end 76.454 -32.9946)
		(width 0.254)
		(layer "B.Cu")
		(net "LED_POSTCODE_4_R1")
	)
	(segment
		(start 65.628774 -86.12632)
		(end 64.744346 -86.12632)
		(width 0.11684)
		(layer "B.Cu")
		(net "LED_POSTCODE_4_R1")
	)
	(segment
		(start 77.06995 -33.34766)
		(end 76.71689 -32.9946)
		(width 0.254)
		(layer "B.Cu")
		(net "LED_POSTCODE_4_R1")
	)
	(segment
		(start 66.3702 -84.8614)
		(end 66.3702 -85.384894)
		(width 0.11684)
		(layer "B.Cu")
		(net "LED_POSTCODE_4_R1")
	)
	(segment
		(start 68.04914 -86.54034)
		(end 72.683624 -86.54034)
		(width 0.08382)
		(layer "In2.Cu")
		(net "LED_POSTCODE_4_R1")
	)
	(segment
		(start 80.25384 -87.23884)
		(end 82.69224 -87.23884)
		(width 0.08382)
		(layer "In2.Cu")
		(net "LED_POSTCODE_4_R1")
	)
	(segment
		(start 83.787234 -35.785552)
		(end 82.876898 -34.875216)
		(width 0.08382)
		(layer "In2.Cu")
		(net "LED_POSTCODE_4_R1")
	)
	(segment
		(start 66.3702 -84.8614)
		(end 68.04914 -86.54034)
		(width 0.08382)
		(layer "In2.Cu")
		(net "LED_POSTCODE_4_R1")
	)
	(segment
		(start 77.20838 -32.9946)
		(end 76.454 -32.9946)
		(width 0.08382)
		(layer "In2.Cu")
		(net "LED_POSTCODE_4_R1")
	)
	(segment
		(start 86.693502 -36.452302)
		(end 84.050378 -36.452302)
		(width 0.08382)
		(layer "In2.Cu")
		(net "LED_POSTCODE_4_R1")
	)
	(segment
		(start 82.69224 -87.23884)
		(end 84.521294 -85.409786)
		(width 0.08382)
		(layer "In2.Cu")
		(net "LED_POSTCODE_4_R1")
	)
	(segment
		(start 79.088996 -34.875216)
		(end 77.20838 -32.9946)
		(width 0.08382)
		(layer "In2.Cu")
		(net "LED_POSTCODE_4_R1")
	)
	(segment
		(start 87.23884 -36.99764)
		(end 86.693502 -36.452302)
		(width 0.08382)
		(layer "In2.Cu")
		(net "LED_POSTCODE_4_R1")
	)
	(segment
		(start 82.876898 -34.875216)
		(end 79.088996 -34.875216)
		(width 0.08382)
		(layer "In2.Cu")
		(net "LED_POSTCODE_4_R1")
	)
	(segment
		(start 87.23884 -77.86624)
		(end 87.23884 -36.99764)
		(width 0.08382)
		(layer "In2.Cu")
		(net "LED_POSTCODE_4_R1")
	)
	(segment
		(start 83.787234 -36.189158)
		(end 83.787234 -35.785552)
		(width 0.08382)
		(layer "In2.Cu")
		(net "LED_POSTCODE_4_R1")
	)
	(segment
		(start 79.61884 -87.87384)
		(end 80.25384 -87.23884)
		(width 0.08382)
		(layer "In2.Cu")
		(net "LED_POSTCODE_4_R1")
	)
	(segment
		(start 84.050378 -36.452302)
		(end 83.787234 -36.189158)
		(width 0.08382)
		(layer "In2.Cu")
		(net "LED_POSTCODE_4_R1")
	)
	(segment
		(start 74.017124 -87.87384)
		(end 79.61884 -87.87384)
		(width 0.08382)
		(layer "In2.Cu")
		(net "LED_POSTCODE_4_R1")
	)
	(segment
		(start 84.521294 -80.583786)
		(end 87.23884 -77.86624)
		(width 0.08382)
		(layer "In2.Cu")
		(net "LED_POSTCODE_4_R1")
	)
	(segment
		(start 84.521294 -85.409786)
		(end 84.521294 -80.583786)
		(width 0.08382)
		(layer "In2.Cu")
		(net "LED_POSTCODE_4_R1")
	)
	(segment
		(start 72.683624 -86.54034)
		(end 74.017124 -87.87384)
		(width 0.08382)
		(layer "In2.Cu")
		(net "LED_POSTCODE_4_R1")
	)
	(segment
		(start 77.1144 -33.5788)
		(end 77.5208 -33.9852)
		(width 0.254)
		(layer "F.Cu")
		(net "LED_POSTCODE_4")
	)
	(segment
		(start 78.16215 -33.9852)
		(end 78.28915 -34.1122)
		(width 0.254)
		(layer "F.Cu")
		(net "LED_POSTCODE_4")
	)
	(segment
		(start 44.895008 -49.7713)
		(end 44.499784 -50.166524)
		(width 0.254)
		(layer "F.Cu")
		(net "LED_POSTCODE_4")
	)
	(segment
		(start 77.1144 -33.0454)
		(end 77.1144 -33.5788)
		(width 0.254)
		(layer "F.Cu")
		(net "LED_POSTCODE_4")
	)
	(segment
		(start 77.3176 -32.8422)
		(end 77.1144 -33.0454)
		(width 0.254)
		(layer "F.Cu")
		(net "LED_POSTCODE_4")
	)
	(segment
		(start 77.5208 -33.9852)
		(end 78.16215 -33.9852)
		(width 0.254)
		(layer "F.Cu")
		(net "LED_POSTCODE_4")
	)
	(segment
		(start 77.91704 -32.8422)
		(end 77.3176 -32.8422)
		(width 0.254)
		(layer "F.Cu")
		(net "LED_POSTCODE_4")
	)
	(segment
		(start 78.12024 -32.639)
		(end 77.91704 -32.8422)
		(width 0.254)
		(layer "F.Cu")
		(net "LED_POSTCODE_4")
	)
	(via
		(at 44.499784 -50.166524)
		(size 0.4572)
		(drill 0.254)
		(layers "F.Cu" "B.Cu")
		(net "LED_POSTCODE_4")
	)
	(via
		(at 78.12024 -32.639)
		(size 0.508)
		(drill 0.254)
		(layers "F.Cu" "B.Cu")
		(net "LED_POSTCODE_4")
	)
	(via
		(at 77.1144 -33.5788)
		(size 0.762)
		(drill 0.381)
		(layers "F.Cu" "B.Cu")
		(net "LED_POSTCODE_4")
	)
	(segment
		(start 77.87005 -32.89935)
		(end 77.87005 -33.34766)
		(width 0.254)
		(layer "B.Cu")
		(net "LED_POSTCODE_4")
	)
	(segment
		(start 78.12024 -32.64916)
		(end 77.87005 -32.89935)
		(width 0.254)
		(layer "B.Cu")
		(net "LED_POSTCODE_4")
	)
	(segment
		(start 78.12024 -32.639)
		(end 78.12024 -32.64916)
		(width 0.254)
		(layer "B.Cu")
		(net "LED_POSTCODE_4")
	)
	(segment
		(start 48.65878 -46.55947)
		(end 48.33493 -46.55947)
		(width 0.10668)
		(layer "In7.Cu")
		(net "LED_POSTCODE_4")
	)
	(segment
		(start 44.499784 -49.295304)
		(end 44.499784 -50.166524)
		(width 0.10668)
		(layer "In7.Cu")
		(net "LED_POSTCODE_4")
	)
	(segment
		(start 48.33493 -46.55947)
		(end 48.1076 -46.7868)
		(width 0.10668)
		(layer "In7.Cu")
		(net "LED_POSTCODE_4")
	)
	(segment
		(start 62.731142 -41.792398)
		(end 60.58154 -43.942)
		(width 0.10668)
		(layer "In7.Cu")
		(net "LED_POSTCODE_4")
	)
	(segment
		(start 64.9224 -40.1828)
		(end 63.312802 -41.792398)
		(width 0.10668)
		(layer "In7.Cu")
		(net "LED_POSTCODE_4")
	)
	(segment
		(start 75.80503 -32.4358)
		(end 73.836276 -34.404554)
		(width 0.254)
		(layer "In7.Cu")
		(net "LED_POSTCODE_4")
	)
	(segment
		(start 69.943218 -36.072572)
		(end 69.943218 -36.69665)
		(width 0.254)
		(layer "In7.Cu")
		(net "LED_POSTCODE_4")
	)
	(segment
		(start 73.836276 -34.404554)
		(end 72.803004 -34.404554)
		(width 0.254)
		(layer "In7.Cu")
		(net "LED_POSTCODE_4")
	)
	(segment
		(start 70.91299 -35.1028)
		(end 69.943218 -36.072572)
		(width 0.254)
		(layer "In7.Cu")
		(net "LED_POSTCODE_4")
	)
	(segment
		(start 49.5554 -45.66285)
		(end 48.65878 -46.55947)
		(width 0.10668)
		(layer "In7.Cu")
		(net "LED_POSTCODE_4")
	)
	(segment
		(start 50.258726 -44.959524)
		(end 49.833022 -44.959524)
		(width 0.10668)
		(layer "In7.Cu")
		(net "LED_POSTCODE_4")
	)
	(segment
		(start 60.58154 -43.942)
		(end 55.7022 -43.942)
		(width 0.10668)
		(layer "In7.Cu")
		(net "LED_POSTCODE_4")
	)
	(segment
		(start 69.943218 -36.69665)
		(end 68.89877 -37.741098)
		(width 0.254)
		(layer "In7.Cu")
		(net "LED_POSTCODE_4")
	)
	(segment
		(start 77.5462 -32.639)
		(end 77.343 -32.4358)
		(width 0.254)
		(layer "In7.Cu")
		(net "LED_POSTCODE_4")
	)
	(segment
		(start 53.272182 -43.7388)
		(end 52.818538 -44.192444)
		(width 0.10668)
		(layer "In7.Cu")
		(net "LED_POSTCODE_4")
	)
	(segment
		(start 66.602356 -37.741098)
		(end 66.34988 -37.993574)
		(width 0.254)
		(layer "In7.Cu")
		(net "LED_POSTCODE_4")
	)
	(segment
		(start 44.664884 -49.130204)
		(end 44.499784 -49.295304)
		(width 0.10668)
		(layer "In7.Cu")
		(net "LED_POSTCODE_4")
	)
	(segment
		(start 47.904146 -47.371)
		(end 45.1358 -47.371)
		(width 0.10668)
		(layer "In7.Cu")
		(net "LED_POSTCODE_4")
	)
	(segment
		(start 66.34988 -38.93312)
		(end 65.1002 -40.1828)
		(width 0.10668)
		(layer "In7.Cu")
		(net "LED_POSTCODE_4")
	)
	(segment
		(start 63.312802 -41.792398)
		(end 62.731142 -41.792398)
		(width 0.10668)
		(layer "In7.Cu")
		(net "LED_POSTCODE_4")
	)
	(segment
		(start 49.5554 -45.237146)
		(end 49.5554 -45.66285)
		(width 0.10668)
		(layer "In7.Cu")
		(net "LED_POSTCODE_4")
	)
	(segment
		(start 45.1358 -47.371)
		(end 44.664884 -47.841916)
		(width 0.10668)
		(layer "In7.Cu")
		(net "LED_POSTCODE_4")
	)
	(segment
		(start 48.1076 -47.167546)
		(end 47.904146 -47.371)
		(width 0.10668)
		(layer "In7.Cu")
		(net "LED_POSTCODE_4")
	)
	(segment
		(start 44.664884 -47.841916)
		(end 44.664884 -49.130204)
		(width 0.10668)
		(layer "In7.Cu")
		(net "LED_POSTCODE_4")
	)
	(segment
		(start 72.104758 -35.1028)
		(end 70.91299 -35.1028)
		(width 0.254)
		(layer "In7.Cu")
		(net "LED_POSTCODE_4")
	)
	(segment
		(start 68.89877 -37.741098)
		(end 66.602356 -37.741098)
		(width 0.254)
		(layer "In7.Cu")
		(net "LED_POSTCODE_4")
	)
	(segment
		(start 77.343 -32.4358)
		(end 75.80503 -32.4358)
		(width 0.254)
		(layer "In7.Cu")
		(net "LED_POSTCODE_4")
	)
	(segment
		(start 52.818538 -44.192444)
		(end 50.600102 -44.192444)
		(width 0.10668)
		(layer "In7.Cu")
		(net "LED_POSTCODE_4")
	)
	(segment
		(start 55.7022 -43.942)
		(end 55.499 -43.7388)
		(width 0.10668)
		(layer "In7.Cu")
		(net "LED_POSTCODE_4")
	)
	(segment
		(start 66.34988 -37.993574)
		(end 66.34988 -38.93312)
		(width 0.10668)
		(layer "In7.Cu")
		(net "LED_POSTCODE_4")
	)
	(segment
		(start 72.803004 -34.404554)
		(end 72.104758 -35.1028)
		(width 0.254)
		(layer "In7.Cu")
		(net "LED_POSTCODE_4")
	)
	(segment
		(start 50.600102 -44.192444)
		(end 50.483262 -44.309284)
		(width 0.10668)
		(layer "In7.Cu")
		(net "LED_POSTCODE_4")
	)
	(segment
		(start 49.833022 -44.959524)
		(end 49.5554 -45.237146)
		(width 0.10668)
		(layer "In7.Cu")
		(net "LED_POSTCODE_4")
	)
	(segment
		(start 65.1002 -40.1828)
		(end 64.9224 -40.1828)
		(width 0.10668)
		(layer "In7.Cu")
		(net "LED_POSTCODE_4")
	)
	(segment
		(start 50.483262 -44.309284)
		(end 50.483262 -44.734988)
		(width 0.10668)
		(layer "In7.Cu")
		(net "LED_POSTCODE_4")
	)
	(segment
		(start 50.483262 -44.734988)
		(end 50.258726 -44.959524)
		(width 0.10668)
		(layer "In7.Cu")
		(net "LED_POSTCODE_4")
	)
	(segment
		(start 78.12024 -32.639)
		(end 77.5462 -32.639)
		(width 0.254)
		(layer "In7.Cu")
		(net "LED_POSTCODE_4")
	)
	(segment
		(start 55.499 -43.7388)
		(end 53.272182 -43.7388)
		(width 0.10668)
		(layer "In7.Cu")
		(net "LED_POSTCODE_4")
	)
	(segment
		(start 48.1076 -46.7868)
		(end 48.1076 -47.167546)
		(width 0.10668)
		(layer "In7.Cu")
		(net "LED_POSTCODE_4")
	)
	(via
		(at 75.83805 -25.8826)
		(size 0.762)
		(drill 0.254)
		(layers "F.Cu" "B.Cu")
		(net "LED_POSTCODE_3_R1")
	)
	(via
		(at 59.3852 -89.9922)
		(size 0.508)
		(drill 0.254)
		(layers "F.Cu" "B.Cu")
		(net "LED_POSTCODE_3_R1")
	)
	(segment
		(start 75.83805 -24.7904)
		(end 75.83805 -25.8826)
		(width 0.254)
		(layer "B.Cu")
		(net "LED_POSTCODE_3_R1")
	)
	(segment
		(start 59.3852 -89.535)
		(end 59.3852 -89.9922)
		(width 0.11684)
		(layer "B.Cu")
		(net "LED_POSTCODE_3_R1")
	)
	(segment
		(start 60.55868 -89.3953)
		(end 59.5249 -89.3953)
		(width 0.11684)
		(layer "B.Cu")
		(net "LED_POSTCODE_3_R1")
	)
	(segment
		(start 59.5249 -89.3953)
		(end 59.3852 -89.535)
		(width 0.11684)
		(layer "B.Cu")
		(net "LED_POSTCODE_3_R1")
	)
	(segment
		(start 85.60054 -31.40456)
		(end 88.43264 -34.23666)
		(width 0.08382)
		(layer "In2.Cu")
		(net "LED_POSTCODE_3_R1")
	)
	(segment
		(start 80.82534 -88.43264)
		(end 80.1243 -89.13368)
		(width 0.08382)
		(layer "In2.Cu")
		(net "LED_POSTCODE_3_R1")
	)
	(segment
		(start 76.708 -25.8826)
		(end 79.4512 -28.6258)
		(width 0.08382)
		(layer "In2.Cu")
		(net "LED_POSTCODE_3_R1")
	)
	(segment
		(start 66.0146 -89.9922)
		(end 59.3852 -89.9922)
		(width 0.08382)
		(layer "In2.Cu")
		(net "LED_POSTCODE_3_R1")
	)
	(segment
		(start 80.1243 -89.13368)
		(end 76.90358 -89.13368)
		(width 0.08382)
		(layer "In2.Cu")
		(net "LED_POSTCODE_3_R1")
	)
	(segment
		(start 75.83805 -25.8826)
		(end 76.708 -25.8826)
		(width 0.08382)
		(layer "In2.Cu")
		(net "LED_POSTCODE_3_R1")
	)
	(segment
		(start 88.43264 -34.23666)
		(end 88.43264 -78.36154)
		(width 0.08382)
		(layer "In2.Cu")
		(net "LED_POSTCODE_3_R1")
	)
	(segment
		(start 75.02652 -91.01074)
		(end 72.45858 -91.01074)
		(width 0.08382)
		(layer "In2.Cu")
		(net "LED_POSTCODE_3_R1")
	)
	(segment
		(start 83.18754 -88.43264)
		(end 80.82534 -88.43264)
		(width 0.08382)
		(layer "In2.Cu")
		(net "LED_POSTCODE_3_R1")
	)
	(segment
		(start 81.232756 -31.848298)
		(end 82.865722 -31.848298)
		(width 0.08382)
		(layer "In2.Cu")
		(net "LED_POSTCODE_3_R1")
	)
	(segment
		(start 66.447162 -90.424762)
		(end 66.0146 -89.9922)
		(width 0.08382)
		(layer "In2.Cu")
		(net "LED_POSTCODE_3_R1")
	)
	(segment
		(start 79.4512 -30.066742)
		(end 81.232756 -31.848298)
		(width 0.08382)
		(layer "In2.Cu")
		(net "LED_POSTCODE_3_R1")
	)
	(segment
		(start 72.45858 -91.01074)
		(end 71.83628 -91.63304)
		(width 0.08382)
		(layer "In2.Cu")
		(net "LED_POSTCODE_3_R1")
	)
	(segment
		(start 76.90358 -89.13368)
		(end 75.02652 -91.01074)
		(width 0.08382)
		(layer "In2.Cu")
		(net "LED_POSTCODE_3_R1")
	)
	(segment
		(start 71.83628 -91.63304)
		(end 70.0151 -91.63304)
		(width 0.08382)
		(layer "In2.Cu")
		(net "LED_POSTCODE_3_R1")
	)
	(segment
		(start 83.30946 -31.40456)
		(end 85.60054 -31.40456)
		(width 0.08382)
		(layer "In2.Cu")
		(net "LED_POSTCODE_3_R1")
	)
	(segment
		(start 82.865722 -31.848298)
		(end 83.30946 -31.40456)
		(width 0.08382)
		(layer "In2.Cu")
		(net "LED_POSTCODE_3_R1")
	)
	(segment
		(start 88.43264 -78.36154)
		(end 85.702394 -81.091786)
		(width 0.08382)
		(layer "In2.Cu")
		(net "LED_POSTCODE_3_R1")
	)
	(segment
		(start 85.702394 -85.917786)
		(end 83.18754 -88.43264)
		(width 0.08382)
		(layer "In2.Cu")
		(net "LED_POSTCODE_3_R1")
	)
	(segment
		(start 85.702394 -81.091786)
		(end 85.702394 -85.917786)
		(width 0.08382)
		(layer "In2.Cu")
		(net "LED_POSTCODE_3_R1")
	)
	(segment
		(start 68.806822 -90.424762)
		(end 66.447162 -90.424762)
		(width 0.08382)
		(layer "In2.Cu")
		(net "LED_POSTCODE_3_R1")
	)
	(segment
		(start 79.4512 -28.6258)
		(end 79.4512 -30.066742)
		(width 0.08382)
		(layer "In2.Cu")
		(net "LED_POSTCODE_3_R1")
	)
	(segment
		(start 70.0151 -91.63304)
		(end 68.806822 -90.424762)
		(width 0.08382)
		(layer "In2.Cu")
		(net "LED_POSTCODE_3_R1")
	)
	(segment
		(start 74.8284 -26.8732)
		(end 75.1586 -26.543)
		(width 0.254)
		(layer "F.Cu")
		(net "LED_POSTCODE_3")
	)
	(segment
		(start 74.8284 -27.1526)
		(end 74.8284 -26.8732)
		(width 0.254)
		(layer "F.Cu")
		(net "LED_POSTCODE_3")
	)
	(segment
		(start 74.752454 -25.5016)
		(end 74.18705 -25.5016)
		(width 0.254)
		(layer "F.Cu")
		(net "LED_POSTCODE_3")
	)
	(segment
		(start 75.1586 -26.543)
		(end 75.1586 -25.907746)
		(width 0.254)
		(layer "F.Cu")
		(net "LED_POSTCODE_3")
	)
	(segment
		(start 75.1586 -25.907746)
		(end 74.752454 -25.5016)
		(width 0.254)
		(layer "F.Cu")
		(net "LED_POSTCODE_3")
	)
	(segment
		(start 46.494954 -48.9712)
		(end 46.09973 -48.575976)
		(width 0.254)
		(layer "F.Cu")
		(net "LED_POSTCODE_3")
	)
	(via
		(at 74.8284 -27.1526)
		(size 0.508)
		(drill 0.254)
		(layers "F.Cu" "B.Cu")
		(net "LED_POSTCODE_3")
	)
	(via
		(at 46.09973 -48.575976)
		(size 0.4572)
		(drill 0.254)
		(layers "F.Cu" "B.Cu")
		(net "LED_POSTCODE_3")
	)
	(via
		(at 73.87336 -24.4729)
		(size 0.6604)
		(drill 0.3302)
		(layers "F.Cu" "B.Cu")
		(net "LED_POSTCODE_3")
	)
	(segment
		(start 73.87336 -24.4729)
		(end 74.72045 -24.4729)
		(width 0.254)
		(layer "B.Cu")
		(net "LED_POSTCODE_3")
	)
	(segment
		(start 74.8284 -25.42794)
		(end 73.87336 -24.4729)
		(width 0.254)
		(layer "B.Cu")
		(net "LED_POSTCODE_3")
	)
	(segment
		(start 74.72045 -24.4729)
		(end 75.03795 -24.7904)
		(width 0.254)
		(layer "B.Cu")
		(net "LED_POSTCODE_3")
	)
	(segment
		(start 74.8284 -27.1526)
		(end 74.8284 -25.42794)
		(width 0.254)
		(layer "B.Cu")
		(net "LED_POSTCODE_3")
	)
	(segment
		(start 63.516002 -43.392598)
		(end 63.81623 -43.392598)
		(width 0.10668)
		(layer "In7.Cu")
		(net "LED_POSTCODE_3")
	)
	(segment
		(start 61.364622 -45.874178)
		(end 61.67374 -45.56506)
		(width 0.10668)
		(layer "In7.Cu")
		(net "LED_POSTCODE_3")
	)
	(segment
		(start 63.81623 -43.392598)
		(end 64.073786 -43.135042)
		(width 0.10668)
		(layer "In7.Cu")
		(net "LED_POSTCODE_3")
	)
	(segment
		(start 59.289696 -45.189902)
		(end 59.289696 -45.655992)
		(width 0.10668)
		(layer "In7.Cu")
		(net "LED_POSTCODE_3")
	)
	(segment
		(start 56.091582 -45.183298)
		(end 56.29402 -44.98086)
		(width 0.10668)
		(layer "In7.Cu")
		(net "LED_POSTCODE_3")
	)
	(segment
		(start 52.674012 -47.0154)
		(end 53.1114 -46.578012)
		(width 0.10668)
		(layer "In7.Cu")
		(net "LED_POSTCODE_3")
	)
	(segment
		(start 73.64603 -36.566094)
		(end 73.64603 -35.998658)
		(width 0.254)
		(layer "In7.Cu")
		(net "LED_POSTCODE_3")
	)
	(segment
		(start 49.237646 -49.203102)
		(end 49.447958 -48.99279)
		(width 0.10668)
		(layer "In7.Cu")
		(net "LED_POSTCODE_3")
	)
	(segment
		(start 80.772 -31.757366)
		(end 77.945234 -28.9306)
		(width 0.254)
		(layer "In7.Cu")
		(net "LED_POSTCODE_3")
	)
	(segment
		(start 70.878954 -37.811202)
		(end 72.400922 -37.811202)
		(width 0.254)
		(layer "In7.Cu")
		(net "LED_POSTCODE_3")
	)
	(segment
		(start 77.945234 -28.9306)
		(end 74.600054 -28.9306)
		(width 0.254)
		(layer "In7.Cu")
		(net "LED_POSTCODE_3")
	)
	(segment
		(start 61.6712 -45.212)
		(end 61.8998 -44.9834)
		(width 0.10668)
		(layer "In7.Cu")
		(net "LED_POSTCODE_3")
	)
	(segment
		(start 62.3316 -44.9834)
		(end 62.484 -44.831)
		(width 0.10668)
		(layer "In7.Cu")
		(net "LED_POSTCODE_3")
	)
	(segment
		(start 74.2442 -27.4066)
		(end 74.4982 -27.1526)
		(width 0.254)
		(layer "In7.Cu")
		(net "LED_POSTCODE_3")
	)
	(segment
		(start 61.6712 -45.21454)
		(end 61.6712 -45.212)
		(width 0.10668)
		(layer "In7.Cu")
		(net "LED_POSTCODE_3")
	)
	(segment
		(start 65.54978 -41.563036)
		(end 66.054732 -41.058084)
		(width 0.10668)
		(layer "In7.Cu")
		(net "LED_POSTCODE_3")
	)
	(segment
		(start 50.503328 -48.402494)
		(end 51.890422 -47.0154)
		(width 0.10668)
		(layer "In7.Cu")
		(net "LED_POSTCODE_3")
	)
	(segment
		(start 65.179956 -42.312844)
		(end 65.179956 -41.71061)
		(width 0.10668)
		(layer "In7.Cu")
		(net "LED_POSTCODE_3")
	)
	(segment
		(start 56.29402 -44.98086)
		(end 59.080654 -44.98086)
		(width 0.10668)
		(layer "In7.Cu")
		(net "LED_POSTCODE_3")
	)
	(segment
		(start 63.119 -44.1706)
		(end 63.2968 -43.9928)
		(width 0.10668)
		(layer "In7.Cu")
		(net "LED_POSTCODE_3")
	)
	(segment
		(start 50.503328 -48.808894)
		(end 50.503328 -48.402494)
		(width 0.10668)
		(layer "In7.Cu")
		(net "LED_POSTCODE_3")
	)
	(segment
		(start 73.64603 -35.998658)
		(end 73.984612 -35.660076)
		(width 0.254)
		(layer "In7.Cu")
		(net "LED_POSTCODE_3")
	)
	(segment
		(start 61.67374 -45.56506)
		(end 61.67374 -45.21708)
		(width 0.10668)
		(layer "In7.Cu")
		(net "LED_POSTCODE_3")
	)
	(segment
		(start 50.319432 -48.99279)
		(end 50.503328 -48.808894)
		(width 0.10668)
		(layer "In7.Cu")
		(net "LED_POSTCODE_3")
	)
	(segment
		(start 66.7512 -40.361616)
		(end 69.043042 -40.361616)
		(width 0.254)
		(layer "In7.Cu")
		(net "LED_POSTCODE_3")
	)
	(segment
		(start 59.289696 -45.655992)
		(end 59.507882 -45.874178)
		(width 0.10668)
		(layer "In7.Cu")
		(net "LED_POSTCODE_3")
	)
	(segment
		(start 77.818234 -35.1536)
		(end 80.772 -32.199834)
		(width 0.254)
		(layer "In7.Cu")
		(net "LED_POSTCODE_3")
	)
	(segment
		(start 62.738 -44.1706)
		(end 63.119 -44.1706)
		(width 0.10668)
		(layer "In7.Cu")
		(net "LED_POSTCODE_3")
	)
	(segment
		(start 46.726856 -49.203102)
		(end 49.237646 -49.203102)
		(width 0.10668)
		(layer "In7.Cu")
		(net "LED_POSTCODE_3")
	)
	(segment
		(start 64.073786 -42.809414)
		(end 64.307212 -42.575988)
		(width 0.10668)
		(layer "In7.Cu")
		(net "LED_POSTCODE_3")
	)
	(segment
		(start 62.484 -44.4246)
		(end 62.738 -44.1706)
		(width 0.10668)
		(layer "In7.Cu")
		(net "LED_POSTCODE_3")
	)
	(segment
		(start 64.307212 -42.575988)
		(end 64.916812 -42.575988)
		(width 0.10668)
		(layer "In7.Cu")
		(net "LED_POSTCODE_3")
	)
	(segment
		(start 53.1114 -46.578012)
		(end 54.40172 -46.578012)
		(width 0.10668)
		(layer "In7.Cu")
		(net "LED_POSTCODE_3")
	)
	(segment
		(start 74.600054 -28.9306)
		(end 74.2442 -28.574746)
		(width 0.254)
		(layer "In7.Cu")
		(net "LED_POSTCODE_3")
	)
	(segment
		(start 63.2968 -43.6118)
		(end 63.516002 -43.392598)
		(width 0.10668)
		(layer "In7.Cu")
		(net "LED_POSTCODE_3")
	)
	(segment
		(start 64.916812 -42.575988)
		(end 65.179956 -42.312844)
		(width 0.10668)
		(layer "In7.Cu")
		(net "LED_POSTCODE_3")
	)
	(segment
		(start 63.2968 -43.9928)
		(end 63.2968 -43.6118)
		(width 0.10668)
		(layer "In7.Cu")
		(net "LED_POSTCODE_3")
	)
	(segment
		(start 49.447958 -48.99279)
		(end 50.319432 -48.99279)
		(width 0.10668)
		(layer "In7.Cu")
		(net "LED_POSTCODE_3")
	)
	(segment
		(start 59.080654 -44.98086)
		(end 59.289696 -45.189902)
		(width 0.10668)
		(layer "In7.Cu")
		(net "LED_POSTCODE_3")
	)
	(segment
		(start 55.814722 -45.900848)
		(end 56.091582 -45.623988)
		(width 0.10668)
		(layer "In7.Cu")
		(net "LED_POSTCODE_3")
	)
	(segment
		(start 65.32753 -41.563036)
		(end 65.54978 -41.563036)
		(width 0.10668)
		(layer "In7.Cu")
		(net "LED_POSTCODE_3")
	)
	(segment
		(start 59.507882 -45.874178)
		(end 61.364622 -45.874178)
		(width 0.10668)
		(layer "In7.Cu")
		(net "LED_POSTCODE_3")
	)
	(segment
		(start 51.890422 -47.0154)
		(end 52.674012 -47.0154)
		(width 0.10668)
		(layer "In7.Cu")
		(net "LED_POSTCODE_3")
	)
	(segment
		(start 73.984612 -35.660076)
		(end 74.727054 -35.660076)
		(width 0.254)
		(layer "In7.Cu")
		(net "LED_POSTCODE_3")
	)
	(segment
		(start 74.727054 -35.660076)
		(end 75.23353 -35.1536)
		(width 0.254)
		(layer "In7.Cu")
		(net "LED_POSTCODE_3")
	)
	(segment
		(start 74.2442 -28.574746)
		(end 74.2442 -27.4066)
		(width 0.254)
		(layer "In7.Cu")
		(net "LED_POSTCODE_3")
	)
	(segment
		(start 74.4982 -27.1526)
		(end 74.8284 -27.1526)
		(width 0.254)
		(layer "In7.Cu")
		(net "LED_POSTCODE_3")
	)
	(segment
		(start 66.054732 -41.058084)
		(end 66.7512 -40.361616)
		(width 0.254)
		(layer "In7.Cu")
		(net "LED_POSTCODE_3")
	)
	(segment
		(start 61.67374 -45.21708)
		(end 61.6712 -45.21454)
		(width 0.10668)
		(layer "In7.Cu")
		(net "LED_POSTCODE_3")
	)
	(segment
		(start 46.09973 -48.575976)
		(end 46.726856 -49.203102)
		(width 0.10668)
		(layer "In7.Cu")
		(net "LED_POSTCODE_3")
	)
	(segment
		(start 55.078884 -45.900848)
		(end 55.814722 -45.900848)
		(width 0.10668)
		(layer "In7.Cu")
		(net "LED_POSTCODE_3")
	)
	(segment
		(start 75.23353 -35.1536)
		(end 77.818234 -35.1536)
		(width 0.254)
		(layer "In7.Cu")
		(net "LED_POSTCODE_3")
	)
	(segment
		(start 70.053454 -38.636702)
		(end 70.878954 -37.811202)
		(width 0.254)
		(layer "In7.Cu")
		(net "LED_POSTCODE_3")
	)
	(segment
		(start 80.772 -32.199834)
		(end 80.772 -31.757366)
		(width 0.254)
		(layer "In7.Cu")
		(net "LED_POSTCODE_3")
	)
	(segment
		(start 62.484 -44.831)
		(end 62.484 -44.4246)
		(width 0.10668)
		(layer "In7.Cu")
		(net "LED_POSTCODE_3")
	)
	(segment
		(start 61.8998 -44.9834)
		(end 62.3316 -44.9834)
		(width 0.10668)
		(layer "In7.Cu")
		(net "LED_POSTCODE_3")
	)
	(segment
		(start 72.400922 -37.811202)
		(end 73.64603 -36.566094)
		(width 0.254)
		(layer "In7.Cu")
		(net "LED_POSTCODE_3")
	)
	(segment
		(start 64.073786 -43.135042)
		(end 64.073786 -42.809414)
		(width 0.10668)
		(layer "In7.Cu")
		(net "LED_POSTCODE_3")
	)
	(segment
		(start 54.40172 -46.578012)
		(end 55.078884 -45.900848)
		(width 0.10668)
		(layer "In7.Cu")
		(net "LED_POSTCODE_3")
	)
	(segment
		(start 56.091582 -45.623988)
		(end 56.091582 -45.183298)
		(width 0.10668)
		(layer "In7.Cu")
		(net "LED_POSTCODE_3")
	)
	(segment
		(start 70.053454 -39.351204)
		(end 70.053454 -38.636702)
		(width 0.254)
		(layer "In7.Cu")
		(net "LED_POSTCODE_3")
	)
	(segment
		(start 65.179956 -41.71061)
		(end 65.32753 -41.563036)
		(width 0.10668)
		(layer "In7.Cu")
		(net "LED_POSTCODE_3")
	)
	(segment
		(start 69.043042 -40.361616)
		(end 70.053454 -39.351204)
		(width 0.254)
		(layer "In7.Cu")
		(net "LED_POSTCODE_3")
	)
	(via
		(at 65.10528 -86.73846)
		(size 0.6604)
		(drill 0.3302)
		(layers "F.Cu" "B.Cu")
		(net "LED_POSTCODE_2_R1")
	)
	(via
		(at 75.93965 -30.2006)
		(size 0.508)
		(drill 0.254)
		(layers "F.Cu" "B.Cu")
		(net "LED_POSTCODE_2_R1")
	)
	(via
		(at 65.89268 -86.52002)
		(size 0.508)
		(drill 0.254)
		(layers "F.Cu" "B.Cu")
		(net "LED_POSTCODE_2_R1")
	)
	(segment
		(start 65.10528 -86.73846)
		(end 64.680084 -86.73846)
		(width 0.11684)
		(layer "B.Cu")
		(net "LED_POSTCODE_2_R1")
	)
	(segment
		(start 75.93965 -29.5402)
		(end 75.93965 -30.2006)
		(width 0.254)
		(layer "B.Cu")
		(net "LED_POSTCODE_2_R1")
	)
	(segment
		(start 64.680084 -86.73846)
		(end 61.373004 -90.04554)
		(width 0.11684)
		(layer "B.Cu")
		(net "LED_POSTCODE_2_R1")
	)
	(segment
		(start 65.89268 -86.52002)
		(end 65.67424 -86.73846)
		(width 0.11684)
		(layer "B.Cu")
		(net "LED_POSTCODE_2_R1")
	)
	(segment
		(start 61.373004 -90.04554)
		(end 60.55868 -90.04554)
		(width 0.11684)
		(layer "B.Cu")
		(net "LED_POSTCODE_2_R1")
	)
	(segment
		(start 65.67424 -86.73846)
		(end 65.10528 -86.73846)
		(width 0.11684)
		(layer "B.Cu")
		(net "LED_POSTCODE_2_R1")
	)
	(segment
		(start 82.98942 -87.95512)
		(end 85.229954 -85.714586)
		(width 0.08382)
		(layer "In2.Cu")
		(net "LED_POSTCODE_2_R1")
	)
	(segment
		(start 87.95512 -35.27552)
		(end 86.160356 -33.480756)
		(width 0.08382)
		(layer "In2.Cu")
		(net "LED_POSTCODE_2_R1")
	)
	(segment
		(start 80.97774 -33.480756)
		(end 79.25562 -31.758636)
		(width 0.08382)
		(layer "In2.Cu")
		(net "LED_POSTCODE_2_R1")
	)
	(segment
		(start 73.719944 -88.59012)
		(end 79.91602 -88.59012)
		(width 0.08382)
		(layer "In2.Cu")
		(net "LED_POSTCODE_2_R1")
	)
	(segment
		(start 87.95512 -78.16342)
		(end 87.95512 -35.27552)
		(width 0.08382)
		(layer "In2.Cu")
		(net "LED_POSTCODE_2_R1")
	)
	(segment
		(start 86.160356 -33.480756)
		(end 80.97774 -33.480756)
		(width 0.08382)
		(layer "In2.Cu")
		(net "LED_POSTCODE_2_R1")
	)
	(segment
		(start 80.55102 -87.95512)
		(end 82.98942 -87.95512)
		(width 0.08382)
		(layer "In2.Cu")
		(net "LED_POSTCODE_2_R1")
	)
	(segment
		(start 79.91602 -88.59012)
		(end 80.55102 -87.95512)
		(width 0.08382)
		(layer "In2.Cu")
		(net "LED_POSTCODE_2_R1")
	)
	(segment
		(start 85.229954 -80.888586)
		(end 87.95512 -78.16342)
		(width 0.08382)
		(layer "In2.Cu")
		(net "LED_POSTCODE_2_R1")
	)
	(segment
		(start 85.229954 -85.714586)
		(end 85.229954 -80.888586)
		(width 0.08382)
		(layer "In2.Cu")
		(net "LED_POSTCODE_2_R1")
	)
	(segment
		(start 72.378824 -87.249)
		(end 73.719944 -88.59012)
		(width 0.08382)
		(layer "In2.Cu")
		(net "LED_POSTCODE_2_R1")
	)
	(segment
		(start 65.89268 -86.52002)
		(end 66.62166 -87.249)
		(width 0.08382)
		(layer "In2.Cu")
		(net "LED_POSTCODE_2_R1")
	)
	(segment
		(start 79.25562 -31.14802)
		(end 78.3082 -30.2006)
		(width 0.08382)
		(layer "In2.Cu")
		(net "LED_POSTCODE_2_R1")
	)
	(segment
		(start 78.3082 -30.2006)
		(end 75.93965 -30.2006)
		(width 0.08382)
		(layer "In2.Cu")
		(net "LED_POSTCODE_2_R1")
	)
	(segment
		(start 79.25562 -31.758636)
		(end 79.25562 -31.14802)
		(width 0.08382)
		(layer "In2.Cu")
		(net "LED_POSTCODE_2_R1")
	)
	(segment
		(start 66.62166 -87.249)
		(end 72.378824 -87.249)
		(width 0.08382)
		(layer "In2.Cu")
		(net "LED_POSTCODE_2_R1")
	)
	(segment
		(start 74.6252 -29.2862)
		(end 73.4314 -29.2862)
		(width 0.254)
		(layer "F.Cu")
		(net "LED_POSTCODE_2")
	)
	(segment
		(start 72.900794 -28.145994)
		(end 72.46493 -28.145994)
		(width 0.254)
		(layer "F.Cu")
		(net "LED_POSTCODE_2")
	)
	(segment
		(start 74.8792 -28.3972)
		(end 74.8792 -29.0322)
		(width 0.254)
		(layer "F.Cu")
		(net "LED_POSTCODE_2")
	)
	(segment
		(start 73.4314 -29.2862)
		(end 73.152 -29.0068)
		(width 0.254)
		(layer "F.Cu")
		(net "LED_POSTCODE_2")
	)
	(segment
		(start 74.8792 -29.0322)
		(end 74.6252 -29.2862)
		(width 0.254)
		(layer "F.Cu")
		(net "LED_POSTCODE_2")
	)
	(segment
		(start 73.152 -29.0068)
		(end 73.152 -28.3972)
		(width 0.254)
		(layer "F.Cu")
		(net "LED_POSTCODE_2")
	)
	(segment
		(start 45.695108 -48.9712)
		(end 45.299884 -48.575976)
		(width 0.254)
		(layer "F.Cu")
		(net "LED_POSTCODE_2")
	)
	(segment
		(start 73.152 -28.3972)
		(end 72.900794 -28.145994)
		(width 0.254)
		(layer "F.Cu")
		(net "LED_POSTCODE_2")
	)
	(via
		(at 45.299884 -48.575976)
		(size 0.4572)
		(drill 0.254)
		(layers "F.Cu" "B.Cu")
		(net "LED_POSTCODE_2")
	)
	(via
		(at 74.8792 -28.3972)
		(size 0.508)
		(drill 0.254)
		(layers "F.Cu" "B.Cu")
		(net "LED_POSTCODE_2")
	)
	(via
		(at 74.00544 -29.56306)
		(size 0.6604)
		(drill 0.3302)
		(layers "F.Cu" "B.Cu")
		(net "LED_POSTCODE_2")
	)
	(segment
		(start 74.632566 -29.5402)
		(end 74.609706 -29.56306)
		(width 0.254)
		(layer "B.Cu")
		(net "LED_POSTCODE_2")
	)
	(segment
		(start 74.00544 -29.56306)
		(end 74.00544 -28.96616)
		(width 0.254)
		(layer "B.Cu")
		(net "LED_POSTCODE_2")
	)
	(segment
		(start 74.609706 -29.56306)
		(end 74.00544 -29.56306)
		(width 0.254)
		(layer "B.Cu")
		(net "LED_POSTCODE_2")
	)
	(segment
		(start 74.00544 -28.96616)
		(end 74.5744 -28.3972)
		(width 0.254)
		(layer "B.Cu")
		(net "LED_POSTCODE_2")
	)
	(segment
		(start 75.13955 -29.5402)
		(end 74.632566 -29.5402)
		(width 0.254)
		(layer "B.Cu")
		(net "LED_POSTCODE_2")
	)
	(segment
		(start 74.5744 -28.3972)
		(end 74.8792 -28.3972)
		(width 0.254)
		(layer "B.Cu")
		(net "LED_POSTCODE_2")
	)
	(segment
		(start 55.407306 -46.233588)
		(end 56.223916 -46.233588)
		(width 0.10668)
		(layer "In7.Cu")
		(net "LED_POSTCODE_2")
	)
	(segment
		(start 56.223916 -46.233588)
		(end 56.6801 -45.777404)
		(width 0.10668)
		(layer "In7.Cu")
		(net "LED_POSTCODE_2")
	)
	(segment
		(start 72.836024 -39.610538)
		(end 73.208388 -39.238174)
		(width 0.254)
		(layer "In7.Cu")
		(net "LED_POSTCODE_2")
	)
	(segment
		(start 64.0842 -43.9674)
		(end 64.0842 -43.50385)
		(width 0.10668)
		(layer "In7.Cu")
		(net "LED_POSTCODE_2")
	)
	(segment
		(start 69.391022 -40.771064)
		(end 70.551548 -39.610538)
		(width 0.254)
		(layer "In7.Cu")
		(net "LED_POSTCODE_2")
	)
	(segment
		(start 65.795906 -42.348912)
		(end 65.795906 -42.087292)
		(width 0.10668)
		(layer "In7.Cu")
		(net "LED_POSTCODE_2")
	)
	(segment
		(start 73.208388 -38.586664)
		(end 74.486516 -37.308536)
		(width 0.254)
		(layer "In7.Cu")
		(net "LED_POSTCODE_2")
	)
	(segment
		(start 62.6872 -44.9834)
		(end 63.119 -44.9834)
		(width 0.10668)
		(layer "In7.Cu")
		(net "LED_POSTCODE_2")
	)
	(segment
		(start 74.802238 -36.546282)
		(end 75.767946 -35.580574)
		(width 0.254)
		(layer "In7.Cu")
		(net "LED_POSTCODE_2")
	)
	(segment
		(start 77.986636 -28.3972)
		(end 74.8792 -28.3972)
		(width 0.254)
		(layer "In7.Cu")
		(net "LED_POSTCODE_2")
	)
	(segment
		(start 52.253896 -47.406052)
		(end 54.234842 -47.406052)
		(width 0.10668)
		(layer "In7.Cu")
		(net "LED_POSTCODE_2")
	)
	(segment
		(start 63.2968 -44.8056)
		(end 63.2968 -44.3992)
		(width 0.10668)
		(layer "In7.Cu")
		(net "LED_POSTCODE_2")
	)
	(segment
		(start 70.551548 -39.610538)
		(end 72.836024 -39.610538)
		(width 0.254)
		(layer "In7.Cu")
		(net "LED_POSTCODE_2")
	)
	(segment
		(start 62.484 -45.538644)
		(end 62.484 -45.1866)
		(width 0.10668)
		(layer "In7.Cu")
		(net "LED_POSTCODE_2")
	)
	(segment
		(start 62.484 -45.1866)
		(end 62.6872 -44.9834)
		(width 0.10668)
		(layer "In7.Cu")
		(net "LED_POSTCODE_2")
	)
	(segment
		(start 81.1784 -32.368236)
		(end 81.1784 -31.588964)
		(width 0.254)
		(layer "In7.Cu")
		(net "LED_POSTCODE_2")
	)
	(segment
		(start 81.1784 -31.588964)
		(end 77.986636 -28.3972)
		(width 0.254)
		(layer "In7.Cu")
		(net "LED_POSTCODE_2")
	)
	(segment
		(start 63.2968 -44.3992)
		(end 63.5254 -44.1706)
		(width 0.10668)
		(layer "In7.Cu")
		(net "LED_POSTCODE_2")
	)
	(segment
		(start 51.295046 -48.837088)
		(end 51.295046 -48.364902)
		(width 0.10668)
		(layer "In7.Cu")
		(net "LED_POSTCODE_2")
	)
	(segment
		(start 74.486516 -37.308536)
		(end 74.802238 -36.546282)
		(width 0.254)
		(layer "In7.Cu")
		(net "LED_POSTCODE_2")
	)
	(segment
		(start 58.382916 -45.777404)
		(end 58.774584 -46.169072)
		(width 0.10668)
		(layer "In7.Cu")
		(net "LED_POSTCODE_2")
	)
	(segment
		(start 46.210474 -49.486566)
		(end 49.39411 -49.486566)
		(width 0.10668)
		(layer "In7.Cu")
		(net "LED_POSTCODE_2")
	)
	(segment
		(start 49.39411 -49.486566)
		(end 49.58334 -49.297336)
		(width 0.10668)
		(layer "In7.Cu")
		(net "LED_POSTCODE_2")
	)
	(segment
		(start 50.834798 -49.297336)
		(end 51.295046 -48.837088)
		(width 0.10668)
		(layer "In7.Cu")
		(net "LED_POSTCODE_2")
	)
	(segment
		(start 61.501528 -46.169072)
		(end 61.910976 -45.759624)
		(width 0.10668)
		(layer "In7.Cu")
		(net "LED_POSTCODE_2")
	)
	(segment
		(start 58.774584 -46.169072)
		(end 61.501528 -46.169072)
		(width 0.10668)
		(layer "In7.Cu")
		(net "LED_POSTCODE_2")
	)
	(segment
		(start 54.234842 -47.406052)
		(end 55.407306 -46.233588)
		(width 0.10668)
		(layer "In7.Cu")
		(net "LED_POSTCODE_2")
	)
	(segment
		(start 75.767946 -35.580574)
		(end 77.966062 -35.580574)
		(width 0.254)
		(layer "In7.Cu")
		(net "LED_POSTCODE_2")
	)
	(segment
		(start 61.910976 -45.759624)
		(end 62.26302 -45.759624)
		(width 0.10668)
		(layer "In7.Cu")
		(net "LED_POSTCODE_2")
	)
	(segment
		(start 63.881 -44.1706)
		(end 64.0842 -43.9674)
		(width 0.10668)
		(layer "In7.Cu")
		(net "LED_POSTCODE_2")
	)
	(segment
		(start 49.58334 -49.297336)
		(end 50.834798 -49.297336)
		(width 0.10668)
		(layer "In7.Cu")
		(net "LED_POSTCODE_2")
	)
	(segment
		(start 64.0842 -43.50385)
		(end 64.2112 -43.37685)
		(width 0.10668)
		(layer "In7.Cu")
		(net "LED_POSTCODE_2")
	)
	(segment
		(start 64.767968 -43.37685)
		(end 65.795906 -42.348912)
		(width 0.10668)
		(layer "In7.Cu")
		(net "LED_POSTCODE_2")
	)
	(segment
		(start 62.26302 -45.759624)
		(end 62.484 -45.538644)
		(width 0.10668)
		(layer "In7.Cu")
		(net "LED_POSTCODE_2")
	)
	(segment
		(start 77.966062 -35.580574)
		(end 81.1784 -32.368236)
		(width 0.254)
		(layer "In7.Cu")
		(net "LED_POSTCODE_2")
	)
	(segment
		(start 56.6801 -45.777404)
		(end 58.382916 -45.777404)
		(width 0.10668)
		(layer "In7.Cu")
		(net "LED_POSTCODE_2")
	)
	(segment
		(start 63.5254 -44.1706)
		(end 63.881 -44.1706)
		(width 0.10668)
		(layer "In7.Cu")
		(net "LED_POSTCODE_2")
	)
	(segment
		(start 64.2112 -43.37685)
		(end 64.767968 -43.37685)
		(width 0.10668)
		(layer "In7.Cu")
		(net "LED_POSTCODE_2")
	)
	(segment
		(start 65.795906 -42.087292)
		(end 66.048636 -41.834562)
		(width 0.10668)
		(layer "In7.Cu")
		(net "LED_POSTCODE_2")
	)
	(segment
		(start 45.299884 -48.575976)
		(end 46.210474 -49.486566)
		(width 0.10668)
		(layer "In7.Cu")
		(net "LED_POSTCODE_2")
	)
	(segment
		(start 63.119 -44.9834)
		(end 63.2968 -44.8056)
		(width 0.10668)
		(layer "In7.Cu")
		(net "LED_POSTCODE_2")
	)
	(segment
		(start 73.208388 -39.238174)
		(end 73.208388 -38.586664)
		(width 0.254)
		(layer "In7.Cu")
		(net "LED_POSTCODE_2")
	)
	(segment
		(start 51.295046 -48.364902)
		(end 52.253896 -47.406052)
		(width 0.10668)
		(layer "In7.Cu")
		(net "LED_POSTCODE_2")
	)
	(segment
		(start 67.112134 -40.771064)
		(end 69.391022 -40.771064)
		(width 0.254)
		(layer "In7.Cu")
		(net "LED_POSTCODE_2")
	)
	(segment
		(start 66.048636 -41.834562)
		(end 67.112134 -40.771064)
		(width 0.254)
		(layer "In7.Cu")
		(net "LED_POSTCODE_2")
	)
	(via
		(at 59.3471 -91.345512)
		(size 0.508)
		(drill 0.254)
		(layers "F.Cu" "B.Cu")
		(net "LED_POSTCODE_1_R1")
	)
	(via
		(at 80.0354 -29.5656)
		(size 0.508)
		(drill 0.254)
		(layers "F.Cu" "B.Cu")
		(net "LED_POSTCODE_1_R1")
	)
	(segment
		(start 78.867 -30.11805)
		(end 79.48295 -30.11805)
		(width 0.254)
		(layer "B.Cu")
		(net "LED_POSTCODE_1_R1")
	)
	(segment
		(start 79.48295 -30.11805)
		(end 80.0354 -29.5656)
		(width 0.254)
		(layer "B.Cu")
		(net "LED_POSTCODE_1_R1")
	)
	(segment
		(start 59.997086 -90.695526)
		(end 59.3471 -91.345512)
		(width 0.11684)
		(layer "B.Cu")
		(net "LED_POSTCODE_1_R1")
	)
	(segment
		(start 60.55868 -90.695526)
		(end 59.997086 -90.695526)
		(width 0.11684)
		(layer "B.Cu")
		(net "LED_POSTCODE_1_R1")
	)
	(segment
		(start 80.33385 -30.611572)
		(end 80.33385 -29.86405)
		(width 0.08382)
		(layer "In2.Cu")
		(net "LED_POSTCODE_1_R1")
	)
	(segment
		(start 72.56018 -91.2622)
		(end 75.13828 -91.2622)
		(width 0.08382)
		(layer "In2.Cu")
		(net "LED_POSTCODE_1_R1")
	)
	(segment
		(start 80.33385 -29.86405)
		(end 80.0354 -29.5656)
		(width 0.08382)
		(layer "In2.Cu")
		(net "LED_POSTCODE_1_R1")
	)
	(segment
		(start 59.989212 -90.7034)
		(end 68.7451 -90.7034)
		(width 0.08382)
		(layer "In2.Cu")
		(net "LED_POSTCODE_1_R1")
	)
	(segment
		(start 59.3471 -91.345512)
		(end 59.989212 -90.7034)
		(width 0.08382)
		(layer "In2.Cu")
		(net "LED_POSTCODE_1_R1")
	)
	(segment
		(start 80.32496 -89.37244)
		(end 81.026 -88.6714)
		(width 0.08382)
		(layer "In2.Cu")
		(net "LED_POSTCODE_1_R1")
	)
	(segment
		(start 81.026 -88.6714)
		(end 83.2866 -88.6714)
		(width 0.08382)
		(layer "In2.Cu")
		(net "LED_POSTCODE_1_R1")
	)
	(segment
		(start 85.938614 -81.193386)
		(end 88.6714 -78.4606)
		(width 0.08382)
		(layer "In2.Cu")
		(net "LED_POSTCODE_1_R1")
	)
	(segment
		(start 82.766662 -31.609538)
		(end 81.331816 -31.609538)
		(width 0.08382)
		(layer "In2.Cu")
		(net "LED_POSTCODE_1_R1")
	)
	(segment
		(start 75.13828 -91.2622)
		(end 77.02804 -89.37244)
		(width 0.08382)
		(layer "In2.Cu")
		(net "LED_POSTCODE_1_R1")
	)
	(segment
		(start 85.938614 -86.019386)
		(end 85.938614 -81.193386)
		(width 0.08382)
		(layer "In2.Cu")
		(net "LED_POSTCODE_1_R1")
	)
	(segment
		(start 71.93534 -91.88704)
		(end 72.56018 -91.2622)
		(width 0.08382)
		(layer "In2.Cu")
		(net "LED_POSTCODE_1_R1")
	)
	(segment
		(start 68.7451 -90.7034)
		(end 69.92874 -91.88704)
		(width 0.08382)
		(layer "In2.Cu")
		(net "LED_POSTCODE_1_R1")
	)
	(segment
		(start 77.02804 -89.37244)
		(end 80.32496 -89.37244)
		(width 0.08382)
		(layer "In2.Cu")
		(net "LED_POSTCODE_1_R1")
	)
	(segment
		(start 88.6714 -78.4606)
		(end 88.6714 -34.1376)
		(width 0.08382)
		(layer "In2.Cu")
		(net "LED_POSTCODE_1_R1")
	)
	(segment
		(start 85.6996 -31.1658)
		(end 83.2104 -31.1658)
		(width 0.08382)
		(layer "In2.Cu")
		(net "LED_POSTCODE_1_R1")
	)
	(segment
		(start 81.331816 -31.609538)
		(end 80.33385 -30.611572)
		(width 0.08382)
		(layer "In2.Cu")
		(net "LED_POSTCODE_1_R1")
	)
	(segment
		(start 69.92874 -91.88704)
		(end 71.93534 -91.88704)
		(width 0.08382)
		(layer "In2.Cu")
		(net "LED_POSTCODE_1_R1")
	)
	(segment
		(start 83.2866 -88.6714)
		(end 85.938614 -86.019386)
		(width 0.08382)
		(layer "In2.Cu")
		(net "LED_POSTCODE_1_R1")
	)
	(segment
		(start 83.2104 -31.1658)
		(end 82.766662 -31.609538)
		(width 0.08382)
		(layer "In2.Cu")
		(net "LED_POSTCODE_1_R1")
	)
	(segment
		(start 88.6714 -34.1376)
		(end 85.6996 -31.1658)
		(width 0.08382)
		(layer "In2.Cu")
		(net "LED_POSTCODE_1_R1")
	)
	(segment
		(start 79.502 -28.194)
		(end 79.6798 -28.0162)
		(width 0.254)
		(layer "F.Cu")
		(net "LED_POSTCODE_1")
	)
	(segment
		(start 77.3684 -29.591)
		(end 78.0542 -28.9052)
		(width 0.254)
		(layer "F.Cu")
		(net "LED_POSTCODE_1")
	)
	(segment
		(start 47.295054 -48.9712)
		(end 46.89983 -48.575976)
		(width 0.254)
		(layer "F.Cu")
		(net "LED_POSTCODE_1")
	)
	(segment
		(start 78.0542 -28.5242)
		(end 78.3844 -28.194)
		(width 0.254)
		(layer "F.Cu")
		(net "LED_POSTCODE_1")
	)
	(segment
		(start 79.6798 -27.1526)
		(end 79.935578 -26.896822)
		(width 0.254)
		(layer "F.Cu")
		(net "LED_POSTCODE_1")
	)
	(segment
		(start 77.216 -29.591)
		(end 77.3684 -29.591)
		(width 0.254)
		(layer "F.Cu")
		(net "LED_POSTCODE_1")
	)
	(segment
		(start 78.3844 -28.194)
		(end 79.502 -28.194)
		(width 0.254)
		(layer "F.Cu")
		(net "LED_POSTCODE_1")
	)
	(segment
		(start 79.6798 -28.0162)
		(end 79.6798 -27.1526)
		(width 0.254)
		(layer "F.Cu")
		(net "LED_POSTCODE_1")
	)
	(segment
		(start 79.935578 -26.896822)
		(end 80.280764 -26.896822)
		(width 0.254)
		(layer "F.Cu")
		(net "LED_POSTCODE_1")
	)
	(segment
		(start 78.0542 -28.9052)
		(end 78.0542 -28.5242)
		(width 0.254)
		(layer "F.Cu")
		(net "LED_POSTCODE_1")
	)
	(via
		(at 46.89983 -48.575976)
		(size 0.4572)
		(drill 0.254)
		(layers "F.Cu" "B.Cu")
		(net "LED_POSTCODE_1")
	)
	(via
		(at 77.216 -29.591)
		(size 0.508)
		(drill 0.254)
		(layers "F.Cu" "B.Cu")
		(net "LED_POSTCODE_1")
	)
	(segment
		(start 78.07325 -29.31795)
		(end 77.8002 -29.591)
		(width 0.254)
		(layer "B.Cu")
		(net "LED_POSTCODE_1")
	)
	(segment
		(start 78.867 -29.31795)
		(end 78.07325 -29.31795)
		(width 0.254)
		(layer "B.Cu")
		(net "LED_POSTCODE_1")
	)
	(segment
		(start 77.8002 -29.591)
		(end 77.216 -29.591)
		(width 0.254)
		(layer "B.Cu")
		(net "LED_POSTCODE_1")
	)
	(segment
		(start 71.723504 -37.398198)
		(end 72.498966 -36.622736)
		(width 0.254)
		(layer "In7.Cu")
		(net "LED_POSTCODE_1")
	)
	(segment
		(start 61.474604 -44.976796)
		(end 61.6966 -44.7548)
		(width 0.10668)
		(layer "In7.Cu")
		(net "LED_POSTCODE_1")
	)
	(segment
		(start 74.878184 -34.62528)
		(end 75.781154 -34.62528)
		(width 0.254)
		(layer "In7.Cu")
		(net "LED_POSTCODE_1")
	)
	(segment
		(start 63.2968 -43.18)
		(end 63.2968 -42.6974)
		(width 0.10668)
		(layer "In7.Cu")
		(net "LED_POSTCODE_1")
	)
	(segment
		(start 52.9082 -46.4058)
		(end 52.9082 -45.90161)
		(width 0.10668)
		(layer "In7.Cu")
		(net "LED_POSTCODE_1")
	)
	(segment
		(start 52.6034 -46.7106)
		(end 52.9082 -46.4058)
		(width 0.10668)
		(layer "In7.Cu")
		(net "LED_POSTCODE_1")
	)
	(segment
		(start 55.745634 -44.7548)
		(end 59.300364 -44.7548)
		(width 0.10668)
		(layer "In7.Cu")
		(net "LED_POSTCODE_1")
	)
	(segment
		(start 74.28611 -35.217354)
		(end 74.878184 -34.62528)
		(width 0.254)
		(layer "In7.Cu")
		(net "LED_POSTCODE_1")
	)
	(segment
		(start 79.1718 -33.163002)
		(end 79.1718 -30.731968)
		(width 0.254)
		(layer "In7.Cu")
		(net "LED_POSTCODE_1")
	)
	(segment
		(start 52.9082 -45.90161)
		(end 53.0352 -45.77461)
		(width 0.10668)
		(layer "In7.Cu")
		(net "LED_POSTCODE_1")
	)
	(segment
		(start 78.377542 -33.95726)
		(end 79.1718 -33.163002)
		(width 0.254)
		(layer "In7.Cu")
		(net "LED_POSTCODE_1")
	)
	(segment
		(start 46.89983 -48.575976)
		(end 47.29607 -48.972216)
		(width 0.10668)
		(layer "In7.Cu")
		(net "LED_POSTCODE_1")
	)
	(segment
		(start 62.484 -44.0182)
		(end 62.484 -43.561)
		(width 0.10668)
		(layer "In7.Cu")
		(net "LED_POSTCODE_1")
	)
	(segment
		(start 72.498966 -36.622736)
		(end 72.498966 -35.858196)
		(width 0.254)
		(layer "In7.Cu")
		(net "LED_POSTCODE_1")
	)
	(segment
		(start 47.29607 -48.972216)
		(end 48.936656 -48.972216)
		(width 0.10668)
		(layer "In7.Cu")
		(net "LED_POSTCODE_1")
	)
	(segment
		(start 61.6966 -44.7548)
		(end 61.6966 -44.4246)
		(width 0.10668)
		(layer "In7.Cu")
		(net "LED_POSTCODE_1")
	)
	(segment
		(start 54.725824 -45.77461)
		(end 55.745634 -44.7548)
		(width 0.10668)
		(layer "In7.Cu")
		(net "LED_POSTCODE_1")
	)
	(segment
		(start 63.881 -42.5704)
		(end 64.0842 -42.3672)
		(width 0.10668)
		(layer "In7.Cu")
		(net "LED_POSTCODE_1")
	)
	(segment
		(start 72.498966 -35.858196)
		(end 73.139808 -35.217354)
		(width 0.254)
		(layer "In7.Cu")
		(net "LED_POSTCODE_1")
	)
	(segment
		(start 53.0352 -45.77461)
		(end 54.725824 -45.77461)
		(width 0.10668)
		(layer "In7.Cu")
		(net "LED_POSTCODE_1")
	)
	(segment
		(start 69.464936 -39.280338)
		(end 69.464936 -38.522656)
		(width 0.254)
		(layer "In7.Cu")
		(net "LED_POSTCODE_1")
	)
	(segment
		(start 64.0842 -41.995344)
		(end 64.2874 -41.792144)
		(width 0.10668)
		(layer "In7.Cu")
		(net "LED_POSTCODE_1")
	)
	(segment
		(start 61.6966 -44.4246)
		(end 61.9506 -44.1706)
		(width 0.10668)
		(layer "In7.Cu")
		(net "LED_POSTCODE_1")
	)
	(segment
		(start 63.4238 -42.5704)
		(end 63.881 -42.5704)
		(width 0.10668)
		(layer "In7.Cu")
		(net "LED_POSTCODE_1")
	)
	(segment
		(start 59.300364 -44.7548)
		(end 59.52236 -44.976796)
		(width 0.10668)
		(layer "In7.Cu")
		(net "LED_POSTCODE_1")
	)
	(segment
		(start 63.2968 -42.6974)
		(end 63.4238 -42.5704)
		(width 0.10668)
		(layer "In7.Cu")
		(net "LED_POSTCODE_1")
	)
	(segment
		(start 68.7959 -39.949374)
		(end 69.464936 -39.280338)
		(width 0.254)
		(layer "In7.Cu")
		(net "LED_POSTCODE_1")
	)
	(segment
		(start 62.3316 -44.1706)
		(end 62.484 -44.0182)
		(width 0.10668)
		(layer "In7.Cu")
		(net "LED_POSTCODE_1")
	)
	(segment
		(start 69.464936 -38.522656)
		(end 70.589394 -37.398198)
		(width 0.254)
		(layer "In7.Cu")
		(net "LED_POSTCODE_1")
	)
	(segment
		(start 59.52236 -44.976796)
		(end 61.474604 -44.976796)
		(width 0.10668)
		(layer "In7.Cu")
		(net "LED_POSTCODE_1")
	)
	(segment
		(start 63.0936 -43.3832)
		(end 63.2968 -43.18)
		(width 0.10668)
		(layer "In7.Cu")
		(net "LED_POSTCODE_1")
	)
	(segment
		(start 64.2874 -41.792144)
		(end 64.633856 -41.792144)
		(width 0.10668)
		(layer "In7.Cu")
		(net "LED_POSTCODE_1")
	)
	(segment
		(start 73.139808 -35.217354)
		(end 74.28611 -35.217354)
		(width 0.254)
		(layer "In7.Cu")
		(net "LED_POSTCODE_1")
	)
	(segment
		(start 61.9506 -44.1706)
		(end 62.3316 -44.1706)
		(width 0.10668)
		(layer "In7.Cu")
		(net "LED_POSTCODE_1")
	)
	(segment
		(start 78.030832 -29.591)
		(end 77.216 -29.591)
		(width 0.254)
		(layer "In7.Cu")
		(net "LED_POSTCODE_1")
	)
	(segment
		(start 75.781154 -34.62528)
		(end 76.449174 -33.95726)
		(width 0.254)
		(layer "In7.Cu")
		(net "LED_POSTCODE_1")
	)
	(segment
		(start 76.449174 -33.95726)
		(end 78.377542 -33.95726)
		(width 0.254)
		(layer "In7.Cu")
		(net "LED_POSTCODE_1")
	)
	(segment
		(start 79.1718 -30.731968)
		(end 78.030832 -29.591)
		(width 0.254)
		(layer "In7.Cu")
		(net "LED_POSTCODE_1")
	)
	(segment
		(start 51.198272 -46.7106)
		(end 52.6034 -46.7106)
		(width 0.10668)
		(layer "In7.Cu")
		(net "LED_POSTCODE_1")
	)
	(segment
		(start 64.633856 -41.792144)
		(end 66.476626 -39.949374)
		(width 0.10668)
		(layer "In7.Cu")
		(net "LED_POSTCODE_1")
	)
	(segment
		(start 48.936656 -48.972216)
		(end 51.198272 -46.7106)
		(width 0.10668)
		(layer "In7.Cu")
		(net "LED_POSTCODE_1")
	)
	(segment
		(start 70.589394 -37.398198)
		(end 71.723504 -37.398198)
		(width 0.254)
		(layer "In7.Cu")
		(net "LED_POSTCODE_1")
	)
	(segment
		(start 62.6618 -43.3832)
		(end 63.0936 -43.3832)
		(width 0.10668)
		(layer "In7.Cu")
		(net "LED_POSTCODE_1")
	)
	(segment
		(start 66.476626 -39.949374)
		(end 68.7959 -39.949374)
		(width 0.254)
		(layer "In7.Cu")
		(net "LED_POSTCODE_1")
	)
	(segment
		(start 62.484 -43.561)
		(end 62.6618 -43.3832)
		(width 0.10668)
		(layer "In7.Cu")
		(net "LED_POSTCODE_1")
	)
	(segment
		(start 64.0842 -42.3672)
		(end 64.0842 -41.995344)
		(width 0.10668)
		(layer "In7.Cu")
		(net "LED_POSTCODE_1")
	)
	(via
		(at 64.60236 -87.96528)
		(size 0.6604)
		(drill 0.3302)
		(layers "F.Cu" "B.Cu")
		(net "LED_POSTCODE_0_R1")
	)
	(via
		(at 79.7052 -31.5722)
		(size 0.508)
		(drill 0.254)
		(layers "F.Cu" "B.Cu")
		(net "LED_POSTCODE_0_R1")
	)
	(via
		(at 65.89268 -87.18042)
		(size 0.508)
		(drill 0.254)
		(layers "F.Cu" "B.Cu")
		(net "LED_POSTCODE_0_R1")
	)
	(segment
		(start 63.4238 -88.4428)
		(end 61.6458 -90.2208)
		(width 0.11684)
		(layer "B.Cu")
		(net "LED_POSTCODE_0_R1")
	)
	(segment
		(start 61.6458 -90.2208)
		(end 61.6458 -90.85834)
		(width 0.11684)
		(layer "B.Cu")
		(net "LED_POSTCODE_0_R1")
	)
	(segment
		(start 79.45755 -31.32455)
		(end 79.7052 -31.5722)
		(width 0.254)
		(layer "B.Cu")
		(net "LED_POSTCODE_0_R1")
	)
	(segment
		(start 64.12484 -88.4428)
		(end 63.4238 -88.4428)
		(width 0.11684)
		(layer "B.Cu")
		(net "LED_POSTCODE_0_R1")
	)
	(segment
		(start 65.465452 -87.607648)
		(end 64.60236 -87.96528)
		(width 0.11684)
		(layer "B.Cu")
		(net "LED_POSTCODE_0_R1")
	)
	(segment
		(start 61.158628 -91.345512)
		(end 60.55868 -91.345512)
		(width 0.11684)
		(layer "B.Cu")
		(net "LED_POSTCODE_0_R1")
	)
	(segment
		(start 64.60236 -87.96528)
		(end 64.12484 -88.4428)
		(width 0.11684)
		(layer "B.Cu")
		(net "LED_POSTCODE_0_R1")
	)
	(segment
		(start 79.45755 -30.988)
		(end 79.45755 -31.32455)
		(width 0.254)
		(layer "B.Cu")
		(net "LED_POSTCODE_0_R1")
	)
	(segment
		(start 65.89268 -87.18042)
		(end 65.465452 -87.607648)
		(width 0.11684)
		(layer "B.Cu")
		(net "LED_POSTCODE_0_R1")
	)
	(segment
		(start 61.6458 -90.85834)
		(end 61.158628 -91.345512)
		(width 0.11684)
		(layer "B.Cu")
		(net "LED_POSTCODE_0_R1")
	)
	(segment
		(start 80.364838 -31.3182)
		(end 79.9592 -31.3182)
		(width 0.08382)
		(layer "In2.Cu")
		(net "LED_POSTCODE_0_R1")
	)
	(segment
		(start 85.50148 -32.02432)
		(end 85.1154 -32.4104)
		(width 0.08382)
		(layer "In2.Cu")
		(net "LED_POSTCODE_0_R1")
	)
	(segment
		(start 85.466174 -80.990186)
		(end 88.19388 -78.26248)
		(width 0.08382)
		(layer "In2.Cu")
		(net "LED_POSTCODE_0_R1")
	)
	(segment
		(start 65.89268 -87.18042)
		(end 66.21526 -87.503)
		(width 0.08382)
		(layer "In2.Cu")
		(net "LED_POSTCODE_0_R1")
	)
	(segment
		(start 72.295004 -87.503)
		(end 73.620884 -88.82888)
		(width 0.08382)
		(layer "In2.Cu")
		(net "LED_POSTCODE_0_R1")
	)
	(segment
		(start 85.88248 -32.02432)
		(end 85.50148 -32.02432)
		(width 0.08382)
		(layer "In2.Cu")
		(net "LED_POSTCODE_0_R1")
	)
	(segment
		(start 85.466174 -85.816186)
		(end 85.466174 -80.990186)
		(width 0.08382)
		(layer "In2.Cu")
		(net "LED_POSTCODE_0_R1")
	)
	(segment
		(start 85.1154 -32.4104)
		(end 81.457038 -32.4104)
		(width 0.08382)
		(layer "In2.Cu")
		(net "LED_POSTCODE_0_R1")
	)
	(segment
		(start 88.19388 -34.33572)
		(end 85.88248 -32.02432)
		(width 0.08382)
		(layer "In2.Cu")
		(net "LED_POSTCODE_0_R1")
	)
	(segment
		(start 73.620884 -88.82888)
		(end 80.01508 -88.82888)
		(width 0.08382)
		(layer "In2.Cu")
		(net "LED_POSTCODE_0_R1")
	)
	(segment
		(start 66.21526 -87.503)
		(end 72.295004 -87.503)
		(width 0.08382)
		(layer "In2.Cu")
		(net "LED_POSTCODE_0_R1")
	)
	(segment
		(start 80.01508 -88.82888)
		(end 80.65008 -88.19388)
		(width 0.08382)
		(layer "In2.Cu")
		(net "LED_POSTCODE_0_R1")
	)
	(segment
		(start 79.9592 -31.3182)
		(end 79.7052 -31.5722)
		(width 0.08382)
		(layer "In2.Cu")
		(net "LED_POSTCODE_0_R1")
	)
	(segment
		(start 88.19388 -78.26248)
		(end 88.19388 -34.33572)
		(width 0.08382)
		(layer "In2.Cu")
		(net "LED_POSTCODE_0_R1")
	)
	(segment
		(start 81.457038 -32.4104)
		(end 80.364838 -31.3182)
		(width 0.08382)
		(layer "In2.Cu")
		(net "LED_POSTCODE_0_R1")
	)
	(segment
		(start 83.08848 -88.19388)
		(end 85.466174 -85.816186)
		(width 0.08382)
		(layer "In2.Cu")
		(net "LED_POSTCODE_0_R1")
	)
	(segment
		(start 80.65008 -88.19388)
		(end 83.08848 -88.19388)
		(width 0.08382)
		(layer "In2.Cu")
		(net "LED_POSTCODE_0_R1")
	)
	(segment
		(start 81.477866 -28.20162)
		(end 81.087722 -28.363164)
		(width 0.254)
		(layer "F.Cu")
		(net "LED_POSTCODE_0")
	)
	(segment
		(start 45.695108 -49.7713)
		(end 45.299884 -50.166524)
		(width 0.254)
		(layer "F.Cu")
		(net "LED_POSTCODE_0")
	)
	(segment
		(start 81.477866 -28.20162)
		(end 81.167986 -27.89174)
		(width 0.254)
		(layer "F.Cu")
		(net "LED_POSTCODE_0")
	)
	(segment
		(start 80.7847 -29.7561)
		(end 80.772 -29.7688)
		(width 0.254)
		(layer "F.Cu")
		(net "LED_POSTCODE_0")
	)
	(segment
		(start 80.8609 -27.89174)
		(end 80.6069 -28.14574)
		(width 0.254)
		(layer "F.Cu")
		(net "LED_POSTCODE_0")
	)
	(segment
		(start 80.6069 -28.14574)
		(end 80.280764 -28.14574)
		(width 0.254)
		(layer "F.Cu")
		(net "LED_POSTCODE_0")
	)
	(segment
		(start 81.087722 -28.363164)
		(end 80.7847 -28.666186)
		(width 0.254)
		(layer "F.Cu")
		(net "LED_POSTCODE_0")
	)
	(segment
		(start 80.7847 -28.666186)
		(end 80.7847 -29.7561)
		(width 0.254)
		(layer "F.Cu")
		(net "LED_POSTCODE_0")
	)
	(segment
		(start 81.167986 -27.89174)
		(end 80.8609 -27.89174)
		(width 0.254)
		(layer "F.Cu")
		(net "LED_POSTCODE_0")
	)
	(via
		(at 81.477866 -28.20162)
		(size 0.762)
		(drill 0.381)
		(layers "F.Cu" "B.Cu")
		(net "LED_POSTCODE_0")
	)
	(via
		(at 80.772 -29.7688)
		(size 0.508)
		(drill 0.254)
		(layers "F.Cu" "B.Cu")
		(net "LED_POSTCODE_0")
	)
	(via
		(at 45.299884 -50.166524)
		(size 0.4572)
		(drill 0.254)
		(layers "F.Cu" "B.Cu")
		(net "LED_POSTCODE_0")
	)
	(segment
		(start 80.25765 -30.988)
		(end 80.25765 -30.28315)
		(width 0.254)
		(layer "B.Cu")
		(net "LED_POSTCODE_0")
	)
	(segment
		(start 80.25765 -30.28315)
		(end 80.772 -29.7688)
		(width 0.254)
		(layer "B.Cu")
		(net "LED_POSTCODE_0")
	)
	(segment
		(start 51.359054 -49.530762)
		(end 49.958752 -49.530762)
		(width 0.10668)
		(layer "In7.Cu")
		(net "LED_POSTCODE_0")
	)
	(segment
		(start 52.102258 -48.787558)
		(end 51.359054 -49.530762)
		(width 0.10668)
		(layer "In7.Cu")
		(net "LED_POSTCODE_0")
	)
	(segment
		(start 62.238128 -46.575472)
		(end 55.45709 -46.575472)
		(width 0.10668)
		(layer "In7.Cu")
		(net "LED_POSTCODE_0")
	)
	(segment
		(start 54.294786 -47.737776)
		(end 52.773072 -47.737776)
		(width 0.10668)
		(layer "In7.Cu")
		(net "LED_POSTCODE_0")
	)
	(segment
		(start 70.798944 -40.078406)
		(end 69.628512 -41.248838)
		(width 0.254)
		(layer "In7.Cu")
		(net "LED_POSTCODE_0")
	)
	(segment
		(start 83.1342 -31.5722)
		(end 82.156046 -32.550354)
		(width 0.254)
		(layer "In7.Cu")
		(net "LED_POSTCODE_0")
	)
	(segment
		(start 62.484 -46.039532)
		(end 62.484 -46.3296)
		(width 0.10668)
		(layer "In7.Cu")
		(net "LED_POSTCODE_0")
	)
	(segment
		(start 55.45709 -46.575472)
		(end 54.294786 -47.737776)
		(width 0.10668)
		(layer "In7.Cu")
		(net "LED_POSTCODE_0")
	)
	(segment
		(start 64.649096 -44.959524)
		(end 64.62268 -44.970446)
		(width 0.10668)
		(layer "In7.Cu")
		(net "LED_POSTCODE_0")
	)
	(segment
		(start 82.156046 -32.550354)
		(end 82.156046 -34.373566)
		(width 0.254)
		(layer "In7.Cu")
		(net "LED_POSTCODE_0")
	)
	(segment
		(start 45.696378 -49.77003)
		(end 45.299884 -50.166524)
		(width 0.10668)
		(layer "In7.Cu")
		(net "LED_POSTCODE_0")
	)
	(segment
		(start 64.62268 -44.970446)
		(end 63.538608 -44.970446)
		(width 0.10668)
		(layer "In7.Cu")
		(net "LED_POSTCODE_0")
	)
	(segment
		(start 64.887348 -44.721272)
		(end 64.649096 -44.959524)
		(width 0.10668)
		(layer "In7.Cu")
		(net "LED_POSTCODE_0")
	)
	(segment
		(start 80.772 -28.7782)
		(end 81.2038 -28.3464)
		(width 0.254)
		(layer "In7.Cu")
		(net "LED_POSTCODE_0")
	)
	(segment
		(start 75.964796 -35.993324)
		(end 75.205336 -36.752784)
		(width 0.254)
		(layer "In7.Cu")
		(net "LED_POSTCODE_0")
	)
	(segment
		(start 62.484 -46.3296)
		(end 62.238128 -46.575472)
		(width 0.10668)
		(layer "In7.Cu")
		(net "LED_POSTCODE_0")
	)
	(segment
		(start 82.156046 -34.373566)
		(end 80.536288 -35.993324)
		(width 0.254)
		(layer "In7.Cu")
		(net "LED_POSTCODE_0")
	)
	(segment
		(start 52.773072 -47.737776)
		(end 52.102258 -48.40859)
		(width 0.10668)
		(layer "In7.Cu")
		(net "LED_POSTCODE_0")
	)
	(segment
		(start 63.07201 -45.79239)
		(end 62.731142 -45.79239)
		(width 0.10668)
		(layer "In7.Cu")
		(net "LED_POSTCODE_0")
	)
	(segment
		(start 63.2968 -45.212254)
		(end 63.2968 -45.5676)
		(width 0.10668)
		(layer "In7.Cu")
		(net "LED_POSTCODE_0")
	)
	(segment
		(start 73.962514 -40.078406)
		(end 70.798944 -40.078406)
		(width 0.254)
		(layer "In7.Cu")
		(net "LED_POSTCODE_0")
	)
	(segment
		(start 75.146408 -36.895024)
		(end 75.146408 -38.894512)
		(width 0.254)
		(layer "In7.Cu")
		(net "LED_POSTCODE_0")
	)
	(segment
		(start 81.2038 -28.3464)
		(end 82.6008 -28.3464)
		(width 0.254)
		(layer "In7.Cu")
		(net "LED_POSTCODE_0")
	)
	(segment
		(start 62.731142 -45.79239)
		(end 62.484 -46.039532)
		(width 0.10668)
		(layer "In7.Cu")
		(net "LED_POSTCODE_0")
	)
	(segment
		(start 49.719484 -49.77003)
		(end 45.696378 -49.77003)
		(width 0.10668)
		(layer "In7.Cu")
		(net "LED_POSTCODE_0")
	)
	(segment
		(start 49.958752 -49.530762)
		(end 49.719484 -49.77003)
		(width 0.10668)
		(layer "In7.Cu")
		(net "LED_POSTCODE_0")
	)
	(segment
		(start 66.997072 -41.495726)
		(end 64.887348 -43.60545)
		(width 0.10668)
		(layer "In7.Cu")
		(net "LED_POSTCODE_0")
	)
	(segment
		(start 63.538608 -44.970446)
		(end 63.2968 -45.212254)
		(width 0.10668)
		(layer "In7.Cu")
		(net "LED_POSTCODE_0")
	)
	(segment
		(start 64.887348 -43.60545)
		(end 64.887348 -44.721272)
		(width 0.10668)
		(layer "In7.Cu")
		(net "LED_POSTCODE_0")
	)
	(segment
		(start 52.102258 -48.40859)
		(end 52.102258 -48.787558)
		(width 0.10668)
		(layer "In7.Cu")
		(net "LED_POSTCODE_0")
	)
	(segment
		(start 69.628512 -41.248838)
		(end 67.24396 -41.248838)
		(width 0.254)
		(layer "In7.Cu")
		(net "LED_POSTCODE_0")
	)
	(segment
		(start 67.24396 -41.248838)
		(end 66.997072 -41.495726)
		(width 0.254)
		(layer "In7.Cu")
		(net "LED_POSTCODE_0")
	)
	(segment
		(start 83.1342 -28.8798)
		(end 83.1342 -31.5722)
		(width 0.254)
		(layer "In7.Cu")
		(net "LED_POSTCODE_0")
	)
	(segment
		(start 80.536288 -35.993324)
		(end 75.964796 -35.993324)
		(width 0.254)
		(layer "In7.Cu")
		(net "LED_POSTCODE_0")
	)
	(segment
		(start 80.772 -29.7688)
		(end 80.772 -28.7782)
		(width 0.254)
		(layer "In7.Cu")
		(net "LED_POSTCODE_0")
	)
	(segment
		(start 82.6008 -28.3464)
		(end 83.1342 -28.8798)
		(width 0.254)
		(layer "In7.Cu")
		(net "LED_POSTCODE_0")
	)
	(segment
		(start 75.205336 -36.752784)
		(end 75.146408 -36.895024)
		(width 0.254)
		(layer "In7.Cu")
		(net "LED_POSTCODE_0")
	)
	(segment
		(start 75.146408 -38.894512)
		(end 73.962514 -40.078406)
		(width 0.254)
		(layer "In7.Cu")
		(net "LED_POSTCODE_0")
	)
	(segment
		(start 63.2968 -45.5676)
		(end 63.07201 -45.79239)
		(width 0.10668)
		(layer "In7.Cu")
		(net "LED_POSTCODE_0")
	)
	(via
		(at 52.86248 -92.30614)
		(size 0.6604)
		(drill 0.3302)
		(layers "F.Cu" "B.Cu")
		(net "FM_UART_SWITCH_N")
	)
	(segment
		(start 53.83022 -90.695526)
		(end 54.71668 -90.695526)
		(width 0.11684)
		(layer "B.Cu")
		(net "FM_UART_SWITCH_N")
	)
	(segment
		(start 51.93284 -91.3765)
		(end 52.86248 -92.30614)
		(width 0.11684)
		(layer "B.Cu")
		(net "FM_UART_SWITCH_N")
	)
	(segment
		(start 52.86248 -92.30614)
		(end 53.71338 -91.45524)
		(width 0.11684)
		(layer "B.Cu")
		(net "FM_UART_SWITCH_N")
	)
	(segment
		(start 53.71338 -90.812366)
		(end 53.83022 -90.695526)
		(width 0.11684)
		(layer "B.Cu")
		(net "FM_UART_SWITCH_N")
	)
	(segment
		(start 51.64455 -92.2655)
		(end 51.64455 -91.3765)
		(width 0.11684)
		(layer "B.Cu")
		(net "FM_UART_SWITCH_N")
	)
	(segment
		(start 53.71338 -91.45524)
		(end 53.71338 -90.812366)
		(width 0.11684)
		(layer "B.Cu")
		(net "FM_UART_SWITCH_N")
	)
	(segment
		(start 51.64455 -91.3765)
		(end 51.93284 -91.3765)
		(width 0.11684)
		(layer "B.Cu")
		(net "FM_UART_SWITCH_N")
	)
	(via
		(at 51.36896 -96.26092)
		(size 0.6604)
		(drill 0.3302)
		(layers "F.Cu" "B.Cu")
		(net "FM_UART_SEL_N")
	)
	(segment
		(start 57.70626 -96.26092)
		(end 51.36896 -96.26092)
		(width 0.11684)
		(layer "B.Cu")
		(net "FM_UART_SEL_N")
	)
	(segment
		(start 49.67478 -94.236286)
		(end 49.67478 -94.22638)
		(width 0.11684)
		(layer "B.Cu")
		(net "FM_UART_SEL_N")
	)
	(segment
		(start 49.67478 -94.22638)
		(end 49.62652 -94.17812)
		(width 0.11684)
		(layer "B.Cu")
		(net "FM_UART_SEL_N")
	)
	(segment
		(start 49.62652 -94.17812)
		(end 49.62652 -93.1037)
		(width 0.11684)
		(layer "B.Cu")
		(net "FM_UART_SEL_N")
	)
	(segment
		(start 51.36896 -95.92056)
		(end 49.95672 -94.50832)
		(width 0.11684)
		(layer "B.Cu")
		(net "FM_UART_SEL_N")
	)
	(segment
		(start 50.46472 -92.2655)
		(end 50.84445 -92.2655)
		(width 0.11684)
		(layer "B.Cu")
		(net "FM_UART_SEL_N")
	)
	(segment
		(start 49.95672 -94.50832)
		(end 49.946814 -94.50832)
		(width 0.11684)
		(layer "B.Cu")
		(net "FM_UART_SEL_N")
	)
	(segment
		(start 49.946814 -94.50832)
		(end 49.67478 -94.236286)
		(width 0.11684)
		(layer "B.Cu")
		(net "FM_UART_SEL_N")
	)
	(segment
		(start 58.436002 -98.11004)
		(end 58.436002 -96.990662)
		(width 0.11684)
		(layer "B.Cu")
		(net "FM_UART_SEL_N")
	)
	(segment
		(start 58.436002 -96.990662)
		(end 57.70626 -96.26092)
		(width 0.11684)
		(layer "B.Cu")
		(net "FM_UART_SEL_N")
	)
	(segment
		(start 51.36896 -96.26092)
		(end 51.36896 -95.92056)
		(width 0.11684)
		(layer "B.Cu")
		(net "FM_UART_SEL_N")
	)
	(segment
		(start 49.62652 -93.1037)
		(end 50.46472 -92.2655)
		(width 0.11684)
		(layer "B.Cu")
		(net "FM_UART_SEL_N")
	)
	(via
		(at 61.7855 -98.02622)
		(size 0.6604)
		(drill 0.3302)
		(layers "F.Cu" "B.Cu")
		(net "FM_SOL_UART_CH_SEL_R3")
	)
	(segment
		(start 61.35878 -96.60382)
		(end 61.58357 -96.37903)
		(width 0.11684)
		(layer "B.Cu")
		(net "FM_SOL_UART_CH_SEL_R3")
	)
	(segment
		(start 61.7855 -98.02622)
		(end 61.35878 -97.5995)
		(width 0.11684)
		(layer "B.Cu")
		(net "FM_SOL_UART_CH_SEL_R3")
	)
	(segment
		(start 61.10605 -99.06)
		(end 61.7855 -99.73945)
		(width 0.11684)
		(layer "B.Cu")
		(net "FM_SOL_UART_CH_SEL_R3")
	)
	(segment
		(start 61.35878 -97.5995)
		(end 61.35878 -96.60382)
		(width 0.11684)
		(layer "B.Cu")
		(net "FM_SOL_UART_CH_SEL_R3")
	)
	(segment
		(start 61.7855 -99.73945)
		(end 61.7855 -98.02622)
		(width 0.11684)
		(layer "B.Cu")
		(net "FM_SOL_UART_CH_SEL_R3")
	)
	(segment
		(start 61.58357 -96.37903)
		(end 61.58357 -96.06788)
		(width 0.11684)
		(layer "B.Cu")
		(net "FM_SOL_UART_CH_SEL_R3")
	)
	(segment
		(start 60.435998 -99.06)
		(end 61.10605 -99.06)
		(width 0.11684)
		(layer "B.Cu")
		(net "FM_SOL_UART_CH_SEL_R3")
	)
	(segment
		(start 31.5468 -97.5614)
		(end 31.75 -97.7646)
		(width 0.11684)
		(layer "F.Cu")
		(net "FM_SOL_UART_CH_SEL")
	)
	(segment
		(start 38.038786 -97.7646)
		(end 38.083998 -97.719388)
		(width 0.11684)
		(layer "F.Cu")
		(net "FM_SOL_UART_CH_SEL")
	)
	(segment
		(start 39.364158 -97.719388)
		(end 39.673022 -97.410524)
		(width 0.11684)
		(layer "F.Cu")
		(net "FM_SOL_UART_CH_SEL")
	)
	(segment
		(start 31.3182 -94.0054)
		(end 31.877 -94.5642)
		(width 0.11684)
		(layer "F.Cu")
		(net "FM_SOL_UART_CH_SEL")
	)
	(segment
		(start 31.877 -96.617282)
		(end 31.5468 -96.947482)
		(width 0.11684)
		(layer "F.Cu")
		(net "FM_SOL_UART_CH_SEL")
	)
	(segment
		(start 38.083998 -97.719388)
		(end 39.364158 -97.719388)
		(width 0.11684)
		(layer "F.Cu")
		(net "FM_SOL_UART_CH_SEL")
	)
	(segment
		(start 66.3194 -112.649)
		(end 67.85991 -114.18951)
		(width 0.11684)
		(layer "F.Cu")
		(net "FM_SOL_UART_CH_SEL")
	)
	(segment
		(start 31.75 -97.7646)
		(end 38.038786 -97.7646)
		(width 0.11684)
		(layer "F.Cu")
		(net "FM_SOL_UART_CH_SEL")
	)
	(segment
		(start 31.5468 -96.947482)
		(end 31.5468 -97.5614)
		(width 0.11684)
		(layer "F.Cu")
		(net "FM_SOL_UART_CH_SEL")
	)
	(segment
		(start 29.0322 -98.3488)
		(end 30.3022 -97.0788)
		(width 0.11684)
		(layer "F.Cu")
		(net "FM_SOL_UART_CH_SEL")
	)
	(segment
		(start 30.3022 -97.0788)
		(end 30.3022 -94.411546)
		(width 0.11684)
		(layer "F.Cu")
		(net "FM_SOL_UART_CH_SEL")
	)
	(segment
		(start 28.575 -103.14305)
		(end 28.83535 -103.14305)
		(width 0.11684)
		(layer "F.Cu")
		(net "FM_SOL_UART_CH_SEL")
	)
	(segment
		(start 28.83535 -103.14305)
		(end 29.0322 -102.9462)
		(width 0.11684)
		(layer "F.Cu")
		(net "FM_SOL_UART_CH_SEL")
	)
	(segment
		(start 31.877 -94.5642)
		(end 31.877 -96.617282)
		(width 0.11684)
		(layer "F.Cu")
		(net "FM_SOL_UART_CH_SEL")
	)
	(segment
		(start 29.0322 -102.9462)
		(end 29.0322 -98.3488)
		(width 0.11684)
		(layer "F.Cu")
		(net "FM_SOL_UART_CH_SEL")
	)
	(segment
		(start 39.673022 -97.410524)
		(end 41.403524 -97.410524)
		(width 0.11684)
		(layer "F.Cu")
		(net "FM_SOL_UART_CH_SEL")
	)
	(segment
		(start 30.708346 -94.0054)
		(end 31.3182 -94.0054)
		(width 0.11684)
		(layer "F.Cu")
		(net "FM_SOL_UART_CH_SEL")
	)
	(segment
		(start 67.85991 -114.18951)
		(end 67.85991 -118.460012)
		(width 0.11684)
		(layer "F.Cu")
		(net "FM_SOL_UART_CH_SEL")
	)
	(segment
		(start 30.3022 -94.411546)
		(end 30.708346 -94.0054)
		(width 0.11684)
		(layer "F.Cu")
		(net "FM_SOL_UART_CH_SEL")
	)
	(segment
		(start 41.403524 -97.410524)
		(end 42.037 -98.044)
		(width 0.11684)
		(layer "F.Cu")
		(net "FM_SOL_UART_CH_SEL")
	)
	(via
		(at 66.3194 -112.649)
		(size 0.508)
		(drill 0.254)
		(layers "F.Cu" "B.Cu")
		(net "FM_SOL_UART_CH_SEL")
	)
	(via
		(at 59.64301 -96.49333)
		(size 0.6604)
		(drill 0.3302)
		(layers "F.Cu" "B.Cu")
		(net "FM_SOL_UART_CH_SEL")
	)
	(via
		(at 42.037 -98.044)
		(size 0.508)
		(drill 0.254)
		(layers "F.Cu" "B.Cu")
		(net "FM_SOL_UART_CH_SEL")
	)
	(via
		(at 44.1452 -57.2516)
		(size 0.508)
		(drill 0.254)
		(layers "F.Cu" "B.Cu")
		(net "FM_SOL_UART_CH_SEL")
	)
	(via
		(at 59.3344 -95.8342)
		(size 0.508)
		(drill 0.254)
		(layers "F.Cu" "B.Cu")
		(net "FM_SOL_UART_CH_SEL")
	)
	(segment
		(start 44.1452 -56.7944)
		(end 45.0342 -55.9054)
		(width 0.11684)
		(layer "B.Cu")
		(net "FM_SOL_UART_CH_SEL")
	)
	(segment
		(start 59.64301 -96.49333)
		(end 60.35802 -96.49333)
		(width 0.11684)
		(layer "B.Cu")
		(net "FM_SOL_UART_CH_SEL")
	)
	(segment
		(start 59.3344 -96.18472)
		(end 59.64301 -96.49333)
		(width 0.11684)
		(layer "B.Cu")
		(net "FM_SOL_UART_CH_SEL")
	)
	(segment
		(start 44.1452 -57.2516)
		(end 44.1452 -56.7944)
		(width 0.11684)
		(layer "B.Cu")
		(net "FM_SOL_UART_CH_SEL")
	)
	(segment
		(start 59.3344 -95.8342)
		(end 59.3344 -96.18472)
		(width 0.11684)
		(layer "B.Cu")
		(net "FM_SOL_UART_CH_SEL")
	)
	(segment
		(start 45.0342 -55.9054)
		(end 45.0342 -55.84825)
		(width 0.11684)
		(layer "B.Cu")
		(net "FM_SOL_UART_CH_SEL")
	)
	(segment
		(start 60.35802 -96.49333)
		(end 60.78347 -96.06788)
		(width 0.11684)
		(layer "B.Cu")
		(net "FM_SOL_UART_CH_SEL")
	)
	(segment
		(start 48.75276 -95.45066)
		(end 55.44566 -95.45066)
		(width 0.08382)
		(layer "In2.Cu")
		(net "FM_SOL_UART_CH_SEL")
	)
	(segment
		(start 48.5775 -95.2754)
		(end 48.75276 -95.45066)
		(width 0.08382)
		(layer "In2.Cu")
		(net "FM_SOL_UART_CH_SEL")
	)
	(segment
		(start 55.44566 -95.45066)
		(end 55.8292 -95.8342)
		(width 0.08382)
		(layer "In2.Cu")
		(net "FM_SOL_UART_CH_SEL")
	)
	(segment
		(start 44.8056 -95.2754)
		(end 48.5775 -95.2754)
		(width 0.08382)
		(layer "In2.Cu")
		(net "FM_SOL_UART_CH_SEL")
	)
	(segment
		(start 55.8292 -95.8342)
		(end 59.3344 -95.8342)
		(width 0.08382)
		(layer "In2.Cu")
		(net "FM_SOL_UART_CH_SEL")
	)
	(segment
		(start 42.037 -98.044)
		(end 44.8056 -95.2754)
		(width 0.08382)
		(layer "In2.Cu")
		(net "FM_SOL_UART_CH_SEL")
	)
	(segment
		(start 44.21632 -89.48928)
		(end 44.2214 -89.4842)
		(width 0.10668)
		(layer "In4.Cu")
		(net "FM_SOL_UART_CH_SEL")
	)
	(segment
		(start 42.5704 -97.5106)
		(end 42.5704 -97.154746)
		(width 0.10668)
		(layer "In4.Cu")
		(net "FM_SOL_UART_CH_SEL")
	)
	(segment
		(start 42.037 -98.044)
		(end 42.5704 -97.5106)
		(width 0.10668)
		(layer "In4.Cu")
		(net "FM_SOL_UART_CH_SEL")
	)
	(segment
		(start 43.66006 -65.156842)
		(end 43.66006 -57.98566)
		(width 0.10668)
		(layer "In4.Cu")
		(net "FM_SOL_UART_CH_SEL")
	)
	(segment
		(start 43.836336 -57.560464)
		(end 44.1452 -57.2516)
		(width 0.10668)
		(layer "In4.Cu")
		(net "FM_SOL_UART_CH_SEL")
	)
	(segment
		(start 44.2214 -81.560162)
		(end 43.98518 -81.323942)
		(width 0.10668)
		(layer "In4.Cu")
		(net "FM_SOL_UART_CH_SEL")
	)
	(segment
		(start 43.66006 -57.98566)
		(end 43.836336 -57.560464)
		(width 0.10668)
		(layer "In4.Cu")
		(net "FM_SOL_UART_CH_SEL")
	)
	(segment
		(start 43.98518 -80.445356)
		(end 43.22318 -79.683356)
		(width 0.10668)
		(layer "In4.Cu")
		(net "FM_SOL_UART_CH_SEL")
	)
	(segment
		(start 44.066206 -69.225922)
		(end 44.066206 -68.170552)
		(width 0.10668)
		(layer "In4.Cu")
		(net "FM_SOL_UART_CH_SEL")
	)
	(segment
		(start 43.795188 -78.480666)
		(end 43.795188 -77.109828)
		(width 0.10668)
		(layer "In4.Cu")
		(net "FM_SOL_UART_CH_SEL")
	)
	(segment
		(start 45.0088 -67.227958)
		(end 45.0088 -66.505582)
		(width 0.10668)
		(layer "In4.Cu")
		(net "FM_SOL_UART_CH_SEL")
	)
	(segment
		(start 44.654978 -76.250038)
		(end 44.654978 -69.814694)
		(width 0.10668)
		(layer "In4.Cu")
		(net "FM_SOL_UART_CH_SEL")
	)
	(segment
		(start 44.066206 -68.170552)
		(end 45.0088 -67.227958)
		(width 0.10668)
		(layer "In4.Cu")
		(net "FM_SOL_UART_CH_SEL")
	)
	(segment
		(start 43.98518 -81.323942)
		(end 43.98518 -80.445356)
		(width 0.10668)
		(layer "In4.Cu")
		(net "FM_SOL_UART_CH_SEL")
	)
	(segment
		(start 43.795188 -77.109828)
		(end 44.654978 -76.250038)
		(width 0.10668)
		(layer "In4.Cu")
		(net "FM_SOL_UART_CH_SEL")
	)
	(segment
		(start 43.22318 -79.052674)
		(end 43.795188 -78.480666)
		(width 0.10668)
		(layer "In4.Cu")
		(net "FM_SOL_UART_CH_SEL")
	)
	(segment
		(start 44.21632 -95.508826)
		(end 44.21632 -89.48928)
		(width 0.10668)
		(layer "In4.Cu")
		(net "FM_SOL_UART_CH_SEL")
	)
	(segment
		(start 42.5704 -97.154746)
		(end 44.21632 -95.508826)
		(width 0.10668)
		(layer "In4.Cu")
		(net "FM_SOL_UART_CH_SEL")
	)
	(segment
		(start 43.22318 -79.683356)
		(end 43.22318 -79.052674)
		(width 0.10668)
		(layer "In4.Cu")
		(net "FM_SOL_UART_CH_SEL")
	)
	(segment
		(start 44.2214 -89.4842)
		(end 44.2214 -81.560162)
		(width 0.10668)
		(layer "In4.Cu")
		(net "FM_SOL_UART_CH_SEL")
	)
	(segment
		(start 44.654978 -69.814694)
		(end 44.066206 -69.225922)
		(width 0.10668)
		(layer "In4.Cu")
		(net "FM_SOL_UART_CH_SEL")
	)
	(segment
		(start 45.0088 -66.505582)
		(end 43.66006 -65.156842)
		(width 0.10668)
		(layer "In4.Cu")
		(net "FM_SOL_UART_CH_SEL")
	)
	(segment
		(start 64.67856 -108.44276)
		(end 64.67856 -104.104694)
		(width 0.10668)
		(layer "In7.Cu")
		(net "FM_SOL_UART_CH_SEL")
	)
	(segment
		(start 62.0268 -98.954082)
		(end 59.3344 -96.261682)
		(width 0.10668)
		(layer "In7.Cu")
		(net "FM_SOL_UART_CH_SEL")
	)
	(segment
		(start 64.67856 -104.104694)
		(end 62.0268 -101.452934)
		(width 0.10668)
		(layer "In7.Cu")
		(net "FM_SOL_UART_CH_SEL")
	)
	(segment
		(start 66.01206 -112.34166)
		(end 66.01206 -109.77626)
		(width 0.10668)
		(layer "In7.Cu")
		(net "FM_SOL_UART_CH_SEL")
	)
	(segment
		(start 59.3344 -96.261682)
		(end 59.3344 -95.8342)
		(width 0.10668)
		(layer "In7.Cu")
		(net "FM_SOL_UART_CH_SEL")
	)
	(segment
		(start 66.01206 -109.77626)
		(end 64.67856 -108.44276)
		(width 0.10668)
		(layer "In7.Cu")
		(net "FM_SOL_UART_CH_SEL")
	)
	(segment
		(start 62.0268 -101.452934)
		(end 62.0268 -98.954082)
		(width 0.10668)
		(layer "In7.Cu")
		(net "FM_SOL_UART_CH_SEL")
	)
	(segment
		(start 66.3194 -112.649)
		(end 66.01206 -112.34166)
		(width 0.10668)
		(layer "In7.Cu")
		(net "FM_SOL_UART_CH_SEL")
	)
	(via
		(at 52.9209 -91.02598)
		(size 0.6604)
		(drill 0.3302)
		(layers "F.Cu" "B.Cu")
		(net "FM_SLPS3_GF_R2_N")
	)
	(segment
		(start 52.9209 -91.02598)
		(end 52.18303 -91.02598)
		(width 0.11684)
		(layer "B.Cu")
		(net "FM_SLPS3_GF_R2_N")
	)
	(segment
		(start 54.71668 -90.04554)
		(end 53.90134 -90.04554)
		(width 0.11684)
		(layer "B.Cu")
		(net "FM_SLPS3_GF_R2_N")
	)
	(segment
		(start 52.18303 -91.02598)
		(end 51.64455 -90.4875)
		(width 0.11684)
		(layer "B.Cu")
		(net "FM_SLPS3_GF_R2_N")
	)
	(segment
		(start 53.90134 -90.04554)
		(end 52.9209 -91.02598)
		(width 0.11684)
		(layer "B.Cu")
		(net "FM_SLPS3_GF_R2_N")
	)
	(segment
		(start 53.695092 -56.171338)
		(end 53.299868 -56.566562)
		(width 0.11684)
		(layer "F.Cu")
		(net "FM_SLPS3_GF_R1_N")
	)
	(via
		(at 53.299868 -56.566562)
		(size 0.4572)
		(drill 0.254)
		(layers "F.Cu" "B.Cu")
		(net "FM_SLPS3_GF_R1_N")
	)
	(via
		(at 13.448792 -50.9778)
		(size 0.508)
		(drill 0.254)
		(layers "F.Cu" "B.Cu")
		(net "FM_SLPS3_GF_R1_N")
	)
	(segment
		(start 53.774086 -60.357512)
		(end 53.954934 -60.176664)
		(width 0.11684)
		(layer "B.Cu")
		(net "FM_SLPS3_GF_R1_N")
	)
	(segment
		(start 53.715412 -62.133988)
		(end 53.715412 -60.49899)
		(width 0.11684)
		(layer "B.Cu")
		(net "FM_SLPS3_GF_R1_N")
	)
	(segment
		(start 53.703728 -59.154314)
		(end 53.703728 -56.970422)
		(width 0.11684)
		(layer "B.Cu")
		(net "FM_SLPS3_GF_R1_N")
	)
	(segment
		(start 53.8734 -62.79515)
		(end 53.8734 -62.291976)
		(width 0.11684)
		(layer "B.Cu")
		(net "FM_SLPS3_GF_R1_N")
	)
	(segment
		(start 53.954934 -59.40552)
		(end 53.703728 -59.154314)
		(width 0.11684)
		(layer "B.Cu")
		(net "FM_SLPS3_GF_R1_N")
	)
	(segment
		(start 53.703728 -56.970422)
		(end 53.299868 -56.566562)
		(width 0.11684)
		(layer "B.Cu")
		(net "FM_SLPS3_GF_R1_N")
	)
	(segment
		(start 53.715412 -60.49899)
		(end 53.774086 -60.357512)
		(width 0.11684)
		(layer "B.Cu")
		(net "FM_SLPS3_GF_R1_N")
	)
	(segment
		(start 53.954934 -60.176664)
		(end 53.954934 -59.40552)
		(width 0.11684)
		(layer "B.Cu")
		(net "FM_SLPS3_GF_R1_N")
	)
	(segment
		(start 53.8734 -62.291976)
		(end 53.715412 -62.133988)
		(width 0.11684)
		(layer "B.Cu")
		(net "FM_SLPS3_GF_R1_N")
	)
	(segment
		(start 14.732 -50.9778)
		(end 15.5829 -51.8287)
		(width 0.08382)
		(layer "In2.Cu")
		(net "FM_SLPS3_GF_R1_N")
	)
	(segment
		(start 46.482 -46.7614)
		(end 46.482 -47.15256)
		(width 0.08382)
		(layer "In2.Cu")
		(net "FM_SLPS3_GF_R1_N")
	)
	(segment
		(start 46.26864 -46.54804)
		(end 46.482 -46.7614)
		(width 0.08382)
		(layer "In2.Cu")
		(net "FM_SLPS3_GF_R1_N")
	)
	(segment
		(start 53.299868 -55.859426)
		(end 53.299868 -56.566562)
		(width 0.08382)
		(layer "In2.Cu")
		(net "FM_SLPS3_GF_R1_N")
	)
	(segment
		(start 30.63748 -47.00651)
		(end 31.583376 -47.952406)
		(width 0.08382)
		(layer "In2.Cu")
		(net "FM_SLPS3_GF_R1_N")
	)
	(segment
		(start 49.646586 -53.81244)
		(end 50.65395 -54.819804)
		(width 0.08382)
		(layer "In2.Cu")
		(net "FM_SLPS3_GF_R1_N")
	)
	(segment
		(start 15.5829 -51.8287)
		(end 17.8435 -51.8287)
		(width 0.08382)
		(layer "In2.Cu")
		(net "FM_SLPS3_GF_R1_N")
	)
	(segment
		(start 50.65395 -54.819804)
		(end 52.260246 -54.819804)
		(width 0.08382)
		(layer "In2.Cu")
		(net "FM_SLPS3_GF_R1_N")
	)
	(segment
		(start 23.235412 -49.404016)
		(end 23.235412 -45.132244)
		(width 0.08382)
		(layer "In2.Cu")
		(net "FM_SLPS3_GF_R1_N")
	)
	(segment
		(start 38.9636 -49.1744)
		(end 40.2336 -47.9044)
		(width 0.08382)
		(layer "In2.Cu")
		(net "FM_SLPS3_GF_R1_N")
	)
	(segment
		(start 44.79036 -46.54804)
		(end 46.26864 -46.54804)
		(width 0.08382)
		(layer "In2.Cu")
		(net "FM_SLPS3_GF_R1_N")
	)
	(segment
		(start 30.63748 -44.984416)
		(end 30.63748 -47.00651)
		(width 0.08382)
		(layer "In2.Cu")
		(net "FM_SLPS3_GF_R1_N")
	)
	(segment
		(start 25.599136 -42.76852)
		(end 28.421584 -42.76852)
		(width 0.08382)
		(layer "In2.Cu")
		(net "FM_SLPS3_GF_R1_N")
	)
	(segment
		(start 31.583376 -47.952406)
		(end 35.924998 -47.952406)
		(width 0.08382)
		(layer "In2.Cu")
		(net "FM_SLPS3_GF_R1_N")
	)
	(segment
		(start 36.584636 -48.612044)
		(end 37.94252 -49.1744)
		(width 0.08382)
		(layer "In2.Cu")
		(net "FM_SLPS3_GF_R1_N")
	)
	(segment
		(start 37.94252 -49.1744)
		(end 38.9636 -49.1744)
		(width 0.08382)
		(layer "In2.Cu")
		(net "FM_SLPS3_GF_R1_N")
	)
	(segment
		(start 42.56024 -47.38116)
		(end 43.95724 -47.38116)
		(width 0.08382)
		(layer "In2.Cu")
		(net "FM_SLPS3_GF_R1_N")
	)
	(segment
		(start 47.43196 -47.38116)
		(end 48.2346 -48.1838)
		(width 0.08382)
		(layer "In2.Cu")
		(net "FM_SLPS3_GF_R1_N")
	)
	(segment
		(start 49.1236 -49.337722)
		(end 49.646586 -49.860708)
		(width 0.08382)
		(layer "In2.Cu")
		(net "FM_SLPS3_GF_R1_N")
	)
	(segment
		(start 49.646586 -49.860708)
		(end 49.646586 -53.81244)
		(width 0.08382)
		(layer "In2.Cu")
		(net "FM_SLPS3_GF_R1_N")
	)
	(segment
		(start 52.260246 -54.819804)
		(end 53.299868 -55.859426)
		(width 0.08382)
		(layer "In2.Cu")
		(net "FM_SLPS3_GF_R1_N")
	)
	(segment
		(start 40.2336 -47.9044)
		(end 42.037 -47.9044)
		(width 0.08382)
		(layer "In2.Cu")
		(net "FM_SLPS3_GF_R1_N")
	)
	(segment
		(start 49.1236 -48.4378)
		(end 49.1236 -49.337722)
		(width 0.08382)
		(layer "In2.Cu")
		(net "FM_SLPS3_GF_R1_N")
	)
	(segment
		(start 21.144738 -51.49469)
		(end 23.235412 -49.404016)
		(width 0.08382)
		(layer "In2.Cu")
		(net "FM_SLPS3_GF_R1_N")
	)
	(segment
		(start 23.235412 -45.132244)
		(end 25.599136 -42.76852)
		(width 0.08382)
		(layer "In2.Cu")
		(net "FM_SLPS3_GF_R1_N")
	)
	(segment
		(start 46.482 -47.15256)
		(end 46.7106 -47.38116)
		(width 0.08382)
		(layer "In2.Cu")
		(net "FM_SLPS3_GF_R1_N")
	)
	(segment
		(start 48.2346 -48.1838)
		(end 48.8696 -48.1838)
		(width 0.08382)
		(layer "In2.Cu")
		(net "FM_SLPS3_GF_R1_N")
	)
	(segment
		(start 46.7106 -47.38116)
		(end 47.43196 -47.38116)
		(width 0.08382)
		(layer "In2.Cu")
		(net "FM_SLPS3_GF_R1_N")
	)
	(segment
		(start 28.421584 -42.76852)
		(end 30.63748 -44.984416)
		(width 0.08382)
		(layer "In2.Cu")
		(net "FM_SLPS3_GF_R1_N")
	)
	(segment
		(start 43.95724 -47.38116)
		(end 44.79036 -46.54804)
		(width 0.08382)
		(layer "In2.Cu")
		(net "FM_SLPS3_GF_R1_N")
	)
	(segment
		(start 42.037 -47.9044)
		(end 42.56024 -47.38116)
		(width 0.08382)
		(layer "In2.Cu")
		(net "FM_SLPS3_GF_R1_N")
	)
	(segment
		(start 13.448792 -50.9778)
		(end 14.732 -50.9778)
		(width 0.08382)
		(layer "In2.Cu")
		(net "FM_SLPS3_GF_R1_N")
	)
	(segment
		(start 35.924998 -47.952406)
		(end 36.584636 -48.612044)
		(width 0.08382)
		(layer "In2.Cu")
		(net "FM_SLPS3_GF_R1_N")
	)
	(segment
		(start 17.8435 -51.8287)
		(end 18.17751 -51.49469)
		(width 0.08382)
		(layer "In2.Cu")
		(net "FM_SLPS3_GF_R1_N")
	)
	(segment
		(start 18.17751 -51.49469)
		(end 21.144738 -51.49469)
		(width 0.08382)
		(layer "In2.Cu")
		(net "FM_SLPS3_GF_R1_N")
	)
	(segment
		(start 48.8696 -48.1838)
		(end 49.1236 -48.4378)
		(width 0.08382)
		(layer "In2.Cu")
		(net "FM_SLPS3_GF_R1_N")
	)
	(segment
		(start 85.69325 -16.764)
		(end 86.3346 -16.764)
		(width 0.11684)
		(layer "F.Cu")
		(net "FM_DEBUG_RST_BTN_N")
	)
	(via
		(at 70.503288 -89.204292)
		(size 0.508)
		(drill 0.254)
		(layers "F.Cu" "B.Cu")
		(net "FM_DEBUG_RST_BTN_N")
	)
	(via
		(at 65.289684 -84.169758)
		(size 0.6604)
		(drill 0.3302)
		(layers "F.Cu" "B.Cu")
		(net "FM_DEBUG_RST_BTN_N")
	)
	(via
		(at 88.1634 -79.6798)
		(size 0.508)
		(drill 0.254)
		(layers "F.Cu" "B.Cu")
		(net "FM_DEBUG_RST_BTN_N")
	)
	(via
		(at 86.3346 -16.764)
		(size 0.508)
		(drill 0.254)
		(layers "F.Cu" "B.Cu")
		(net "FM_DEBUG_RST_BTN_N")
	)
	(segment
		(start 69.977 -88.678004)
		(end 69.977 -87.092536)
		(width 0.11684)
		(layer "B.Cu")
		(net "FM_DEBUG_RST_BTN_N")
	)
	(segment
		(start 87.1982 -17.6276)
		(end 86.3346 -16.764)
		(width 0.11684)
		(layer "B.Cu")
		(net "FM_DEBUG_RST_BTN_N")
	)
	(segment
		(start 88.6333 -79.2099)
		(end 88.6333 -22.0599)
		(width 0.11684)
		(layer "B.Cu")
		(net "FM_DEBUG_RST_BTN_N")
	)
	(segment
		(start 65.289684 -84.169758)
		(end 63.785242 -85.6742)
		(width 0.11684)
		(layer "B.Cu")
		(net "FM_DEBUG_RST_BTN_N")
	)
	(segment
		(start 88.1634 -79.6798)
		(end 88.6333 -79.2099)
		(width 0.11684)
		(layer "B.Cu")
		(net "FM_DEBUG_RST_BTN_N")
	)
	(segment
		(start 63.785242 -85.6742)
		(end 58.440828 -85.6742)
		(width 0.11684)
		(layer "B.Cu")
		(net "FM_DEBUG_RST_BTN_N")
	)
	(segment
		(start 67.054222 -84.169758)
		(end 65.289684 -84.169758)
		(width 0.11684)
		(layer "B.Cu")
		(net "FM_DEBUG_RST_BTN_N")
	)
	(segment
		(start 55.35803 -86.14537)
		(end 54.71668 -86.14537)
		(width 0.11684)
		(layer "B.Cu")
		(net "FM_DEBUG_RST_BTN_N")
	)
	(segment
		(start 58.440828 -85.6742)
		(end 57.436258 -84.66963)
		(width 0.11684)
		(layer "B.Cu")
		(net "FM_DEBUG_RST_BTN_N")
	)
	(segment
		(start 70.503288 -89.204292)
		(end 69.977 -88.678004)
		(width 0.11684)
		(layer "B.Cu")
		(net "FM_DEBUG_RST_BTN_N")
	)
	(segment
		(start 88.6333 -22.0599)
		(end 87.1982 -20.6248)
		(width 0.11684)
		(layer "B.Cu")
		(net "FM_DEBUG_RST_BTN_N")
	)
	(segment
		(start 69.977 -87.092536)
		(end 67.054222 -84.169758)
		(width 0.11684)
		(layer "B.Cu")
		(net "FM_DEBUG_RST_BTN_N")
	)
	(segment
		(start 87.1982 -20.6248)
		(end 87.1982 -17.6276)
		(width 0.11684)
		(layer "B.Cu")
		(net "FM_DEBUG_RST_BTN_N")
	)
	(segment
		(start 57.436258 -84.66963)
		(end 56.83377 -84.66963)
		(width 0.11684)
		(layer "B.Cu")
		(net "FM_DEBUG_RST_BTN_N")
	)
	(segment
		(start 56.83377 -84.66963)
		(end 55.35803 -86.14537)
		(width 0.11684)
		(layer "B.Cu")
		(net "FM_DEBUG_RST_BTN_N")
	)
	(segment
		(start 85.3694 -81.435956)
		(end 87.125556 -79.6798)
		(width 0.10668)
		(layer "In7.Cu")
		(net "FM_DEBUG_RST_BTN_N")
	)
	(segment
		(start 71.882 -99.656138)
		(end 72.009 -99.783138)
		(width 0.10668)
		(layer "In7.Cu")
		(net "FM_DEBUG_RST_BTN_N")
	)
	(segment
		(start 71.5518 -98.165412)
		(end 71.882 -98.962718)
		(width 0.10668)
		(layer "In7.Cu")
		(net "FM_DEBUG_RST_BTN_N")
	)
	(segment
		(start 71.431658 -95.910908)
		(end 71.5518 -96.03105)
		(width 0.10668)
		(layer "In7.Cu")
		(net "FM_DEBUG_RST_BTN_N")
	)
	(segment
		(start 83.7946 -95.4278)
		(end 83.7946 -91.4654)
		(width 0.10668)
		(layer "In7.Cu")
		(net "FM_DEBUG_RST_BTN_N")
	)
	(segment
		(start 87.125556 -79.6798)
		(end 88.1634 -79.6798)
		(width 0.10668)
		(layer "In7.Cu")
		(net "FM_DEBUG_RST_BTN_N")
	)
	(segment
		(start 83.7946 -91.4654)
		(end 85.3694 -89.8906)
		(width 0.10668)
		(layer "In7.Cu")
		(net "FM_DEBUG_RST_BTN_N")
	)
	(segment
		(start 71.431658 -92.208604)
		(end 71.431658 -95.910908)
		(width 0.10668)
		(layer "In7.Cu")
		(net "FM_DEBUG_RST_BTN_N")
	)
	(segment
		(start 73.69683 -99.783138)
		(end 74.294492 -100.3808)
		(width 0.10668)
		(layer "In7.Cu")
		(net "FM_DEBUG_RST_BTN_N")
	)
	(segment
		(start 71.5518 -96.03105)
		(end 71.5518 -98.165412)
		(width 0.10668)
		(layer "In7.Cu")
		(net "FM_DEBUG_RST_BTN_N")
	)
	(segment
		(start 71.3486 -92.125546)
		(end 71.431658 -92.208604)
		(width 0.10668)
		(layer "In7.Cu")
		(net "FM_DEBUG_RST_BTN_N")
	)
	(segment
		(start 71.3486 -90.24239)
		(end 71.3486 -92.125546)
		(width 0.10668)
		(layer "In7.Cu")
		(net "FM_DEBUG_RST_BTN_N")
	)
	(segment
		(start 70.503288 -89.204292)
		(end 70.503288 -89.397078)
		(width 0.10668)
		(layer "In7.Cu")
		(net "FM_DEBUG_RST_BTN_N")
	)
	(segment
		(start 85.3694 -89.8906)
		(end 85.3694 -81.435956)
		(width 0.10668)
		(layer "In7.Cu")
		(net "FM_DEBUG_RST_BTN_N")
	)
	(segment
		(start 77.3684 -100.3808)
		(end 79.154274 -98.594926)
		(width 0.10668)
		(layer "In7.Cu")
		(net "FM_DEBUG_RST_BTN_N")
	)
	(segment
		(start 74.294492 -100.3808)
		(end 77.3684 -100.3808)
		(width 0.10668)
		(layer "In7.Cu")
		(net "FM_DEBUG_RST_BTN_N")
	)
	(segment
		(start 83.1596 -96.0628)
		(end 83.7946 -95.4278)
		(width 0.10668)
		(layer "In7.Cu")
		(net "FM_DEBUG_RST_BTN_N")
	)
	(segment
		(start 72.009 -99.783138)
		(end 73.69683 -99.783138)
		(width 0.10668)
		(layer "In7.Cu")
		(net "FM_DEBUG_RST_BTN_N")
	)
	(segment
		(start 79.154274 -98.594926)
		(end 80.357726 -98.594926)
		(width 0.10668)
		(layer "In7.Cu")
		(net "FM_DEBUG_RST_BTN_N")
	)
	(segment
		(start 82.889852 -96.0628)
		(end 83.1596 -96.0628)
		(width 0.10668)
		(layer "In7.Cu")
		(net "FM_DEBUG_RST_BTN_N")
	)
	(segment
		(start 80.357726 -98.594926)
		(end 82.889852 -96.0628)
		(width 0.10668)
		(layer "In7.Cu")
		(net "FM_DEBUG_RST_BTN_N")
	)
	(segment
		(start 70.503288 -89.397078)
		(end 71.3486 -90.24239)
		(width 0.10668)
		(layer "In7.Cu")
		(net "FM_DEBUG_RST_BTN_N")
	)
	(segment
		(start 71.882 -98.962718)
		(end 71.882 -99.656138)
		(width 0.10668)
		(layer "In7.Cu")
		(net "FM_DEBUG_RST_BTN_N")
	)
	(segment
		(start 14.312392 -9.19734)
		(end 14.002512 -9.19734)
		(width 0.11684)
		(layer "F.Cu")
		(net "FM_DEBUG_PWR_BTN_N")
	)
	(segment
		(start 14.002512 -9.19734)
		(end 13.662914 -8.857742)
		(width 0.11684)
		(layer "F.Cu")
		(net "FM_DEBUG_PWR_BTN_N")
	)
	(via
		(at 28.6512 -15.3416)
		(size 0.508)
		(drill 0.254)
		(layers "F.Cu" "B.Cu")
		(net "FM_DEBUG_PWR_BTN_N")
	)
	(via
		(at 14.312392 -9.19734)
		(size 0.508)
		(drill 0.254)
		(layers "F.Cu" "B.Cu")
		(net "FM_DEBUG_PWR_BTN_N")
	)
	(via
		(at 30.147768 -34.875216)
		(size 0.508)
		(drill 0.254)
		(layers "F.Cu" "B.Cu")
		(net "FM_DEBUG_PWR_BTN_N")
	)
	(via
		(at 56.134 -89.408)
		(size 0.508)
		(drill 0.254)
		(layers "F.Cu" "B.Cu")
		(net "FM_DEBUG_PWR_BTN_N")
	)
	(via
		(at 37.973 -90.6018)
		(size 0.508)
		(drill 0.254)
		(layers "F.Cu" "B.Cu")
		(net "FM_DEBUG_PWR_BTN_N")
	)
	(segment
		(start 56.134 -89.408)
		(end 56.7182 -88.8238)
		(width 0.11684)
		(layer "B.Cu")
		(net "FM_DEBUG_PWR_BTN_N")
	)
	(segment
		(start 56.7182 -86.91245)
		(end 56.36895 -86.5632)
		(width 0.11684)
		(layer "B.Cu")
		(net "FM_DEBUG_PWR_BTN_N")
	)
	(segment
		(start 55.622444 -86.795356)
		(end 54.71668 -86.795356)
		(width 0.11684)
		(layer "B.Cu")
		(net "FM_DEBUG_PWR_BTN_N")
	)
	(segment
		(start 55.8546 -86.5632)
		(end 55.622444 -86.795356)
		(width 0.11684)
		(layer "B.Cu")
		(net "FM_DEBUG_PWR_BTN_N")
	)
	(segment
		(start 56.7182 -88.8238)
		(end 56.7182 -86.91245)
		(width 0.11684)
		(layer "B.Cu")
		(net "FM_DEBUG_PWR_BTN_N")
	)
	(segment
		(start 56.36895 -86.5632)
		(end 55.8546 -86.5632)
		(width 0.11684)
		(layer "B.Cu")
		(net "FM_DEBUG_PWR_BTN_N")
	)
	(segment
		(start 51.445668 -87.34298)
		(end 49.083214 -87.34298)
		(width 0.08382)
		(layer "In2.Cu")
		(net "FM_DEBUG_PWR_BTN_N")
	)
	(segment
		(start 12.954 -10.392156)
		(end 14.148816 -9.19734)
		(width 0.08382)
		(layer "In2.Cu")
		(net "FM_DEBUG_PWR_BTN_N")
	)
	(segment
		(start 14.3764 -14.5288)
		(end 12.954 -13.1064)
		(width 0.08382)
		(layer "In2.Cu")
		(net "FM_DEBUG_PWR_BTN_N")
	)
	(segment
		(start 14.148816 -9.19734)
		(end 14.312392 -9.19734)
		(width 0.08382)
		(layer "In2.Cu")
		(net "FM_DEBUG_PWR_BTN_N")
	)
	(segment
		(start 38.11651 -90.45829)
		(end 37.973 -90.6018)
		(width 0.08382)
		(layer "In2.Cu")
		(net "FM_DEBUG_PWR_BTN_N")
	)
	(segment
		(start 12.954 -13.1064)
		(end 12.954 -10.392156)
		(width 0.08382)
		(layer "In2.Cu")
		(net "FM_DEBUG_PWR_BTN_N")
	)
	(segment
		(start 28.6512 -15.3416)
		(end 27.8384 -14.5288)
		(width 0.08382)
		(layer "In2.Cu")
		(net "FM_DEBUG_PWR_BTN_N")
	)
	(segment
		(start 53.510688 -89.408)
		(end 51.445668 -87.34298)
		(width 0.08382)
		(layer "In2.Cu")
		(net "FM_DEBUG_PWR_BTN_N")
	)
	(segment
		(start 47.68342 -87.39378)
		(end 47.68342 -88.00338)
		(width 0.08382)
		(layer "In2.Cu")
		(net "FM_DEBUG_PWR_BTN_N")
	)
	(segment
		(start 47.68342 -88.00338)
		(end 43.6626 -92.0242)
		(width 0.08382)
		(layer "In2.Cu")
		(net "FM_DEBUG_PWR_BTN_N")
	)
	(segment
		(start 38.716458 -90.45829)
		(end 38.11651 -90.45829)
		(width 0.08382)
		(layer "In2.Cu")
		(net "FM_DEBUG_PWR_BTN_N")
	)
	(segment
		(start 48.776128 -87.035894)
		(end 48.041306 -87.035894)
		(width 0.08382)
		(layer "In2.Cu")
		(net "FM_DEBUG_PWR_BTN_N")
	)
	(segment
		(start 27.8384 -14.5288)
		(end 14.3764 -14.5288)
		(width 0.08382)
		(layer "In2.Cu")
		(net "FM_DEBUG_PWR_BTN_N")
	)
	(segment
		(start 40.282368 -92.0242)
		(end 38.716458 -90.45829)
		(width 0.08382)
		(layer "In2.Cu")
		(net "FM_DEBUG_PWR_BTN_N")
	)
	(segment
		(start 56.134 -89.408)
		(end 53.510688 -89.408)
		(width 0.08382)
		(layer "In2.Cu")
		(net "FM_DEBUG_PWR_BTN_N")
	)
	(segment
		(start 49.083214 -87.34298)
		(end 48.776128 -87.035894)
		(width 0.08382)
		(layer "In2.Cu")
		(net "FM_DEBUG_PWR_BTN_N")
	)
	(segment
		(start 43.6626 -92.0242)
		(end 40.282368 -92.0242)
		(width 0.08382)
		(layer "In2.Cu")
		(net "FM_DEBUG_PWR_BTN_N")
	)
	(segment
		(start 48.041306 -87.035894)
		(end 47.68342 -87.39378)
		(width 0.08382)
		(layer "In2.Cu")
		(net "FM_DEBUG_PWR_BTN_N")
	)
	(segment
		(start 28.83154 -77.67701)
		(end 28.83154 -80.311752)
		(width 0.10668)
		(layer "In7.Cu")
		(net "FM_DEBUG_PWR_BTN_N")
	)
	(segment
		(start 31.26232 -85.928454)
		(end 31.574486 -86.24062)
		(width 0.10668)
		(layer "In7.Cu")
		(net "FM_DEBUG_PWR_BTN_N")
	)
	(segment
		(start 33.06318 -86.946232)
		(end 33.06318 -89.29878)
		(width 0.10668)
		(layer "In7.Cu")
		(net "FM_DEBUG_PWR_BTN_N")
	)
	(segment
		(start 27.94 -38.809676)
		(end 22.69236 -44.057316)
		(width 0.10668)
		(layer "In7.Cu")
		(net "FM_DEBUG_PWR_BTN_N")
	)
	(segment
		(start 21.27504 -52.362862)
		(end 21.27504 -56.970168)
		(width 0.10668)
		(layer "In7.Cu")
		(net "FM_DEBUG_PWR_BTN_N")
	)
	(segment
		(start 33.2486 -89.4842)
		(end 36.8554 -89.4842)
		(width 0.10668)
		(layer "In7.Cu")
		(net "FM_DEBUG_PWR_BTN_N")
	)
	(segment
		(start 26.7081 -74.106024)
		(end 26.7081 -75.55357)
		(width 0.10668)
		(layer "In7.Cu")
		(net "FM_DEBUG_PWR_BTN_N")
	)
	(segment
		(start 26.046176 -73.4441)
		(end 26.7081 -74.106024)
		(width 0.10668)
		(layer "In7.Cu")
		(net "FM_DEBUG_PWR_BTN_N")
	)
	(segment
		(start 31.26232 -83.820254)
		(end 31.26232 -85.928454)
		(width 0.10668)
		(layer "In7.Cu")
		(net "FM_DEBUG_PWR_BTN_N")
	)
	(segment
		(start 23.37308 -62.58052)
		(end 23.98522 -63.19266)
		(width 0.10668)
		(layer "In7.Cu")
		(net "FM_DEBUG_PWR_BTN_N")
	)
	(segment
		(start 23.98522 -63.19266)
		(end 23.98522 -65.922398)
		(width 0.10668)
		(layer "In7.Cu")
		(net "FM_DEBUG_PWR_BTN_N")
	)
	(segment
		(start 30.147768 -36.044378)
		(end 27.94 -38.252146)
		(width 0.10668)
		(layer "In7.Cu")
		(net "FM_DEBUG_PWR_BTN_N")
	)
	(segment
		(start 30.147768 -34.875216)
		(end 30.147768 -36.044378)
		(width 0.10668)
		(layer "In7.Cu")
		(net "FM_DEBUG_PWR_BTN_N")
	)
	(segment
		(start 22.69236 -44.057316)
		(end 21.9075 -45.952156)
		(width 0.10668)
		(layer "In7.Cu")
		(net "FM_DEBUG_PWR_BTN_N")
	)
	(segment
		(start 23.628858 -67.320414)
		(end 24.22652 -67.918076)
		(width 0.10668)
		(layer "In7.Cu")
		(net "FM_DEBUG_PWR_BTN_N")
	)
	(segment
		(start 31.574486 -86.24062)
		(end 32.357568 -86.24062)
		(width 0.10668)
		(layer "In7.Cu")
		(net "FM_DEBUG_PWR_BTN_N")
	)
	(segment
		(start 26.7081 -75.55357)
		(end 28.83154 -77.67701)
		(width 0.10668)
		(layer "In7.Cu")
		(net "FM_DEBUG_PWR_BTN_N")
	)
	(segment
		(start 28.83154 -80.311752)
		(end 30.0228 -81.503012)
		(width 0.10668)
		(layer "In7.Cu")
		(net "FM_DEBUG_PWR_BTN_N")
	)
	(segment
		(start 23.628858 -66.27876)
		(end 23.628858 -67.320414)
		(width 0.10668)
		(layer "In7.Cu")
		(net "FM_DEBUG_PWR_BTN_N")
	)
	(segment
		(start 23.37308 -59.068208)
		(end 23.37308 -62.58052)
		(width 0.10668)
		(layer "In7.Cu")
		(net "FM_DEBUG_PWR_BTN_N")
	)
	(segment
		(start 24.22652 -71.224902)
		(end 24.2824 -71.280782)
		(width 0.10668)
		(layer "In7.Cu")
		(net "FM_DEBUG_PWR_BTN_N")
	)
	(segment
		(start 23.98522 -65.922398)
		(end 23.628858 -66.27876)
		(width 0.10668)
		(layer "In7.Cu")
		(net "FM_DEBUG_PWR_BTN_N")
	)
	(segment
		(start 36.8554 -89.4842)
		(end 37.973 -90.6018)
		(width 0.10668)
		(layer "In7.Cu")
		(net "FM_DEBUG_PWR_BTN_N")
	)
	(segment
		(start 30.0228 -82.580734)
		(end 31.26232 -83.820254)
		(width 0.10668)
		(layer "In7.Cu")
		(net "FM_DEBUG_PWR_BTN_N")
	)
	(segment
		(start 21.9075 -45.952156)
		(end 21.9075 -51.730402)
		(width 0.10668)
		(layer "In7.Cu")
		(net "FM_DEBUG_PWR_BTN_N")
	)
	(segment
		(start 32.357568 -86.24062)
		(end 33.06318 -86.946232)
		(width 0.10668)
		(layer "In7.Cu")
		(net "FM_DEBUG_PWR_BTN_N")
	)
	(segment
		(start 24.2824 -71.280782)
		(end 24.2824 -72.214994)
		(width 0.10668)
		(layer "In7.Cu")
		(net "FM_DEBUG_PWR_BTN_N")
	)
	(segment
		(start 30.0228 -81.503012)
		(end 30.0228 -82.580734)
		(width 0.10668)
		(layer "In7.Cu")
		(net "FM_DEBUG_PWR_BTN_N")
	)
	(segment
		(start 24.22652 -67.918076)
		(end 24.22652 -71.224902)
		(width 0.10668)
		(layer "In7.Cu")
		(net "FM_DEBUG_PWR_BTN_N")
	)
	(segment
		(start 27.94 -38.252146)
		(end 27.94 -38.809676)
		(width 0.10668)
		(layer "In7.Cu")
		(net "FM_DEBUG_PWR_BTN_N")
	)
	(segment
		(start 21.27504 -56.970168)
		(end 23.37308 -59.068208)
		(width 0.10668)
		(layer "In7.Cu")
		(net "FM_DEBUG_PWR_BTN_N")
	)
	(segment
		(start 24.2824 -72.214994)
		(end 25.511506 -73.4441)
		(width 0.10668)
		(layer "In7.Cu")
		(net "FM_DEBUG_PWR_BTN_N")
	)
	(segment
		(start 25.511506 -73.4441)
		(end 26.046176 -73.4441)
		(width 0.10668)
		(layer "In7.Cu")
		(net "FM_DEBUG_PWR_BTN_N")
	)
	(segment
		(start 21.9075 -51.730402)
		(end 21.27504 -52.362862)
		(width 0.10668)
		(layer "In7.Cu")
		(net "FM_DEBUG_PWR_BTN_N")
	)
	(segment
		(start 33.06318 -89.29878)
		(end 33.2486 -89.4842)
		(width 0.10668)
		(layer "In7.Cu")
		(net "FM_DEBUG_PWR_BTN_N")
	)
	(segment
		(start 28.72486 -27.49296)
		(end 29.972 -28.7401)
		(width 0.08382)
		(layer "In9.Cu")
		(net "FM_DEBUG_PWR_BTN_N")
	)
	(segment
		(start 29.14269 -21.70811)
		(end 28.72486 -22.12594)
		(width 0.08382)
		(layer "In9.Cu")
		(net "FM_DEBUG_PWR_BTN_N")
	)
	(segment
		(start 29.718 -29.717238)
		(end 29.718 -34.445448)
		(width 0.08382)
		(layer "In9.Cu")
		(net "FM_DEBUG_PWR_BTN_N")
	)
	(segment
		(start 29.972 -28.7401)
		(end 29.972 -29.463238)
		(width 0.08382)
		(layer "In9.Cu")
		(net "FM_DEBUG_PWR_BTN_N")
	)
	(segment
		(start 28.72486 -22.12594)
		(end 28.72486 -27.49296)
		(width 0.08382)
		(layer "In9.Cu")
		(net "FM_DEBUG_PWR_BTN_N")
	)
	(segment
		(start 29.718 -34.445448)
		(end 30.147768 -34.875216)
		(width 0.08382)
		(layer "In9.Cu")
		(net "FM_DEBUG_PWR_BTN_N")
	)
	(segment
		(start 28.6512 -16.5608)
		(end 29.14269 -17.05229)
		(width 0.08382)
		(layer "In9.Cu")
		(net "FM_DEBUG_PWR_BTN_N")
	)
	(segment
		(start 29.972 -29.463238)
		(end 29.718 -29.717238)
		(width 0.08382)
		(layer "In9.Cu")
		(net "FM_DEBUG_PWR_BTN_N")
	)
	(segment
		(start 29.14269 -17.05229)
		(end 29.14269 -21.70811)
		(width 0.08382)
		(layer "In9.Cu")
		(net "FM_DEBUG_PWR_BTN_N")
	)
	(segment
		(start 28.6512 -15.3416)
		(end 28.6512 -16.5608)
		(width 0.08382)
		(layer "In9.Cu")
		(net "FM_DEBUG_PWR_BTN_N")
	)
	(via
		(at 57.404 -17.272)
		(size 0.6604)
		(drill 0.3302)
		(layers "F.Cu" "B.Cu")
		(net "FM_DEBUG_PORT_R_PRSNT_N")
	)
	(segment
		(start 58.65495 -16.716248)
		(end 58.7375 -16.633698)
		(width 0.11684)
		(layer "B.Cu")
		(net "FM_DEBUG_PORT_R_PRSNT_N")
	)
	(segment
		(start 57.404 -17.272)
		(end 56.36895 -17.272)
		(width 0.11684)
		(layer "B.Cu")
		(net "FM_DEBUG_PORT_R_PRSNT_N")
	)
	(segment
		(start 58.65495 -18.034)
		(end 58.166 -18.034)
		(width 0.11684)
		(layer "B.Cu")
		(net "FM_DEBUG_PORT_R_PRSNT_N")
	)
	(segment
		(start 58.166 -18.034)
		(end 57.404 -17.272)
		(width 0.11684)
		(layer "B.Cu")
		(net "FM_DEBUG_PORT_R_PRSNT_N")
	)
	(segment
		(start 58.65495 -18.034)
		(end 58.65495 -16.716248)
		(width 0.11684)
		(layer "B.Cu")
		(net "FM_DEBUG_PORT_R_PRSNT_N")
	)
	(segment
		(start 56.36895 -17.272)
		(end 56.261 -17.16405)
		(width 0.11684)
		(layer "B.Cu")
		(net "FM_DEBUG_PORT_R_PRSNT_N")
	)
	(segment
		(start 26.3906 -111.8616)
		(end 26.3906 -113.70056)
		(width 0.11684)
		(layer "F.Cu")
		(net "FM_DEBUG_PORT_PRSNT_N")
	)
	(segment
		(start 24.52116 -109.99216)
		(end 26.3906 -111.8616)
		(width 0.11684)
		(layer "F.Cu")
		(net "FM_DEBUG_PORT_PRSNT_N")
	)
	(segment
		(start 23.495 -103.14305)
		(end 23.495 -103.79202)
		(width 0.11684)
		(layer "F.Cu")
		(net "FM_DEBUG_PORT_PRSNT_N")
	)
	(segment
		(start 22.49551 -108.33989)
		(end 22.49551 -109.99216)
		(width 0.11684)
		(layer "F.Cu")
		(net "FM_DEBUG_PORT_PRSNT_N")
	)
	(segment
		(start 22.49551 -109.99216)
		(end 24.52116 -109.99216)
		(width 0.11684)
		(layer "F.Cu")
		(net "FM_DEBUG_PORT_PRSNT_N")
	)
	(via
		(at 26.3906 -113.70056)
		(size 0.508)
		(drill 0.254)
		(layers "F.Cu" "B.Cu")
		(net "FM_DEBUG_PORT_PRSNT_N")
	)
	(via
		(at 22.49551 -109.99216)
		(size 0.762)
		(drill 0.381)
		(layers "F.Cu" "B.Cu")
		(net "FM_DEBUG_PORT_PRSNT_N")
	)
	(via
		(at 58.42 -64.9478)
		(size 0.508)
		(drill 0.254)
		(layers "F.Cu" "B.Cu")
		(net "FM_DEBUG_PORT_PRSNT_N")
	)
	(via
		(at 11.557 -23.495)
		(size 0.508)
		(drill 0.254)
		(layers "F.Cu" "B.Cu")
		(net "FM_DEBUG_PORT_PRSNT_N")
	)
	(via
		(at 11.303 -89.3064)
		(size 0.508)
		(drill 0.254)
		(layers "F.Cu" "B.Cu")
		(net "FM_DEBUG_PORT_PRSNT_N")
	)
	(via
		(at 23.495 -103.79202)
		(size 0.508)
		(drill 0.254)
		(layers "F.Cu" "B.Cu")
		(net "FM_DEBUG_PORT_PRSNT_N")
	)
	(via
		(at 57.97042 -86.37016)
		(size 0.762)
		(drill 0.254)
		(layers "F.Cu" "B.Cu")
		(net "FM_DEBUG_PORT_PRSNT_N")
	)
	(via
		(at 22.49551 -108.33989)
		(size 0.508)
		(drill 0.254)
		(layers "F.Cu" "B.Cu")
		(net "FM_DEBUG_PORT_PRSNT_N")
	)
	(via
		(at 47.5996 -25.781)
		(size 0.508)
		(drill 0.254)
		(layers "F.Cu" "B.Cu")
		(net "FM_DEBUG_PORT_PRSNT_N")
	)
	(segment
		(start 54.251606 -14.354556)
		(end 51.444144 -14.354556)
		(width 0.11684)
		(layer "B.Cu")
		(net "FM_DEBUG_PORT_PRSNT_N")
	)
	(segment
		(start 49.85766 -15.94104)
		(end 49.85766 -18.43786)
		(width 0.11684)
		(layer "B.Cu")
		(net "FM_DEBUG_PORT_PRSNT_N")
	)
	(segment
		(start 23.0632 -107.7722)
		(end 22.49551 -108.33989)
		(width 0.11684)
		(layer "B.Cu")
		(net "FM_DEBUG_PORT_PRSNT_N")
	)
	(segment
		(start 48.5902 -26.035)
		(end 47.8536 -26.035)
		(width 0.11684)
		(layer "B.Cu")
		(net "FM_DEBUG_PORT_PRSNT_N")
	)
	(segment
		(start 48.9712 -24.4094)
		(end 48.9712 -25.654)
		(width 0.11684)
		(layer "B.Cu")
		(net "FM_DEBUG_PORT_PRSNT_N")
	)
	(segment
		(start 51.816 -20.3962)
		(end 51.816 -21.5646)
		(width 0.11684)
		(layer "B.Cu")
		(net "FM_DEBUG_PORT_PRSNT_N")
	)
	(segment
		(start 51.816 -21.5646)
		(end 48.9712 -24.4094)
		(width 0.11684)
		(layer "B.Cu")
		(net "FM_DEBUG_PORT_PRSNT_N")
	)
	(segment
		(start 56.261 -16.36395)
		(end 54.251606 -14.354556)
		(width 0.11684)
		(layer "B.Cu")
		(net "FM_DEBUG_PORT_PRSNT_N")
	)
	(segment
		(start 47.8536 -26.035)
		(end 47.5996 -25.781)
		(width 0.11684)
		(layer "B.Cu")
		(net "FM_DEBUG_PORT_PRSNT_N")
	)
	(segment
		(start 58.7375 -63.63335)
		(end 58.42 -63.95085)
		(width 0.11684)
		(layer "B.Cu")
		(net "FM_DEBUG_PORT_PRSNT_N")
	)
	(segment
		(start 48.9712 -25.654)
		(end 48.5902 -26.035)
		(width 0.11684)
		(layer "B.Cu")
		(net "FM_DEBUG_PORT_PRSNT_N")
	)
	(segment
		(start 23.0632 -104.22382)
		(end 23.0632 -107.7722)
		(width 0.11684)
		(layer "B.Cu")
		(net "FM_DEBUG_PORT_PRSNT_N")
	)
	(segment
		(start 49.85766 -18.43786)
		(end 51.816 -20.3962)
		(width 0.11684)
		(layer "B.Cu")
		(net "FM_DEBUG_PORT_PRSNT_N")
	)
	(segment
		(start 58.42 -63.95085)
		(end 58.42 -64.9478)
		(width 0.11684)
		(layer "B.Cu")
		(net "FM_DEBUG_PORT_PRSNT_N")
	)
	(segment
		(start 51.444144 -14.354556)
		(end 49.85766 -15.94104)
		(width 0.11684)
		(layer "B.Cu")
		(net "FM_DEBUG_PORT_PRSNT_N")
	)
	(segment
		(start 23.495 -103.79202)
		(end 23.0632 -104.22382)
		(width 0.11684)
		(layer "B.Cu")
		(net "FM_DEBUG_PORT_PRSNT_N")
	)
	(segment
		(start 25.945338 -21.40331)
		(end 24.519128 -19.9771)
		(width 0.08382)
		(layer "In2.Cu")
		(net "FM_DEBUG_PORT_PRSNT_N")
	)
	(segment
		(start 30.322774 -21.40331)
		(end 25.945338 -21.40331)
		(width 0.08382)
		(layer "In2.Cu")
		(net "FM_DEBUG_PORT_PRSNT_N")
	)
	(segment
		(start 56.311292 -86.37016)
		(end 57.97042 -86.37016)
		(width 0.08382)
		(layer "In2.Cu")
		(net "FM_DEBUG_PORT_PRSNT_N")
	)
	(segment
		(start 20.5486 -86.5124)
		(end 21.0312 -86.5124)
		(width 0.08382)
		(layer "In2.Cu")
		(net "FM_DEBUG_PORT_PRSNT_N")
	)
	(segment
		(start 12.319 -22.733)
		(end 11.557 -23.495)
		(width 0.08382)
		(layer "In2.Cu")
		(net "FM_DEBUG_PORT_PRSNT_N")
	)
	(segment
		(start 17.9832 -87.0458)
		(end 20.0152 -87.0458)
		(width 0.08382)
		(layer "In2.Cu")
		(net "FM_DEBUG_PORT_PRSNT_N")
	)
	(segment
		(start 11.303 -89.3064)
		(end 11.69924 -89.3064)
		(width 0.08382)
		(layer "In2.Cu")
		(net "FM_DEBUG_PORT_PRSNT_N")
	)
	(segment
		(start 33.40608 -86.62416)
		(end 34.14395 -87.36203)
		(width 0.08382)
		(layer "In2.Cu")
		(net "FM_DEBUG_PORT_PRSNT_N")
	)
	(segment
		(start 36.504118 -87.36203)
		(end 38.753288 -89.6112)
		(width 0.08382)
		(layer "In2.Cu")
		(net "FM_DEBUG_PORT_PRSNT_N")
	)
	(segment
		(start 38.753288 -89.6112)
		(end 43.840146 -89.6112)
		(width 0.08382)
		(layer "In2.Cu")
		(net "FM_DEBUG_PORT_PRSNT_N")
	)
	(segment
		(start 46.806612 -86.372954)
		(end 47.889414 -85.290152)
		(width 0.08382)
		(layer "In2.Cu")
		(net "FM_DEBUG_PORT_PRSNT_N")
	)
	(segment
		(start 24.5872 -86.7156)
		(end 29.894276 -86.7156)
		(width 0.08382)
		(layer "In2.Cu")
		(net "FM_DEBUG_PORT_PRSNT_N")
	)
	(segment
		(start 14.986 -22.733)
		(end 12.319 -22.733)
		(width 0.08382)
		(layer "In2.Cu")
		(net "FM_DEBUG_PORT_PRSNT_N")
	)
	(segment
		(start 51.963574 -86.6902)
		(end 55.991252 -86.6902)
		(width 0.08382)
		(layer "In2.Cu")
		(net "FM_DEBUG_PORT_PRSNT_N")
	)
	(segment
		(start 46.8884 -26.4922)
		(end 42.9006 -26.4922)
		(width 0.08382)
		(layer "In2.Cu")
		(net "FM_DEBUG_PORT_PRSNT_N")
	)
	(segment
		(start 21.0312 -86.5124)
		(end 21.550884 -87.032084)
		(width 0.08382)
		(layer "In2.Cu")
		(net "FM_DEBUG_PORT_PRSNT_N")
	)
	(segment
		(start 42.9006 -26.4922)
		(end 41.99382 -25.58542)
		(width 0.08382)
		(layer "In2.Cu")
		(net "FM_DEBUG_PORT_PRSNT_N")
	)
	(segment
		(start 21.550884 -87.032084)
		(end 24.270716 -87.032084)
		(width 0.08382)
		(layer "In2.Cu")
		(net "FM_DEBUG_PORT_PRSNT_N")
	)
	(segment
		(start 41.99382 -25.58542)
		(end 40.674036 -25.58542)
		(width 0.08382)
		(layer "In2.Cu")
		(net "FM_DEBUG_PORT_PRSNT_N")
	)
	(segment
		(start 48.663606 -85.290152)
		(end 49.192434 -85.81898)
		(width 0.08382)
		(layer "In2.Cu")
		(net "FM_DEBUG_PORT_PRSNT_N")
	)
	(segment
		(start 20.0152 -87.0458)
		(end 20.5486 -86.5124)
		(width 0.08382)
		(layer "In2.Cu")
		(net "FM_DEBUG_PORT_PRSNT_N")
	)
	(segment
		(start 45.989494 -86.372954)
		(end 46.806612 -86.372954)
		(width 0.08382)
		(layer "In2.Cu")
		(net "FM_DEBUG_PORT_PRSNT_N")
	)
	(segment
		(start 47.5996 -25.781)
		(end 46.8884 -26.4922)
		(width 0.08382)
		(layer "In2.Cu")
		(net "FM_DEBUG_PORT_PRSNT_N")
	)
	(segment
		(start 17.7546 -86.8172)
		(end 17.9832 -87.0458)
		(width 0.08382)
		(layer "In2.Cu")
		(net "FM_DEBUG_PORT_PRSNT_N")
	)
	(segment
		(start 35.18916 -20.15744)
		(end 33.7566 -21.59)
		(width 0.08382)
		(layer "In2.Cu")
		(net "FM_DEBUG_PORT_PRSNT_N")
	)
	(segment
		(start 40.674036 -25.58542)
		(end 39.497 -24.408384)
		(width 0.08382)
		(layer "In2.Cu")
		(net "FM_DEBUG_PORT_PRSNT_N")
	)
	(segment
		(start 36.292028 -20.15744)
		(end 35.18916 -20.15744)
		(width 0.08382)
		(layer "In2.Cu")
		(net "FM_DEBUG_PORT_PRSNT_N")
	)
	(segment
		(start 43.840146 -89.6112)
		(end 45.62475 -87.826596)
		(width 0.08382)
		(layer "In2.Cu")
		(net "FM_DEBUG_PORT_PRSNT_N")
	)
	(segment
		(start 45.62475 -87.826596)
		(end 45.62475 -86.737698)
		(width 0.08382)
		(layer "In2.Cu")
		(net "FM_DEBUG_PORT_PRSNT_N")
	)
	(segment
		(start 11.69924 -89.3064)
		(end 14.18844 -86.8172)
		(width 0.08382)
		(layer "In2.Cu")
		(net "FM_DEBUG_PORT_PRSNT_N")
	)
	(segment
		(start 34.14395 -87.36203)
		(end 36.504118 -87.36203)
		(width 0.08382)
		(layer "In2.Cu")
		(net "FM_DEBUG_PORT_PRSNT_N")
	)
	(segment
		(start 55.991252 -86.6902)
		(end 56.311292 -86.37016)
		(width 0.08382)
		(layer "In2.Cu")
		(net "FM_DEBUG_PORT_PRSNT_N")
	)
	(segment
		(start 47.889414 -85.290152)
		(end 48.663606 -85.290152)
		(width 0.08382)
		(layer "In2.Cu")
		(net "FM_DEBUG_PORT_PRSNT_N")
	)
	(segment
		(start 37.96919 -20.85213)
		(end 36.292028 -20.15744)
		(width 0.08382)
		(layer "In2.Cu")
		(net "FM_DEBUG_PORT_PRSNT_N")
	)
	(segment
		(start 24.270716 -87.032084)
		(end 24.5872 -86.7156)
		(width 0.08382)
		(layer "In2.Cu")
		(net "FM_DEBUG_PORT_PRSNT_N")
	)
	(segment
		(start 29.894276 -86.7156)
		(end 29.985716 -86.62416)
		(width 0.08382)
		(layer "In2.Cu")
		(net "FM_DEBUG_PORT_PRSNT_N")
	)
	(segment
		(start 24.519128 -19.9771)
		(end 17.7419 -19.9771)
		(width 0.08382)
		(layer "In2.Cu")
		(net "FM_DEBUG_PORT_PRSNT_N")
	)
	(segment
		(start 45.62475 -86.737698)
		(end 45.989494 -86.372954)
		(width 0.08382)
		(layer "In2.Cu")
		(net "FM_DEBUG_PORT_PRSNT_N")
	)
	(segment
		(start 31.69793 -21.77923)
		(end 30.698694 -21.77923)
		(width 0.08382)
		(layer "In2.Cu")
		(net "FM_DEBUG_PORT_PRSNT_N")
	)
	(segment
		(start 33.7566 -21.59)
		(end 31.88716 -21.59)
		(width 0.08382)
		(layer "In2.Cu")
		(net "FM_DEBUG_PORT_PRSNT_N")
	)
	(segment
		(start 49.192434 -85.81898)
		(end 51.092354 -85.81898)
		(width 0.08382)
		(layer "In2.Cu")
		(net "FM_DEBUG_PORT_PRSNT_N")
	)
	(segment
		(start 31.88716 -21.59)
		(end 31.69793 -21.77923)
		(width 0.08382)
		(layer "In2.Cu")
		(net "FM_DEBUG_PORT_PRSNT_N")
	)
	(segment
		(start 14.18844 -86.8172)
		(end 17.7546 -86.8172)
		(width 0.08382)
		(layer "In2.Cu")
		(net "FM_DEBUG_PORT_PRSNT_N")
	)
	(segment
		(start 30.698694 -21.77923)
		(end 30.322774 -21.40331)
		(width 0.08382)
		(layer "In2.Cu")
		(net "FM_DEBUG_PORT_PRSNT_N")
	)
	(segment
		(start 17.7419 -19.9771)
		(end 14.986 -22.733)
		(width 0.08382)
		(layer "In2.Cu")
		(net "FM_DEBUG_PORT_PRSNT_N")
	)
	(segment
		(start 29.985716 -86.62416)
		(end 33.40608 -86.62416)
		(width 0.08382)
		(layer "In2.Cu")
		(net "FM_DEBUG_PORT_PRSNT_N")
	)
	(segment
		(start 39.497 -24.408384)
		(end 39.497 -22.37994)
		(width 0.08382)
		(layer "In2.Cu")
		(net "FM_DEBUG_PORT_PRSNT_N")
	)
	(segment
		(start 39.497 -22.37994)
		(end 37.96919 -20.85213)
		(width 0.08382)
		(layer "In2.Cu")
		(net "FM_DEBUG_PORT_PRSNT_N")
	)
	(segment
		(start 51.092354 -85.81898)
		(end 51.963574 -86.6902)
		(width 0.08382)
		(layer "In2.Cu")
		(net "FM_DEBUG_PORT_PRSNT_N")
	)
	(segment
		(start 4.072636 -81.15173)
		(end 4.072636 -85.255354)
		(width 0.10668)
		(layer "In4.Cu")
		(net "FM_DEBUG_PORT_PRSNT_N")
	)
	(segment
		(start 22.287738 -114.82324)
		(end 23.410418 -113.70056)
		(width 0.10668)
		(layer "In4.Cu")
		(net "FM_DEBUG_PORT_PRSNT_N")
	)
	(segment
		(start 16.462248 -112.8776)
		(end 16.972026 -113.387378)
		(width 0.10668)
		(layer "In4.Cu")
		(net "FM_DEBUG_PORT_PRSNT_N")
	)
	(segment
		(start 10.71626 -23.495)
		(end 6.85292 -27.35834)
		(width 0.10668)
		(layer "In4.Cu")
		(net "FM_DEBUG_PORT_PRSNT_N")
	)
	(segment
		(start 1.322832 -30.706568)
		(end 1.322832 -78.401926)
		(width 0.10668)
		(layer "In4.Cu")
		(net "FM_DEBUG_PORT_PRSNT_N")
	)
	(segment
		(start 23.410418 -113.70056)
		(end 26.3906 -113.70056)
		(width 0.10668)
		(layer "In4.Cu")
		(net "FM_DEBUG_PORT_PRSNT_N")
	)
	(segment
		(start 4.67106 -27.35834)
		(end 1.322832 -30.706568)
		(width 0.10668)
		(layer "In4.Cu")
		(net "FM_DEBUG_PORT_PRSNT_N")
	)
	(segment
		(start 6.85292 -27.35834)
		(end 4.67106 -27.35834)
		(width 0.10668)
		(layer "In4.Cu")
		(net "FM_DEBUG_PORT_PRSNT_N")
	)
	(segment
		(start 11.557 -23.495)
		(end 10.71626 -23.495)
		(width 0.10668)
		(layer "In4.Cu")
		(net "FM_DEBUG_PORT_PRSNT_N")
	)
	(segment
		(start 6.1976 -112.8776)
		(end 16.462248 -112.8776)
		(width 0.10668)
		(layer "In4.Cu")
		(net "FM_DEBUG_PORT_PRSNT_N")
	)
	(segment
		(start 20.13204 -114.82324)
		(end 22.287738 -114.82324)
		(width 0.10668)
		(layer "In4.Cu")
		(net "FM_DEBUG_PORT_PRSNT_N")
	)
	(segment
		(start 1.424432 -87.903558)
		(end 1.424432 -108.104432)
		(width 0.10668)
		(layer "In4.Cu")
		(net "FM_DEBUG_PORT_PRSNT_N")
	)
	(segment
		(start 1.322832 -78.401926)
		(end 4.072636 -81.15173)
		(width 0.10668)
		(layer "In4.Cu")
		(net "FM_DEBUG_PORT_PRSNT_N")
	)
	(segment
		(start 18.696178 -113.387378)
		(end 20.13204 -114.82324)
		(width 0.10668)
		(layer "In4.Cu")
		(net "FM_DEBUG_PORT_PRSNT_N")
	)
	(segment
		(start 1.424432 -108.104432)
		(end 6.1976 -112.8776)
		(width 0.10668)
		(layer "In4.Cu")
		(net "FM_DEBUG_PORT_PRSNT_N")
	)
	(segment
		(start 4.072636 -85.255354)
		(end 1.424432 -87.903558)
		(width 0.10668)
		(layer "In4.Cu")
		(net "FM_DEBUG_PORT_PRSNT_N")
	)
	(segment
		(start 16.972026 -113.387378)
		(end 18.696178 -113.387378)
		(width 0.10668)
		(layer "In4.Cu")
		(net "FM_DEBUG_PORT_PRSNT_N")
	)
	(segment
		(start 10.69848 -102.29342)
		(end 10.69848 -89.7636)
		(width 0.10668)
		(layer "In7.Cu")
		(net "FM_DEBUG_PORT_PRSNT_N")
	)
	(segment
		(start 11.004296 -102.599236)
		(end 10.69848 -102.29342)
		(width 0.10668)
		(layer "In7.Cu")
		(net "FM_DEBUG_PORT_PRSNT_N")
	)
	(segment
		(start 17.600168 -109.0168)
		(end 14.712696 -106.129328)
		(width 0.10668)
		(layer "In7.Cu")
		(net "FM_DEBUG_PORT_PRSNT_N")
	)
	(segment
		(start 10.69848 -89.7636)
		(end 11.15568 -89.3064)
		(width 0.10668)
		(layer "In7.Cu")
		(net "FM_DEBUG_PORT_PRSNT_N")
	)
	(segment
		(start 14.712696 -105.467912)
		(end 13.60678 -104.361996)
		(width 0.10668)
		(layer "In7.Cu")
		(net "FM_DEBUG_PORT_PRSNT_N")
	)
	(segment
		(start 22.49551 -108.33989)
		(end 21.07311 -108.33989)
		(width 0.10668)
		(layer "In7.Cu")
		(net "FM_DEBUG_PORT_PRSNT_N")
	)
	(segment
		(start 13.60678 -104.361996)
		(end 13.60678 -103.850948)
		(width 0.10668)
		(layer "In7.Cu")
		(net "FM_DEBUG_PORT_PRSNT_N")
	)
	(segment
		(start 11.15568 -89.3064)
		(end 11.303 -89.3064)
		(width 0.10668)
		(layer "In7.Cu")
		(net "FM_DEBUG_PORT_PRSNT_N")
	)
	(segment
		(start 12.355068 -102.599236)
		(end 11.004296 -102.599236)
		(width 0.10668)
		(layer "In7.Cu")
		(net "FM_DEBUG_PORT_PRSNT_N")
	)
	(segment
		(start 21.07311 -108.33989)
		(end 20.3962 -109.0168)
		(width 0.10668)
		(layer "In7.Cu")
		(net "FM_DEBUG_PORT_PRSNT_N")
	)
	(segment
		(start 13.60678 -103.850948)
		(end 12.355068 -102.599236)
		(width 0.10668)
		(layer "In7.Cu")
		(net "FM_DEBUG_PORT_PRSNT_N")
	)
	(segment
		(start 14.712696 -106.129328)
		(end 14.712696 -105.467912)
		(width 0.10668)
		(layer "In7.Cu")
		(net "FM_DEBUG_PORT_PRSNT_N")
	)
	(segment
		(start 20.3962 -109.0168)
		(end 17.600168 -109.0168)
		(width 0.10668)
		(layer "In7.Cu")
		(net "FM_DEBUG_PORT_PRSNT_N")
	)
	(segment
		(start 58.36285 -73.53427)
		(end 58.36285 -76.38034)
		(width 0.08382)
		(layer "In9.Cu")
		(net "FM_DEBUG_PORT_PRSNT_N")
	)
	(segment
		(start 57.86501 -83.649566)
		(end 57.86501 -86.26475)
		(width 0.08382)
		(layer "In9.Cu")
		(net "FM_DEBUG_PORT_PRSNT_N")
	)
	(segment
		(start 59.08294 -82.131916)
		(end 59.08294 -83.213956)
		(width 0.08382)
		(layer "In9.Cu")
		(net "FM_DEBUG_PORT_PRSNT_N")
	)
	(segment
		(start 58.42 -65.58026)
		(end 57.87644 -66.12382)
		(width 0.08382)
		(layer "In9.Cu")
		(net "FM_DEBUG_PORT_PRSNT_N")
	)
	(segment
		(start 58.42 -64.9478)
		(end 58.42 -65.58026)
		(width 0.08382)
		(layer "In9.Cu")
		(net "FM_DEBUG_PORT_PRSNT_N")
	)
	(segment
		(start 59.08294 -83.213956)
		(end 58.934096 -83.3628)
		(width 0.08382)
		(layer "In9.Cu")
		(net "FM_DEBUG_PORT_PRSNT_N")
	)
	(segment
		(start 58.934096 -83.3628)
		(end 58.151776 -83.3628)
		(width 0.08382)
		(layer "In9.Cu")
		(net "FM_DEBUG_PORT_PRSNT_N")
	)
	(segment
		(start 58.81116 -73.08596)
		(end 58.36285 -73.53427)
		(width 0.08382)
		(layer "In9.Cu")
		(net "FM_DEBUG_PORT_PRSNT_N")
	)
	(segment
		(start 58.56351 -81.612486)
		(end 59.08294 -82.131916)
		(width 0.08382)
		(layer "In9.Cu")
		(net "FM_DEBUG_PORT_PRSNT_N")
	)
	(segment
		(start 57.87644 -66.12382)
		(end 57.87644 -67.34556)
		(width 0.08382)
		(layer "In9.Cu")
		(net "FM_DEBUG_PORT_PRSNT_N")
	)
	(segment
		(start 58.36285 -76.38034)
		(end 58.56351 -76.581)
		(width 0.08382)
		(layer "In9.Cu")
		(net "FM_DEBUG_PORT_PRSNT_N")
	)
	(segment
		(start 58.81116 -71.628)
		(end 58.81116 -73.08596)
		(width 0.08382)
		(layer "In9.Cu")
		(net "FM_DEBUG_PORT_PRSNT_N")
	)
	(segment
		(start 58.01868 -67.4878)
		(end 58.01868 -68.125086)
		(width 0.08382)
		(layer "In9.Cu")
		(net "FM_DEBUG_PORT_PRSNT_N")
	)
	(segment
		(start 58.4454 -71.26224)
		(end 58.81116 -71.628)
		(width 0.08382)
		(layer "In9.Cu")
		(net "FM_DEBUG_PORT_PRSNT_N")
	)
	(segment
		(start 58.01868 -68.125086)
		(end 58.4454 -68.551806)
		(width 0.08382)
		(layer "In9.Cu")
		(net "FM_DEBUG_PORT_PRSNT_N")
	)
	(segment
		(start 57.87644 -67.34556)
		(end 58.01868 -67.4878)
		(width 0.08382)
		(layer "In9.Cu")
		(net "FM_DEBUG_PORT_PRSNT_N")
	)
	(segment
		(start 58.4454 -68.551806)
		(end 58.4454 -71.26224)
		(width 0.08382)
		(layer "In9.Cu")
		(net "FM_DEBUG_PORT_PRSNT_N")
	)
	(segment
		(start 57.86501 -86.26475)
		(end 57.97042 -86.37016)
		(width 0.08382)
		(layer "In9.Cu")
		(net "FM_DEBUG_PORT_PRSNT_N")
	)
	(segment
		(start 58.56351 -76.581)
		(end 58.56351 -81.612486)
		(width 0.08382)
		(layer "In9.Cu")
		(net "FM_DEBUG_PORT_PRSNT_N")
	)
	(segment
		(start 58.151776 -83.3628)
		(end 57.86501 -83.649566)
		(width 0.08382)
		(layer "In9.Cu")
		(net "FM_DEBUG_PORT_PRSNT_N")
	)
	(via
		(at 52.91836 -89.75344)
		(size 0.6604)
		(drill 0.3302)
		(layers "F.Cu" "B.Cu")
		(net "FM_CPU_MSMI_CATERR_LVT3_R3_N")
	)
	(segment
		(start 52.91836 -89.75344)
		(end 52.76342 -89.5985)
		(width 0.11684)
		(layer "B.Cu")
		(net "FM_CPU_MSMI_CATERR_LVT3_R3_N")
	)
	(segment
		(start 52.76342 -89.5985)
		(end 51.64455 -89.5985)
		(width 0.11684)
		(layer "B.Cu")
		(net "FM_CPU_MSMI_CATERR_LVT3_R3_N")
	)
	(segment
		(start 54.71668 -89.3953)
		(end 53.2765 -89.3953)
		(width 0.11684)
		(layer "B.Cu")
		(net "FM_CPU_MSMI_CATERR_LVT3_R3_N")
	)
	(segment
		(start 53.2765 -89.3953)
		(end 52.91836 -89.75344)
		(width 0.11684)
		(layer "B.Cu")
		(net "FM_CPU_MSMI_CATERR_LVT3_R3_N")
	)
	(segment
		(start 23.72995 -98.78695)
		(end 23.45944 -98.78695)
		(width 0.11684)
		(layer "F.Cu")
		(net "FM_BMC_CRASHLOG_TRIG_R2_N")
	)
	(segment
		(start 22.59584 -100.5332)
		(end 23.6728 -100.5332)
		(width 0.11684)
		(layer "F.Cu")
		(net "FM_BMC_CRASHLOG_TRIG_R2_N")
	)
	(segment
		(start 22.479 -100.65004)
		(end 22.59584 -100.5332)
		(width 0.11684)
		(layer "F.Cu")
		(net "FM_BMC_CRASHLOG_TRIG_R2_N")
	)
	(segment
		(start 21.463 -102.34295)
		(end 22.479 -101.32695)
		(width 0.11684)
		(layer "F.Cu")
		(net "FM_BMC_CRASHLOG_TRIG_R2_N")
	)
	(segment
		(start 22.479 -101.32695)
		(end 22.479 -100.65004)
		(width 0.11684)
		(layer "F.Cu")
		(net "FM_BMC_CRASHLOG_TRIG_R2_N")
	)
	(segment
		(start 23.8506 -100.3554)
		(end 23.8506 -98.9076)
		(width 0.11684)
		(layer "F.Cu")
		(net "FM_BMC_CRASHLOG_TRIG_R2_N")
	)
	(segment
		(start 23.8506 -98.9076)
		(end 23.72995 -98.78695)
		(width 0.11684)
		(layer "F.Cu")
		(net "FM_BMC_CRASHLOG_TRIG_R2_N")
	)
	(segment
		(start 23.6728 -100.5332)
		(end 23.8506 -100.3554)
		(width 0.11684)
		(layer "F.Cu")
		(net "FM_BMC_CRASHLOG_TRIG_R2_N")
	)
	(segment
		(start 24.25954 -100.56241)
		(end 24.25954 -99.58705)
		(width 0.11684)
		(layer "F.Cu")
		(net "IRQ_PCH_TPM_SPI_R2_N")
	)
	(segment
		(start 22.479 -102.34295)
		(end 24.25954 -100.56241)
		(width 0.11684)
		(layer "F.Cu")
		(net "IRQ_PCH_TPM_SPI_R2_N")
	)
	(segment
		(start 13.67028 -82.8548)
		(end 15.33906 -82.8548)
		(width 0.11684)
		(layer "F.Cu")
		(net "PVCCIO_AUX_PLD")
	)
	(segment
		(start 31.5722 -88.5952)
		(end 31.3436 -88.8238)
		(width 0.11684)
		(layer "F.Cu")
		(net "PVCCIO_AUX_PLD")
	)
	(segment
		(start 15.33906 -82.8548)
		(end 15.494 -83.00974)
		(width 0.11684)
		(layer "F.Cu")
		(net "PVCCIO_AUX_PLD")
	)
	(segment
		(start 31.3436 -88.8238)
		(end 31.10865 -88.8238)
		(width 0.11684)
		(layer "F.Cu")
		(net "PVCCIO_AUX_PLD")
	)
	(segment
		(start 13.41628 -82.6008)
		(end 13.67028 -82.8548)
		(width 0.11684)
		(layer "F.Cu")
		(net "PVCCIO_AUX_PLD")
	)
	(segment
		(start 15.494 -83.00974)
		(end 15.494 -83.29295)
		(width 0.11684)
		(layer "F.Cu")
		(net "PVCCIO_AUX_PLD")
	)
	(segment
		(start 31.10865 -88.8238)
		(end 30.95625 -88.9762)
		(width 0.11684)
		(layer "F.Cu")
		(net "PVCCIO_AUX_PLD")
	)
	(via
		(at 31.73349 -82.5246)
		(size 0.508)
		(drill 0.254)
		(layers "F.Cu" "B.Cu")
		(net "PVCCIO_AUX_PLD")
	)
	(via
		(at 31.5722 -88.5952)
		(size 0.508)
		(drill 0.254)
		(layers "F.Cu" "B.Cu")
		(net "PVCCIO_AUX_PLD")
	)
	(via
		(at 13.41628 -82.6008)
		(size 0.508)
		(drill 0.254)
		(layers "F.Cu" "B.Cu")
		(net "PVCCIO_AUX_PLD")
	)
	(segment
		(start 32.36595 -90.805)
		(end 32.36595 -89.789)
		(width 0.11684)
		(layer "B.Cu")
		(net "PVCCIO_AUX_PLD")
	)
	(segment
		(start 32.36595 -89.789)
		(end 32.36595 -89.38895)
		(width 0.11684)
		(layer "B.Cu")
		(net "PVCCIO_AUX_PLD")
	)
	(segment
		(start 32.36595 -91.821)
		(end 32.36595 -90.805)
		(width 0.11684)
		(layer "B.Cu")
		(net "PVCCIO_AUX_PLD")
	)
	(segment
		(start 32.36595 -89.38895)
		(end 31.5722 -88.5952)
		(width 0.11684)
		(layer "B.Cu")
		(net "PVCCIO_AUX_PLD")
	)
	(segment
		(start 13.41628 -82.6008)
		(end 14.10843 -83.29295)
		(width 0.11684)
		(layer "B.Cu")
		(net "PVCCIO_AUX_PLD")
	)
	(segment
		(start 14.10843 -83.29295)
		(end 14.2494 -83.29295)
		(width 0.11684)
		(layer "B.Cu")
		(net "PVCCIO_AUX_PLD")
	)
	(segment
		(start 14.5542 -82.8548)
		(end 13.67028 -82.8548)
		(width 0.08382)
		(layer "In2.Cu")
		(net "PVCCIO_AUX_PLD")
	)
	(segment
		(start 31.73349 -82.5246)
		(end 31.63189 -82.6262)
		(width 0.08382)
		(layer "In2.Cu")
		(net "PVCCIO_AUX_PLD")
	)
	(segment
		(start 16.4592 -80.9498)
		(end 14.5542 -82.8548)
		(width 0.08382)
		(layer "In2.Cu")
		(net "PVCCIO_AUX_PLD")
	)
	(segment
		(start 31.63189 -82.6262)
		(end 28.878276 -82.6262)
		(width 0.08382)
		(layer "In2.Cu")
		(net "PVCCIO_AUX_PLD")
	)
	(segment
		(start 26.41346 -83.258914)
		(end 25.654 -82.499454)
		(width 0.08382)
		(layer "In2.Cu")
		(net "PVCCIO_AUX_PLD")
	)
	(segment
		(start 26.675842 -83.688936)
		(end 26.41346 -83.426554)
		(width 0.08382)
		(layer "In2.Cu")
		(net "PVCCIO_AUX_PLD")
	)
	(segment
		(start 26.41346 -83.426554)
		(end 26.41346 -83.258914)
		(width 0.08382)
		(layer "In2.Cu")
		(net "PVCCIO_AUX_PLD")
	)
	(segment
		(start 13.67028 -82.8548)
		(end 13.41628 -82.6008)
		(width 0.08382)
		(layer "In2.Cu")
		(net "PVCCIO_AUX_PLD")
	)
	(segment
		(start 25.654 -82.499454)
		(end 25.654 -82.013806)
		(width 0.08382)
		(layer "In2.Cu")
		(net "PVCCIO_AUX_PLD")
	)
	(segment
		(start 19.761454 -80.9498)
		(end 16.4592 -80.9498)
		(width 0.08382)
		(layer "In2.Cu")
		(net "PVCCIO_AUX_PLD")
	)
	(segment
		(start 20.091654 -80.6196)
		(end 19.761454 -80.9498)
		(width 0.08382)
		(layer "In2.Cu")
		(net "PVCCIO_AUX_PLD")
	)
	(segment
		(start 24.259794 -80.6196)
		(end 20.091654 -80.6196)
		(width 0.08382)
		(layer "In2.Cu")
		(net "PVCCIO_AUX_PLD")
	)
	(segment
		(start 25.654 -82.013806)
		(end 24.259794 -80.6196)
		(width 0.08382)
		(layer "In2.Cu")
		(net "PVCCIO_AUX_PLD")
	)
	(segment
		(start 27.81554 -83.688936)
		(end 26.675842 -83.688936)
		(width 0.08382)
		(layer "In2.Cu")
		(net "PVCCIO_AUX_PLD")
	)
	(segment
		(start 28.878276 -82.6262)
		(end 27.81554 -83.688936)
		(width 0.08382)
		(layer "In2.Cu")
		(net "PVCCIO_AUX_PLD")
	)
	(segment
		(start 31.13786 -84.36737)
		(end 31.13786 -88.16086)
		(width 0.10668)
		(layer "In4.Cu")
		(net "PVCCIO_AUX_PLD")
	)
	(segment
		(start 31.841948 -82.633058)
		(end 31.841948 -83.663282)
		(width 0.10668)
		(layer "In4.Cu")
		(net "PVCCIO_AUX_PLD")
	)
	(segment
		(start 31.73349 -82.5246)
		(end 31.841948 -82.633058)
		(width 0.10668)
		(layer "In4.Cu")
		(net "PVCCIO_AUX_PLD")
	)
	(segment
		(start 31.841948 -83.663282)
		(end 31.13786 -84.36737)
		(width 0.10668)
		(layer "In4.Cu")
		(net "PVCCIO_AUX_PLD")
	)
	(segment
		(start 31.13786 -88.16086)
		(end 31.5722 -88.5952)
		(width 0.10668)
		(layer "In4.Cu")
		(net "PVCCIO_AUX_PLD")
	)
	(via
		(at 43.8912 -90.080084)
		(size 0.6604)
		(drill 0.3302)
		(layers "F.Cu" "B.Cu")
		(net "USB3_MUX_PD")
	)
	(segment
		(start 43.18 -91.185746)
		(end 43.8912 -90.474546)
		(width 0.11684)
		(layer "B.Cu")
		(net "USB3_MUX_PD")
	)
	(segment
		(start 44.8818 -88.89365)
		(end 43.8912 -88.89365)
		(width 0.11684)
		(layer "B.Cu")
		(net "USB3_MUX_PD")
	)
	(segment
		(start 43.8912 -90.080084)
		(end 43.8912 -88.89365)
		(width 0.11684)
		(layer "B.Cu")
		(net "USB3_MUX_PD")
	)
	(segment
		(start 43.8912 -90.474546)
		(end 43.8912 -90.080084)
		(width 0.11684)
		(layer "B.Cu")
		(net "USB3_MUX_PD")
	)
	(segment
		(start 43.18 -91.398852)
		(end 43.18 -91.185746)
		(width 0.11684)
		(layer "B.Cu")
		(net "USB3_MUX_PD")
	)
	(segment
		(start 20.82927 -116.339874)
		(end 19.5707 -113.301526)
		(width 0.14224)
		(layer "F.Cu")
		(net "USB3_FPNL_TXP")
	)
	(segment
		(start 20.82927 -117.440964)
		(end 20.82927 -116.339874)
		(width 0.14224)
		(layer "F.Cu")
		(net "USB3_FPNL_TXP")
	)
	(segment
		(start 19.5707 -110.426246)
		(end 18.95475 -109.810296)
		(width 0.14224)
		(layer "F.Cu")
		(net "USB3_FPNL_TXP")
	)
	(segment
		(start 20.945094 -118.25986)
		(end 20.945094 -117.556788)
		(width 0.14224)
		(layer "F.Cu")
		(net "USB3_FPNL_TXP")
	)
	(segment
		(start 18.95475 -108.006896)
		(end 19.2151 -107.746546)
		(width 0.14224)
		(layer "F.Cu")
		(net "USB3_FPNL_TXP")
	)
	(segment
		(start 20.945094 -117.556788)
		(end 20.82927 -117.440964)
		(width 0.14224)
		(layer "F.Cu")
		(net "USB3_FPNL_TXP")
	)
	(segment
		(start 18.95475 -109.810296)
		(end 18.95475 -108.006896)
		(width 0.14224)
		(layer "F.Cu")
		(net "USB3_FPNL_TXP")
	)
	(segment
		(start 19.5707 -113.301526)
		(end 19.5707 -110.426246)
		(width 0.14224)
		(layer "F.Cu")
		(net "USB3_FPNL_TXP")
	)
	(via
		(at 46.3169 -97.951036)
		(size 0.508)
		(drill 0.254)
		(layers "F.Cu" "B.Cu")
		(net "USB3_FPNL_TXP")
	)
	(via
		(at 19.2151 -107.746546)
		(size 0.508)
		(drill 0.254)
		(layers "F.Cu" "B.Cu")
		(net "USB3_FPNL_TXP")
	)
	(segment
		(start 46.0629 -97.697036)
		(end 46.3169 -97.951036)
		(width 0.14224)
		(layer "B.Cu")
		(net "USB3_FPNL_TXP")
	)
	(segment
		(start 46.0629 -97.4217)
		(end 46.0629 -97.697036)
		(width 0.14224)
		(layer "B.Cu")
		(net "USB3_FPNL_TXP")
	)
	(segment
		(start 46.355 -97.22485)
		(end 46.25975 -97.22485)
		(width 0.14224)
		(layer "B.Cu")
		(net "USB3_FPNL_TXP")
	)
	(segment
		(start 46.25975 -97.22485)
		(end 46.0629 -97.4217)
		(width 0.14224)
		(layer "B.Cu")
		(net "USB3_FPNL_TXP")
	)
	(segment
		(start 45.493686 -99.455732)
		(end 46.04004 -98.909378)
		(width 0.1143)
		(layer "In9.Cu")
		(net "USB3_FPNL_TXP")
	)
	(segment
		(start 29.87421 -109.95279)
		(end 30.34792 -109.47908)
		(width 0.1143)
		(layer "In9.Cu")
		(net "USB3_FPNL_TXP")
	)
	(segment
		(start 37.94506 -109.47908)
		(end 38.98773 -109.04728)
		(width 0.1143)
		(layer "In9.Cu")
		(net "USB3_FPNL_TXP")
	)
	(segment
		(start 42.57548 -107.352338)
		(end 42.57548 -101.129338)
		(width 0.1143)
		(layer "In9.Cu")
		(net "USB3_FPNL_TXP")
	)
	(segment
		(start 42.57548 -101.129338)
		(end 43.368976 -100.335842)
		(width 0.1143)
		(layer "In9.Cu")
		(net "USB3_FPNL_TXP")
	)
	(segment
		(start 46.04004 -98.909378)
		(end 46.04004 -98.227896)
		(width 0.1143)
		(layer "In9.Cu")
		(net "USB3_FPNL_TXP")
	)
	(segment
		(start 28.131262 -109.95279)
		(end 29.87421 -109.95279)
		(width 0.1143)
		(layer "In9.Cu")
		(net "USB3_FPNL_TXP")
	)
	(segment
		(start 19.2151 -107.746546)
		(end 18.93824 -107.469686)
		(width 0.1143)
		(layer "In9.Cu")
		(net "USB3_FPNL_TXP")
	)
	(segment
		(start 46.04004 -98.227896)
		(end 46.3169 -97.951036)
		(width 0.1143)
		(layer "In9.Cu")
		(net "USB3_FPNL_TXP")
	)
	(segment
		(start 41.47185 -108.455968)
		(end 42.57548 -107.352338)
		(width 0.1143)
		(layer "In9.Cu")
		(net "USB3_FPNL_TXP")
	)
	(segment
		(start 18.93824 -107.190032)
		(end 19.138392 -106.98988)
		(width 0.1143)
		(layer "In9.Cu")
		(net "USB3_FPNL_TXP")
	)
	(segment
		(start 25.67305 -110.2614)
		(end 27.822652 -110.2614)
		(width 0.1143)
		(layer "In9.Cu")
		(net "USB3_FPNL_TXP")
	)
	(segment
		(start 19.138392 -106.98988)
		(end 20.015708 -106.98988)
		(width 0.1143)
		(layer "In9.Cu")
		(net "USB3_FPNL_TXP")
	)
	(segment
		(start 30.34792 -109.47908)
		(end 37.94506 -109.47908)
		(width 0.1143)
		(layer "In9.Cu")
		(net "USB3_FPNL_TXP")
	)
	(segment
		(start 25.08885 -109.6772)
		(end 25.67305 -110.2614)
		(width 0.1143)
		(layer "In9.Cu")
		(net "USB3_FPNL_TXP")
	)
	(segment
		(start 20.015708 -106.98988)
		(end 22.703028 -109.6772)
		(width 0.1143)
		(layer "In9.Cu")
		(net "USB3_FPNL_TXP")
	)
	(segment
		(start 43.368976 -100.335842)
		(end 45.493686 -99.455732)
		(width 0.1143)
		(layer "In9.Cu")
		(net "USB3_FPNL_TXP")
	)
	(segment
		(start 27.822652 -110.2614)
		(end 28.131262 -109.95279)
		(width 0.1143)
		(layer "In9.Cu")
		(net "USB3_FPNL_TXP")
	)
	(segment
		(start 22.703028 -109.6772)
		(end 25.08885 -109.6772)
		(width 0.1143)
		(layer "In9.Cu")
		(net "USB3_FPNL_TXP")
	)
	(segment
		(start 38.98773 -109.04728)
		(end 40.04437 -109.04728)
		(width 0.1143)
		(layer "In9.Cu")
		(net "USB3_FPNL_TXP")
	)
	(segment
		(start 40.04437 -109.04728)
		(end 41.47185 -108.455968)
		(width 0.1143)
		(layer "In9.Cu")
		(net "USB3_FPNL_TXP")
	)
	(segment
		(start 18.93824 -107.469686)
		(end 18.93824 -107.190032)
		(width 0.1143)
		(layer "In9.Cu")
		(net "USB3_FPNL_TXP")
	)
	(segment
		(start 20.46097 -116.41328)
		(end 19.2024 -113.374932)
		(width 0.14224)
		(layer "F.Cu")
		(net "USB3_FPNL_TXN")
	)
	(segment
		(start 19.2024 -113.374932)
		(end 19.2024 -110.5789)
		(width 0.14224)
		(layer "F.Cu")
		(net "USB3_FPNL_TXN")
	)
	(segment
		(start 19.2024 -110.5789)
		(end 18.58645 -109.96295)
		(width 0.14224)
		(layer "F.Cu")
		(net "USB3_FPNL_TXN")
	)
	(segment
		(start 20.344892 -117.526562)
		(end 20.46097 -117.410484)
		(width 0.14224)
		(layer "F.Cu")
		(net "USB3_FPNL_TXN")
	)
	(segment
		(start 18.58645 -108.006896)
		(end 18.3261 -107.746546)
		(width 0.14224)
		(layer "F.Cu")
		(net "USB3_FPNL_TXN")
	)
	(segment
		(start 20.344892 -118.25986)
		(end 20.344892 -117.526562)
		(width 0.14224)
		(layer "F.Cu")
		(net "USB3_FPNL_TXN")
	)
	(segment
		(start 18.58645 -109.96295)
		(end 18.58645 -108.006896)
		(width 0.14224)
		(layer "F.Cu")
		(net "USB3_FPNL_TXN")
	)
	(segment
		(start 20.46097 -117.410484)
		(end 20.46097 -116.41328)
		(width 0.14224)
		(layer "F.Cu")
		(net "USB3_FPNL_TXN")
	)
	(via
		(at 45.4279 -97.951036)
		(size 0.508)
		(drill 0.254)
		(layers "F.Cu" "B.Cu")
		(net "USB3_FPNL_TXN")
	)
	(via
		(at 18.3261 -107.746546)
		(size 0.508)
		(drill 0.254)
		(layers "F.Cu" "B.Cu")
		(net "USB3_FPNL_TXN")
	)
	(segment
		(start 45.6946 -97.684336)
		(end 45.4279 -97.951036)
		(width 0.14224)
		(layer "B.Cu")
		(net "USB3_FPNL_TXN")
	)
	(segment
		(start 45.339 -97.22485)
		(end 45.434504 -97.22485)
		(width 0.14224)
		(layer "B.Cu")
		(net "USB3_FPNL_TXN")
	)
	(segment
		(start 45.434504 -97.22485)
		(end 45.6946 -97.484946)
		(width 0.14224)
		(layer "B.Cu")
		(net "USB3_FPNL_TXN")
	)
	(segment
		(start 45.6946 -97.484946)
		(end 45.6946 -97.684336)
		(width 0.14224)
		(layer "B.Cu")
		(net "USB3_FPNL_TXN")
	)
	(segment
		(start 27.683714 -109.92612)
		(end 27.992324 -109.61751)
		(width 0.1143)
		(layer "In9.Cu")
		(net "USB3_FPNL_TXN")
	)
	(segment
		(start 29.735272 -109.61751)
		(end 30.208982 -109.1438)
		(width 0.1143)
		(layer "In9.Cu")
		(net "USB3_FPNL_TXN")
	)
	(segment
		(start 41.281858 -108.171742)
		(end 42.2402 -107.2134)
		(width 0.1143)
		(layer "In9.Cu")
		(net "USB3_FPNL_TXN")
	)
	(segment
		(start 45.303694 -99.171506)
		(end 45.70476 -98.77044)
		(width 0.1143)
		(layer "In9.Cu")
		(net "USB3_FPNL_TXN")
	)
	(segment
		(start 39.977568 -108.712)
		(end 41.281858 -108.171742)
		(width 0.1143)
		(layer "In9.Cu")
		(net "USB3_FPNL_TXN")
	)
	(segment
		(start 18.60296 -107.469686)
		(end 18.60296 -107.051094)
		(width 0.1143)
		(layer "In9.Cu")
		(net "USB3_FPNL_TXN")
	)
	(segment
		(start 22.841966 -109.34192)
		(end 25.227788 -109.34192)
		(width 0.1143)
		(layer "In9.Cu")
		(net "USB3_FPNL_TXN")
	)
	(segment
		(start 30.208982 -109.1438)
		(end 37.878258 -109.1438)
		(width 0.1143)
		(layer "In9.Cu")
		(net "USB3_FPNL_TXN")
	)
	(segment
		(start 42.2402 -100.9904)
		(end 43.178984 -100.051616)
		(width 0.1143)
		(layer "In9.Cu")
		(net "USB3_FPNL_TXN")
	)
	(segment
		(start 25.811988 -109.92612)
		(end 27.683714 -109.92612)
		(width 0.1143)
		(layer "In9.Cu")
		(net "USB3_FPNL_TXN")
	)
	(segment
		(start 27.992324 -109.61751)
		(end 29.735272 -109.61751)
		(width 0.1143)
		(layer "In9.Cu")
		(net "USB3_FPNL_TXN")
	)
	(segment
		(start 18.999454 -106.6546)
		(end 20.154646 -106.6546)
		(width 0.1143)
		(layer "In9.Cu")
		(net "USB3_FPNL_TXN")
	)
	(segment
		(start 43.178984 -100.051616)
		(end 45.303694 -99.171506)
		(width 0.1143)
		(layer "In9.Cu")
		(net "USB3_FPNL_TXN")
	)
	(segment
		(start 18.60296 -107.051094)
		(end 18.999454 -106.6546)
		(width 0.1143)
		(layer "In9.Cu")
		(net "USB3_FPNL_TXN")
	)
	(segment
		(start 38.920928 -108.712)
		(end 39.977568 -108.712)
		(width 0.1143)
		(layer "In9.Cu")
		(net "USB3_FPNL_TXN")
	)
	(segment
		(start 20.154646 -106.6546)
		(end 22.841966 -109.34192)
		(width 0.1143)
		(layer "In9.Cu")
		(net "USB3_FPNL_TXN")
	)
	(segment
		(start 42.2402 -107.2134)
		(end 42.2402 -100.9904)
		(width 0.1143)
		(layer "In9.Cu")
		(net "USB3_FPNL_TXN")
	)
	(segment
		(start 25.227788 -109.34192)
		(end 25.811988 -109.92612)
		(width 0.1143)
		(layer "In9.Cu")
		(net "USB3_FPNL_TXN")
	)
	(segment
		(start 45.70476 -98.77044)
		(end 45.70476 -98.227896)
		(width 0.1143)
		(layer "In9.Cu")
		(net "USB3_FPNL_TXN")
	)
	(segment
		(start 45.70476 -98.227896)
		(end 45.4279 -97.951036)
		(width 0.1143)
		(layer "In9.Cu")
		(net "USB3_FPNL_TXN")
	)
	(segment
		(start 18.3261 -107.746546)
		(end 18.60296 -107.469686)
		(width 0.1143)
		(layer "In9.Cu")
		(net "USB3_FPNL_TXN")
	)
	(segment
		(start 37.878258 -109.1438)
		(end 38.920928 -108.712)
		(width 0.1143)
		(layer "In9.Cu")
		(net "USB3_FPNL_TXN")
	)
	(via
		(at 16.286988 -109.543342)
		(size 0.508)
		(drill 0.254)
		(layers "F.Cu" "B.Cu")
		(net "USB3_FPNL_RXP")
	)
	(via
		(at 41.2877 -98.382836)
		(size 0.508)
		(drill 0.254)
		(layers "F.Cu" "B.Cu")
		(net "USB3_FPNL_RXP")
	)
	(segment
		(start 41.0337 -98.128836)
		(end 41.2877 -98.382836)
		(width 0.14224)
		(layer "B.Cu")
		(net "USB3_FPNL_RXP")
	)
	(segment
		(start 16.0147 -111.5441)
		(end 16.0147 -109.81563)
		(width 0.14224)
		(layer "B.Cu")
		(net "USB3_FPNL_RXP")
	)
	(segment
		(start 20.945094 -117.516148)
		(end 20.82927 -117.400324)
		(width 0.14224)
		(layer "B.Cu")
		(net "USB3_FPNL_RXP")
	)
	(segment
		(start 20.82927 -116.952776)
		(end 20.409154 -115.938554)
		(width 0.14224)
		(layer "B.Cu")
		(net "USB3_FPNL_RXP")
	)
	(segment
		(start 20.82927 -117.400324)
		(end 20.82927 -116.952776)
		(width 0.14224)
		(layer "B.Cu")
		(net "USB3_FPNL_RXP")
	)
	(segment
		(start 42.180002 -93.811598)
		(end 42.114216 -93.877384)
		(width 0.14224)
		(layer "B.Cu")
		(net "USB3_FPNL_RXP")
	)
	(segment
		(start 42.114216 -93.877384)
		(end 42.114216 -96.23933)
		(width 0.14224)
		(layer "B.Cu")
		(net "USB3_FPNL_RXP")
	)
	(segment
		(start 42.180002 -93.599)
		(end 42.180002 -93.811598)
		(width 0.14224)
		(layer "B.Cu")
		(net "USB3_FPNL_RXP")
	)
	(segment
		(start 41.0337 -97.319846)
		(end 41.0337 -98.128836)
		(width 0.14224)
		(layer "B.Cu")
		(net "USB3_FPNL_RXP")
	)
	(segment
		(start 20.945094 -118.25986)
		(end 20.945094 -117.516148)
		(width 0.14224)
		(layer "B.Cu")
		(net "USB3_FPNL_RXP")
	)
	(segment
		(start 20.409154 -115.938554)
		(end 16.0147 -111.5441)
		(width 0.14224)
		(layer "B.Cu")
		(net "USB3_FPNL_RXP")
	)
	(segment
		(start 42.114216 -96.23933)
		(end 41.0337 -97.319846)
		(width 0.14224)
		(layer "B.Cu")
		(net "USB3_FPNL_RXP")
	)
	(segment
		(start 16.0147 -109.81563)
		(end 16.286988 -109.543342)
		(width 0.14224)
		(layer "B.Cu")
		(net "USB3_FPNL_RXP")
	)
	(segment
		(start 26.0604 -109.2454)
		(end 27.432 -109.2454)
		(width 0.1143)
		(layer "In9.Cu")
		(net "USB3_FPNL_RXP")
	)
	(segment
		(start 16.286988 -109.543342)
		(end 16.010128 -109.266482)
		(width 0.1143)
		(layer "In9.Cu")
		(net "USB3_FPNL_RXP")
	)
	(segment
		(start 20.818094 -106.0069)
		(end 23.497794 -108.6866)
		(width 0.1143)
		(layer "In9.Cu")
		(net "USB3_FPNL_RXP")
	)
	(segment
		(start 40.11168 -103.829866)
		(end 41.01084 -102.930706)
		(width 0.1143)
		(layer "In9.Cu")
		(net "USB3_FPNL_RXP")
	)
	(segment
		(start 29.925518 -108.4961)
		(end 35.622484 -108.4961)
		(width 0.1143)
		(layer "In9.Cu")
		(net "USB3_FPNL_RXP")
	)
	(segment
		(start 16.010128 -107.17149)
		(end 17.174718 -106.0069)
		(width 0.1143)
		(layer "In9.Cu")
		(net "USB3_FPNL_RXP")
	)
	(segment
		(start 25.5016 -108.6866)
		(end 26.0604 -109.2454)
		(width 0.1143)
		(layer "In9.Cu")
		(net "USB3_FPNL_RXP")
	)
	(segment
		(start 35.622484 -108.4961)
		(end 37.326316 -106.792268)
		(width 0.1143)
		(layer "In9.Cu")
		(net "USB3_FPNL_RXP")
	)
	(segment
		(start 23.497794 -108.6866)
		(end 25.5016 -108.6866)
		(width 0.1143)
		(layer "In9.Cu")
		(net "USB3_FPNL_RXP")
	)
	(segment
		(start 41.01084 -102.930706)
		(end 41.01084 -98.659696)
		(width 0.1143)
		(layer "In9.Cu")
		(net "USB3_FPNL_RXP")
	)
	(segment
		(start 27.70759 -108.96981)
		(end 29.451808 -108.96981)
		(width 0.1143)
		(layer "In9.Cu")
		(net "USB3_FPNL_RXP")
	)
	(segment
		(start 41.01084 -98.659696)
		(end 41.2877 -98.382836)
		(width 0.1143)
		(layer "In9.Cu")
		(net "USB3_FPNL_RXP")
	)
	(segment
		(start 27.432 -109.2454)
		(end 27.70759 -108.96981)
		(width 0.1143)
		(layer "In9.Cu")
		(net "USB3_FPNL_RXP")
	)
	(segment
		(start 37.891466 -106.55808)
		(end 39.178738 -106.55808)
		(width 0.1143)
		(layer "In9.Cu")
		(net "USB3_FPNL_RXP")
	)
	(segment
		(start 29.451808 -108.96981)
		(end 29.925518 -108.4961)
		(width 0.1143)
		(layer "In9.Cu")
		(net "USB3_FPNL_RXP")
	)
	(segment
		(start 39.178738 -106.55808)
		(end 40.11168 -105.625138)
		(width 0.1143)
		(layer "In9.Cu")
		(net "USB3_FPNL_RXP")
	)
	(segment
		(start 40.11168 -105.625138)
		(end 40.11168 -103.829866)
		(width 0.1143)
		(layer "In9.Cu")
		(net "USB3_FPNL_RXP")
	)
	(segment
		(start 16.010128 -109.266482)
		(end 16.010128 -107.17149)
		(width 0.1143)
		(layer "In9.Cu")
		(net "USB3_FPNL_RXP")
	)
	(segment
		(start 17.174718 -106.0069)
		(end 20.818094 -106.0069)
		(width 0.1143)
		(layer "In9.Cu")
		(net "USB3_FPNL_RXP")
	)
	(segment
		(start 37.326316 -106.792268)
		(end 37.891466 -106.55808)
		(width 0.1143)
		(layer "In9.Cu")
		(net "USB3_FPNL_RXP")
	)
	(via
		(at 15.397988 -109.543342)
		(size 0.508)
		(drill 0.254)
		(layers "F.Cu" "B.Cu")
		(net "USB3_FPNL_RXN")
	)
	(via
		(at 40.3987 -98.382836)
		(size 0.508)
		(drill 0.254)
		(layers "F.Cu" "B.Cu")
		(net "USB3_FPNL_RXN")
	)
	(segment
		(start 40.6654 -97.167192)
		(end 40.6654 -98.116136)
		(width 0.14224)
		(layer "B.Cu")
		(net "USB3_FPNL_RXN")
	)
	(segment
		(start 41.745916 -93.892116)
		(end 41.745916 -96.086676)
		(width 0.14224)
		(layer "B.Cu")
		(net "USB3_FPNL_RXN")
	)
	(segment
		(start 40.6654 -98.116136)
		(end 40.3987 -98.382836)
		(width 0.14224)
		(layer "B.Cu")
		(net "USB3_FPNL_RXN")
	)
	(segment
		(start 20.46097 -117.385084)
		(end 20.46097 -117.026182)
		(width 0.14224)
		(layer "B.Cu")
		(net "USB3_FPNL_RXN")
	)
	(segment
		(start 20.096734 -116.147342)
		(end 15.6464 -111.696754)
		(width 0.14224)
		(layer "B.Cu")
		(net "USB3_FPNL_RXN")
	)
	(segment
		(start 41.745916 -96.086676)
		(end 40.6654 -97.167192)
		(width 0.14224)
		(layer "B.Cu")
		(net "USB3_FPNL_RXN")
	)
	(segment
		(start 41.679876 -93.826076)
		(end 41.745916 -93.892116)
		(width 0.14224)
		(layer "B.Cu")
		(net "USB3_FPNL_RXN")
	)
	(segment
		(start 15.6464 -109.791754)
		(end 15.397988 -109.543342)
		(width 0.14224)
		(layer "B.Cu")
		(net "USB3_FPNL_RXN")
	)
	(segment
		(start 20.344892 -118.25986)
		(end 20.344892 -117.501162)
		(width 0.14224)
		(layer "B.Cu")
		(net "USB3_FPNL_RXN")
	)
	(segment
		(start 15.6464 -111.696754)
		(end 15.6464 -109.791754)
		(width 0.14224)
		(layer "B.Cu")
		(net "USB3_FPNL_RXN")
	)
	(segment
		(start 20.46097 -117.026182)
		(end 20.096734 -116.147342)
		(width 0.14224)
		(layer "B.Cu")
		(net "USB3_FPNL_RXN")
	)
	(segment
		(start 20.344892 -117.501162)
		(end 20.46097 -117.385084)
		(width 0.14224)
		(layer "B.Cu")
		(net "USB3_FPNL_RXN")
	)
	(segment
		(start 41.679876 -93.599)
		(end 41.679876 -93.826076)
		(width 0.14224)
		(layer "B.Cu")
		(net "USB3_FPNL_RXN")
	)
	(segment
		(start 25.640538 -108.35132)
		(end 26.199338 -108.91012)
		(width 0.1143)
		(layer "In9.Cu")
		(net "USB3_FPNL_RXN")
	)
	(segment
		(start 39.0398 -106.2228)
		(end 39.7764 -105.4862)
		(width 0.1143)
		(layer "In9.Cu")
		(net "USB3_FPNL_RXN")
	)
	(segment
		(start 26.199338 -108.91012)
		(end 27.293062 -108.91012)
		(width 0.1143)
		(layer "In9.Cu")
		(net "USB3_FPNL_RXN")
	)
	(segment
		(start 15.674848 -107.032552)
		(end 17.03578 -105.67162)
		(width 0.1143)
		(layer "In9.Cu")
		(net "USB3_FPNL_RXN")
	)
	(segment
		(start 37.136324 -106.508042)
		(end 37.824664 -106.2228)
		(width 0.1143)
		(layer "In9.Cu")
		(net "USB3_FPNL_RXN")
	)
	(segment
		(start 17.03578 -105.67162)
		(end 20.957032 -105.67162)
		(width 0.1143)
		(layer "In9.Cu")
		(net "USB3_FPNL_RXN")
	)
	(segment
		(start 23.636732 -108.35132)
		(end 25.640538 -108.35132)
		(width 0.1143)
		(layer "In9.Cu")
		(net "USB3_FPNL_RXN")
	)
	(segment
		(start 35.483546 -108.16082)
		(end 37.136324 -106.508042)
		(width 0.1143)
		(layer "In9.Cu")
		(net "USB3_FPNL_RXN")
	)
	(segment
		(start 39.7764 -105.4862)
		(end 39.7764 -103.690928)
		(width 0.1143)
		(layer "In9.Cu")
		(net "USB3_FPNL_RXN")
	)
	(segment
		(start 37.824664 -106.2228)
		(end 39.0398 -106.2228)
		(width 0.1143)
		(layer "In9.Cu")
		(net "USB3_FPNL_RXN")
	)
	(segment
		(start 40.67556 -102.791768)
		(end 40.67556 -98.659696)
		(width 0.1143)
		(layer "In9.Cu")
		(net "USB3_FPNL_RXN")
	)
	(segment
		(start 29.78658 -108.16082)
		(end 35.483546 -108.16082)
		(width 0.1143)
		(layer "In9.Cu")
		(net "USB3_FPNL_RXN")
	)
	(segment
		(start 27.568652 -108.63453)
		(end 29.31287 -108.63453)
		(width 0.1143)
		(layer "In9.Cu")
		(net "USB3_FPNL_RXN")
	)
	(segment
		(start 15.674848 -109.266482)
		(end 15.674848 -107.032552)
		(width 0.1143)
		(layer "In9.Cu")
		(net "USB3_FPNL_RXN")
	)
	(segment
		(start 39.7764 -103.690928)
		(end 40.67556 -102.791768)
		(width 0.1143)
		(layer "In9.Cu")
		(net "USB3_FPNL_RXN")
	)
	(segment
		(start 40.67556 -98.659696)
		(end 40.3987 -98.382836)
		(width 0.1143)
		(layer "In9.Cu")
		(net "USB3_FPNL_RXN")
	)
	(segment
		(start 29.31287 -108.63453)
		(end 29.78658 -108.16082)
		(width 0.1143)
		(layer "In9.Cu")
		(net "USB3_FPNL_RXN")
	)
	(segment
		(start 20.957032 -105.67162)
		(end 23.636732 -108.35132)
		(width 0.1143)
		(layer "In9.Cu")
		(net "USB3_FPNL_RXN")
	)
	(segment
		(start 15.397988 -109.543342)
		(end 15.674848 -109.266482)
		(width 0.1143)
		(layer "In9.Cu")
		(net "USB3_FPNL_RXN")
	)
	(segment
		(start 27.293062 -108.91012)
		(end 27.568652 -108.63453)
		(width 0.1143)
		(layer "In9.Cu")
		(net "USB3_FPNL_RXN")
	)
	(segment
		(start 44.930822 -94.334076)
		(end 43.256454 -94.334076)
		(width 0.14224)
		(layer "B.Cu")
		(net "USB3_01_TXP_C")
	)
	(segment
		(start 43.18 -93.853254)
		(end 43.18 -93.599)
		(width 0.14224)
		(layer "B.Cu")
		(net "USB3_01_TXP_C")
	)
	(segment
		(start 43.256454 -94.334076)
		(end 43.114214 -94.191836)
		(width 0.14224)
		(layer "B.Cu")
		(net "USB3_01_TXP_C")
	)
	(segment
		(start 43.114214 -94.191836)
		(end 43.114214 -93.91904)
		(width 0.14224)
		(layer "B.Cu")
		(net "USB3_01_TXP_C")
	)
	(segment
		(start 46.0375 -96.10725)
		(end 46.0375 -95.440754)
		(width 0.14224)
		(layer "B.Cu")
		(net "USB3_01_TXP_C")
	)
	(segment
		(start 46.355 -96.42475)
		(end 46.0375 -96.10725)
		(width 0.14224)
		(layer "B.Cu")
		(net "USB3_01_TXP_C")
	)
	(segment
		(start 46.0375 -95.440754)
		(end 44.930822 -94.334076)
		(width 0.14224)
		(layer "B.Cu")
		(net "USB3_01_TXP_C")
	)
	(segment
		(start 43.114214 -93.91904)
		(end 43.18 -93.853254)
		(width 0.14224)
		(layer "B.Cu")
		(net "USB3_01_TXP_C")
	)
	(segment
		(start 42.745914 -94.34449)
		(end 42.745914 -93.927168)
		(width 0.14224)
		(layer "B.Cu")
		(net "USB3_01_TXN_C")
	)
	(segment
		(start 43.1038 -94.702376)
		(end 42.745914 -94.34449)
		(width 0.14224)
		(layer "B.Cu")
		(net "USB3_01_TXN_C")
	)
	(segment
		(start 42.745914 -93.927168)
		(end 42.679874 -93.861128)
		(width 0.14224)
		(layer "B.Cu")
		(net "USB3_01_TXN_C")
	)
	(segment
		(start 45.339 -96.42475)
		(end 45.6692 -96.09455)
		(width 0.14224)
		(layer "B.Cu")
		(net "USB3_01_TXN_C")
	)
	(segment
		(start 42.679874 -93.861128)
		(end 42.679874 -93.599)
		(width 0.14224)
		(layer "B.Cu")
		(net "USB3_01_TXN_C")
	)
	(segment
		(start 45.6692 -96.09455)
		(end 45.6692 -95.593408)
		(width 0.14224)
		(layer "B.Cu")
		(net "USB3_01_TXN_C")
	)
	(segment
		(start 45.6692 -95.593408)
		(end 44.778168 -94.702376)
		(width 0.14224)
		(layer "B.Cu")
		(net "USB3_01_TXN_C")
	)
	(segment
		(start 44.778168 -94.702376)
		(end 43.1038 -94.702376)
		(width 0.14224)
		(layer "B.Cu")
		(net "USB3_01_TXN_C")
	)
	(segment
		(start 40.620442 -24.455374)
		(end 40.861742 -24.214074)
		(width 0.14224)
		(layer "F.Cu")
		(net "USB3_01_MUX_FB_TXP")
	)
	(segment
		(start 40.861742 -24.214074)
		(end 40.861742 -23.570184)
		(width 0.14224)
		(layer "F.Cu")
		(net "USB3_01_MUX_FB_TXP")
	)
	(segment
		(start 40.556942 -22.55647)
		(end 40.636952 -22.63648)
		(width 0.14224)
		(layer "F.Cu")
		(net "USB3_01_MUX_FB_TXP")
	)
	(segment
		(start 40.636952 -23.345394)
		(end 40.636952 -23.00986)
		(width 0.14224)
		(layer "F.Cu")
		(net "USB3_01_MUX_FB_TXP")
	)
	(segment
		(start 40.861742 -23.570184)
		(end 40.636952 -23.345394)
		(width 0.14224)
		(layer "F.Cu")
		(net "USB3_01_MUX_FB_TXP")
	)
	(segment
		(start 40.636952 -22.63648)
		(end 40.636952 -23.00986)
		(width 0.14224)
		(layer "F.Cu")
		(net "USB3_01_MUX_FB_TXP")
	)
	(via
		(at 40.620442 -24.455374)
		(size 0.508)
		(drill 0.254)
		(layers "F.Cu" "B.Cu")
		(net "USB3_01_MUX_FB_TXP")
	)
	(segment
		(start 31.419038 -26.800556)
		(end 31.419038 -26.517092)
		(width 0.14224)
		(layer "B.Cu")
		(net "USB3_01_MUX_FB_TXP")
	)
	(segment
		(start 42.614088 -91.077288)
		(end 42.679874 -91.143074)
		(width 0.14224)
		(layer "B.Cu")
		(net "USB3_01_MUX_FB_TXP")
	)
	(segment
		(start 23.5712 -62.8904)
		(end 24.1681 -63.4873)
		(width 0.14224)
		(layer "B.Cu")
		(net "USB3_01_MUX_FB_TXP")
	)
	(segment
		(start 31.721044 -27.102562)
		(end 31.419038 -26.800556)
		(width 0.14224)
		(layer "B.Cu")
		(net "USB3_01_MUX_FB_TXP")
	)
	(segment
		(start 42.8244 -89.967054)
		(end 42.8244 -90.6272)
		(width 0.14224)
		(layer "B.Cu")
		(net "USB3_01_MUX_FB_TXP")
	)
	(segment
		(start 25.44572 -39.6748)
		(end 25.64638 -39.87546)
		(width 0.14224)
		(layer "B.Cu")
		(net "USB3_01_MUX_FB_TXP")
	)
	(segment
		(start 35.14852 -27.68346)
		(end 34.7218 -27.68346)
		(width 0.14224)
		(layer "B.Cu")
		(net "USB3_01_MUX_FB_TXP")
	)
	(segment
		(start 42.614088 -90.837512)
		(end 42.614088 -91.077288)
		(width 0.14224)
		(layer "B.Cu")
		(net "USB3_01_MUX_FB_TXP")
	)
	(segment
		(start 21.862796 -54.860698)
		(end 21.968714 -55.116222)
		(width 0.14224)
		(layer "B.Cu")
		(net "USB3_01_MUX_FB_TXP")
	)
	(segment
		(start 40.631872 -23.2918)
		(end 40.0304 -23.2918)
		(width 0.14224)
		(layer "B.Cu")
		(net "USB3_01_MUX_FB_TXP")
	)
	(segment
		(start 31.15564 -26.253694)
		(end 30.168088 -25.8445)
		(width 0.14224)
		(layer "B.Cu")
		(net "USB3_01_MUX_FB_TXP")
	)
	(segment
		(start 26.33726 -30.281118)
		(end 25.97023 -31.167578)
		(width 0.14224)
		(layer "B.Cu")
		(net "USB3_01_MUX_FB_TXP")
	)
	(segment
		(start 35.966654 -86.2965)
		(end 36.728908 -86.2965)
		(width 0.14224)
		(layer "B.Cu")
		(net "USB3_01_MUX_FB_TXP")
	)
	(segment
		(start 31.419038 -26.517092)
		(end 31.15564 -26.253694)
		(width 0.14224)
		(layer "B.Cu")
		(net "USB3_01_MUX_FB_TXP")
	)
	(segment
		(start 32.385 -27.4828)
		(end 32.004762 -27.102562)
		(width 0.14224)
		(layer "B.Cu")
		(net "USB3_01_MUX_FB_TXP")
	)
	(segment
		(start 40.620442 -24.455374)
		(end 40.620442 -24.454358)
		(width 0.14224)
		(layer "B.Cu")
		(net "USB3_01_MUX_FB_TXP")
	)
	(segment
		(start 22.227794 -58.295794)
		(end 22.5044 -58.295794)
		(width 0.14224)
		(layer "B.Cu")
		(net "USB3_01_MUX_FB_TXP")
	)
	(segment
		(start 21.549614 -55.616602)
		(end 21.3106 -56.193944)
		(width 0.14224)
		(layer "B.Cu")
		(net "USB3_01_MUX_FB_TXP")
	)
	(segment
		(start 21.3106 -57.3786)
		(end 22.227794 -58.295794)
		(width 0.14224)
		(layer "B.Cu")
		(net "USB3_01_MUX_FB_TXP")
	)
	(segment
		(start 25.1079 -33.393126)
		(end 25.44572 -33.730946)
		(width 0.14224)
		(layer "B.Cu")
		(net "USB3_01_MUX_FB_TXP")
	)
	(segment
		(start 28.15336 -25.8445)
		(end 26.837894 -27.16022)
		(width 0.14224)
		(layer "B.Cu")
		(net "USB3_01_MUX_FB_TXP")
	)
	(segment
		(start 24.1681 -63.4873)
		(end 24.1681 -67.808094)
		(width 0.14224)
		(layer "B.Cu")
		(net "USB3_01_MUX_FB_TXP")
	)
	(segment
		(start 22.806406 -58.5978)
		(end 22.806406 -58.874406)
		(width 0.14224)
		(layer "B.Cu")
		(net "USB3_01_MUX_FB_TXP")
	)
	(segment
		(start 22.5044 -58.295794)
		(end 22.806406 -58.5978)
		(width 0.14224)
		(layer "B.Cu")
		(net "USB3_01_MUX_FB_TXP")
	)
	(segment
		(start 23.241 -44.7548)
		(end 23.241 -51.533552)
		(width 0.14224)
		(layer "B.Cu")
		(net "USB3_01_MUX_FB_TXP")
	)
	(segment
		(start 35.077654 -85.4075)
		(end 35.966654 -86.2965)
		(width 0.14224)
		(layer "B.Cu")
		(net "USB3_01_MUX_FB_TXP")
	)
	(segment
		(start 34.52114 -27.4828)
		(end 32.385 -27.4828)
		(width 0.14224)
		(layer "B.Cu")
		(net "USB3_01_MUX_FB_TXP")
	)
	(segment
		(start 25.44572 -41.7576)
		(end 25.44572 -42.55008)
		(width 0.14224)
		(layer "B.Cu")
		(net "USB3_01_MUX_FB_TXP")
	)
	(segment
		(start 42.8244 -90.6272)
		(end 42.614088 -90.837512)
		(width 0.14224)
		(layer "B.Cu")
		(net "USB3_01_MUX_FB_TXP")
	)
	(segment
		(start 21.805392 -55.510938)
		(end 21.549614 -55.616602)
		(width 0.14224)
		(layer "B.Cu")
		(net "USB3_01_MUX_FB_TXP")
	)
	(segment
		(start 31.525718 -83.265518)
		(end 33.6677 -85.4075)
		(width 0.14224)
		(layer "B.Cu")
		(net "USB3_01_MUX_FB_TXP")
	)
	(segment
		(start 23.5712 -59.6392)
		(end 23.5712 -62.8904)
		(width 0.14224)
		(layer "B.Cu")
		(net "USB3_01_MUX_FB_TXP")
	)
	(segment
		(start 25.27935 -31.858458)
		(end 25.1079 -32.27197)
		(width 0.14224)
		(layer "B.Cu")
		(net "USB3_01_MUX_FB_TXP")
	)
	(segment
		(start 25.44572 -33.730946)
		(end 25.44572 -39.6748)
		(width 0.14224)
		(layer "B.Cu")
		(net "USB3_01_MUX_FB_TXP")
	)
	(segment
		(start 29.05252 -77.20584)
		(end 29.05252 -79.563976)
		(width 0.14224)
		(layer "B.Cu")
		(net "USB3_01_MUX_FB_TXP")
	)
	(segment
		(start 42.679874 -91.143074)
		(end 42.679874 -91.398852)
		(width 0.14224)
		(layer "B.Cu")
		(net "USB3_01_MUX_FB_TXP")
	)
	(segment
		(start 29.05252 -79.563976)
		(end 31.525718 -83.265518)
		(width 0.14224)
		(layer "B.Cu")
		(net "USB3_01_MUX_FB_TXP")
	)
	(segment
		(start 24.1681 -67.808094)
		(end 27.358594 -75.51166)
		(width 0.14224)
		(layer "B.Cu")
		(net "USB3_01_MUX_FB_TXP")
	)
	(segment
		(start 26.33726 -28.044394)
		(end 26.33726 -30.281118)
		(width 0.14224)
		(layer "B.Cu")
		(net "USB3_01_MUX_FB_TXP")
	)
	(segment
		(start 25.97023 -31.167578)
		(end 25.27935 -31.858458)
		(width 0.14224)
		(layer "B.Cu")
		(net "USB3_01_MUX_FB_TXP")
	)
	(segment
		(start 34.7218 -27.68346)
		(end 34.52114 -27.4828)
		(width 0.14224)
		(layer "B.Cu")
		(net "USB3_01_MUX_FB_TXP")
	)
	(segment
		(start 38.344856 -26.200862)
		(end 38.061138 -26.200862)
		(width 0.14224)
		(layer "B.Cu")
		(net "USB3_01_MUX_FB_TXP")
	)
	(segment
		(start 38.481508 -88.0491)
		(end 40.906446 -88.0491)
		(width 0.14224)
		(layer "B.Cu")
		(net "USB3_01_MUX_FB_TXP")
	)
	(segment
		(start 25.44572 -40.92956)
		(end 25.64638 -41.13022)
		(width 0.14224)
		(layer "B.Cu")
		(net "USB3_01_MUX_FB_TXP")
	)
	(segment
		(start 26.484834 -27.688286)
		(end 26.411428 -27.865578)
		(width 0.14224)
		(layer "B.Cu")
		(net "USB3_01_MUX_FB_TXP")
	)
	(segment
		(start 30.168088 -25.8445)
		(end 28.15336 -25.8445)
		(width 0.14224)
		(layer "B.Cu")
		(net "USB3_01_MUX_FB_TXP")
	)
	(segment
		(start 35.34918 -27.4828)
		(end 35.14852 -27.68346)
		(width 0.14224)
		(layer "B.Cu")
		(net "USB3_01_MUX_FB_TXP")
	)
	(segment
		(start 33.6677 -85.4075)
		(end 35.077654 -85.4075)
		(width 0.14224)
		(layer "B.Cu")
		(net "USB3_01_MUX_FB_TXP")
	)
	(segment
		(start 38.061138 -26.200862)
		(end 36.7792 -27.4828)
		(width 0.14224)
		(layer "B.Cu")
		(net "USB3_01_MUX_FB_TXP")
	)
	(segment
		(start 40.873426 -24.201374)
		(end 40.873426 -23.533354)
		(width 0.14224)
		(layer "B.Cu")
		(net "USB3_01_MUX_FB_TXP")
	)
	(segment
		(start 25.44572 -42.55008)
		(end 23.241 -44.7548)
		(width 0.14224)
		(layer "B.Cu")
		(net "USB3_01_MUX_FB_TXP")
	)
	(segment
		(start 25.1079 -32.27197)
		(end 25.1079 -33.393126)
		(width 0.14224)
		(layer "B.Cu")
		(net "USB3_01_MUX_FB_TXP")
	)
	(segment
		(start 26.411174 -27.865832)
		(end 26.33726 -28.044394)
		(width 0.14224)
		(layer "B.Cu")
		(net "USB3_01_MUX_FB_TXP")
	)
	(segment
		(start 27.358594 -75.51166)
		(end 29.05252 -77.20584)
		(width 0.14224)
		(layer "B.Cu")
		(net "USB3_01_MUX_FB_TXP")
	)
	(segment
		(start 25.64638 -41.13022)
		(end 25.64638 -41.55694)
		(width 0.14224)
		(layer "B.Cu")
		(net "USB3_01_MUX_FB_TXP")
	)
	(segment
		(start 40.906446 -88.0491)
		(end 42.8244 -89.967054)
		(width 0.14224)
		(layer "B.Cu")
		(net "USB3_01_MUX_FB_TXP")
	)
	(segment
		(start 36.7792 -27.4828)
		(end 35.34918 -27.4828)
		(width 0.14224)
		(layer "B.Cu")
		(net "USB3_01_MUX_FB_TXP")
	)
	(segment
		(start 26.411428 -27.865578)
		(end 26.411174 -27.865832)
		(width 0.14224)
		(layer "B.Cu")
		(net "USB3_01_MUX_FB_TXP")
	)
	(segment
		(start 21.968714 -55.116222)
		(end 21.805392 -55.510938)
		(width 0.14224)
		(layer "B.Cu")
		(net "USB3_01_MUX_FB_TXP")
	)
	(segment
		(start 38.646862 -25.615138)
		(end 38.646862 -25.898856)
		(width 0.14224)
		(layer "B.Cu")
		(net "USB3_01_MUX_FB_TXP")
	)
	(segment
		(start 25.64638 -39.87546)
		(end 25.64638 -40.30218)
		(width 0.14224)
		(layer "B.Cu")
		(net "USB3_01_MUX_FB_TXP")
	)
	(segment
		(start 40.620442 -24.454358)
		(end 40.873426 -24.201374)
		(width 0.14224)
		(layer "B.Cu")
		(net "USB3_01_MUX_FB_TXP")
	)
	(segment
		(start 21.3106 -56.193944)
		(end 21.3106 -57.3786)
		(width 0.14224)
		(layer "B.Cu")
		(net "USB3_01_MUX_FB_TXP")
	)
	(segment
		(start 36.728908 -86.2965)
		(end 38.481508 -88.0491)
		(width 0.14224)
		(layer "B.Cu")
		(net "USB3_01_MUX_FB_TXP")
	)
	(segment
		(start 39.1414 -24.1808)
		(end 39.1414 -25.1206)
		(width 0.14224)
		(layer "B.Cu")
		(net "USB3_01_MUX_FB_TXP")
	)
	(segment
		(start 25.44572 -40.50284)
		(end 25.44572 -40.92956)
		(width 0.14224)
		(layer "B.Cu")
		(net "USB3_01_MUX_FB_TXP")
	)
	(segment
		(start 22.806406 -58.874406)
		(end 23.5712 -59.6392)
		(width 0.14224)
		(layer "B.Cu")
		(net "USB3_01_MUX_FB_TXP")
	)
	(segment
		(start 32.004762 -27.102562)
		(end 31.721044 -27.102562)
		(width 0.14224)
		(layer "B.Cu")
		(net "USB3_01_MUX_FB_TXP")
	)
	(segment
		(start 38.646862 -25.898856)
		(end 38.344856 -26.200862)
		(width 0.14224)
		(layer "B.Cu")
		(net "USB3_01_MUX_FB_TXP")
	)
	(segment
		(start 40.0304 -23.2918)
		(end 39.1414 -24.1808)
		(width 0.14224)
		(layer "B.Cu")
		(net "USB3_01_MUX_FB_TXP")
	)
	(segment
		(start 25.64638 -40.30218)
		(end 25.44572 -40.50284)
		(width 0.14224)
		(layer "B.Cu")
		(net "USB3_01_MUX_FB_TXP")
	)
	(segment
		(start 39.1414 -25.1206)
		(end 38.646862 -25.615138)
		(width 0.14224)
		(layer "B.Cu")
		(net "USB3_01_MUX_FB_TXP")
	)
	(segment
		(start 26.837894 -27.16022)
		(end 26.484834 -27.688286)
		(width 0.14224)
		(layer "B.Cu")
		(net "USB3_01_MUX_FB_TXP")
	)
	(segment
		(start 25.64638 -41.55694)
		(end 25.44572 -41.7576)
		(width 0.14224)
		(layer "B.Cu")
		(net "USB3_01_MUX_FB_TXP")
	)
	(segment
		(start 23.241 -51.533552)
		(end 21.862796 -54.860698)
		(width 0.14224)
		(layer "B.Cu")
		(net "USB3_01_MUX_FB_TXP")
	)
	(segment
		(start 40.873426 -23.533354)
		(end 40.631872 -23.2918)
		(width 0.14224)
		(layer "B.Cu")
		(net "USB3_01_MUX_FB_TXP")
	)
	(segment
		(start 41.230042 -24.175974)
		(end 41.230042 -23.589234)
		(width 0.14224)
		(layer "F.Cu")
		(net "USB3_01_MUX_FB_TXN")
	)
	(segment
		(start 41.572942 -22.55647)
		(end 41.486836 -22.642576)
		(width 0.14224)
		(layer "F.Cu")
		(net "USB3_01_MUX_FB_TXN")
	)
	(segment
		(start 41.486836 -22.642576)
		(end 41.486836 -23.00986)
		(width 0.14224)
		(layer "F.Cu")
		(net "USB3_01_MUX_FB_TXN")
	)
	(segment
		(start 41.230042 -23.589234)
		(end 41.486836 -23.33244)
		(width 0.14224)
		(layer "F.Cu")
		(net "USB3_01_MUX_FB_TXN")
	)
	(segment
		(start 41.486836 -23.33244)
		(end 41.486836 -23.00986)
		(width 0.14224)
		(layer "F.Cu")
		(net "USB3_01_MUX_FB_TXN")
	)
	(segment
		(start 41.509442 -24.455374)
		(end 41.230042 -24.175974)
		(width 0.14224)
		(layer "F.Cu")
		(net "USB3_01_MUX_FB_TXN")
	)
	(via
		(at 41.509442 -24.455374)
		(size 0.508)
		(drill 0.254)
		(layers "F.Cu" "B.Cu")
		(net "USB3_01_MUX_FB_TXN")
	)
	(segment
		(start 34.925 -85.7758)
		(end 35.814 -86.6648)
		(width 0.14224)
		(layer "B.Cu")
		(net "USB3_01_MUX_FB_TXN")
	)
	(segment
		(start 40.753792 -88.4174)
		(end 42.4561 -90.119708)
		(width 0.14224)
		(layer "B.Cu")
		(net "USB3_01_MUX_FB_TXN")
	)
	(segment
		(start 35.814 -86.6648)
		(end 36.576254 -86.6648)
		(width 0.14224)
		(layer "B.Cu")
		(net "USB3_01_MUX_FB_TXN")
	)
	(segment
		(start 23.2029 -63.043054)
		(end 23.7998 -63.639954)
		(width 0.14224)
		(layer "B.Cu")
		(net "USB3_01_MUX_FB_TXN")
	)
	(segment
		(start 41.509442 -24.455374)
		(end 41.241726 -24.187658)
		(width 0.14224)
		(layer "B.Cu")
		(net "USB3_01_MUX_FB_TXN")
	)
	(segment
		(start 40.784526 -22.9235)
		(end 39.877746 -22.9235)
		(width 0.14224)
		(layer "B.Cu")
		(net "USB3_01_MUX_FB_TXN")
	)
	(segment
		(start 36.576254 -86.6648)
		(end 38.328854 -88.4174)
		(width 0.14224)
		(layer "B.Cu")
		(net "USB3_01_MUX_FB_TXN")
	)
	(segment
		(start 23.2029 -59.791854)
		(end 23.2029 -63.043054)
		(width 0.14224)
		(layer "B.Cu")
		(net "USB3_01_MUX_FB_TXN")
	)
	(segment
		(start 26.551636 -26.92527)
		(end 26.158698 -27.513026)
		(width 0.14224)
		(layer "B.Cu")
		(net "USB3_01_MUX_FB_TXN")
	)
	(segment
		(start 27.046174 -75.720448)
		(end 28.68422 -77.358494)
		(width 0.14224)
		(layer "B.Cu")
		(net "USB3_01_MUX_FB_TXN")
	)
	(segment
		(start 25.96896 -27.970988)
		(end 25.96896 -30.207712)
		(width 0.14224)
		(layer "B.Cu")
		(net "USB3_01_MUX_FB_TXN")
	)
	(segment
		(start 25.07742 -33.8836)
		(end 25.07742 -42.397426)
		(width 0.14224)
		(layer "B.Cu")
		(net "USB3_01_MUX_FB_TXN")
	)
	(segment
		(start 28.000706 -25.4762)
		(end 26.551636 -26.92527)
		(width 0.14224)
		(layer "B.Cu")
		(net "USB3_01_MUX_FB_TXN")
	)
	(segment
		(start 38.7731 -24.967946)
		(end 36.626546 -27.1145)
		(width 0.14224)
		(layer "B.Cu")
		(net "USB3_01_MUX_FB_TXN")
	)
	(segment
		(start 28.68422 -77.358494)
		(end 28.68422 -79.675736)
		(width 0.14224)
		(layer "B.Cu")
		(net "USB3_01_MUX_FB_TXN")
	)
	(segment
		(start 24.967184 -31.64967)
		(end 24.7396 -32.198564)
		(width 0.14224)
		(layer "B.Cu")
		(net "USB3_01_MUX_FB_TXN")
	)
	(segment
		(start 39.877746 -22.9235)
		(end 38.7731 -24.028146)
		(width 0.14224)
		(layer "B.Cu")
		(net "USB3_01_MUX_FB_TXN")
	)
	(segment
		(start 42.4561 -90.474546)
		(end 42.245788 -90.684858)
		(width 0.14224)
		(layer "B.Cu")
		(net "USB3_01_MUX_FB_TXN")
	)
	(segment
		(start 42.180002 -91.144598)
		(end 42.180002 -91.398852)
		(width 0.14224)
		(layer "B.Cu")
		(net "USB3_01_MUX_FB_TXN")
	)
	(segment
		(start 33.515046 -85.7758)
		(end 34.925 -85.7758)
		(width 0.14224)
		(layer "B.Cu")
		(net "USB3_01_MUX_FB_TXN")
	)
	(segment
		(start 22.8727 -44.602146)
		(end 22.8727 -51.460146)
		(width 0.14224)
		(layer "B.Cu")
		(net "USB3_01_MUX_FB_TXN")
	)
	(segment
		(start 42.245788 -91.078812)
		(end 42.180002 -91.144598)
		(width 0.14224)
		(layer "B.Cu")
		(net "USB3_01_MUX_FB_TXN")
	)
	(segment
		(start 30.241494 -25.4762)
		(end 28.000706 -25.4762)
		(width 0.14224)
		(layer "B.Cu")
		(net "USB3_01_MUX_FB_TXN")
	)
	(segment
		(start 22.8727 -51.460146)
		(end 20.9423 -56.120538)
		(width 0.14224)
		(layer "B.Cu")
		(net "USB3_01_MUX_FB_TXN")
	)
	(segment
		(start 42.4561 -90.119708)
		(end 42.4561 -90.474546)
		(width 0.14224)
		(layer "B.Cu")
		(net "USB3_01_MUX_FB_TXN")
	)
	(segment
		(start 28.68422 -79.675736)
		(end 31.23946 -83.500468)
		(width 0.14224)
		(layer "B.Cu")
		(net "USB3_01_MUX_FB_TXN")
	)
	(segment
		(start 25.07742 -42.397426)
		(end 22.8727 -44.602146)
		(width 0.14224)
		(layer "B.Cu")
		(net "USB3_01_MUX_FB_TXN")
	)
	(segment
		(start 20.9423 -56.120538)
		(end 20.9423 -57.531254)
		(width 0.14224)
		(layer "B.Cu")
		(net "USB3_01_MUX_FB_TXN")
	)
	(segment
		(start 20.9423 -57.531254)
		(end 23.2029 -59.791854)
		(width 0.14224)
		(layer "B.Cu")
		(net "USB3_01_MUX_FB_TXN")
	)
	(segment
		(start 31.23946 -83.500468)
		(end 33.515046 -85.7758)
		(width 0.14224)
		(layer "B.Cu")
		(net "USB3_01_MUX_FB_TXN")
	)
	(segment
		(start 25.96896 -30.207712)
		(end 25.65781 -30.95879)
		(width 0.14224)
		(layer "B.Cu")
		(net "USB3_01_MUX_FB_TXN")
	)
	(segment
		(start 38.328854 -88.4174)
		(end 40.753792 -88.4174)
		(width 0.14224)
		(layer "B.Cu")
		(net "USB3_01_MUX_FB_TXN")
	)
	(segment
		(start 41.241726 -23.3807)
		(end 40.784526 -22.9235)
		(width 0.14224)
		(layer "B.Cu")
		(net "USB3_01_MUX_FB_TXN")
	)
	(segment
		(start 23.7998 -63.639954)
		(end 23.7998 -67.8815)
		(width 0.14224)
		(layer "B.Cu")
		(net "USB3_01_MUX_FB_TXN")
	)
	(segment
		(start 25.65781 -30.95879)
		(end 24.967184 -31.64967)
		(width 0.14224)
		(layer "B.Cu")
		(net "USB3_01_MUX_FB_TXN")
	)
	(segment
		(start 23.7998 -67.8815)
		(end 27.046174 -75.720448)
		(width 0.14224)
		(layer "B.Cu")
		(net "USB3_01_MUX_FB_TXN")
	)
	(segment
		(start 26.158698 -27.513026)
		(end 25.96896 -27.970988)
		(width 0.14224)
		(layer "B.Cu")
		(net "USB3_01_MUX_FB_TXN")
	)
	(segment
		(start 42.245788 -90.684858)
		(end 42.245788 -91.078812)
		(width 0.14224)
		(layer "B.Cu")
		(net "USB3_01_MUX_FB_TXN")
	)
	(segment
		(start 31.364428 -25.941274)
		(end 30.241494 -25.4762)
		(width 0.14224)
		(layer "B.Cu")
		(net "USB3_01_MUX_FB_TXN")
	)
	(segment
		(start 36.626546 -27.1145)
		(end 32.537654 -27.1145)
		(width 0.14224)
		(layer "B.Cu")
		(net "USB3_01_MUX_FB_TXN")
	)
	(segment
		(start 32.537654 -27.1145)
		(end 31.364428 -25.941274)
		(width 0.14224)
		(layer "B.Cu")
		(net "USB3_01_MUX_FB_TXN")
	)
	(segment
		(start 41.241726 -24.187658)
		(end 41.241726 -23.3807)
		(width 0.14224)
		(layer "B.Cu")
		(net "USB3_01_MUX_FB_TXN")
	)
	(segment
		(start 24.7396 -33.54578)
		(end 25.07742 -33.8836)
		(width 0.14224)
		(layer "B.Cu")
		(net "USB3_01_MUX_FB_TXN")
	)
	(segment
		(start 24.7396 -32.198564)
		(end 24.7396 -33.54578)
		(width 0.14224)
		(layer "B.Cu")
		(net "USB3_01_MUX_FB_TXN")
	)
	(segment
		(start 38.7731 -24.028146)
		(end 38.7731 -24.967946)
		(width 0.14224)
		(layer "B.Cu")
		(net "USB3_01_MUX_FB_TXN")
	)
	(segment
		(start 43.030648 -22.63648)
		(end 43.030648 -23.00986)
		(width 0.14224)
		(layer "F.Cu")
		(net "USB3_01_MUX_FB_RXP")
	)
	(segment
		(start 43.030648 -23.319994)
		(end 43.260518 -23.549864)
		(width 0.14224)
		(layer "F.Cu")
		(net "USB3_01_MUX_FB_RXP")
	)
	(segment
		(start 43.260518 -24.208994)
		(end 43.014138 -24.455374)
		(width 0.14224)
		(layer "F.Cu")
		(net "USB3_01_MUX_FB_RXP")
	)
	(segment
		(start 43.260518 -23.549864)
		(end 43.260518 -24.208994)
		(width 0.14224)
		(layer "F.Cu")
		(net "USB3_01_MUX_FB_RXP")
	)
	(segment
		(start 42.950638 -22.55647)
		(end 43.030648 -22.63648)
		(width 0.14224)
		(layer "F.Cu")
		(net "USB3_01_MUX_FB_RXP")
	)
	(segment
		(start 43.030648 -23.00986)
		(end 43.030648 -23.319994)
		(width 0.14224)
		(layer "F.Cu")
		(net "USB3_01_MUX_FB_RXP")
	)
	(via
		(at 43.014138 -24.455374)
		(size 0.508)
		(drill 0.254)
		(layers "F.Cu" "B.Cu")
		(net "USB3_01_MUX_FB_RXP")
	)
	(segment
		(start 23.856696 -72.62495)
		(end 23.488904 -72.62495)
		(width 0.14224)
		(layer "B.Cu")
		(net "USB3_01_MUX_FB_RXP")
	)
	(segment
		(start 40.614092 -90.621612)
		(end 40.473884 -90.28303)
		(width 0.14224)
		(layer "B.Cu")
		(net "USB3_01_MUX_FB_RXP")
	)
	(segment
		(start 21.9456 -51.284886)
		(end 21.9456 -44.069)
		(width 0.14224)
		(layer "B.Cu")
		(net "USB3_01_MUX_FB_RXP")
	)
	(segment
		(start 40.8432 -21.6154)
		(end 41.431972 -21.6154)
		(width 0.14224)
		(layer "B.Cu")
		(net "USB3_01_MUX_FB_RXP")
	)
	(segment
		(start 37.182552 -88.9635)
		(end 35.433508 -88.9635)
		(width 0.14224)
		(layer "B.Cu")
		(net "USB3_01_MUX_FB_RXP")
	)
	(segment
		(start 38.879526 -22.571202)
		(end 38.879526 -22.283674)
		(width 0.14224)
		(layer "B.Cu")
		(net "USB3_01_MUX_FB_RXP")
	)
	(segment
		(start 37.712142 -23.451312)
		(end 38.304724 -22.85873)
		(width 0.14224)
		(layer "B.Cu")
		(net "USB3_01_MUX_FB_RXP")
	)
	(segment
		(start 28.652216 -81.96199)
		(end 28.652216 -81.25587)
		(width 0.14224)
		(layer "B.Cu")
		(net "USB3_01_MUX_FB_RXP")
	)
	(segment
		(start 39.535354 -89.3445)
		(end 38.10254 -89.3445)
		(width 0.14224)
		(layer "B.Cu")
		(net "USB3_01_MUX_FB_RXP")
	)
	(segment
		(start 38.879526 -22.283674)
		(end 39.5478 -21.6154)
		(width 0.14224)
		(layer "B.Cu")
		(net "USB3_01_MUX_FB_RXP")
	)
	(segment
		(start 42.686224 -23.15718)
		(end 42.973752 -23.15718)
		(width 0.14224)
		(layer "B.Cu")
		(net "USB3_01_MUX_FB_RXP")
	)
	(segment
		(start 37.217858 -24.644604)
		(end 37.712142 -23.451312)
		(width 0.14224)
		(layer "B.Cu")
		(net "USB3_01_MUX_FB_RXP")
	)
	(segment
		(start 25.418796 -26.917904)
		(end 26.056336 -25.963118)
		(width 0.14224)
		(layer "B.Cu")
		(net "USB3_01_MUX_FB_RXP")
	)
	(segment
		(start 27.77744 -77.764894)
		(end 25.10028 -75.087734)
		(width 0.14224)
		(layer "B.Cu")
		(net "USB3_01_MUX_FB_RXP")
	)
	(segment
		(start 30.112462 -84.37499)
		(end 29.82849 -84.37499)
		(width 0.14224)
		(layer "B.Cu")
		(net "USB3_01_MUX_FB_RXP")
	)
	(segment
		(start 26.056336 -25.963118)
		(end 27.584654 -24.4348)
		(width 0.14224)
		(layer "B.Cu")
		(net "USB3_01_MUX_FB_RXP")
	)
	(segment
		(start 23.7871 -42.2275)
		(end 23.7871 -32.133794)
		(width 0.14224)
		(layer "B.Cu")
		(net "USB3_01_MUX_FB_RXP")
	)
	(segment
		(start 40.64 -21.8186)
		(end 40.8432 -21.6154)
		(width 0.14224)
		(layer "B.Cu")
		(net "USB3_01_MUX_FB_RXP")
	)
	(segment
		(start 22.479 -66.56578)
		(end 22.479 -64.643)
		(width 0.14224)
		(layer "B.Cu")
		(net "USB3_01_MUX_FB_RXP")
	)
	(segment
		(start 33.325308 -86.8553)
		(end 32.3088 -86.8553)
		(width 0.14224)
		(layer "B.Cu")
		(net "USB3_01_MUX_FB_RXP")
	)
	(segment
		(start 25.10028 -73.868534)
		(end 23.856696 -72.62495)
		(width 0.14224)
		(layer "B.Cu")
		(net "USB3_01_MUX_FB_RXP")
	)
	(segment
		(start 22.479 -71.615046)
		(end 22.479 -70.24878)
		(width 0.14224)
		(layer "B.Cu")
		(net "USB3_01_MUX_FB_RXP")
	)
	(segment
		(start 21.971 -61.2648)
		(end 19.8755 -59.1693)
		(width 0.14224)
		(layer "B.Cu")
		(net "USB3_01_MUX_FB_RXP")
	)
	(segment
		(start 42.398696 -22.582124)
		(end 42.398696 -22.869652)
		(width 0.14224)
		(layer "B.Cu")
		(net "USB3_01_MUX_FB_RXP")
	)
	(segment
		(start 22.70252 -67.21602)
		(end 22.70252 -66.7893)
		(width 0.14224)
		(layer "B.Cu")
		(net "USB3_01_MUX_FB_RXP")
	)
	(segment
		(start 33.224216 -25.7302)
		(end 35.804094 -25.7302)
		(width 0.14224)
		(layer "B.Cu")
		(net "USB3_01_MUX_FB_RXP")
	)
	(segment
		(start 25.10028 -75.087734)
		(end 25.10028 -73.868534)
		(width 0.14224)
		(layer "B.Cu")
		(net "USB3_01_MUX_FB_RXP")
	)
	(segment
		(start 22.70252 -69.59854)
		(end 22.479 -69.37502)
		(width 0.14224)
		(layer "B.Cu")
		(net "USB3_01_MUX_FB_RXP")
	)
	(segment
		(start 42.398696 -22.869652)
		(end 42.686224 -23.15718)
		(width 0.14224)
		(layer "B.Cu")
		(net "USB3_01_MUX_FB_RXP")
	)
	(segment
		(start 35.804094 -25.7302)
		(end 36.36391 -25.498552)
		(width 0.14224)
		(layer "B.Cu")
		(net "USB3_01_MUX_FB_RXP")
	)
	(segment
		(start 42.973752 -23.15718)
		(end 43.261026 -23.444454)
		(width 0.14224)
		(layer "B.Cu")
		(net "USB3_01_MUX_FB_RXP")
	)
	(segment
		(start 19.8755 -59.1693)
		(end 19.8755 -56.284114)
		(width 0.14224)
		(layer "B.Cu")
		(net "USB3_01_MUX_FB_RXP")
	)
	(segment
		(start 22.479 -64.643)
		(end 21.971 -64.135)
		(width 0.14224)
		(layer "B.Cu")
		(net "USB3_01_MUX_FB_RXP")
	)
	(segment
		(start 39.5478 -21.6154)
		(end 40.0304 -21.6154)
		(width 0.14224)
		(layer "B.Cu")
		(net "USB3_01_MUX_FB_RXP")
	)
	(segment
		(start 25.057354 -27.79014)
		(end 25.418796 -26.917904)
		(width 0.14224)
		(layer "B.Cu")
		(net "USB3_01_MUX_FB_RXP")
	)
	(segment
		(start 40.2336 -21.8186)
		(end 40.64 -21.8186)
		(width 0.14224)
		(layer "B.Cu")
		(net "USB3_01_MUX_FB_RXP")
	)
	(segment
		(start 22.479 -67.43954)
		(end 22.70252 -67.21602)
		(width 0.14224)
		(layer "B.Cu")
		(net "USB3_01_MUX_FB_RXP")
	)
	(segment
		(start 27.584654 -24.4348)
		(end 30.096714 -24.4348)
		(width 0.14224)
		(layer "B.Cu")
		(net "USB3_01_MUX_FB_RXP")
	)
	(segment
		(start 40.614092 -91.077288)
		(end 40.614092 -90.621612)
		(width 0.14224)
		(layer "B.Cu")
		(net "USB3_01_MUX_FB_RXP")
	)
	(segment
		(start 29.82849 -84.37499)
		(end 29.526992 -84.073492)
		(width 0.14224)
		(layer "B.Cu")
		(net "USB3_01_MUX_FB_RXP")
	)
	(segment
		(start 38.591998 -22.85873)
		(end 38.879526 -22.571202)
		(width 0.14224)
		(layer "B.Cu")
		(net "USB3_01_MUX_FB_RXP")
	)
	(segment
		(start 27.77744 -79.946246)
		(end 27.77744 -77.764894)
		(width 0.14224)
		(layer "B.Cu")
		(net "USB3_01_MUX_FB_RXP")
	)
	(segment
		(start 30.096714 -24.4348)
		(end 33.224216 -25.7302)
		(width 0.14224)
		(layer "B.Cu")
		(net "USB3_01_MUX_FB_RXP")
	)
	(segment
		(start 40.473884 -90.28303)
		(end 39.535354 -89.3445)
		(width 0.14224)
		(layer "B.Cu")
		(net "USB3_01_MUX_FB_RXP")
	)
	(segment
		(start 40.679878 -91.143074)
		(end 40.614092 -91.077288)
		(width 0.14224)
		(layer "B.Cu")
		(net "USB3_01_MUX_FB_RXP")
	)
	(segment
		(start 22.70252 -66.7893)
		(end 22.479 -66.56578)
		(width 0.14224)
		(layer "B.Cu")
		(net "USB3_01_MUX_FB_RXP")
	)
	(segment
		(start 22.479 -69.37502)
		(end 22.479 -68.74002)
		(width 0.14224)
		(layer "B.Cu")
		(net "USB3_01_MUX_FB_RXP")
	)
	(segment
		(start 23.7871 -32.133794)
		(end 25.0571 -29.070554)
		(width 0.14224)
		(layer "B.Cu")
		(net "USB3_01_MUX_FB_RXP")
	)
	(segment
		(start 30.414468 -84.676996)
		(end 30.112462 -84.37499)
		(width 0.14224)
		(layer "B.Cu")
		(net "USB3_01_MUX_FB_RXP")
	)
	(segment
		(start 21.971 -64.135)
		(end 21.971 -61.2648)
		(width 0.14224)
		(layer "B.Cu")
		(net "USB3_01_MUX_FB_RXP")
	)
	(segment
		(start 19.8755 -56.284114)
		(end 21.9456 -51.284886)
		(width 0.14224)
		(layer "B.Cu")
		(net "USB3_01_MUX_FB_RXP")
	)
	(segment
		(start 25.0571 -29.070554)
		(end 25.057354 -27.79014)
		(width 0.14224)
		(layer "B.Cu")
		(net "USB3_01_MUX_FB_RXP")
	)
	(segment
		(start 22.70252 -68.5165)
		(end 22.70252 -68.08978)
		(width 0.14224)
		(layer "B.Cu")
		(net "USB3_01_MUX_FB_RXP")
	)
	(segment
		(start 35.433508 -88.9635)
		(end 33.325308 -86.8553)
		(width 0.14224)
		(layer "B.Cu")
		(net "USB3_01_MUX_FB_RXP")
	)
	(segment
		(start 40.679878 -91.398852)
		(end 40.679878 -91.143074)
		(width 0.14224)
		(layer "B.Cu")
		(net "USB3_01_MUX_FB_RXP")
	)
	(segment
		(start 22.479 -70.24878)
		(end 22.70252 -70.02526)
		(width 0.14224)
		(layer "B.Cu")
		(net "USB3_01_MUX_FB_RXP")
	)
	(segment
		(start 22.70252 -70.02526)
		(end 22.70252 -69.59854)
		(width 0.14224)
		(layer "B.Cu")
		(net "USB3_01_MUX_FB_RXP")
	)
	(segment
		(start 38.304724 -22.85873)
		(end 38.591998 -22.85873)
		(width 0.14224)
		(layer "B.Cu")
		(net "USB3_01_MUX_FB_RXP")
	)
	(segment
		(start 32.3088 -86.8553)
		(end 30.414468 -84.960968)
		(width 0.14224)
		(layer "B.Cu")
		(net "USB3_01_MUX_FB_RXP")
	)
	(segment
		(start 43.261026 -24.208486)
		(end 43.014138 -24.455374)
		(width 0.14224)
		(layer "B.Cu")
		(net "USB3_01_MUX_FB_RXP")
	)
	(segment
		(start 43.261026 -23.444454)
		(end 43.261026 -24.208486)
		(width 0.14224)
		(layer "B.Cu")
		(net "USB3_01_MUX_FB_RXP")
	)
	(segment
		(start 29.526992 -84.073492)
		(end 28.652216 -81.96199)
		(width 0.14224)
		(layer "B.Cu")
		(net "USB3_01_MUX_FB_RXP")
	)
	(segment
		(start 28.652216 -81.25587)
		(end 27.77744 -79.946246)
		(width 0.14224)
		(layer "B.Cu")
		(net "USB3_01_MUX_FB_RXP")
	)
	(segment
		(start 41.431972 -21.6154)
		(end 42.398696 -22.582124)
		(width 0.14224)
		(layer "B.Cu")
		(net "USB3_01_MUX_FB_RXP")
	)
	(segment
		(start 21.9456 -44.069)
		(end 23.7871 -42.2275)
		(width 0.14224)
		(layer "B.Cu")
		(net "USB3_01_MUX_FB_RXP")
	)
	(segment
		(start 38.10254 -89.3445)
		(end 37.182552 -88.9635)
		(width 0.14224)
		(layer "B.Cu")
		(net "USB3_01_MUX_FB_RXP")
	)
	(segment
		(start 22.70252 -68.08978)
		(end 22.479 -67.86626)
		(width 0.14224)
		(layer "B.Cu")
		(net "USB3_01_MUX_FB_RXP")
	)
	(segment
		(start 23.488904 -72.62495)
		(end 22.479 -71.615046)
		(width 0.14224)
		(layer "B.Cu")
		(net "USB3_01_MUX_FB_RXP")
	)
	(segment
		(start 40.0304 -21.6154)
		(end 40.2336 -21.8186)
		(width 0.14224)
		(layer "B.Cu")
		(net "USB3_01_MUX_FB_RXP")
	)
	(segment
		(start 36.36391 -25.498552)
		(end 37.217858 -24.644604)
		(width 0.14224)
		(layer "B.Cu")
		(net "USB3_01_MUX_FB_RXP")
	)
	(segment
		(start 22.479 -67.86626)
		(end 22.479 -67.43954)
		(width 0.14224)
		(layer "B.Cu")
		(net "USB3_01_MUX_FB_RXP")
	)
	(segment
		(start 22.479 -68.74002)
		(end 22.70252 -68.5165)
		(width 0.14224)
		(layer "B.Cu")
		(net "USB3_01_MUX_FB_RXP")
	)
	(segment
		(start 30.414468 -84.960968)
		(end 30.414468 -84.676996)
		(width 0.14224)
		(layer "B.Cu")
		(net "USB3_01_MUX_FB_RXP")
	)
	(segment
		(start 43.880532 -22.642576)
		(end 43.880532 -23.00986)
		(width 0.14224)
		(layer "F.Cu")
		(net "USB3_01_MUX_FB_RXN")
	)
	(segment
		(start 43.880532 -23.33244)
		(end 43.880532 -23.00986)
		(width 0.14224)
		(layer "F.Cu")
		(net "USB3_01_MUX_FB_RXN")
	)
	(segment
		(start 43.903138 -24.455374)
		(end 43.628818 -24.181054)
		(width 0.14224)
		(layer "F.Cu")
		(net "USB3_01_MUX_FB_RXN")
	)
	(segment
		(start 43.628818 -23.584154)
		(end 43.880532 -23.33244)
		(width 0.14224)
		(layer "F.Cu")
		(net "USB3_01_MUX_FB_RXN")
	)
	(segment
		(start 43.966638 -22.55647)
		(end 43.880532 -22.642576)
		(width 0.14224)
		(layer "F.Cu")
		(net "USB3_01_MUX_FB_RXN")
	)
	(segment
		(start 43.628818 -24.181054)
		(end 43.628818 -23.584154)
		(width 0.14224)
		(layer "F.Cu")
		(net "USB3_01_MUX_FB_RXN")
	)
	(via
		(at 43.903138 -24.455374)
		(size 0.508)
		(drill 0.254)
		(layers "F.Cu" "B.Cu")
		(net "USB3_01_MUX_FB_RXN")
	)
	(segment
		(start 41.584626 -21.2471)
		(end 43.629326 -23.2918)
		(width 0.14224)
		(layer "B.Cu")
		(net "USB3_01_MUX_FB_RXN")
	)
	(segment
		(start 19.5072 -56.210708)
		(end 21.5773 -51.21148)
		(width 0.14224)
		(layer "B.Cu")
		(net "USB3_01_MUX_FB_RXN")
	)
	(segment
		(start 43.629326 -24.181562)
		(end 43.903138 -24.455374)
		(width 0.14224)
		(layer "B.Cu")
		(net "USB3_01_MUX_FB_RXN")
	)
	(segment
		(start 24.73198 -75.240388)
		(end 24.73198 -74.021188)
		(width 0.14224)
		(layer "B.Cu")
		(net "USB3_01_MUX_FB_RXN")
	)
	(segment
		(start 39.3827 -89.7128)
		(end 38.029134 -89.7128)
		(width 0.14224)
		(layer "B.Cu")
		(net "USB3_01_MUX_FB_RXN")
	)
	(segment
		(start 23.4188 -32.060388)
		(end 24.6888 -28.997148)
		(width 0.14224)
		(layer "B.Cu")
		(net "USB3_01_MUX_FB_RXN")
	)
	(segment
		(start 23.704042 -72.99325)
		(end 23.33625 -72.99325)
		(width 0.14224)
		(layer "B.Cu")
		(net "USB3_01_MUX_FB_RXN")
	)
	(segment
		(start 24.689054 -27.716734)
		(end 25.092406 -26.743406)
		(width 0.14224)
		(layer "B.Cu")
		(net "USB3_01_MUX_FB_RXN")
	)
	(segment
		(start 21.6027 -64.287654)
		(end 21.6027 -61.417454)
		(width 0.14224)
		(layer "B.Cu")
		(net "USB3_01_MUX_FB_RXN")
	)
	(segment
		(start 36.905438 -24.435816)
		(end 37.399722 -23.242524)
		(width 0.14224)
		(layer "B.Cu")
		(net "USB3_01_MUX_FB_RXN")
	)
	(segment
		(start 25.092406 -26.743406)
		(end 25.770078 -25.728168)
		(width 0.14224)
		(layer "B.Cu")
		(net "USB3_01_MUX_FB_RXN")
	)
	(segment
		(start 40.161464 -90.491818)
		(end 39.3827 -89.7128)
		(width 0.14224)
		(layer "B.Cu")
		(net "USB3_01_MUX_FB_RXN")
	)
	(segment
		(start 19.5072 -59.321954)
		(end 19.5072 -56.210708)
		(width 0.14224)
		(layer "B.Cu")
		(net "USB3_01_MUX_FB_RXN")
	)
	(segment
		(start 28.283662 -81.36763)
		(end 27.40914 -80.058006)
		(width 0.14224)
		(layer "B.Cu")
		(net "USB3_01_MUX_FB_RXN")
	)
	(segment
		(start 27.40914 -77.917548)
		(end 24.73198 -75.240388)
		(width 0.14224)
		(layer "B.Cu")
		(net "USB3_01_MUX_FB_RXN")
	)
	(segment
		(start 40.180006 -91.144598)
		(end 40.245792 -91.078812)
		(width 0.14224)
		(layer "B.Cu")
		(net "USB3_01_MUX_FB_RXN")
	)
	(segment
		(start 28.283916 -82.035396)
		(end 28.283916 -81.367884)
		(width 0.14224)
		(layer "B.Cu")
		(net "USB3_01_MUX_FB_RXN")
	)
	(segment
		(start 23.33625 -72.99325)
		(end 22.1107 -71.7677)
		(width 0.14224)
		(layer "B.Cu")
		(net "USB3_01_MUX_FB_RXN")
	)
	(segment
		(start 37.109146 -89.3318)
		(end 35.280854 -89.3318)
		(width 0.14224)
		(layer "B.Cu")
		(net "USB3_01_MUX_FB_RXN")
	)
	(segment
		(start 43.629326 -23.2918)
		(end 43.629326 -24.181562)
		(width 0.14224)
		(layer "B.Cu")
		(net "USB3_01_MUX_FB_RXN")
	)
	(segment
		(start 35.730688 -25.3619)
		(end 36.155122 -25.186132)
		(width 0.14224)
		(layer "B.Cu")
		(net "USB3_01_MUX_FB_RXN")
	)
	(segment
		(start 22.1107 -64.795654)
		(end 21.6027 -64.287654)
		(width 0.14224)
		(layer "B.Cu")
		(net "USB3_01_MUX_FB_RXN")
	)
	(segment
		(start 33.297622 -25.3619)
		(end 35.730688 -25.3619)
		(width 0.14224)
		(layer "B.Cu")
		(net "USB3_01_MUX_FB_RXN")
	)
	(segment
		(start 28.283916 -81.367884)
		(end 28.283662 -81.36763)
		(width 0.14224)
		(layer "B.Cu")
		(net "USB3_01_MUX_FB_RXN")
	)
	(segment
		(start 29.214572 -84.28228)
		(end 28.283916 -82.035396)
		(width 0.14224)
		(layer "B.Cu")
		(net "USB3_01_MUX_FB_RXN")
	)
	(segment
		(start 30.17012 -24.0665)
		(end 33.297622 -25.3619)
		(width 0.14224)
		(layer "B.Cu")
		(net "USB3_01_MUX_FB_RXN")
	)
	(segment
		(start 21.5773 -43.916346)
		(end 23.4188 -42.074846)
		(width 0.14224)
		(layer "B.Cu")
		(net "USB3_01_MUX_FB_RXN")
	)
	(segment
		(start 40.245792 -91.078812)
		(end 40.245792 -90.695018)
		(width 0.14224)
		(layer "B.Cu")
		(net "USB3_01_MUX_FB_RXN")
	)
	(segment
		(start 27.40914 -80.058006)
		(end 27.40914 -77.917548)
		(width 0.14224)
		(layer "B.Cu")
		(net "USB3_01_MUX_FB_RXN")
	)
	(segment
		(start 36.155122 -25.186132)
		(end 36.905438 -24.435816)
		(width 0.14224)
		(layer "B.Cu")
		(net "USB3_01_MUX_FB_RXN")
	)
	(segment
		(start 35.280854 -89.3318)
		(end 33.172654 -87.2236)
		(width 0.14224)
		(layer "B.Cu")
		(net "USB3_01_MUX_FB_RXN")
	)
	(segment
		(start 21.5773 -51.21148)
		(end 21.5773 -43.916346)
		(width 0.14224)
		(layer "B.Cu")
		(net "USB3_01_MUX_FB_RXN")
	)
	(segment
		(start 32.156146 -87.2236)
		(end 29.214572 -84.28228)
		(width 0.14224)
		(layer "B.Cu")
		(net "USB3_01_MUX_FB_RXN")
	)
	(segment
		(start 27.432 -24.0665)
		(end 30.17012 -24.0665)
		(width 0.14224)
		(layer "B.Cu")
		(net "USB3_01_MUX_FB_RXN")
	)
	(segment
		(start 21.6027 -61.417454)
		(end 19.5072 -59.321954)
		(width 0.14224)
		(layer "B.Cu")
		(net "USB3_01_MUX_FB_RXN")
	)
	(segment
		(start 24.73198 -74.021188)
		(end 23.704042 -72.99325)
		(width 0.14224)
		(layer "B.Cu")
		(net "USB3_01_MUX_FB_RXN")
	)
	(segment
		(start 24.6888 -28.997148)
		(end 24.689054 -27.716734)
		(width 0.14224)
		(layer "B.Cu")
		(net "USB3_01_MUX_FB_RXN")
	)
	(segment
		(start 40.180006 -91.398852)
		(end 40.180006 -91.144598)
		(width 0.14224)
		(layer "B.Cu")
		(net "USB3_01_MUX_FB_RXN")
	)
	(segment
		(start 25.770078 -25.728168)
		(end 27.432 -24.0665)
		(width 0.14224)
		(layer "B.Cu")
		(net "USB3_01_MUX_FB_RXN")
	)
	(segment
		(start 22.1107 -71.7677)
		(end 22.1107 -64.795654)
		(width 0.14224)
		(layer "B.Cu")
		(net "USB3_01_MUX_FB_RXN")
	)
	(segment
		(start 23.4188 -42.074846)
		(end 23.4188 -32.060388)
		(width 0.14224)
		(layer "B.Cu")
		(net "USB3_01_MUX_FB_RXN")
	)
	(segment
		(start 38.029134 -89.7128)
		(end 37.109146 -89.3318)
		(width 0.14224)
		(layer "B.Cu")
		(net "USB3_01_MUX_FB_RXN")
	)
	(segment
		(start 37.399722 -23.242524)
		(end 39.395146 -21.2471)
		(width 0.14224)
		(layer "B.Cu")
		(net "USB3_01_MUX_FB_RXN")
	)
	(segment
		(start 33.172654 -87.2236)
		(end 32.156146 -87.2236)
		(width 0.14224)
		(layer "B.Cu")
		(net "USB3_01_MUX_FB_RXN")
	)
	(segment
		(start 39.395146 -21.2471)
		(end 41.584626 -21.2471)
		(width 0.14224)
		(layer "B.Cu")
		(net "USB3_01_MUX_FB_RXN")
	)
	(segment
		(start 40.245792 -90.695018)
		(end 40.161464 -90.491818)
		(width 0.14224)
		(layer "B.Cu")
		(net "USB3_01_MUX_FB_RXN")
	)
	(segment
		(start 40.636952 -21.01342)
		(end 40.636952 -21.310092)
		(width 0.14224)
		(layer "F.Cu")
		(net "USB3_01_FB_TXP")
	)
	(segment
		(start 39.738046 -15.022322)
		(end 39.738046 -15.748)
		(width 0.14224)
		(layer "F.Cu")
		(net "USB3_01_FB_TXP")
	)
	(segment
		(start 40.627046 -16.637)
		(end 41.1099 -16.637)
		(width 0.14224)
		(layer "F.Cu")
		(net "USB3_01_FB_TXP")
	)
	(segment
		(start 38.922198 -14.880082)
		(end 39.595806 -14.880082)
		(width 0.14224)
		(layer "F.Cu")
		(net "USB3_01_FB_TXP")
	)
	(segment
		(start 41.412668 -17.469104)
		(end 41.346628 -17.535144)
		(width 0.14224)
		(layer "F.Cu")
		(net "USB3_01_FB_TXP")
	)
	(segment
		(start 39.595806 -14.880082)
		(end 39.738046 -15.022322)
		(width 0.14224)
		(layer "F.Cu")
		(net "USB3_01_FB_TXP")
	)
	(segment
		(start 41.346628 -18.574004)
		(end 41.346628 -18.837656)
		(width 0.14224)
		(layer "F.Cu")
		(net "USB3_01_FB_TXP")
	)
	(segment
		(start 41.346628 -18.837656)
		(end 41.412668 -18.903696)
		(width 0.14224)
		(layer "F.Cu")
		(net "USB3_01_FB_TXP")
	)
	(segment
		(start 41.1099 -16.637)
		(end 41.412668 -16.939768)
		(width 0.14224)
		(layer "F.Cu")
		(net "USB3_01_FB_TXP")
	)
	(segment
		(start 40.877744 -20.772628)
		(end 40.636952 -21.01342)
		(width 0.14224)
		(layer "F.Cu")
		(net "USB3_01_FB_TXP")
	)
	(segment
		(start 40.877744 -20.036282)
		(end 40.877744 -20.772628)
		(width 0.14224)
		(layer "F.Cu")
		(net "USB3_01_FB_TXP")
	)
	(segment
		(start 41.346628 -17.535144)
		(end 41.346628 -17.798796)
		(width 0.14224)
		(layer "F.Cu")
		(net "USB3_01_FB_TXP")
	)
	(segment
		(start 41.412668 -19.501358)
		(end 40.877744 -20.036282)
		(width 0.14224)
		(layer "F.Cu")
		(net "USB3_01_FB_TXP")
	)
	(segment
		(start 41.346628 -17.798796)
		(end 41.346628 -18.574004)
		(width 0.14224)
		(layer "F.Cu")
		(net "USB3_01_FB_TXP")
	)
	(segment
		(start 41.412668 -18.903696)
		(end 41.412668 -19.501358)
		(width 0.14224)
		(layer "F.Cu")
		(net "USB3_01_FB_TXP")
	)
	(segment
		(start 39.738046 -15.748)
		(end 40.627046 -16.637)
		(width 0.14224)
		(layer "F.Cu")
		(net "USB3_01_FB_TXP")
	)
	(segment
		(start 41.412668 -16.939768)
		(end 41.412668 -17.469104)
		(width 0.14224)
		(layer "F.Cu")
		(net "USB3_01_FB_TXP")
	)
	(segment
		(start 40.922194 -14.880082)
		(end 40.248586 -14.880082)
		(width 0.14224)
		(layer "F.Cu")
		(net "USB3_01_FB_TXN")
	)
	(segment
		(start 41.846754 -17.533874)
		(end 41.846754 -17.798796)
		(width 0.14224)
		(layer "F.Cu")
		(net "USB3_01_FB_TXN")
	)
	(segment
		(start 41.246044 -20.793964)
		(end 41.486836 -21.034756)
		(width 0.14224)
		(layer "F.Cu")
		(net "USB3_01_FB_TXN")
	)
	(segment
		(start 41.846754 -18.574004)
		(end 41.846754 -18.838926)
		(width 0.14224)
		(layer "F.Cu")
		(net "USB3_01_FB_TXN")
	)
	(segment
		(start 41.780968 -18.904712)
		(end 41.780968 -19.654012)
		(width 0.14224)
		(layer "F.Cu")
		(net "USB3_01_FB_TXN")
	)
	(segment
		(start 41.780968 -17.468088)
		(end 41.846754 -17.533874)
		(width 0.14224)
		(layer "F.Cu")
		(net "USB3_01_FB_TXN")
	)
	(segment
		(start 41.486836 -21.034756)
		(end 41.486836 -21.310092)
		(width 0.14224)
		(layer "F.Cu")
		(net "USB3_01_FB_TXN")
	)
	(segment
		(start 40.106346 -15.595346)
		(end 40.7797 -16.2687)
		(width 0.14224)
		(layer "F.Cu")
		(net "USB3_01_FB_TXN")
	)
	(segment
		(start 41.780968 -19.654012)
		(end 41.246044 -20.188936)
		(width 0.14224)
		(layer "F.Cu")
		(net "USB3_01_FB_TXN")
	)
	(segment
		(start 41.262554 -16.2687)
		(end 41.780968 -16.787114)
		(width 0.14224)
		(layer "F.Cu")
		(net "USB3_01_FB_TXN")
	)
	(segment
		(start 41.780968 -16.787114)
		(end 41.780968 -17.468088)
		(width 0.14224)
		(layer "F.Cu")
		(net "USB3_01_FB_TXN")
	)
	(segment
		(start 41.846754 -17.798796)
		(end 41.846754 -18.574004)
		(width 0.14224)
		(layer "F.Cu")
		(net "USB3_01_FB_TXN")
	)
	(segment
		(start 40.248586 -14.880082)
		(end 40.106346 -15.022322)
		(width 0.14224)
		(layer "F.Cu")
		(net "USB3_01_FB_TXN")
	)
	(segment
		(start 40.106346 -15.022322)
		(end 40.106346 -15.595346)
		(width 0.14224)
		(layer "F.Cu")
		(net "USB3_01_FB_TXN")
	)
	(segment
		(start 40.7797 -16.2687)
		(end 41.262554 -16.2687)
		(width 0.14224)
		(layer "F.Cu")
		(net "USB3_01_FB_TXN")
	)
	(segment
		(start 41.246044 -20.188936)
		(end 41.246044 -20.793964)
		(width 0.14224)
		(layer "F.Cu")
		(net "USB3_01_FB_TXN")
	)
	(segment
		(start 41.846754 -18.838926)
		(end 41.780968 -18.904712)
		(width 0.14224)
		(layer "F.Cu")
		(net "USB3_01_FB_TXN")
	)
	(segment
		(start 43.27144 -20.203414)
		(end 43.27144 -20.766532)
		(width 0.14224)
		(layer "F.Cu")
		(net "USB3_01_FB_RXP")
	)
	(segment
		(start 45.326046 -15.9766)
		(end 43.642026 -15.9766)
		(width 0.14224)
		(layer "F.Cu")
		(net "USB3_01_FB_RXP")
	)
	(segment
		(start 45.738034 -15.022322)
		(end 45.738034 -15.564612)
		(width 0.14224)
		(layer "F.Cu")
		(net "USB3_01_FB_RXP")
	)
	(segment
		(start 43.030648 -21.007324)
		(end 43.030648 -21.310092)
		(width 0.14224)
		(layer "F.Cu")
		(net "USB3_01_FB_RXP")
	)
	(segment
		(start 44.922186 -14.880082)
		(end 45.595794 -14.880082)
		(width 0.14224)
		(layer "F.Cu")
		(net "USB3_01_FB_RXP")
	)
	(segment
		(start 42.846498 -18.574004)
		(end 42.846498 -18.838672)
		(width 0.14224)
		(layer "F.Cu")
		(net "USB3_01_FB_RXP")
	)
	(segment
		(start 43.27144 -20.766532)
		(end 43.030648 -21.007324)
		(width 0.14224)
		(layer "F.Cu")
		(net "USB3_01_FB_RXP")
	)
	(segment
		(start 42.846498 -18.838672)
		(end 42.912538 -18.904712)
		(width 0.14224)
		(layer "F.Cu")
		(net "USB3_01_FB_RXP")
	)
	(segment
		(start 42.846498 -17.798796)
		(end 42.846498 -18.574004)
		(width 0.14224)
		(layer "F.Cu")
		(net "USB3_01_FB_RXP")
	)
	(segment
		(start 42.912538 -19.844512)
		(end 43.27144 -20.203414)
		(width 0.14224)
		(layer "F.Cu")
		(net "USB3_01_FB_RXP")
	)
	(segment
		(start 42.912538 -16.706088)
		(end 42.912538 -17.468088)
		(width 0.14224)
		(layer "F.Cu")
		(net "USB3_01_FB_RXP")
	)
	(segment
		(start 42.912538 -17.468088)
		(end 42.846498 -17.534128)
		(width 0.14224)
		(layer "F.Cu")
		(net "USB3_01_FB_RXP")
	)
	(segment
		(start 42.912538 -18.904712)
		(end 42.912538 -19.844512)
		(width 0.14224)
		(layer "F.Cu")
		(net "USB3_01_FB_RXP")
	)
	(segment
		(start 42.846498 -17.534128)
		(end 42.846498 -17.798796)
		(width 0.14224)
		(layer "F.Cu")
		(net "USB3_01_FB_RXP")
	)
	(segment
		(start 45.595794 -14.880082)
		(end 45.738034 -15.022322)
		(width 0.14224)
		(layer "F.Cu")
		(net "USB3_01_FB_RXP")
	)
	(segment
		(start 43.642026 -15.9766)
		(end 42.912538 -16.706088)
		(width 0.14224)
		(layer "F.Cu")
		(net "USB3_01_FB_RXP")
	)
	(segment
		(start 45.738034 -15.564612)
		(end 45.326046 -15.9766)
		(width 0.14224)
		(layer "F.Cu")
		(net "USB3_01_FB_RXP")
	)
	(segment
		(start 43.346624 -17.798796)
		(end 43.346624 -18.574004)
		(width 0.14224)
		(layer "F.Cu")
		(net "USB3_01_FB_RXN")
	)
	(segment
		(start 43.880532 -21.015452)
		(end 43.880532 -21.310092)
		(width 0.14224)
		(layer "F.Cu")
		(net "USB3_01_FB_RXN")
	)
	(segment
		(start 43.346624 -17.535398)
		(end 43.346624 -17.798796)
		(width 0.14224)
		(layer "F.Cu")
		(net "USB3_01_FB_RXN")
	)
	(segment
		(start 43.346624 -18.574004)
		(end 43.346624 -18.837402)
		(width 0.14224)
		(layer "F.Cu")
		(net "USB3_01_FB_RXN")
	)
	(segment
		(start 43.63974 -20.05076)
		(end 43.63974 -20.77466)
		(width 0.14224)
		(layer "F.Cu")
		(net "USB3_01_FB_RXN")
	)
	(segment
		(start 46.106334 -15.022322)
		(end 46.106334 -15.717266)
		(width 0.14224)
		(layer "F.Cu")
		(net "USB3_01_FB_RXN")
	)
	(segment
		(start 46.106334 -15.717266)
		(end 45.4787 -16.3449)
		(width 0.14224)
		(layer "F.Cu")
		(net "USB3_01_FB_RXN")
	)
	(segment
		(start 43.280838 -17.469612)
		(end 43.346624 -17.535398)
		(width 0.14224)
		(layer "F.Cu")
		(net "USB3_01_FB_RXN")
	)
	(segment
		(start 43.280838 -18.903188)
		(end 43.280838 -19.691858)
		(width 0.14224)
		(layer "F.Cu")
		(net "USB3_01_FB_RXN")
	)
	(segment
		(start 43.79468 -16.3449)
		(end 43.280838 -16.858742)
		(width 0.14224)
		(layer "F.Cu")
		(net "USB3_01_FB_RXN")
	)
	(segment
		(start 43.280838 -16.858742)
		(end 43.280838 -17.469612)
		(width 0.14224)
		(layer "F.Cu")
		(net "USB3_01_FB_RXN")
	)
	(segment
		(start 45.4787 -16.3449)
		(end 43.79468 -16.3449)
		(width 0.14224)
		(layer "F.Cu")
		(net "USB3_01_FB_RXN")
	)
	(segment
		(start 46.922182 -14.880082)
		(end 46.248574 -14.880082)
		(width 0.14224)
		(layer "F.Cu")
		(net "USB3_01_FB_RXN")
	)
	(segment
		(start 43.280838 -19.691858)
		(end 43.63974 -20.05076)
		(width 0.14224)
		(layer "F.Cu")
		(net "USB3_01_FB_RXN")
	)
	(segment
		(start 43.346624 -18.837402)
		(end 43.280838 -18.903188)
		(width 0.14224)
		(layer "F.Cu")
		(net "USB3_01_FB_RXN")
	)
	(segment
		(start 46.248574 -14.880082)
		(end 46.106334 -15.022322)
		(width 0.14224)
		(layer "F.Cu")
		(net "USB3_01_FB_RXN")
	)
	(segment
		(start 43.63974 -20.77466)
		(end 43.880532 -21.015452)
		(width 0.14224)
		(layer "F.Cu")
		(net "USB3_01_FB_RXN")
	)
	(via
		(at 15.113 -61.087)
		(size 0.6604)
		(drill 0.3302)
		(layers "F.Cu" "B.Cu")
		(net "SMB_BMC_MM15_R1_SDA")
	)
	(segment
		(start 15.113 -61.087)
		(end 15.113 -61.493146)
		(width 0.11684)
		(layer "B.Cu")
		(net "SMB_BMC_MM15_R1_SDA")
	)
	(segment
		(start 15.545054 -61.9252)
		(end 15.926054 -61.9252)
		(width 0.11684)
		(layer "B.Cu")
		(net "SMB_BMC_MM15_R1_SDA")
	)
	(segment
		(start 16.31188 -62.311026)
		(end 16.31188 -62.916054)
		(width 0.11684)
		(layer "B.Cu")
		(net "SMB_BMC_MM15_R1_SDA")
	)
	(segment
		(start 15.113 -61.493146)
		(end 15.545054 -61.9252)
		(width 0.11684)
		(layer "B.Cu")
		(net "SMB_BMC_MM15_R1_SDA")
	)
	(segment
		(start 15.875 -59.8932)
		(end 15.548864 -60.219336)
		(width 0.11684)
		(layer "B.Cu")
		(net "SMB_BMC_MM15_R1_SDA")
	)
	(segment
		(start 15.875 -59.476386)
		(end 15.875 -59.8932)
		(width 0.11684)
		(layer "B.Cu")
		(net "SMB_BMC_MM15_R1_SDA")
	)
	(segment
		(start 15.548864 -59.15025)
		(end 15.875 -59.476386)
		(width 0.11684)
		(layer "B.Cu")
		(net "SMB_BMC_MM15_R1_SDA")
	)
	(segment
		(start 15.548864 -60.219336)
		(end 15.548864 -60.651136)
		(width 0.11684)
		(layer "B.Cu")
		(net "SMB_BMC_MM15_R1_SDA")
	)
	(segment
		(start 15.926054 -61.9252)
		(end 16.31188 -62.311026)
		(width 0.11684)
		(layer "B.Cu")
		(net "SMB_BMC_MM15_R1_SDA")
	)
	(segment
		(start 15.548864 -60.651136)
		(end 15.113 -61.087)
		(width 0.11684)
		(layer "B.Cu")
		(net "SMB_BMC_MM15_R1_SDA")
	)
	(via
		(at 16.383 -61.0616)
		(size 0.6604)
		(drill 0.3302)
		(layers "F.Cu" "B.Cu")
		(net "SMB_BMC_MM15_R1_SCL")
	)
	(segment
		(start 16.96212 -62.30112)
		(end 16.96212 -62.916054)
		(width 0.11684)
		(layer "B.Cu")
		(net "SMB_BMC_MM15_R1_SCL")
	)
	(segment
		(start 16.637 -60.8076)
		(end 16.383 -61.0616)
		(width 0.11684)
		(layer "B.Cu")
		(net "SMB_BMC_MM15_R1_SCL")
	)
	(segment
		(start 16.564864 -59.15025)
		(end 16.564864 -59.564524)
		(width 0.11684)
		(layer "B.Cu")
		(net "SMB_BMC_MM15_R1_SCL")
	)
	(segment
		(start 16.383 -61.722)
		(end 16.96212 -62.30112)
		(width 0.11684)
		(layer "B.Cu")
		(net "SMB_BMC_MM15_R1_SCL")
	)
	(segment
		(start 16.564864 -59.564524)
		(end 16.637 -59.63666)
		(width 0.11684)
		(layer "B.Cu")
		(net "SMB_BMC_MM15_R1_SCL")
	)
	(segment
		(start 16.383 -61.0616)
		(end 16.383 -61.722)
		(width 0.11684)
		(layer "B.Cu")
		(net "SMB_BMC_MM15_R1_SCL")
	)
	(segment
		(start 16.637 -59.63666)
		(end 16.637 -60.8076)
		(width 0.11684)
		(layer "B.Cu")
		(net "SMB_BMC_MM15_R1_SCL")
	)
	(via
		(at 42.92219 -18.034)
		(size 0.6604)
		(drill 0.3302)
		(layers "F.Cu" "B.Cu")
		(net "DEBUG_PORT_PRSNT_R")
	)
	(segment
		(start 42.92219 -19.02714)
		(end 42.926 -19.03095)
		(width 0.11684)
		(layer "B.Cu")
		(net "DEBUG_PORT_PRSNT_R")
	)
	(segment
		(start 42.92219 -14.880082)
		(end 42.92219 -18.034)
		(width 0.11684)
		(layer "B.Cu")
		(net "DEBUG_PORT_PRSNT_R")
	)
	(segment
		(start 43.942 -19.03095)
		(end 42.926 -19.03095)
		(width 0.11684)
		(layer "B.Cu")
		(net "DEBUG_PORT_PRSNT_R")
	)
	(segment
		(start 42.92219 -18.034)
		(end 42.92219 -19.02714)
		(width 0.11684)
		(layer "B.Cu")
		(net "DEBUG_PORT_PRSNT_R")
	)
	(via
		(at 49.4284 -22.8346)
		(size 0.6604)
		(drill 0.3302)
		(layers "F.Cu" "B.Cu")
		(net "DEBUG_PORT_PRSNT_BUF_R_EN")
	)
	(segment
		(start 49.4284 -22.4536)
		(end 49.1871 -22.2123)
		(width 0.11684)
		(layer "B.Cu")
		(net "DEBUG_PORT_PRSNT_BUF_R_EN")
	)
	(segment
		(start 49.4284 -23.38451)
		(end 49.4284 -22.8346)
		(width 0.11684)
		(layer "B.Cu")
		(net "DEBUG_PORT_PRSNT_BUF_R_EN")
	)
	(segment
		(start 49.4284 -22.8346)
		(end 49.4284 -22.4536)
		(width 0.11684)
		(layer "B.Cu")
		(net "DEBUG_PORT_PRSNT_BUF_R_EN")
	)
	(segment
		(start 49.09312 -23.71979)
		(end 49.4284 -23.38451)
		(width 0.11684)
		(layer "B.Cu")
		(net "DEBUG_PORT_PRSNT_BUF_R_EN")
	)
	(segment
		(start 47.11192 -23.71979)
		(end 47.10938 -23.71725)
		(width 0.11684)
		(layer "B.Cu")
		(net "DEBUG_PORT_PRSNT_BUF_R_EN")
	)
	(segment
		(start 49.1871 -22.2123)
		(end 47.701962 -22.2123)
		(width 0.11684)
		(layer "B.Cu")
		(net "DEBUG_PORT_PRSNT_BUF_R_EN")
	)
	(segment
		(start 48.00092 -23.71979)
		(end 49.09312 -23.71979)
		(width 0.11684)
		(layer "B.Cu")
		(net "DEBUG_PORT_PRSNT_BUF_R_EN")
	)
	(segment
		(start 48.00092 -23.71979)
		(end 47.11192 -23.71979)
		(width 0.11684)
		(layer "B.Cu")
		(net "DEBUG_PORT_PRSNT_BUF_R_EN")
	)
	(segment
		(start 47.10938 -23.71725)
		(end 46.21784 -23.71725)
		(width 0.11684)
		(layer "B.Cu")
		(net "DEBUG_PORT_PRSNT_BUF_R_EN")
	)
	(segment
		(start 24.654764 -98.382328)
		(end 24.25954 -97.987104)
		(width 0.11684)
		(layer "F.Cu")
		(net "TP_PLD_C13")
	)
	(via
		(at 24.654764 -98.382328)
		(size 0.4572)
		(drill 0.254)
		(layers "F.Cu" "B.Cu")
		(net "TP_PLD_C13")
	)
	(segment
		(start 66.73342 -103.0732)
		(end 67.4878 -103.0732)
		(width 0.11684)
		(layer "F.Cu")
		(net "SMB_PCH_TPM_SDA")
	)
	(segment
		(start 67.4878 -103.0732)
		(end 68.56095 -102.00005)
		(width 0.11684)
		(layer "F.Cu")
		(net "SMB_PCH_TPM_SDA")
	)
	(segment
		(start 66.1162 -98.161094)
		(end 65.311274 -97.356168)
		(width 0.11684)
		(layer "F.Cu")
		(net "SMB_PCH_TPM_SDA")
	)
	(segment
		(start 68.56095 -102.00005)
		(end 68.56095 -101.473)
		(width 0.11684)
		(layer "F.Cu")
		(net "SMB_PCH_TPM_SDA")
	)
	(segment
		(start 65.311274 -97.356168)
		(end 64.81191 -97.356168)
		(width 0.11684)
		(layer "F.Cu")
		(net "SMB_PCH_TPM_SDA")
	)
	(segment
		(start 66.1162 -102.45598)
		(end 66.73342 -103.0732)
		(width 0.11684)
		(layer "F.Cu")
		(net "SMB_PCH_TPM_SDA")
	)
	(segment
		(start 66.1162 -102.45598)
		(end 66.1162 -98.161094)
		(width 0.11684)
		(layer "F.Cu")
		(net "SMB_PCH_TPM_SDA")
	)
	(via
		(at 66.1162 -102.45598)
		(size 0.762)
		(drill 0.381)
		(layers "F.Cu" "B.Cu")
		(net "SMB_PCH_TPM_SDA")
	)
	(segment
		(start 60.036202 -95.856044)
		(end 59.580526 -96.31172)
		(width 0.11684)
		(layer "F.Cu")
		(net "SMB_PCH_TPM_SCL")
	)
	(segment
		(start 60.591954 -95.856044)
		(end 60.036202 -95.856044)
		(width 0.11684)
		(layer "F.Cu")
		(net "SMB_PCH_TPM_SCL")
	)
	(segment
		(start 59.580526 -96.31172)
		(end 58.61939 -96.31172)
		(width 0.11684)
		(layer "F.Cu")
		(net "SMB_PCH_TPM_SCL")
	)
	(segment
		(start 58.61939 -96.31172)
		(end 57.58307 -97.34804)
		(width 0.11684)
		(layer "F.Cu")
		(net "SMB_PCH_TPM_SCL")
	)
	(segment
		(start 61.8998 -27.73045)
		(end 61.8998 -28.575)
		(width 0.11684)
		(layer "F.Cu")
		(net "PD_CLK_125M_PHY_BMC_RGMII")
	)
	(segment
		(start 57.695084 -39.37127)
		(end 57.317132 -38.955726)
		(width 0.11684)
		(layer "F.Cu")
		(net "PD_CLK_125M_PHY_BMC_RGMII")
	)
	(segment
		(start 61.8998 -28.575)
		(end 61.4426 -29.0322)
		(width 0.11684)
		(layer "F.Cu")
		(net "PD_CLK_125M_PHY_BMC_RGMII")
	)
	(segment
		(start 60.758324 -28.5242)
		(end 61.266324 -29.0322)
		(width 0.11684)
		(layer "F.Cu")
		(net "PD_CLK_125M_PHY_BMC_RGMII")
	)
	(segment
		(start 61.266324 -29.0322)
		(end 61.4426 -29.0322)
		(width 0.11684)
		(layer "F.Cu")
		(net "PD_CLK_125M_PHY_BMC_RGMII")
	)
	(via
		(at 60.758324 -28.5242)
		(size 0.508)
		(drill 0.254)
		(layers "F.Cu" "B.Cu")
		(net "PD_CLK_125M_PHY_BMC_RGMII")
	)
	(via
		(at 61.4426 -29.0322)
		(size 0.762)
		(drill 0.381)
		(layers "F.Cu" "B.Cu")
		(net "PD_CLK_125M_PHY_BMC_RGMII")
	)
	(via
		(at 57.317132 -38.955726)
		(size 0.4572)
		(drill 0.254)
		(layers "F.Cu" "B.Cu")
		(net "PD_CLK_125M_PHY_BMC_RGMII")
	)
	(segment
		(start 60.192412 -29.286454)
		(end 60.192412 -28.811474)
		(width 0.10668)
		(layer "In4.Cu")
		(net "PD_CLK_125M_PHY_BMC_RGMII")
	)
	(segment
		(start 62.846204 -34.0106)
		(end 62.846204 -31.731204)
		(width 0.10668)
		(layer "In4.Cu")
		(net "PD_CLK_125M_PHY_BMC_RGMII")
	)
	(segment
		(start 60.479686 -28.5242)
		(end 60.758324 -28.5242)
		(width 0.10668)
		(layer "In4.Cu")
		(net "PD_CLK_125M_PHY_BMC_RGMII")
	)
	(segment
		(start 62.719204 -34.1376)
		(end 62.846204 -34.0106)
		(width 0.10668)
		(layer "In4.Cu")
		(net "PD_CLK_125M_PHY_BMC_RGMII")
	)
	(segment
		(start 60.36056 -29.692346)
		(end 60.192412 -29.286454)
		(width 0.10668)
		(layer "In4.Cu")
		(net "PD_CLK_125M_PHY_BMC_RGMII")
	)
	(segment
		(start 57.317132 -38.955726)
		(end 57.317132 -37.221668)
		(width 0.10668)
		(layer "In4.Cu")
		(net "PD_CLK_125M_PHY_BMC_RGMII")
	)
	(segment
		(start 61.976 -30.861)
		(end 61.28766 -30.861)
		(width 0.10668)
		(layer "In4.Cu")
		(net "PD_CLK_125M_PHY_BMC_RGMII")
	)
	(segment
		(start 60.4012 -34.1376)
		(end 62.719204 -34.1376)
		(width 0.10668)
		(layer "In4.Cu")
		(net "PD_CLK_125M_PHY_BMC_RGMII")
	)
	(segment
		(start 61.28766 -30.861)
		(end 60.36056 -29.9339)
		(width 0.10668)
		(layer "In4.Cu")
		(net "PD_CLK_125M_PHY_BMC_RGMII")
	)
	(segment
		(start 60.36056 -29.9339)
		(end 60.36056 -29.692346)
		(width 0.10668)
		(layer "In4.Cu")
		(net "PD_CLK_125M_PHY_BMC_RGMII")
	)
	(segment
		(start 60.192412 -28.811474)
		(end 60.479686 -28.5242)
		(width 0.10668)
		(layer "In4.Cu")
		(net "PD_CLK_125M_PHY_BMC_RGMII")
	)
	(segment
		(start 57.317132 -37.221668)
		(end 60.4012 -34.1376)
		(width 0.10668)
		(layer "In4.Cu")
		(net "PD_CLK_125M_PHY_BMC_RGMII")
	)
	(segment
		(start 62.846204 -31.731204)
		(end 61.976 -30.861)
		(width 0.10668)
		(layer "In4.Cu")
		(net "PD_CLK_125M_PHY_BMC_RGMII")
	)
	(segment
		(start 23.064216 -84.68233)
		(end 23.064216 -87.99195)
		(width 0.11684)
		(layer "F.Cu")
		(net "FM_JTAG_BMC_MUX_SEL_R2")
	)
	(segment
		(start 23.064216 -87.99195)
		(end 23.45944 -88.387174)
		(width 0.11684)
		(layer "F.Cu")
		(net "FM_JTAG_BMC_MUX_SEL_R2")
	)
	(segment
		(start 46.494954 -57.771284)
		(end 46.09973 -58.166508)
		(width 0.11684)
		(layer "F.Cu")
		(net "FM_JTAG_BMC_MUX_SEL_R1")
	)
	(via
		(at 46.09973 -58.166508)
		(size 0.4572)
		(drill 0.254)
		(layers "F.Cu" "B.Cu")
		(net "FM_JTAG_BMC_MUX_SEL_R1")
	)
	(via
		(at 38.6842 -63.0428)
		(size 0.6604)
		(drill 0.3302)
		(layers "F.Cu" "B.Cu")
		(net "FM_JTAG_BMC_MUX_SEL_R1")
	)
	(segment
		(start 46.09973 -58.64987)
		(end 45.265086 -59.484514)
		(width 0.11684)
		(layer "B.Cu")
		(net "FM_JTAG_BMC_MUX_SEL_R1")
	)
	(segment
		(start 38.9255 -62.8015)
		(end 38.6842 -63.0428)
		(width 0.11684)
		(layer "B.Cu")
		(net "FM_JTAG_BMC_MUX_SEL_R1")
	)
	(segment
		(start 42.5196 -61.5442)
		(end 42.5196 -62.0014)
		(width 0.11684)
		(layer "B.Cu")
		(net "FM_JTAG_BMC_MUX_SEL_R1")
	)
	(segment
		(start 41.7195 -62.8015)
		(end 38.9255 -62.8015)
		(width 0.11684)
		(layer "B.Cu")
		(net "FM_JTAG_BMC_MUX_SEL_R1")
	)
	(segment
		(start 46.09973 -58.166508)
		(end 46.09973 -58.64987)
		(width 0.11684)
		(layer "B.Cu")
		(net "FM_JTAG_BMC_MUX_SEL_R1")
	)
	(segment
		(start 42.5196 -62.0014)
		(end 41.7195 -62.8015)
		(width 0.11684)
		(layer "B.Cu")
		(net "FM_JTAG_BMC_MUX_SEL_R1")
	)
	(segment
		(start 38.6842 -63.0428)
		(end 38.608 -63.119)
		(width 0.11684)
		(layer "B.Cu")
		(net "FM_JTAG_BMC_MUX_SEL_R1")
	)
	(segment
		(start 38.608 -63.119)
		(end 38.608 -64.19215)
		(width 0.11684)
		(layer "B.Cu")
		(net "FM_JTAG_BMC_MUX_SEL_R1")
	)
	(segment
		(start 45.265086 -59.484514)
		(end 44.09948 -60.262516)
		(width 0.11684)
		(layer "B.Cu")
		(net "FM_JTAG_BMC_MUX_SEL_R1")
	)
	(segment
		(start 43.590718 -60.473082)
		(end 42.5196 -61.5442)
		(width 0.11684)
		(layer "B.Cu")
		(net "FM_JTAG_BMC_MUX_SEL_R1")
	)
	(segment
		(start 44.09948 -60.262516)
		(end 43.590718 -60.473082)
		(width 0.11684)
		(layer "B.Cu")
		(net "FM_JTAG_BMC_MUX_SEL_R1")
	)
	(segment
		(start 23.064216 -83.88223)
		(end 23.42007 -83.88223)
		(width 0.11684)
		(layer "F.Cu")
		(net "FM_JTAG_BMC_MUX_SEL")
	)
	(segment
		(start 23.42007 -83.88223)
		(end 23.431246 -83.893406)
		(width 0.11684)
		(layer "F.Cu")
		(net "FM_JTAG_BMC_MUX_SEL")
	)
	(segment
		(start 23.431246 -83.893406)
		(end 23.695152 -83.893406)
		(width 0.11684)
		(layer "F.Cu")
		(net "FM_JTAG_BMC_MUX_SEL")
	)
	(via
		(at 23.695152 -83.893406)
		(size 0.508)
		(drill 0.254)
		(layers "F.Cu" "B.Cu")
		(net "FM_JTAG_BMC_MUX_SEL")
	)
	(via
		(at 41.05529 -70.231)
		(size 0.6604)
		(drill 0.3302)
		(layers "F.Cu" "B.Cu")
		(net "FM_JTAG_BMC_MUX_SEL")
	)
	(via
		(at 28.08351 -75.268074)
		(size 0.508)
		(drill 0.254)
		(layers "F.Cu" "B.Cu")
		(net "FM_JTAG_BMC_MUX_SEL")
	)
	(segment
		(start 39.076376 -72.75957)
		(end 36.07943 -72.75957)
		(width 0.11684)
		(layer "B.Cu")
		(net "FM_JTAG_BMC_MUX_SEL")
	)
	(segment
		(start 30.174184 -73.1774)
		(end 28.764484 -74.5871)
		(width 0.11684)
		(layer "B.Cu")
		(net "FM_JTAG_BMC_MUX_SEL")
	)
	(segment
		(start 42.138854 -68.713096)
		(end 39.274496 -68.713096)
		(width 0.11684)
		(layer "B.Cu")
		(net "FM_JTAG_BMC_MUX_SEL")
	)
	(segment
		(start 41.7322 -70.231)
		(end 42.1132 -70.612)
		(width 0.11684)
		(layer "B.Cu")
		(net "FM_JTAG_BMC_MUX_SEL")
	)
	(segment
		(start 41.05529 -70.231)
		(end 41.7322 -70.231)
		(width 0.11684)
		(layer "B.Cu")
		(net "FM_JTAG_BMC_MUX_SEL")
	)
	(segment
		(start 35.6616 -73.1774)
		(end 30.174184 -73.1774)
		(width 0.11684)
		(layer "B.Cu")
		(net "FM_JTAG_BMC_MUX_SEL")
	)
	(segment
		(start 43.31716 -70.49516)
		(end 43.31716 -68.69176)
		(width 0.11684)
		(layer "B.Cu")
		(net "FM_JTAG_BMC_MUX_SEL")
	)
	(segment
		(start 39.622476 -71.663814)
		(end 39.622476 -72.21347)
		(width 0.11684)
		(layer "B.Cu")
		(net "FM_JTAG_BMC_MUX_SEL")
	)
	(segment
		(start 43.03395 -68.40855)
		(end 43.03395 -67.818)
		(width 0.11684)
		(layer "B.Cu")
		(net "FM_JTAG_BMC_MUX_SEL")
	)
	(segment
		(start 28.764484 -74.5871)
		(end 28.764484 -74.717148)
		(width 0.11684)
		(layer "B.Cu")
		(net "FM_JTAG_BMC_MUX_SEL")
	)
	(segment
		(start 37.9984 -66.294)
		(end 38.27145 -66.02095)
		(width 0.11684)
		(layer "B.Cu")
		(net "FM_JTAG_BMC_MUX_SEL")
	)
	(segment
		(start 39.622476 -72.21347)
		(end 39.076376 -72.75957)
		(width 0.11684)
		(layer "B.Cu")
		(net "FM_JTAG_BMC_MUX_SEL")
	)
	(segment
		(start 43.20032 -70.612)
		(end 43.31716 -70.49516)
		(width 0.11684)
		(layer "B.Cu")
		(net "FM_JTAG_BMC_MUX_SEL")
	)
	(segment
		(start 28.456128 -75.025504)
		(end 28.32608 -75.025504)
		(width 0.11684)
		(layer "B.Cu")
		(net "FM_JTAG_BMC_MUX_SEL")
	)
	(segment
		(start 41.05529 -70.231)
		(end 39.622476 -71.663814)
		(width 0.11684)
		(layer "B.Cu")
		(net "FM_JTAG_BMC_MUX_SEL")
	)
	(segment
		(start 42.1132 -70.612)
		(end 43.20032 -70.612)
		(width 0.11684)
		(layer "B.Cu")
		(net "FM_JTAG_BMC_MUX_SEL")
	)
	(segment
		(start 38.27145 -66.02095)
		(end 38.608 -66.02095)
		(width 0.11684)
		(layer "B.Cu")
		(net "FM_JTAG_BMC_MUX_SEL")
	)
	(segment
		(start 37.9984 -67.437)
		(end 37.9984 -66.294)
		(width 0.11684)
		(layer "B.Cu")
		(net "FM_JTAG_BMC_MUX_SEL")
	)
	(segment
		(start 43.31716 -68.69176)
		(end 43.03395 -68.40855)
		(width 0.11684)
		(layer "B.Cu")
		(net "FM_JTAG_BMC_MUX_SEL")
	)
	(segment
		(start 28.764484 -74.717148)
		(end 28.456128 -75.025504)
		(width 0.11684)
		(layer "B.Cu")
		(net "FM_JTAG_BMC_MUX_SEL")
	)
	(segment
		(start 39.274496 -68.713096)
		(end 37.9984 -67.437)
		(width 0.11684)
		(layer "B.Cu")
		(net "FM_JTAG_BMC_MUX_SEL")
	)
	(segment
		(start 28.32608 -75.025504)
		(end 28.08351 -75.268074)
		(width 0.11684)
		(layer "B.Cu")
		(net "FM_JTAG_BMC_MUX_SEL")
	)
	(segment
		(start 38.608 -64.99225)
		(end 38.608 -66.02095)
		(width 0.11684)
		(layer "B.Cu")
		(net "FM_JTAG_BMC_MUX_SEL")
	)
	(segment
		(start 43.03395 -67.818)
		(end 42.138854 -68.713096)
		(width 0.11684)
		(layer "B.Cu")
		(net "FM_JTAG_BMC_MUX_SEL")
	)
	(segment
		(start 36.07943 -72.75957)
		(end 35.6616 -73.1774)
		(width 0.11684)
		(layer "B.Cu")
		(net "FM_JTAG_BMC_MUX_SEL")
	)
	(segment
		(start 27.01036 -77.06868)
		(end 27.01036 -77.079094)
		(width 0.08382)
		(layer "In9.Cu")
		(net "FM_JTAG_BMC_MUX_SEL")
	)
	(segment
		(start 25.60193 -82.74177)
		(end 24.20112 -84.14258)
		(width 0.08382)
		(layer "In9.Cu")
		(net "FM_JTAG_BMC_MUX_SEL")
	)
	(segment
		(start 28.162758 -75.347322)
		(end 28.162758 -75.916282)
		(width 0.08382)
		(layer "In9.Cu")
		(net "FM_JTAG_BMC_MUX_SEL")
	)
	(segment
		(start 28.08351 -75.268074)
		(end 28.162758 -75.347322)
		(width 0.08382)
		(layer "In9.Cu")
		(net "FM_JTAG_BMC_MUX_SEL")
	)
	(segment
		(start 23.944326 -84.14258)
		(end 23.695152 -83.893406)
		(width 0.08382)
		(layer "In9.Cu")
		(net "FM_JTAG_BMC_MUX_SEL")
	)
	(segment
		(start 26.18359 -77.905864)
		(end 26.18359 -78.616556)
		(width 0.08382)
		(layer "In9.Cu")
		(net "FM_JTAG_BMC_MUX_SEL")
	)
	(segment
		(start 26.18359 -78.678532)
		(end 26.18359 -79.552038)
		(width 0.08382)
		(layer "In9.Cu")
		(net "FM_JTAG_BMC_MUX_SEL")
	)
	(segment
		(start 26.176224 -78.623922)
		(end 26.176224 -78.671166)
		(width 0.08382)
		(layer "In9.Cu")
		(net "FM_JTAG_BMC_MUX_SEL")
	)
	(segment
		(start 26.18359 -78.616556)
		(end 26.176224 -78.623922)
		(width 0.08382)
		(layer "In9.Cu")
		(net "FM_JTAG_BMC_MUX_SEL")
	)
	(segment
		(start 26.176224 -78.671166)
		(end 26.18359 -78.678532)
		(width 0.08382)
		(layer "In9.Cu")
		(net "FM_JTAG_BMC_MUX_SEL")
	)
	(segment
		(start 28.162758 -75.916282)
		(end 27.01036 -77.06868)
		(width 0.08382)
		(layer "In9.Cu")
		(net "FM_JTAG_BMC_MUX_SEL")
	)
	(segment
		(start 27.01036 -77.079094)
		(end 26.18359 -77.905864)
		(width 0.08382)
		(layer "In9.Cu")
		(net "FM_JTAG_BMC_MUX_SEL")
	)
	(segment
		(start 26.18359 -79.552038)
		(end 25.60193 -80.133698)
		(width 0.08382)
		(layer "In9.Cu")
		(net "FM_JTAG_BMC_MUX_SEL")
	)
	(segment
		(start 24.20112 -84.14258)
		(end 23.944326 -84.14258)
		(width 0.08382)
		(layer "In9.Cu")
		(net "FM_JTAG_BMC_MUX_SEL")
	)
	(segment
		(start 25.60193 -80.133698)
		(end 25.60193 -82.74177)
		(width 0.08382)
		(layer "In9.Cu")
		(net "FM_JTAG_BMC_MUX_SEL")
	)
	(segment
		(start 25.527 -102.34295)
		(end 25.467056 -102.283006)
		(width 0.11684)
		(layer "F.Cu")
		(net "FM_BMC_SUSACK_R2_N")
	)
	(segment
		(start 25.467056 -102.283006)
		(end 25.467056 -99.19462)
		(width 0.11684)
		(layer "F.Cu")
		(net "FM_BMC_SUSACK_R2_N")
	)
	(segment
		(start 25.467056 -99.19462)
		(end 25.059386 -98.78695)
		(width 0.11684)
		(layer "F.Cu")
		(net "FM_BMC_SUSACK_R2_N")
	)
	(segment
		(start 53.695092 -57.771284)
		(end 53.299868 -58.166508)
		(width 0.11684)
		(layer "F.Cu")
		(net "FM_BMC_SUSACK_R1_N")
	)
	(via
		(at 53.299868 -58.166508)
		(size 0.4572)
		(drill 0.254)
		(layers "F.Cu" "B.Cu")
		(net "FM_BMC_SUSACK_R1_N")
	)
	(via
		(at 52.2986 -67.59702)
		(size 0.762)
		(drill 0.254)
		(layers "F.Cu" "B.Cu")
		(net "FM_BMC_SUSACK_R1_N")
	)
	(segment
		(start 52.05222 -67.59702)
		(end 51.816 -67.3608)
		(width 0.11684)
		(layer "B.Cu")
		(net "FM_BMC_SUSACK_R1_N")
	)
	(segment
		(start 52.2986 -67.59702)
		(end 52.05222 -67.59702)
		(width 0.11684)
		(layer "B.Cu")
		(net "FM_BMC_SUSACK_R1_N")
	)
	(segment
		(start 51.816 -67.3608)
		(end 51.816 -67.10045)
		(width 0.11684)
		(layer "B.Cu")
		(net "FM_BMC_SUSACK_R1_N")
	)
	(segment
		(start 52.760372 -64.597026)
		(end 51.528726 -63.36538)
		(width 0.10668)
		(layer "In4.Cu")
		(net "FM_BMC_SUSACK_R1_N")
	)
	(segment
		(start 52.888642 -58.815478)
		(end 53.1114 -58.59272)
		(width 0.10668)
		(layer "In4.Cu")
		(net "FM_BMC_SUSACK_R1_N")
	)
	(segment
		(start 52.235608 -59.900058)
		(end 52.888642 -59.247024)
		(width 0.10668)
		(layer "In4.Cu")
		(net "FM_BMC_SUSACK_R1_N")
	)
	(segment
		(start 53.1114 -58.354976)
		(end 53.299868 -58.166508)
		(width 0.10668)
		(layer "In4.Cu")
		(net "FM_BMC_SUSACK_R1_N")
	)
	(segment
		(start 52.2986 -67.59702)
		(end 52.2986 -67.102482)
		(width 0.10668)
		(layer "In4.Cu")
		(net "FM_BMC_SUSACK_R1_N")
	)
	(segment
		(start 52.9336 -65.015364)
		(end 52.760372 -64.597026)
		(width 0.10668)
		(layer "In4.Cu")
		(net "FM_BMC_SUSACK_R1_N")
	)
	(segment
		(start 52.2986 -67.102482)
		(end 52.48275 -66.657982)
		(width 0.10668)
		(layer "In4.Cu")
		(net "FM_BMC_SUSACK_R1_N")
	)
	(segment
		(start 53.1114 -58.59272)
		(end 53.1114 -58.354976)
		(width 0.10668)
		(layer "In4.Cu")
		(net "FM_BMC_SUSACK_R1_N")
	)
	(segment
		(start 52.9336 -66.207132)
		(end 52.9336 -65.015364)
		(width 0.10668)
		(layer "In4.Cu")
		(net "FM_BMC_SUSACK_R1_N")
	)
	(segment
		(start 52.888642 -59.247024)
		(end 52.888642 -58.815478)
		(width 0.10668)
		(layer "In4.Cu")
		(net "FM_BMC_SUSACK_R1_N")
	)
	(segment
		(start 51.528726 -63.36538)
		(end 51.528726 -62.47511)
		(width 0.10668)
		(layer "In4.Cu")
		(net "FM_BMC_SUSACK_R1_N")
	)
	(segment
		(start 52.48275 -66.657982)
		(end 52.9336 -66.207132)
		(width 0.10668)
		(layer "In4.Cu")
		(net "FM_BMC_SUSACK_R1_N")
	)
	(segment
		(start 52.235608 -61.768228)
		(end 52.235608 -59.900058)
		(width 0.10668)
		(layer "In4.Cu")
		(net "FM_BMC_SUSACK_R1_N")
	)
	(segment
		(start 51.528726 -62.47511)
		(end 52.235608 -61.768228)
		(width 0.10668)
		(layer "In4.Cu")
		(net "FM_BMC_SUSACK_R1_N")
	)
	(segment
		(start 25.859486 -101.659436)
		(end 25.859486 -99.58705)
		(width 0.11684)
		(layer "F.Cu")
		(net "RST_WDTRST_PLD_R2_N")
	)
	(segment
		(start 26.543 -102.34295)
		(end 25.859486 -101.659436)
		(width 0.11684)
		(layer "F.Cu")
		(net "RST_WDTRST_PLD_R2_N")
	)
	(segment
		(start 56.094884 -57.771284)
		(end 56.490108 -58.166508)
		(width 0.11684)
		(layer "F.Cu")
		(net "RST_WDTRST_PLD_R1_N")
	)
	(via
		(at 56.490108 -58.166508)
		(size 0.4572)
		(drill 0.254)
		(layers "F.Cu" "B.Cu")
		(net "RST_WDTRST_PLD_R1_N")
	)
	(via
		(at 54.73954 -64.34074)
		(size 0.508)
		(drill 0.254)
		(layers "F.Cu" "B.Cu")
		(net "RST_WDTRST_PLD_R1_N")
	)
	(segment
		(start 54.920642 -63.646558)
		(end 55.551832 -63.646558)
		(width 0.11684)
		(layer "B.Cu")
		(net "RST_WDTRST_PLD_R1_N")
	)
	(segment
		(start 54.73954 -63.82766)
		(end 54.920642 -63.646558)
		(width 0.11684)
		(layer "B.Cu")
		(net "RST_WDTRST_PLD_R1_N")
	)
	(segment
		(start 55.551832 -63.646558)
		(end 55.5752 -63.62319)
		(width 0.11684)
		(layer "B.Cu")
		(net "RST_WDTRST_PLD_R1_N")
	)
	(segment
		(start 54.73954 -64.34074)
		(end 54.73954 -63.82766)
		(width 0.11684)
		(layer "B.Cu")
		(net "RST_WDTRST_PLD_R1_N")
	)
	(segment
		(start 56.77154 -62.98946)
		(end 55.422546 -64.338454)
		(width 0.08382)
		(layer "In9.Cu")
		(net "RST_WDTRST_PLD_R1_N")
	)
	(segment
		(start 54.74208 -64.3382)
		(end 54.73954 -64.34074)
		(width 0.08382)
		(layer "In9.Cu")
		(net "RST_WDTRST_PLD_R1_N")
	)
	(segment
		(start 56.6166 -58.293)
		(end 56.6166 -61.0108)
		(width 0.08382)
		(layer "In9.Cu")
		(net "RST_WDTRST_PLD_R1_N")
	)
	(segment
		(start 55.16372 -64.3382)
		(end 54.74208 -64.3382)
		(width 0.08382)
		(layer "In9.Cu")
		(net "RST_WDTRST_PLD_R1_N")
	)
	(segment
		(start 56.6166 -61.0108)
		(end 56.896 -61.2902)
		(width 0.08382)
		(layer "In9.Cu")
		(net "RST_WDTRST_PLD_R1_N")
	)
	(segment
		(start 55.422546 -64.338454)
		(end 55.163974 -64.338454)
		(width 0.08382)
		(layer "In9.Cu")
		(net "RST_WDTRST_PLD_R1_N")
	)
	(segment
		(start 56.896 -61.2902)
		(end 56.896 -62.103)
		(width 0.08382)
		(layer "In9.Cu")
		(net "RST_WDTRST_PLD_R1_N")
	)
	(segment
		(start 56.77154 -62.22746)
		(end 56.77154 -62.98946)
		(width 0.08382)
		(layer "In9.Cu")
		(net "RST_WDTRST_PLD_R1_N")
	)
	(segment
		(start 56.896 -62.103)
		(end 56.77154 -62.22746)
		(width 0.08382)
		(layer "In9.Cu")
		(net "RST_WDTRST_PLD_R1_N")
	)
	(segment
		(start 56.490108 -58.166508)
		(end 56.6166 -58.293)
		(width 0.08382)
		(layer "In9.Cu")
		(net "RST_WDTRST_PLD_R1_N")
	)
	(segment
		(start 55.163974 -64.338454)
		(end 55.16372 -64.3382)
		(width 0.08382)
		(layer "In9.Cu")
		(net "RST_WDTRST_PLD_R1_N")
	)
	(segment
		(start 26.543 -103.14305)
		(end 26.543 -103.558594)
		(width 0.11684)
		(layer "F.Cu")
		(net "RST_WDTRST_PLD_N")
	)
	(segment
		(start 26.543 -103.558594)
		(end 27.517344 -104.532938)
		(width 0.11684)
		(layer "F.Cu")
		(net "RST_WDTRST_PLD_N")
	)
	(via
		(at 31.2674 -99.2124)
		(size 0.508)
		(drill 0.254)
		(layers "F.Cu" "B.Cu")
		(net "RST_WDTRST_PLD_N")
	)
	(via
		(at 55.0672 -64.9097)
		(size 0.508)
		(drill 0.254)
		(layers "F.Cu" "B.Cu")
		(net "RST_WDTRST_PLD_N")
	)
	(via
		(at 59.04738 -97.09912)
		(size 0.508)
		(drill 0.254)
		(layers "F.Cu" "B.Cu")
		(net "RST_WDTRST_PLD_N")
	)
	(via
		(at 27.517344 -104.532938)
		(size 0.508)
		(drill 0.254)
		(layers "F.Cu" "B.Cu")
		(net "RST_WDTRST_PLD_N")
	)
	(segment
		(start 55.5752 -64.76746)
		(end 55.5752 -64.42329)
		(width 0.11684)
		(layer "B.Cu")
		(net "RST_WDTRST_PLD_N")
	)
	(segment
		(start 55.0672 -64.9097)
		(end 55.43296 -64.9097)
		(width 0.11684)
		(layer "B.Cu")
		(net "RST_WDTRST_PLD_N")
	)
	(segment
		(start 55.43296 -64.9097)
		(end 55.5752 -64.76746)
		(width 0.11684)
		(layer "B.Cu")
		(net "RST_WDTRST_PLD_N")
	)
	(segment
		(start 54.40045 -64.9097)
		(end 54.3814 -64.92875)
		(width 0.11684)
		(layer "B.Cu")
		(net "RST_WDTRST_PLD_N")
	)
	(segment
		(start 55.0672 -64.9097)
		(end 54.40045 -64.9097)
		(width 0.11684)
		(layer "B.Cu")
		(net "RST_WDTRST_PLD_N")
	)
	(segment
		(start 48.76292 -95.90278)
		(end 55.42534 -95.90278)
		(width 0.08382)
		(layer "In2.Cu")
		(net "RST_WDTRST_PLD_N")
	)
	(segment
		(start 32.737806 -98.945192)
		(end 33.383728 -98.29927)
		(width 0.08382)
		(layer "In2.Cu")
		(net "RST_WDTRST_PLD_N")
	)
	(segment
		(start 45.811948 -95.60687)
		(end 48.46701 -95.60687)
		(width 0.08382)
		(layer "In2.Cu")
		(net "RST_WDTRST_PLD_N")
	)
	(segment
		(start 31.91256 -98.945192)
		(end 32.737806 -98.945192)
		(width 0.08382)
		(layer "In2.Cu")
		(net "RST_WDTRST_PLD_N")
	)
	(segment
		(start 56.62168 -97.09912)
		(end 59.04738 -97.09912)
		(width 0.08382)
		(layer "In2.Cu")
		(net "RST_WDTRST_PLD_N")
	)
	(segment
		(start 31.2674 -99.2124)
		(end 31.91256 -98.945192)
		(width 0.08382)
		(layer "In2.Cu")
		(net "RST_WDTRST_PLD_N")
	)
	(segment
		(start 37.974016 -99.280218)
		(end 42.1386 -99.280218)
		(width 0.08382)
		(layer "In2.Cu")
		(net "RST_WDTRST_PLD_N")
	)
	(segment
		(start 33.383728 -98.29927)
		(end 36.993068 -98.29927)
		(width 0.08382)
		(layer "In2.Cu")
		(net "RST_WDTRST_PLD_N")
	)
	(segment
		(start 55.42534 -95.90278)
		(end 56.62168 -97.09912)
		(width 0.08382)
		(layer "In2.Cu")
		(net "RST_WDTRST_PLD_N")
	)
	(segment
		(start 36.993068 -98.29927)
		(end 37.974016 -99.280218)
		(width 0.08382)
		(layer "In2.Cu")
		(net "RST_WDTRST_PLD_N")
	)
	(segment
		(start 42.1386 -99.280218)
		(end 45.811948 -95.60687)
		(width 0.08382)
		(layer "In2.Cu")
		(net "RST_WDTRST_PLD_N")
	)
	(segment
		(start 48.46701 -95.60687)
		(end 48.76292 -95.90278)
		(width 0.08382)
		(layer "In2.Cu")
		(net "RST_WDTRST_PLD_N")
	)
	(segment
		(start 58.99531 -95.207328)
		(end 58.99531 -94.656148)
		(width 0.08382)
		(layer "In9.Cu")
		(net "RST_WDTRST_PLD_N")
	)
	(segment
		(start 55.88 -86.801452)
		(end 55.88 -83.806284)
		(width 0.08382)
		(layer "In9.Cu")
		(net "RST_WDTRST_PLD_N")
	)
	(segment
		(start 29.921454 -100.5332)
		(end 30.403546 -100.5332)
		(width 0.08382)
		(layer "In9.Cu")
		(net "RST_WDTRST_PLD_N")
	)
	(segment
		(start 54.690264 -67.908678)
		(end 53.916326 -67.13474)
		(width 0.08382)
		(layer "In9.Cu")
		(net "RST_WDTRST_PLD_N")
	)
	(segment
		(start 54.690264 -70.734936)
		(end 54.690264 -67.908678)
		(width 0.08382)
		(layer "In9.Cu")
		(net "RST_WDTRST_PLD_N")
	)
	(segment
		(start 58.88609 -92.99829)
		(end 55.58409 -89.69629)
		(width 0.08382)
		(layer "In9.Cu")
		(net "RST_WDTRST_PLD_N")
	)
	(segment
		(start 58.55208 -96.645222)
		(end 58.55208 -95.650558)
		(width 0.08382)
		(layer "In9.Cu")
		(net "RST_WDTRST_PLD_N")
	)
	(segment
		(start 30.403546 -100.5332)
		(end 30.69209 -100.244656)
		(width 0.08382)
		(layer "In9.Cu")
		(net "RST_WDTRST_PLD_N")
	)
	(segment
		(start 59.001406 -97.094548)
		(end 58.55208 -96.645222)
		(width 0.08382)
		(layer "In9.Cu")
		(net "RST_WDTRST_PLD_N")
	)
	(segment
		(start 58.99531 -94.656148)
		(end 58.88609 -94.546928)
		(width 0.08382)
		(layer "In9.Cu")
		(net "RST_WDTRST_PLD_N")
	)
	(segment
		(start 31.2674 -99.466908)
		(end 31.2674 -99.2124)
		(width 0.08382)
		(layer "In9.Cu")
		(net "RST_WDTRST_PLD_N")
	)
	(segment
		(start 27.517344 -104.532938)
		(end 27.11069 -104.126284)
		(width 0.08382)
		(layer "In9.Cu")
		(net "RST_WDTRST_PLD_N")
	)
	(segment
		(start 53.916326 -66.2305)
		(end 55.0672 -65.079626)
		(width 0.08382)
		(layer "In9.Cu")
		(net "RST_WDTRST_PLD_N")
	)
	(segment
		(start 58.55208 -95.650558)
		(end 58.99531 -95.207328)
		(width 0.08382)
		(layer "In9.Cu")
		(net "RST_WDTRST_PLD_N")
	)
	(segment
		(start 53.562504 -81.488788)
		(end 53.562504 -71.862696)
		(width 0.08382)
		(layer "In9.Cu")
		(net "RST_WDTRST_PLD_N")
	)
	(segment
		(start 53.916326 -67.13474)
		(end 53.916326 -66.2305)
		(width 0.08382)
		(layer "In9.Cu")
		(net "RST_WDTRST_PLD_N")
	)
	(segment
		(start 55.0672 -65.079626)
		(end 55.0672 -64.9097)
		(width 0.08382)
		(layer "In9.Cu")
		(net "RST_WDTRST_PLD_N")
	)
	(segment
		(start 30.76067 -99.973638)
		(end 31.2674 -99.466908)
		(width 0.08382)
		(layer "In9.Cu")
		(net "RST_WDTRST_PLD_N")
	)
	(segment
		(start 30.69209 -100.139246)
		(end 30.76067 -99.973638)
		(width 0.08382)
		(layer "In9.Cu")
		(net "RST_WDTRST_PLD_N")
	)
	(segment
		(start 55.88 -83.806284)
		(end 53.562504 -81.488788)
		(width 0.08382)
		(layer "In9.Cu")
		(net "RST_WDTRST_PLD_N")
	)
	(segment
		(start 27.11069 -103.343964)
		(end 29.921454 -100.5332)
		(width 0.08382)
		(layer "In9.Cu")
		(net "RST_WDTRST_PLD_N")
	)
	(segment
		(start 58.88609 -94.546928)
		(end 58.88609 -92.99829)
		(width 0.08382)
		(layer "In9.Cu")
		(net "RST_WDTRST_PLD_N")
	)
	(segment
		(start 53.562504 -71.862696)
		(end 54.690264 -70.734936)
		(width 0.08382)
		(layer "In9.Cu")
		(net "RST_WDTRST_PLD_N")
	)
	(segment
		(start 55.58409 -89.69629)
		(end 55.58409 -87.097362)
		(width 0.08382)
		(layer "In9.Cu")
		(net "RST_WDTRST_PLD_N")
	)
	(segment
		(start 30.69209 -100.244656)
		(end 30.69209 -100.139246)
		(width 0.08382)
		(layer "In9.Cu")
		(net "RST_WDTRST_PLD_N")
	)
	(segment
		(start 55.58409 -87.097362)
		(end 55.88 -86.801452)
		(width 0.08382)
		(layer "In9.Cu")
		(net "RST_WDTRST_PLD_N")
	)
	(segment
		(start 27.11069 -104.126284)
		(end 27.11069 -103.343964)
		(width 0.08382)
		(layer "In9.Cu")
		(net "RST_WDTRST_PLD_N")
	)
	(segment
		(start 59.001406 -97.09912)
		(end 59.001406 -97.094548)
		(width 0.08382)
		(layer "In9.Cu")
		(net "RST_WDTRST_PLD_N")
	)
	(segment
		(start 59.04738 -97.09912)
		(end 59.001406 -97.09912)
		(width 0.08382)
		(layer "In9.Cu")
		(net "RST_WDTRST_PLD_N")
	)
	(segment
		(start 56.3372 -63.25235)
		(end 56.3372 -62.966346)
		(width 0.11684)
		(layer "F.Cu")
		(net "RST_BMC_SELF_HW_R1")
	)
	(segment
		(start 55.957978 -62.587124)
		(end 55.61584 -61.761116)
		(width 0.11684)
		(layer "F.Cu")
		(net "RST_BMC_SELF_HW_R1")
	)
	(segment
		(start 56.892444 -60.123578)
		(end 56.894984 -60.121038)
		(width 0.11684)
		(layer "F.Cu")
		(net "RST_BMC_SELF_HW_R1")
	)
	(segment
		(start 56.892444 -60.55741)
		(end 56.892444 -60.123578)
		(width 0.11684)
		(layer "F.Cu")
		(net "RST_BMC_SELF_HW_R1")
	)
	(segment
		(start 56.3372 -62.966346)
		(end 55.957978 -62.587124)
		(width 0.11684)
		(layer "F.Cu")
		(net "RST_BMC_SELF_HW_R1")
	)
	(segment
		(start 56.261254 -61.1886)
		(end 56.892444 -60.55741)
		(width 0.11684)
		(layer "F.Cu")
		(net "RST_BMC_SELF_HW_R1")
	)
	(segment
		(start 55.754778 -61.1886)
		(end 56.261254 -61.1886)
		(width 0.11684)
		(layer "F.Cu")
		(net "RST_BMC_SELF_HW_R1")
	)
	(segment
		(start 56.894984 -60.121038)
		(end 56.894984 -59.37123)
		(width 0.11684)
		(layer "F.Cu")
		(net "RST_BMC_SELF_HW_R1")
	)
	(segment
		(start 55.61584 -61.327538)
		(end 55.754778 -61.1886)
		(width 0.11684)
		(layer "F.Cu")
		(net "RST_BMC_SELF_HW_R1")
	)
	(segment
		(start 55.61584 -61.761116)
		(end 55.61584 -61.327538)
		(width 0.11684)
		(layer "F.Cu")
		(net "RST_BMC_SELF_HW_R1")
	)
	(segment
		(start 13.208 -96.52)
		(end 15.070836 -94.657164)
		(width 0.11684)
		(layer "F.Cu")
		(net "RST_BMC_HW_R")
	)
	(segment
		(start 15.070836 -94.657164)
		(end 15.070836 -94.625922)
		(width 0.11684)
		(layer "F.Cu")
		(net "RST_BMC_HW_R")
	)
	(segment
		(start 15.070836 -94.625922)
		(end 15.29842 -94.398338)
		(width 0.11684)
		(layer "F.Cu")
		(net "RST_BMC_HW_R")
	)
	(segment
		(start 12.71905 -96.52)
		(end 13.208 -96.52)
		(width 0.11684)
		(layer "F.Cu")
		(net "RST_BMC_HW_R")
	)
	(segment
		(start 15.329662 -94.398338)
		(end 15.345664 -94.382336)
		(width 0.11684)
		(layer "F.Cu")
		(net "RST_BMC_HW_R")
	)
	(segment
		(start 15.29842 -94.398338)
		(end 15.329662 -94.398338)
		(width 0.11684)
		(layer "F.Cu")
		(net "RST_BMC_HW_R")
	)
	(segment
		(start 15.345664 -94.382336)
		(end 15.864332 -94.382336)
		(width 0.11684)
		(layer "F.Cu")
		(net "RST_BMC_HW_R")
	)
	(segment
		(start 15.864332 -94.382336)
		(end 16.259556 -93.987112)
		(width 0.11684)
		(layer "F.Cu")
		(net "RST_BMC_HW_R")
	)
	(segment
		(start 11.02995 -96.79305)
		(end 11.303 -96.52)
		(width 0.11684)
		(layer "F.Cu")
		(net "RST_BMC_HW")
	)
	(segment
		(start 10.287 -96.79305)
		(end 11.02995 -96.79305)
		(width 0.11684)
		(layer "F.Cu")
		(net "RST_BMC_HW")
	)
	(segment
		(start 11.91895 -96.52)
		(end 11.303 -96.52)
		(width 0.11684)
		(layer "F.Cu")
		(net "RST_BMC_HW")
	)
	(via
		(at 31.114492 -106.59745)
		(size 0.508)
		(drill 0.254)
		(layers "F.Cu" "B.Cu")
		(net "RST_BMC_HW")
	)
	(via
		(at 11.303 -96.52)
		(size 0.508)
		(drill 0.254)
		(layers "F.Cu" "B.Cu")
		(net "RST_BMC_HW")
	)
	(segment
		(start 33.02 -103.123746)
		(end 33.02 -102.25405)
		(width 0.11684)
		(layer "B.Cu")
		(net "RST_BMC_HW")
	)
	(segment
		(start 31.70174 -105.256838)
		(end 31.70174 -104.442006)
		(width 0.11684)
		(layer "B.Cu")
		(net "RST_BMC_HW")
	)
	(segment
		(start 31.70174 -104.442006)
		(end 33.02 -103.123746)
		(width 0.11684)
		(layer "B.Cu")
		(net "RST_BMC_HW")
	)
	(segment
		(start 31.114492 -105.844086)
		(end 31.70174 -105.256838)
		(width 0.11684)
		(layer "B.Cu")
		(net "RST_BMC_HW")
	)
	(segment
		(start 31.114492 -106.59745)
		(end 31.114492 -105.844086)
		(width 0.11684)
		(layer "B.Cu")
		(net "RST_BMC_HW")
	)
	(segment
		(start 26.582878 -108.87964)
		(end 26.8478 -108.614718)
		(width 0.10668)
		(layer "In4.Cu")
		(net "RST_BMC_HW")
	)
	(segment
		(start 23.39848 -108.59262)
		(end 25.624028 -108.59262)
		(width 0.10668)
		(layer "In4.Cu")
		(net "RST_BMC_HW")
	)
	(segment
		(start 12.951206 -103.70566)
		(end 14.386306 -105.14076)
		(width 0.10668)
		(layer "In4.Cu")
		(net "RST_BMC_HW")
	)
	(segment
		(start 11.303 -96.52)
		(end 11.303 -96.891856)
		(width 0.10668)
		(layer "In4.Cu")
		(net "RST_BMC_HW")
	)
	(segment
		(start 26.8478 -108.614718)
		(end 26.8478 -107.823)
		(width 0.10668)
		(layer "In4.Cu")
		(net "RST_BMC_HW")
	)
	(segment
		(start 26.8478 -107.823)
		(end 28.07335 -106.59745)
		(width 0.10668)
		(layer "In4.Cu")
		(net "RST_BMC_HW")
	)
	(segment
		(start 11.303 -96.891856)
		(end 8.9154 -99.279456)
		(width 0.10668)
		(layer "In4.Cu")
		(net "RST_BMC_HW")
	)
	(segment
		(start 15.4432 -105.5878)
		(end 15.907258 -105.5878)
		(width 0.10668)
		(layer "In4.Cu")
		(net "RST_BMC_HW")
	)
	(segment
		(start 14.386306 -105.14076)
		(end 14.99616 -105.14076)
		(width 0.10668)
		(layer "In4.Cu")
		(net "RST_BMC_HW")
	)
	(segment
		(start 17.86255 -105.97515)
		(end 18.669 -106.7816)
		(width 0.10668)
		(layer "In4.Cu")
		(net "RST_BMC_HW")
	)
	(segment
		(start 10.961624 -103.70566)
		(end 12.951206 -103.70566)
		(width 0.10668)
		(layer "In4.Cu")
		(net "RST_BMC_HW")
	)
	(segment
		(start 18.669 -106.7816)
		(end 21.58746 -106.7816)
		(width 0.10668)
		(layer "In4.Cu")
		(net "RST_BMC_HW")
	)
	(segment
		(start 28.07335 -106.59745)
		(end 31.114492 -106.59745)
		(width 0.10668)
		(layer "In4.Cu")
		(net "RST_BMC_HW")
	)
	(segment
		(start 25.624028 -108.59262)
		(end 25.911048 -108.87964)
		(width 0.10668)
		(layer "In4.Cu")
		(net "RST_BMC_HW")
	)
	(segment
		(start 14.99616 -105.14076)
		(end 15.4432 -105.5878)
		(width 0.10668)
		(layer "In4.Cu")
		(net "RST_BMC_HW")
	)
	(segment
		(start 8.9154 -101.659436)
		(end 10.961624 -103.70566)
		(width 0.10668)
		(layer "In4.Cu")
		(net "RST_BMC_HW")
	)
	(segment
		(start 25.911048 -108.87964)
		(end 26.582878 -108.87964)
		(width 0.10668)
		(layer "In4.Cu")
		(net "RST_BMC_HW")
	)
	(segment
		(start 21.58746 -106.7816)
		(end 23.39848 -108.59262)
		(width 0.10668)
		(layer "In4.Cu")
		(net "RST_BMC_HW")
	)
	(segment
		(start 16.294608 -105.97515)
		(end 17.86255 -105.97515)
		(width 0.10668)
		(layer "In4.Cu")
		(net "RST_BMC_HW")
	)
	(segment
		(start 15.907258 -105.5878)
		(end 16.294608 -105.97515)
		(width 0.10668)
		(layer "In4.Cu")
		(net "RST_BMC_HW")
	)
	(segment
		(start 8.9154 -99.279456)
		(end 8.9154 -101.659436)
		(width 0.10668)
		(layer "In4.Cu")
		(net "RST_BMC_HW")
	)
	(segment
		(start 33.459928 -18.981928)
		(end 34.097976 -19.619976)
		(width 0.508)
		(layer "F.Cu")
		(net "CRT_VCC5_2_FUSE")
	)
	(segment
		(start 33.147 -18.9738)
		(end 33.155128 -18.981928)
		(width 0.508)
		(layer "F.Cu")
		(net "CRT_VCC5_2_FUSE")
	)
	(segment
		(start 33.155128 -18.981928)
		(end 33.459928 -18.981928)
		(width 0.508)
		(layer "F.Cu")
		(net "CRT_VCC5_2_FUSE")
	)
	(segment
		(start 34.097976 -19.619976)
		(end 34.625026 -19.619976)
		(width 0.508)
		(layer "F.Cu")
		(net "CRT_VCC5_2_FUSE")
	)
	(via
		(at 33.147 -18.9738)
		(size 0.508)
		(drill 0.254)
		(layers "F.Cu" "B.Cu")
		(net "CRT_VCC5_2_FUSE")
	)
	(via
		(at 31.9532 -17.526)
		(size 0.6604)
		(drill 0.3302)
		(layers "F.Cu" "B.Cu")
		(net "CRT_VCC5_2_FUSE")
	)
	(via
		(at 28.702 -22.479)
		(size 0.6604)
		(drill 0.3302)
		(layers "F.Cu" "B.Cu")
		(net "CRT_VCC5_2_D")
	)
	(segment
		(start 29.591 -21.262594)
		(end 29.21 -21.262594)
		(width 0.508)
		(layer "B.Cu")
		(net "CRT_VCC5_2_D")
	)
	(segment
		(start 29.21 -21.262594)
		(end 28.702 -21.770594)
		(width 0.508)
		(layer "B.Cu")
		(net "CRT_VCC5_2_D")
	)
	(segment
		(start 28.702 -21.770594)
		(end 28.702 -22.479)
		(width 0.508)
		(layer "B.Cu")
		(net "CRT_VCC5_2_D")
	)
	(segment
		(start 31.7754 -21.973286)
		(end 31.593282 -21.791168)
		(width 0.508)
		(layer "B.Cu")
		(net "CRT_VCC5_2_D")
	)
	(segment
		(start 31.047182 -21.791168)
		(end 30.518608 -21.262594)
		(width 0.508)
		(layer "B.Cu")
		(net "CRT_VCC5_2_D")
	)
	(segment
		(start 31.593282 -21.791168)
		(end 31.047182 -21.791168)
		(width 0.508)
		(layer "B.Cu")
		(net "CRT_VCC5_2_D")
	)
	(segment
		(start 30.518608 -21.262594)
		(end 29.591 -21.262594)
		(width 0.508)
		(layer "B.Cu")
		(net "CRT_VCC5_2_D")
	)
	(segment
		(start 9.8298 -22.733)
		(end 9.8298 -25.2984)
		(width 0.11684)
		(layer "F.Cu")
		(net "UART_BMC_5_TXD_BUF_R")
	)
	(segment
		(start 8.128 -27.0002)
		(end 6.5024 -27.0002)
		(width 0.11684)
		(layer "F.Cu")
		(net "UART_BMC_5_TXD_BUF_R")
	)
	(segment
		(start 9.8298 -25.2984)
		(end 8.128 -27.0002)
		(width 0.11684)
		(layer "F.Cu")
		(net "UART_BMC_5_TXD_BUF_R")
	)
	(segment
		(start 11.500104 -22.606)
		(end 9.9568 -22.606)
		(width 0.11684)
		(layer "F.Cu")
		(net "UART_BMC_5_TXD_BUF_R")
	)
	(segment
		(start 6.5024 -27.0002)
		(end 4.2672 -27.0002)
		(width 0.11684)
		(layer "F.Cu")
		(net "UART_BMC_5_TXD_BUF_R")
	)
	(segment
		(start 9.9568 -22.606)
		(end 9.8298 -22.733)
		(width 0.11684)
		(layer "F.Cu")
		(net "UART_BMC_5_TXD_BUF_R")
	)
	(segment
		(start 4.2672 -27.0002)
		(end 3.175 -25.908)
		(width 0.11684)
		(layer "F.Cu")
		(net "UART_BMC_5_TXD_BUF_R")
	)
	(via
		(at 6.5024 -27.0002)
		(size 0.762)
		(drill 0.381)
		(layers "F.Cu" "B.Cu")
		(net "UART_BMC_5_TXD_BUF_R")
	)
	(via
		(at 3.175 -25.908)
		(size 0.508)
		(drill 0.254)
		(layers "F.Cu" "B.Cu")
		(net "UART_BMC_5_TXD_BUF_R")
	)
	(segment
		(start 4.24815 -28.5877)
		(end 4.2672 -28.56865)
		(width 0.11684)
		(layer "B.Cu")
		(net "UART_BMC_5_TXD_BUF_R")
	)
	(segment
		(start 3.175 -25.908)
		(end 2.7432 -26.3398)
		(width 0.11684)
		(layer "B.Cu")
		(net "UART_BMC_5_TXD_BUF_R")
	)
	(segment
		(start 4.247896 -28.587954)
		(end 4.24815 -28.5877)
		(width 0.11684)
		(layer "B.Cu")
		(net "UART_BMC_5_TXD_BUF_R")
	)
	(segment
		(start 4.24815 -28.5877)
		(end 4.24815 -29.5148)
		(width 0.11684)
		(layer "B.Cu")
		(net "UART_BMC_5_TXD_BUF_R")
	)
	(segment
		(start 3.670554 -28.587954)
		(end 4.247896 -28.587954)
		(width 0.11684)
		(layer "B.Cu")
		(net "UART_BMC_5_TXD_BUF_R")
	)
	(segment
		(start 2.7432 -26.3398)
		(end 2.7432 -27.6606)
		(width 0.11684)
		(layer "B.Cu")
		(net "UART_BMC_5_TXD_BUF_R")
	)
	(segment
		(start 2.7432 -27.6606)
		(end 3.670554 -28.587954)
		(width 0.11684)
		(layer "B.Cu")
		(net "UART_BMC_5_TXD_BUF_R")
	)
	(via
		(at 5.588 -28.2956)
		(size 0.6604)
		(drill 0.3302)
		(layers "F.Cu" "B.Cu")
		(net "UART_BMC_5_TXD_BUF")
	)
	(segment
		(start 5.588 -28.2956)
		(end 5.679186 -28.386786)
		(width 0.11684)
		(layer "B.Cu")
		(net "UART_BMC_5_TXD_BUF")
	)
	(segment
		(start 5.588 -28.2956)
		(end 4.76885 -28.2956)
		(width 0.11684)
		(layer "B.Cu")
		(net "UART_BMC_5_TXD_BUF")
	)
	(segment
		(start 4.76885 -28.2956)
		(end 4.2672 -27.79395)
		(width 0.11684)
		(layer "B.Cu")
		(net "UART_BMC_5_TXD_BUF")
	)
	(segment
		(start 5.679186 -28.386786)
		(end 7.02564 -28.386786)
		(width 0.11684)
		(layer "B.Cu")
		(net "UART_BMC_5_TXD_BUF")
	)
	(segment
		(start 4.2672 -27.79395)
		(end 4.2672 -27.76855)
		(width 0.11684)
		(layer "B.Cu")
		(net "UART_BMC_5_TXD_BUF")
	)
	(via
		(at 10.16 -26.4668)
		(size 0.6604)
		(drill 0.3302)
		(layers "F.Cu" "B.Cu")
		(net "UART_BMC_5_RXD_BUF_R")
	)
	(segment
		(start 7.86384 -27.086814)
		(end 7.02564 -27.086814)
		(width 0.11684)
		(layer "B.Cu")
		(net "UART_BMC_5_RXD_BUF_R")
	)
	(segment
		(start 11.51255 -25.9842)
		(end 10.87755 -25.9842)
		(width 0.11684)
		(layer "B.Cu")
		(net "UART_BMC_5_RXD_BUF_R")
	)
	(segment
		(start 8.483854 -26.4668)
		(end 7.86384 -27.086814)
		(width 0.11684)
		(layer "B.Cu")
		(net "UART_BMC_5_RXD_BUF_R")
	)
	(segment
		(start 10.39495 -26.4668)
		(end 10.16 -26.4668)
		(width 0.11684)
		(layer "B.Cu")
		(net "UART_BMC_5_RXD_BUF_R")
	)
	(segment
		(start 10.87755 -25.9842)
		(end 10.39495 -26.4668)
		(width 0.11684)
		(layer "B.Cu")
		(net "UART_BMC_5_RXD_BUF_R")
	)
	(segment
		(start 10.16 -26.4668)
		(end 8.483854 -26.4668)
		(width 0.11684)
		(layer "B.Cu")
		(net "UART_BMC_5_RXD_BUF_R")
	)
	(segment
		(start 10.68324 -27.686)
		(end 11.500104 -27.686)
		(width 0.11684)
		(layer "F.Cu")
		(net "UART_BMC_5_RXD_BUF")
	)
	(segment
		(start 10.39876 -28.589986)
		(end 10.39876 -27.97048)
		(width 0.11684)
		(layer "F.Cu")
		(net "UART_BMC_5_RXD_BUF")
	)
	(segment
		(start 10.39876 -27.97048)
		(end 10.68324 -27.686)
		(width 0.11684)
		(layer "F.Cu")
		(net "UART_BMC_5_RXD_BUF")
	)
	(via
		(at 10.39876 -28.589986)
		(size 0.508)
		(drill 0.254)
		(layers "F.Cu" "B.Cu")
		(net "UART_BMC_5_RXD_BUF")
	)
	(segment
		(start 10.75944 -27.086814)
		(end 10.871454 -26.9748)
		(width 0.11684)
		(layer "B.Cu")
		(net "UART_BMC_5_RXD_BUF")
	)
	(segment
		(start 8.92556 -27.086814)
		(end 10.75944 -27.086814)
		(width 0.11684)
		(layer "B.Cu")
		(net "UART_BMC_5_RXD_BUF")
	)
	(segment
		(start 10.871454 -26.9748)
		(end 11.51255 -26.9748)
		(width 0.11684)
		(layer "B.Cu")
		(net "UART_BMC_5_RXD_BUF")
	)
	(segment
		(start 11.51255 -27.349704)
		(end 11.51255 -26.9748)
		(width 0.11684)
		(layer "B.Cu")
		(net "UART_BMC_5_RXD_BUF")
	)
	(segment
		(start 10.39876 -28.589986)
		(end 10.39876 -28.463494)
		(width 0.11684)
		(layer "B.Cu")
		(net "UART_BMC_5_RXD_BUF")
	)
	(segment
		(start 10.39876 -28.463494)
		(end 11.51255 -27.349704)
		(width 0.11684)
		(layer "B.Cu")
		(net "UART_BMC_5_RXD_BUF")
	)
	(segment
		(start 40.91178 -104.53878)
		(end 40.135302 -103.762302)
		(width 0.11684)
		(layer "F.Cu")
		(net "TP_J40_12")
	)
	(segment
		(start 41.8592 -105.7656)
		(end 41.8592 -104.8258)
		(width 0.11684)
		(layer "F.Cu")
		(net "TP_J40_12")
	)
	(segment
		(start 41.57218 -104.53878)
		(end 40.91178 -104.53878)
		(width 0.11684)
		(layer "F.Cu")
		(net "TP_J40_12")
	)
	(segment
		(start 40.92448 -107.84586)
		(end 40.92448 -106.70032)
		(width 0.11684)
		(layer "F.Cu")
		(net "TP_J40_12")
	)
	(segment
		(start 40.92448 -106.70032)
		(end 41.8592 -105.7656)
		(width 0.11684)
		(layer "F.Cu")
		(net "TP_J40_12")
	)
	(segment
		(start 41.8592 -104.8258)
		(end 41.57218 -104.53878)
		(width 0.11684)
		(layer "F.Cu")
		(net "TP_J40_12")
	)
	(segment
		(start 40.135302 -103.762302)
		(end 40.135302 -103.060246)
		(width 0.11684)
		(layer "F.Cu")
		(net "TP_J40_12")
	)
	(via
		(at 40.92448 -107.84586)
		(size 0.762)
		(drill 0.381)
		(layers "F.Cu" "B.Cu")
		(net "TP_J40_12")
	)
	(segment
		(start 41.405302 -103.711502)
		(end 42.3164 -104.6226)
		(width 0.11684)
		(layer "F.Cu")
		(net "TP_J40_11")
	)
	(segment
		(start 42.3164 -104.6226)
		(end 42.3164 -107.86364)
		(width 0.11684)
		(layer "F.Cu")
		(net "TP_J40_11")
	)
	(segment
		(start 42.3164 -107.86364)
		(end 42.2783 -107.90174)
		(width 0.11684)
		(layer "F.Cu")
		(net "TP_J40_11")
	)
	(segment
		(start 41.405302 -103.060246)
		(end 41.405302 -103.711502)
		(width 0.11684)
		(layer "F.Cu")
		(net "TP_J40_11")
	)
	(via
		(at 42.2783 -107.90174)
		(size 0.762)
		(drill 0.381)
		(layers "F.Cu" "B.Cu")
		(net "TP_J40_11")
	)
	(via
		(at 47.812706 -106.084116)
		(size 0.6604)
		(drill 0.3302)
		(layers "F.Cu" "B.Cu")
		(net "TP_BIOS_MUX1_PIN14")
	)
	(segment
		(start 47.81042 -106.084116)
		(end 47.812706 -106.084116)
		(width 0.11684)
		(layer "B.Cu")
		(net "TP_BIOS_MUX1_PIN14")
	)
	(segment
		(start 47.81042 -105.160064)
		(end 47.81042 -106.084116)
		(width 0.11684)
		(layer "B.Cu")
		(net "TP_BIOS_MUX1_PIN14")
	)
	(segment
		(start 41.895776 -102.677976)
		(end 44.153074 -104.935274)
		(width 0.11684)
		(layer "B.Cu")
		(net "TP_BIOS_MUX1_PIN14")
	)
	(segment
		(start 44.153074 -104.935274)
		(end 47.58563 -104.935274)
		(width 0.11684)
		(layer "B.Cu")
		(net "TP_BIOS_MUX1_PIN14")
	)
	(segment
		(start 40.969184 -102.677976)
		(end 41.895776 -102.677976)
		(width 0.11684)
		(layer "B.Cu")
		(net "TP_BIOS_MUX1_PIN14")
	)
	(segment
		(start 47.58563 -104.935274)
		(end 47.81042 -105.160064)
		(width 0.11684)
		(layer "B.Cu")
		(net "TP_BIOS_MUX1_PIN14")
	)
	(via
		(at 48.88738 -105.3719)
		(size 0.6604)
		(drill 0.3302)
		(layers "F.Cu" "B.Cu")
		(net "TP_BIOS_MUX1_PIN13")
	)
	(segment
		(start 47.69739 -104.666034)
		(end 48.403256 -105.3719)
		(width 0.11684)
		(layer "B.Cu")
		(net "TP_BIOS_MUX1_PIN13")
	)
	(segment
		(start 40.969184 -102.02799)
		(end 41.62679 -102.02799)
		(width 0.11684)
		(layer "B.Cu")
		(net "TP_BIOS_MUX1_PIN13")
	)
	(segment
		(start 41.62679 -102.02799)
		(end 44.264834 -104.666034)
		(width 0.11684)
		(layer "B.Cu")
		(net "TP_BIOS_MUX1_PIN13")
	)
	(segment
		(start 48.403256 -105.3719)
		(end 48.88738 -105.3719)
		(width 0.11684)
		(layer "B.Cu")
		(net "TP_BIOS_MUX1_PIN13")
	)
	(segment
		(start 44.264834 -104.666034)
		(end 47.69739 -104.666034)
		(width 0.11684)
		(layer "B.Cu")
		(net "TP_BIOS_MUX1_PIN13")
	)
	(via
		(at 49.4284 -106.59364)
		(size 0.6604)
		(drill 0.3302)
		(layers "F.Cu" "B.Cu")
		(net "TP_BIOS_MUX1_PIN12")
	)
	(segment
		(start 41.99001 -101.37775)
		(end 45.009054 -104.396794)
		(width 0.11684)
		(layer "B.Cu")
		(net "TP_BIOS_MUX1_PIN12")
	)
	(segment
		(start 48.238918 -104.826562)
		(end 49.236122 -104.826562)
		(width 0.11684)
		(layer "B.Cu")
		(net "TP_BIOS_MUX1_PIN12")
	)
	(segment
		(start 49.4284 -105.01884)
		(end 49.4284 -106.59364)
		(width 0.11684)
		(layer "B.Cu")
		(net "TP_BIOS_MUX1_PIN12")
	)
	(segment
		(start 49.236122 -104.826562)
		(end 49.4284 -105.01884)
		(width 0.11684)
		(layer "B.Cu")
		(net "TP_BIOS_MUX1_PIN12")
	)
	(segment
		(start 45.009054 -104.396794)
		(end 47.80915 -104.396794)
		(width 0.11684)
		(layer "B.Cu")
		(net "TP_BIOS_MUX1_PIN12")
	)
	(segment
		(start 47.80915 -104.396794)
		(end 48.238918 -104.826562)
		(width 0.11684)
		(layer "B.Cu")
		(net "TP_BIOS_MUX1_PIN12")
	)
	(segment
		(start 40.969184 -101.37775)
		(end 41.99001 -101.37775)
		(width 0.11684)
		(layer "B.Cu")
		(net "TP_BIOS_MUX1_PIN12")
	)
	(segment
		(start 55.473854 -102.9462)
		(end 56.5404 -102.9462)
		(width 0.11684)
		(layer "F.Cu")
		(net "SPI_PCH_SECURE_CS0_N")
	)
	(segment
		(start 56.446928 -104.79532)
		(end 55.02148 -104.79532)
		(width 0.11684)
		(layer "F.Cu")
		(net "SPI_PCH_SECURE_CS0_N")
	)
	(segment
		(start 47.8282 -101.473)
		(end 48.2854 -101.473)
		(width 0.11684)
		(layer "F.Cu")
		(net "SPI_PCH_SECURE_CS0_N")
	)
	(segment
		(start 54.796436 -107.843828)
		(end 54.911244 -107.958636)
		(width 0.11684)
		(layer "F.Cu")
		(net "SPI_PCH_SECURE_CS0_N")
	)
	(segment
		(start 54.71922 -102.191566)
		(end 55.473854 -102.9462)
		(width 0.11684)
		(layer "F.Cu")
		(net "SPI_PCH_SECURE_CS0_N")
	)
	(segment
		(start 55.02148 -104.79532)
		(end 54.47792 -105.33888)
		(width 0.11684)
		(layer "F.Cu")
		(net "SPI_PCH_SECURE_CS0_N")
	)
	(segment
		(start 54.78018 -100.254308)
		(end 54.78018 -100.745036)
		(width 0.11684)
		(layer "F.Cu")
		(net "SPI_PCH_SECURE_CS0_N")
	)
	(segment
		(start 38.9636 -100.6348)
		(end 46.99 -100.6348)
		(width 0.11684)
		(layer "F.Cu")
		(net "SPI_PCH_SECURE_CS0_N")
	)
	(segment
		(start 38.32606 -99.99726)
		(end 38.9636 -100.6348)
		(width 0.11684)
		(layer "F.Cu")
		(net "SPI_PCH_SECURE_CS0_N")
	)
	(segment
		(start 51.1302 -99.822)
		(end 54.347872 -99.822)
		(width 0.11684)
		(layer "F.Cu")
		(net "SPI_PCH_SECURE_CS0_N")
	)
	(segment
		(start 54.347872 -99.822)
		(end 54.78018 -100.254308)
		(width 0.11684)
		(layer "F.Cu")
		(net "SPI_PCH_SECURE_CS0_N")
	)
	(segment
		(start 48.2854 -101.473)
		(end 49.4792 -100.2792)
		(width 0.11684)
		(layer "F.Cu")
		(net "SPI_PCH_SECURE_CS0_N")
	)
	(segment
		(start 56.9722 -103.90632)
		(end 56.714898 -104.52735)
		(width 0.11684)
		(layer "F.Cu")
		(net "SPI_PCH_SECURE_CS0_N")
	)
	(segment
		(start 55.032656 -108.252006)
		(end 55.7784 -108.99775)
		(width 0.11684)
		(layer "F.Cu")
		(net "SPI_PCH_SECURE_CS0_N")
	)
	(segment
		(start 54.47792 -107.072938)
		(end 54.796436 -107.843828)
		(width 0.11684)
		(layer "F.Cu")
		(net "SPI_PCH_SECURE_CS0_N")
	)
	(segment
		(start 56.5404 -102.9462)
		(end 56.9722 -103.378)
		(width 0.11684)
		(layer "F.Cu")
		(net "SPI_PCH_SECURE_CS0_N")
	)
	(segment
		(start 50.673 -100.2792)
		(end 51.1302 -99.822)
		(width 0.11684)
		(layer "F.Cu")
		(net "SPI_PCH_SECURE_CS0_N")
	)
	(segment
		(start 54.71922 -100.805996)
		(end 54.71922 -102.191566)
		(width 0.11684)
		(layer "F.Cu")
		(net "SPI_PCH_SECURE_CS0_N")
	)
	(segment
		(start 56.9722 -103.378)
		(end 56.9722 -103.90632)
		(width 0.11684)
		(layer "F.Cu")
		(net "SPI_PCH_SECURE_CS0_N")
	)
	(segment
		(start 54.78018 -100.745036)
		(end 54.71922 -100.805996)
		(width 0.11684)
		(layer "F.Cu")
		(net "SPI_PCH_SECURE_CS0_N")
	)
	(segment
		(start 54.911244 -107.958636)
		(end 55.032656 -108.252006)
		(width 0.11684)
		(layer "F.Cu")
		(net "SPI_PCH_SECURE_CS0_N")
	)
	(segment
		(start 56.714898 -104.52735)
		(end 56.446928 -104.79532)
		(width 0.11684)
		(layer "F.Cu")
		(net "SPI_PCH_SECURE_CS0_N")
	)
	(segment
		(start 54.47792 -105.33888)
		(end 54.47792 -107.072938)
		(width 0.11684)
		(layer "F.Cu")
		(net "SPI_PCH_SECURE_CS0_N")
	)
	(segment
		(start 36.197794 -99.99726)
		(end 38.32606 -99.99726)
		(width 0.11684)
		(layer "F.Cu")
		(net "SPI_PCH_SECURE_CS0_N")
	)
	(segment
		(start 49.4792 -100.2792)
		(end 50.673 -100.2792)
		(width 0.11684)
		(layer "F.Cu")
		(net "SPI_PCH_SECURE_CS0_N")
	)
	(segment
		(start 46.99 -100.6348)
		(end 47.8282 -101.473)
		(width 0.11684)
		(layer "F.Cu")
		(net "SPI_PCH_SECURE_CS0_N")
	)
	(via
		(at 39.278052 -100.727764)
		(size 0.6604)
		(drill 0.3302)
		(layers "F.Cu" "B.Cu")
		(net "SPI_PCH_SECURE_CS0_N")
	)
	(via
		(at 36.197794 -99.99726)
		(size 0.508)
		(drill 0.254)
		(layers "F.Cu" "B.Cu")
		(net "SPI_PCH_SECURE_CS0_N")
	)
	(segment
		(start 36.77666 -99.99726)
		(end 37.1856 -100.4062)
		(width 0.11684)
		(layer "B.Cu")
		(net "SPI_PCH_SECURE_CS0_N")
	)
	(segment
		(start 36.197794 -99.99726)
		(end 36.77666 -99.99726)
		(width 0.11684)
		(layer "B.Cu")
		(net "SPI_PCH_SECURE_CS0_N")
	)
	(segment
		(start 37.1856 -100.4062)
		(end 38.956488 -100.4062)
		(width 0.11684)
		(layer "B.Cu")
		(net "SPI_PCH_SECURE_CS0_N")
	)
	(segment
		(start 40.969184 -100.727764)
		(end 39.278052 -100.727764)
		(width 0.11684)
		(layer "B.Cu")
		(net "SPI_PCH_SECURE_CS0_N")
	)
	(segment
		(start 38.956488 -100.4062)
		(end 39.278052 -100.727764)
		(width 0.11684)
		(layer "B.Cu")
		(net "SPI_PCH_SECURE_CS0_N")
	)
	(segment
		(start 81.312004 -94.356174)
		(end 82.6516 -94.356174)
		(width 0.11684)
		(layer "F.Cu")
		(net "SPI_BMC_TPM_MOSI_R")
	)
	(segment
		(start 83.80095 -94.488)
		(end 83.465924 -94.152974)
		(width 0.11684)
		(layer "F.Cu")
		(net "SPI_BMC_TPM_MOSI_R")
	)
	(segment
		(start 83.465924 -94.152974)
		(end 82.8548 -94.152974)
		(width 0.11684)
		(layer "F.Cu")
		(net "SPI_BMC_TPM_MOSI_R")
	)
	(segment
		(start 82.6516 -94.356174)
		(end 82.8548 -94.152974)
		(width 0.11684)
		(layer "F.Cu")
		(net "SPI_BMC_TPM_MOSI_R")
	)
	(via
		(at 82.8548 -94.152974)
		(size 0.508)
		(drill 0.254)
		(layers "F.Cu" "B.Cu")
		(net "SPI_BMC_TPM_MOSI_R")
	)
	(segment
		(start 83.80095 -95.631)
		(end 83.028282 -95.631)
		(width 0.11684)
		(layer "F.Cu")
		(net "SPI_BMC_TPM_MISO_R")
	)
	(segment
		(start 82.8294 -95.432118)
		(end 81.388204 -95.432118)
		(width 0.11684)
		(layer "F.Cu")
		(net "SPI_BMC_TPM_MISO_R")
	)
	(segment
		(start 83.028282 -95.631)
		(end 82.8294 -95.432118)
		(width 0.11684)
		(layer "F.Cu")
		(net "SPI_BMC_TPM_MISO_R")
	)
	(segment
		(start 81.388204 -95.432118)
		(end 81.312004 -95.355918)
		(width 0.11684)
		(layer "F.Cu")
		(net "SPI_BMC_TPM_MISO_R")
	)
	(via
		(at 82.8294 -95.432118)
		(size 0.508)
		(drill 0.254)
		(layers "F.Cu" "B.Cu")
		(net "SPI_BMC_TPM_MISO_R")
	)
	(segment
		(start 67.6148 -71.7804)
		(end 67.6148 -74.8792)
		(width 0.11684)
		(layer "F.Cu")
		(net "SPI_BMC_TPM_CS2_R_N")
	)
	(segment
		(start 80.198976 -101.465126)
		(end 71.736966 -101.465126)
		(width 0.11684)
		(layer "F.Cu")
		(net "SPI_BMC_TPM_CS2_R_N")
	)
	(segment
		(start 82.29346 -100.1522)
		(end 81.511902 -100.1522)
		(width 0.11684)
		(layer "F.Cu")
		(net "SPI_BMC_TPM_CS2_R_N")
	)
	(segment
		(start 67.91325 -71.48195)
		(end 67.6148 -71.7804)
		(width 0.11684)
		(layer "F.Cu")
		(net "SPI_BMC_TPM_CS2_R_N")
	)
	(segment
		(start 71.736966 -101.465126)
		(end 69.94144 -99.6696)
		(width 0.11684)
		(layer "F.Cu")
		(net "SPI_BMC_TPM_CS2_R_N")
	)
	(segment
		(start 84.60105 -97.917)
		(end 84.52866 -97.917)
		(width 0.11684)
		(layer "F.Cu")
		(net "SPI_BMC_TPM_CS2_R_N")
	)
	(segment
		(start 68.4276 -70.97395)
		(end 69.4055 -69.99605)
		(width 0.11684)
		(layer "F.Cu")
		(net "SPI_BMC_TPM_CS2_R_N")
	)
	(segment
		(start 84.52866 -97.917)
		(end 82.29346 -100.1522)
		(width 0.11684)
		(layer "F.Cu")
		(net "SPI_BMC_TPM_CS2_R_N")
	)
	(segment
		(start 81.511902 -100.1522)
		(end 80.198976 -101.465126)
		(width 0.11684)
		(layer "F.Cu")
		(net "SPI_BMC_TPM_CS2_R_N")
	)
	(segment
		(start 68.4276 -71.48195)
		(end 68.4276 -70.97395)
		(width 0.11684)
		(layer "F.Cu")
		(net "SPI_BMC_TPM_CS2_R_N")
	)
	(segment
		(start 69.94144 -99.6696)
		(end 69.1896 -99.6696)
		(width 0.11684)
		(layer "F.Cu")
		(net "SPI_BMC_TPM_CS2_R_N")
	)
	(segment
		(start 68.4276 -71.48195)
		(end 67.91325 -71.48195)
		(width 0.11684)
		(layer "F.Cu")
		(net "SPI_BMC_TPM_CS2_R_N")
	)
	(via
		(at 60.5536 -77.2668)
		(size 0.508)
		(drill 0.254)
		(layers "F.Cu" "B.Cu")
		(net "SPI_BMC_TPM_CS2_R_N")
	)
	(via
		(at 69.1896 -99.6696)
		(size 0.508)
		(drill 0.254)
		(layers "F.Cu" "B.Cu")
		(net "SPI_BMC_TPM_CS2_R_N")
	)
	(via
		(at 66.167 -76.327)
		(size 0.6604)
		(drill 0.3302)
		(layers "F.Cu" "B.Cu")
		(net "SPI_BMC_TPM_CS2_R_N")
	)
	(via
		(at 67.6148 -74.8792)
		(size 0.508)
		(drill 0.254)
		(layers "F.Cu" "B.Cu")
		(net "SPI_BMC_TPM_CS2_R_N")
	)
	(segment
		(start 60.96 -76.8604)
		(end 65.6336 -76.8604)
		(width 0.11684)
		(layer "B.Cu")
		(net "SPI_BMC_TPM_CS2_R_N")
	)
	(segment
		(start 67.6148 -74.8792)
		(end 66.167 -76.327)
		(width 0.11684)
		(layer "B.Cu")
		(net "SPI_BMC_TPM_CS2_R_N")
	)
	(segment
		(start 65.6336 -76.8604)
		(end 66.167 -76.327)
		(width 0.11684)
		(layer "B.Cu")
		(net "SPI_BMC_TPM_CS2_R_N")
	)
	(segment
		(start 60.5536 -77.2668)
		(end 60.96 -76.8604)
		(width 0.11684)
		(layer "B.Cu")
		(net "SPI_BMC_TPM_CS2_R_N")
	)
	(segment
		(start 63.254636 -83.755992)
		(end 63.254636 -89.79535)
		(width 0.10668)
		(layer "In7.Cu")
		(net "SPI_BMC_TPM_CS2_R_N")
	)
	(segment
		(start 62.36208 -79.96428)
		(end 62.36208 -80.73644)
		(width 0.10668)
		(layer "In7.Cu")
		(net "SPI_BMC_TPM_CS2_R_N")
	)
	(segment
		(start 69.1896 -99.433126)
		(end 69.1896 -99.6696)
		(width 0.10668)
		(layer "In7.Cu")
		(net "SPI_BMC_TPM_CS2_R_N")
	)
	(segment
		(start 67.43446 -97.677986)
		(end 69.1896 -99.433126)
		(width 0.10668)
		(layer "In7.Cu")
		(net "SPI_BMC_TPM_CS2_R_N")
	)
	(segment
		(start 62.36208 -80.73644)
		(end 62.43066 -80.80502)
		(width 0.10668)
		(layer "In7.Cu")
		(net "SPI_BMC_TPM_CS2_R_N")
	)
	(segment
		(start 62.691772 -83.149186)
		(end 62.72276 -83.224116)
		(width 0.10668)
		(layer "In7.Cu")
		(net "SPI_BMC_TPM_CS2_R_N")
	)
	(segment
		(start 60.5536 -77.2668)
		(end 60.5536 -78.1558)
		(width 0.10668)
		(layer "In7.Cu")
		(net "SPI_BMC_TPM_CS2_R_N")
	)
	(segment
		(start 62.43066 -80.80502)
		(end 62.43066 -82.519266)
		(width 0.10668)
		(layer "In7.Cu")
		(net "SPI_BMC_TPM_CS2_R_N")
	)
	(segment
		(start 63.254636 -89.79535)
		(end 67.43446 -93.975174)
		(width 0.10668)
		(layer "In7.Cu")
		(net "SPI_BMC_TPM_CS2_R_N")
	)
	(segment
		(start 67.43446 -93.975174)
		(end 67.43446 -97.677986)
		(width 0.10668)
		(layer "In7.Cu")
		(net "SPI_BMC_TPM_CS2_R_N")
	)
	(segment
		(start 60.5536 -78.1558)
		(end 62.36208 -79.96428)
		(width 0.10668)
		(layer "In7.Cu")
		(net "SPI_BMC_TPM_CS2_R_N")
	)
	(segment
		(start 62.72276 -83.224116)
		(end 63.254636 -83.755992)
		(width 0.10668)
		(layer "In7.Cu")
		(net "SPI_BMC_TPM_CS2_R_N")
	)
	(segment
		(start 62.43066 -82.519266)
		(end 62.690756 -83.1469)
		(width 0.10668)
		(layer "In7.Cu")
		(net "SPI_BMC_TPM_CS2_R_N")
	)
	(segment
		(start 62.690756 -83.1469)
		(end 62.691772 -83.149186)
		(width 0.10668)
		(layer "In7.Cu")
		(net "SPI_BMC_TPM_CS2_R_N")
	)
	(segment
		(start 83.80095 -97.605596)
		(end 82.89925 -96.703896)
		(width 0.11684)
		(layer "F.Cu")
		(net "SPI_BMC_TPM_CS2_N_R")
	)
	(segment
		(start 81.312004 -96.35617)
		(end 82.551524 -96.35617)
		(width 0.11684)
		(layer "F.Cu")
		(net "SPI_BMC_TPM_CS2_N_R")
	)
	(segment
		(start 82.551524 -96.35617)
		(end 82.89925 -96.703896)
		(width 0.11684)
		(layer "F.Cu")
		(net "SPI_BMC_TPM_CS2_N_R")
	)
	(segment
		(start 83.80095 -97.917)
		(end 83.80095 -97.605596)
		(width 0.11684)
		(layer "F.Cu")
		(net "SPI_BMC_TPM_CS2_N_R")
	)
	(via
		(at 82.89925 -96.703896)
		(size 0.508)
		(drill 0.254)
		(layers "F.Cu" "B.Cu")
		(net "SPI_BMC_TPM_CS2_N_R")
	)
	(segment
		(start 82.677 -91.593924)
		(end 83.192874 -91.593924)
		(width 0.11684)
		(layer "F.Cu")
		(net "SPI_BMC_TPM_CLK_R")
	)
	(segment
		(start 81.312004 -92.355924)
		(end 81.786476 -92.355924)
		(width 0.11684)
		(layer "F.Cu")
		(net "SPI_BMC_TPM_CLK_R")
	)
	(segment
		(start 82.322924 -91.948)
		(end 82.677 -91.593924)
		(width 0.11684)
		(layer "F.Cu")
		(net "SPI_BMC_TPM_CLK_R")
	)
	(segment
		(start 81.786476 -92.355924)
		(end 82.1944 -91.948)
		(width 0.11684)
		(layer "F.Cu")
		(net "SPI_BMC_TPM_CLK_R")
	)
	(segment
		(start 83.192874 -91.593924)
		(end 83.80095 -92.202)
		(width 0.11684)
		(layer "F.Cu")
		(net "SPI_BMC_TPM_CLK_R")
	)
	(segment
		(start 82.1944 -91.948)
		(end 82.322924 -91.948)
		(width 0.11684)
		(layer "F.Cu")
		(net "SPI_BMC_TPM_CLK_R")
	)
	(via
		(at 29.500322 -58.62066)
		(size 0.508)
		(drill 0.254)
		(layers "F.Cu" "B.Cu")
		(net "SPA_SOUT_SW_DBG")
	)
	(via
		(at 57.85104 -20.961096)
		(size 0.762)
		(drill 0.254)
		(layers "F.Cu" "B.Cu")
		(net "SPA_SOUT_SW_DBG")
	)
	(segment
		(start 57.925716 -20.88642)
		(end 58.109612 -20.88642)
		(width 0.11684)
		(layer "B.Cu")
		(net "SPA_SOUT_SW_DBG")
	)
	(segment
		(start 58.547 -20.449032)
		(end 58.547 -20.182078)
		(width 0.11684)
		(layer "B.Cu")
		(net "SPA_SOUT_SW_DBG")
	)
	(segment
		(start 28.459176 -58.62066)
		(end 29.500322 -58.62066)
		(width 0.11684)
		(layer "B.Cu")
		(net "SPA_SOUT_SW_DBG")
	)
	(segment
		(start 57.85104 -20.961096)
		(end 57.925716 -20.88642)
		(width 0.11684)
		(layer "B.Cu")
		(net "SPA_SOUT_SW_DBG")
	)
	(segment
		(start 28.544266 -62.979808)
		(end 27.761946 -62.197488)
		(width 0.11684)
		(layer "B.Cu")
		(net "SPA_SOUT_SW_DBG")
	)
	(segment
		(start 27.761946 -62.197488)
		(end 27.761946 -59.31789)
		(width 0.11684)
		(layer "B.Cu")
		(net "SPA_SOUT_SW_DBG")
	)
	(segment
		(start 27.761946 -59.31789)
		(end 28.459176 -58.62066)
		(width 0.11684)
		(layer "B.Cu")
		(net "SPA_SOUT_SW_DBG")
	)
	(segment
		(start 32.06115 -63.4238)
		(end 30.844998 -63.4238)
		(width 0.11684)
		(layer "B.Cu")
		(net "SPA_SOUT_SW_DBG")
	)
	(segment
		(start 30.401006 -62.979808)
		(end 28.544266 -62.979808)
		(width 0.11684)
		(layer "B.Cu")
		(net "SPA_SOUT_SW_DBG")
	)
	(segment
		(start 58.109612 -20.88642)
		(end 58.547 -20.449032)
		(width 0.11684)
		(layer "B.Cu")
		(net "SPA_SOUT_SW_DBG")
	)
	(segment
		(start 30.844998 -63.4238)
		(end 30.401006 -62.979808)
		(width 0.11684)
		(layer "B.Cu")
		(net "SPA_SOUT_SW_DBG")
	)
	(segment
		(start 57.85104 -20.961096)
		(end 57.85104 -21.220176)
		(width 0.08382)
		(layer "In9.Cu")
		(net "SPA_SOUT_SW_DBG")
	)
	(segment
		(start 31.278576 -44.929044)
		(end 31.278576 -48.906176)
		(width 0.08382)
		(layer "In9.Cu")
		(net "SPA_SOUT_SW_DBG")
	)
	(segment
		(start 30.091888 -54.962806)
		(end 29.500322 -56.391048)
		(width 0.08382)
		(layer "In9.Cu")
		(net "SPA_SOUT_SW_DBG")
	)
	(segment
		(start 34.490914 -29.126434)
		(end 33.600644 -30.016704)
		(width 0.08382)
		(layer "In9.Cu")
		(net "SPA_SOUT_SW_DBG")
	)
	(segment
		(start 39.68877 -22.71903)
		(end 39.68877 -24.935434)
		(width 0.08382)
		(layer "In9.Cu")
		(net "SPA_SOUT_SW_DBG")
	)
	(segment
		(start 49.940972 -20.710144)
		(end 41.697656 -20.710144)
		(width 0.08382)
		(layer "In9.Cu")
		(net "SPA_SOUT_SW_DBG")
	)
	(segment
		(start 41.697656 -20.710144)
		(end 39.68877 -22.71903)
		(width 0.08382)
		(layer "In9.Cu")
		(net "SPA_SOUT_SW_DBG")
	)
	(segment
		(start 57.85104 -21.220176)
		(end 57.244996 -21.82622)
		(width 0.08382)
		(layer "In9.Cu")
		(net "SPA_SOUT_SW_DBG")
	)
	(segment
		(start 31.69031 -31.386526)
		(end 31.69031 -38.425882)
		(width 0.08382)
		(layer "In9.Cu")
		(net "SPA_SOUT_SW_DBG")
	)
	(segment
		(start 35.225736 -28.016708)
		(end 34.490914 -28.75153)
		(width 0.08382)
		(layer "In9.Cu")
		(net "SPA_SOUT_SW_DBG")
	)
	(segment
		(start 29.500322 -56.391048)
		(end 29.500322 -58.62066)
		(width 0.08382)
		(layer "In9.Cu")
		(net "SPA_SOUT_SW_DBG")
	)
	(segment
		(start 30.977586 -53.350414)
		(end 30.091888 -54.236112)
		(width 0.08382)
		(layer "In9.Cu")
		(net "SPA_SOUT_SW_DBG")
	)
	(segment
		(start 51.057048 -21.82622)
		(end 49.940972 -20.710144)
		(width 0.08382)
		(layer "In9.Cu")
		(net "SPA_SOUT_SW_DBG")
	)
	(segment
		(start 31.69031 -38.425882)
		(end 30.356556 -39.759636)
		(width 0.08382)
		(layer "In9.Cu")
		(net "SPA_SOUT_SW_DBG")
	)
	(segment
		(start 30.977586 -49.207166)
		(end 30.977586 -53.350414)
		(width 0.08382)
		(layer "In9.Cu")
		(net "SPA_SOUT_SW_DBG")
	)
	(segment
		(start 34.490914 -28.75153)
		(end 34.490914 -29.126434)
		(width 0.08382)
		(layer "In9.Cu")
		(net "SPA_SOUT_SW_DBG")
	)
	(segment
		(start 33.600644 -30.016704)
		(end 33.060132 -30.016704)
		(width 0.08382)
		(layer "In9.Cu")
		(net "SPA_SOUT_SW_DBG")
	)
	(segment
		(start 36.607496 -28.016708)
		(end 35.225736 -28.016708)
		(width 0.08382)
		(layer "In9.Cu")
		(net "SPA_SOUT_SW_DBG")
	)
	(segment
		(start 33.060132 -30.016704)
		(end 31.69031 -31.386526)
		(width 0.08382)
		(layer "In9.Cu")
		(net "SPA_SOUT_SW_DBG")
	)
	(segment
		(start 39.68877 -24.935434)
		(end 36.607496 -28.016708)
		(width 0.08382)
		(layer "In9.Cu")
		(net "SPA_SOUT_SW_DBG")
	)
	(segment
		(start 30.356556 -39.759636)
		(end 30.356556 -44.007024)
		(width 0.08382)
		(layer "In9.Cu")
		(net "SPA_SOUT_SW_DBG")
	)
	(segment
		(start 57.244996 -21.82622)
		(end 51.057048 -21.82622)
		(width 0.08382)
		(layer "In9.Cu")
		(net "SPA_SOUT_SW_DBG")
	)
	(segment
		(start 30.091888 -54.236112)
		(end 30.091888 -54.962806)
		(width 0.08382)
		(layer "In9.Cu")
		(net "SPA_SOUT_SW_DBG")
	)
	(segment
		(start 30.356556 -44.007024)
		(end 31.278576 -44.929044)
		(width 0.08382)
		(layer "In9.Cu")
		(net "SPA_SOUT_SW_DBG")
	)
	(segment
		(start 31.278576 -48.906176)
		(end 30.977586 -49.207166)
		(width 0.08382)
		(layer "In9.Cu")
		(net "SPA_SOUT_SW_DBG")
	)
	(via
		(at 10.24636 -25.58034)
		(size 0.508)
		(drill 0.254)
		(layers "F.Cu" "B.Cu")
		(net "SPA_SIN_SW_DBG")
	)
	(via
		(at 58.9661 -20.94992)
		(size 0.508)
		(drill 0.254)
		(layers "F.Cu" "B.Cu")
		(net "SPA_SIN_SW_DBG")
	)
	(via
		(at 26.30932 -60.2996)
		(size 0.508)
		(drill 0.254)
		(layers "F.Cu" "B.Cu")
		(net "SPA_SIN_SW_DBG")
	)
	(via
		(at 12.95654 -59.32678)
		(size 0.508)
		(drill 0.254)
		(layers "F.Cu" "B.Cu")
		(net "SPA_SIN_SW_DBG")
	)
	(segment
		(start 27.06878 -69.712586)
		(end 27.340814 -69.98462)
		(width 0.11684)
		(layer "B.Cu")
		(net "SPA_SIN_SW_DBG")
	)
	(segment
		(start 27.06878 -68.968874)
		(end 27.06878 -69.712586)
		(width 0.11684)
		(layer "B.Cu")
		(net "SPA_SIN_SW_DBG")
	)
	(segment
		(start 59.551824 -20.94992)
		(end 58.9661 -20.94992)
		(width 0.11684)
		(layer "B.Cu")
		(net "SPA_SIN_SW_DBG")
	)
	(segment
		(start 59.775344 -21.17344)
		(end 59.551824 -20.94992)
		(width 0.11684)
		(layer "B.Cu")
		(net "SPA_SIN_SW_DBG")
	)
	(segment
		(start 26.754836 -60.745116)
		(end 26.754836 -62.043564)
		(width 0.11684)
		(layer "B.Cu")
		(net "SPA_SIN_SW_DBG")
	)
	(segment
		(start 61.468 -22.48408)
		(end 61.479938 -22.472142)
		(width 0.11684)
		(layer "B.Cu")
		(net "SPA_SIN_SW_DBG")
	)
	(segment
		(start 61.468 -23.366476)
		(end 61.468 -22.48408)
		(width 0.11684)
		(layer "B.Cu")
		(net "SPA_SIN_SW_DBG")
	)
	(segment
		(start 27.340814 -69.98462)
		(end 27.767534 -69.98462)
		(width 0.11684)
		(layer "B.Cu")
		(net "SPA_SIN_SW_DBG")
	)
	(segment
		(start 61.479938 -22.472142)
		(end 61.479938 -21.981922)
		(width 0.11684)
		(layer "B.Cu")
		(net "SPA_SIN_SW_DBG")
	)
	(segment
		(start 61.3918 -23.442676)
		(end 61.468 -23.366476)
		(width 0.11684)
		(layer "B.Cu")
		(net "SPA_SIN_SW_DBG")
	)
	(segment
		(start 26.035 -62.7634)
		(end 26.035 -66.473832)
		(width 0.11684)
		(layer "B.Cu")
		(net "SPA_SIN_SW_DBG")
	)
	(segment
		(start 29.664914 -71.882)
		(end 32.26435 -71.882)
		(width 0.11684)
		(layer "B.Cu")
		(net "SPA_SIN_SW_DBG")
	)
	(segment
		(start 27.767534 -69.98462)
		(end 29.664914 -71.882)
		(width 0.11684)
		(layer "B.Cu")
		(net "SPA_SIN_SW_DBG")
	)
	(segment
		(start 61.479938 -21.981922)
		(end 61.479938 -21.353018)
		(width 0.11684)
		(layer "B.Cu")
		(net "SPA_SIN_SW_DBG")
	)
	(segment
		(start 26.754836 -62.043564)
		(end 26.035 -62.7634)
		(width 0.11684)
		(layer "B.Cu")
		(net "SPA_SIN_SW_DBG")
	)
	(segment
		(start 61.30036 -21.17344)
		(end 59.775344 -21.17344)
		(width 0.11684)
		(layer "B.Cu")
		(net "SPA_SIN_SW_DBG")
	)
	(segment
		(start 26.30932 -60.2996)
		(end 26.754836 -60.745116)
		(width 0.11684)
		(layer "B.Cu")
		(net "SPA_SIN_SW_DBG")
	)
	(segment
		(start 26.035 -66.473832)
		(end 27.06878 -68.968874)
		(width 0.11684)
		(layer "B.Cu")
		(net "SPA_SIN_SW_DBG")
	)
	(segment
		(start 61.479938 -21.353018)
		(end 61.30036 -21.17344)
		(width 0.11684)
		(layer "B.Cu")
		(net "SPA_SIN_SW_DBG")
	)
	(segment
		(start 61.3918 -23.85695)
		(end 61.3918 -23.442676)
		(width 0.11684)
		(layer "B.Cu")
		(net "SPA_SIN_SW_DBG")
	)
	(segment
		(start 25.80132 -60.8076)
		(end 22.098 -60.8076)
		(width 0.08382)
		(layer "In2.Cu")
		(net "SPA_SIN_SW_DBG")
	)
	(segment
		(start 16.3322 -60.8076)
		(end 15.935452 -60.8076)
		(width 0.08382)
		(layer "In2.Cu")
		(net "SPA_SIN_SW_DBG")
	)
	(segment
		(start 21.5392 -60.2488)
		(end 19.177 -60.2488)
		(width 0.08382)
		(layer "In2.Cu")
		(net "SPA_SIN_SW_DBG")
	)
	(segment
		(start 19.05 -60.3758)
		(end 16.764 -60.3758)
		(width 0.08382)
		(layer "In2.Cu")
		(net "SPA_SIN_SW_DBG")
	)
	(segment
		(start 19.177 -60.2488)
		(end 19.05 -60.3758)
		(width 0.08382)
		(layer "In2.Cu")
		(net "SPA_SIN_SW_DBG")
	)
	(segment
		(start 22.098 -60.8076)
		(end 21.5392 -60.2488)
		(width 0.08382)
		(layer "In2.Cu")
		(net "SPA_SIN_SW_DBG")
	)
	(segment
		(start 26.30932 -60.2996)
		(end 25.80132 -60.8076)
		(width 0.08382)
		(layer "In2.Cu")
		(net "SPA_SIN_SW_DBG")
	)
	(segment
		(start 15.935452 -60.8076)
		(end 13.377926 -59.748166)
		(width 0.08382)
		(layer "In2.Cu")
		(net "SPA_SIN_SW_DBG")
	)
	(segment
		(start 16.764 -60.3758)
		(end 16.3322 -60.8076)
		(width 0.08382)
		(layer "In2.Cu")
		(net "SPA_SIN_SW_DBG")
	)
	(segment
		(start 13.377926 -59.748166)
		(end 12.95654 -59.32678)
		(width 0.08382)
		(layer "In2.Cu")
		(net "SPA_SIN_SW_DBG")
	)
	(segment
		(start 12.60602 -24.19985)
		(end 12.60602 -23.401274)
		(width 0.10668)
		(layer "In4.Cu")
		(net "SPA_SIN_SW_DBG")
	)
	(segment
		(start 55.198518 -21.9456)
		(end 57.97042 -21.9456)
		(width 0.10668)
		(layer "In4.Cu")
		(net "SPA_SIN_SW_DBG")
	)
	(segment
		(start 10.24636 -25.58034)
		(end 11.62939 -25.58034)
		(width 0.10668)
		(layer "In4.Cu")
		(net "SPA_SIN_SW_DBG")
	)
	(segment
		(start 42.24401 -17.273016)
		(end 46.18609 -17.273016)
		(width 0.10668)
		(layer "In4.Cu")
		(net "SPA_SIN_SW_DBG")
	)
	(segment
		(start 11.57986 -11.78814)
		(end 28.32354 -11.78814)
		(width 0.10668)
		(layer "In4.Cu")
		(net "SPA_SIN_SW_DBG")
	)
	(segment
		(start 29.2608 -12.7254)
		(end 29.2608 -14.0208)
		(width 0.10668)
		(layer "In4.Cu")
		(net "SPA_SIN_SW_DBG")
	)
	(segment
		(start 31.86176 -16.62176)
		(end 31.86176 -18.937986)
		(width 0.10668)
		(layer "In4.Cu")
		(net "SPA_SIN_SW_DBG")
	)
	(segment
		(start 11.983212 -24.822658)
		(end 12.60602 -24.19985)
		(width 0.10668)
		(layer "In4.Cu")
		(net "SPA_SIN_SW_DBG")
	)
	(segment
		(start 48.176434 -19.26336)
		(end 49.635664 -19.26336)
		(width 0.10668)
		(layer "In4.Cu")
		(net "SPA_SIN_SW_DBG")
	)
	(segment
		(start 12.60602 -23.401274)
		(end 10.410952 -21.206206)
		(width 0.10668)
		(layer "In4.Cu")
		(net "SPA_SIN_SW_DBG")
	)
	(segment
		(start 41.147746 -18.36928)
		(end 42.24401 -17.273016)
		(width 0.10668)
		(layer "In4.Cu")
		(net "SPA_SIN_SW_DBG")
	)
	(segment
		(start 28.32354 -11.78814)
		(end 29.2608 -12.7254)
		(width 0.10668)
		(layer "In4.Cu")
		(net "SPA_SIN_SW_DBG")
	)
	(segment
		(start 11.983212 -25.226518)
		(end 11.983212 -24.822658)
		(width 0.10668)
		(layer "In4.Cu")
		(net "SPA_SIN_SW_DBG")
	)
	(segment
		(start 41.147746 -19.764756)
		(end 41.147746 -18.36928)
		(width 0.10668)
		(layer "In4.Cu")
		(net "SPA_SIN_SW_DBG")
	)
	(segment
		(start 49.635664 -19.26336)
		(end 50.019204 -19.6469)
		(width 0.10668)
		(layer "In4.Cu")
		(net "SPA_SIN_SW_DBG")
	)
	(segment
		(start 10.410952 -21.206206)
		(end 10.410952 -12.957048)
		(width 0.10668)
		(layer "In4.Cu")
		(net "SPA_SIN_SW_DBG")
	)
	(segment
		(start 46.18609 -17.273016)
		(end 48.176434 -19.26336)
		(width 0.10668)
		(layer "In4.Cu")
		(net "SPA_SIN_SW_DBG")
	)
	(segment
		(start 50.019204 -19.6469)
		(end 52.899818 -19.6469)
		(width 0.10668)
		(layer "In4.Cu")
		(net "SPA_SIN_SW_DBG")
	)
	(segment
		(start 40.142922 -20.76958)
		(end 41.147746 -19.764756)
		(width 0.10668)
		(layer "In4.Cu")
		(net "SPA_SIN_SW_DBG")
	)
	(segment
		(start 29.2608 -14.0208)
		(end 31.86176 -16.62176)
		(width 0.10668)
		(layer "In4.Cu")
		(net "SPA_SIN_SW_DBG")
	)
	(segment
		(start 33.68675 -19.4818)
		(end 34.69005 -20.4851)
		(width 0.10668)
		(layer "In4.Cu")
		(net "SPA_SIN_SW_DBG")
	)
	(segment
		(start 52.899818 -19.6469)
		(end 55.198518 -21.9456)
		(width 0.10668)
		(layer "In4.Cu")
		(net "SPA_SIN_SW_DBG")
	)
	(segment
		(start 11.62939 -25.58034)
		(end 11.983212 -25.226518)
		(width 0.10668)
		(layer "In4.Cu")
		(net "SPA_SIN_SW_DBG")
	)
	(segment
		(start 34.69005 -20.4851)
		(end 36.455604 -20.4851)
		(width 0.10668)
		(layer "In4.Cu")
		(net "SPA_SIN_SW_DBG")
	)
	(segment
		(start 57.97042 -21.9456)
		(end 58.9661 -20.94992)
		(width 0.10668)
		(layer "In4.Cu")
		(net "SPA_SIN_SW_DBG")
	)
	(segment
		(start 10.410952 -12.957048)
		(end 11.57986 -11.78814)
		(width 0.10668)
		(layer "In4.Cu")
		(net "SPA_SIN_SW_DBG")
	)
	(segment
		(start 32.405574 -19.4818)
		(end 33.68675 -19.4818)
		(width 0.10668)
		(layer "In4.Cu")
		(net "SPA_SIN_SW_DBG")
	)
	(segment
		(start 36.740084 -20.76958)
		(end 40.142922 -20.76958)
		(width 0.10668)
		(layer "In4.Cu")
		(net "SPA_SIN_SW_DBG")
	)
	(segment
		(start 36.455604 -20.4851)
		(end 36.740084 -20.76958)
		(width 0.10668)
		(layer "In4.Cu")
		(net "SPA_SIN_SW_DBG")
	)
	(segment
		(start 31.86176 -18.937986)
		(end 32.405574 -19.4818)
		(width 0.10668)
		(layer "In4.Cu")
		(net "SPA_SIN_SW_DBG")
	)
	(segment
		(start 14.07668 -29.682694)
		(end 14.07668 -33.807146)
		(width 0.08382)
		(layer "In9.Cu")
		(net "SPA_SIN_SW_DBG")
	)
	(segment
		(start 10.97534 -25.58034)
		(end 12.322302 -26.927302)
		(width 0.08382)
		(layer "In9.Cu")
		(net "SPA_SIN_SW_DBG")
	)
	(segment
		(start 11.358626 -55.131462)
		(end 12.75969 -56.532526)
		(width 0.08382)
		(layer "In9.Cu")
		(net "SPA_SIN_SW_DBG")
	)
	(segment
		(start 12.75969 -56.532526)
		(end 12.75969 -59.12993)
		(width 0.08382)
		(layer "In9.Cu")
		(net "SPA_SIN_SW_DBG")
	)
	(segment
		(start 14.351 -35.44062)
		(end 14.351 -45.4533)
		(width 0.08382)
		(layer "In9.Cu")
		(net "SPA_SIN_SW_DBG")
	)
	(segment
		(start 14.351 -45.4533)
		(end 12.86383 -46.94047)
		(width 0.08382)
		(layer "In9.Cu")
		(net "SPA_SIN_SW_DBG")
	)
	(segment
		(start 11.358626 -50.706528)
		(end 11.358626 -55.131462)
		(width 0.08382)
		(layer "In9.Cu")
		(net "SPA_SIN_SW_DBG")
	)
	(segment
		(start 12.86383 -46.94047)
		(end 12.86383 -49.201324)
		(width 0.08382)
		(layer "In9.Cu")
		(net "SPA_SIN_SW_DBG")
	)
	(segment
		(start 12.86383 -49.201324)
		(end 11.358626 -50.706528)
		(width 0.08382)
		(layer "In9.Cu")
		(net "SPA_SIN_SW_DBG")
	)
	(segment
		(start 14.07668 -33.807146)
		(end 14.29385 -34.331656)
		(width 0.08382)
		(layer "In9.Cu")
		(net "SPA_SIN_SW_DBG")
	)
	(segment
		(start 14.29385 -34.331656)
		(end 14.29385 -35.38347)
		(width 0.08382)
		(layer "In9.Cu")
		(net "SPA_SIN_SW_DBG")
	)
	(segment
		(start 14.29385 -35.38347)
		(end 14.351 -35.44062)
		(width 0.08382)
		(layer "In9.Cu")
		(net "SPA_SIN_SW_DBG")
	)
	(segment
		(start 12.75969 -59.12993)
		(end 12.95654 -59.32678)
		(width 0.08382)
		(layer "In9.Cu")
		(net "SPA_SIN_SW_DBG")
	)
	(segment
		(start 10.24636 -25.58034)
		(end 10.97534 -25.58034)
		(width 0.08382)
		(layer "In9.Cu")
		(net "SPA_SIN_SW_DBG")
	)
	(segment
		(start 12.322302 -27.928316)
		(end 14.07668 -29.682694)
		(width 0.08382)
		(layer "In9.Cu")
		(net "SPA_SIN_SW_DBG")
	)
	(segment
		(start 12.322302 -26.927302)
		(end 12.322302 -27.928316)
		(width 0.08382)
		(layer "In9.Cu")
		(net "SPA_SIN_SW_DBG")
	)
	(via
		(at 27.571954 -74.737214)
		(size 0.508)
		(drill 0.254)
		(layers "F.Cu" "B.Cu")
		(net "SMB_DEBUG_AUX_LVC3_USB_SDA")
	)
	(via
		(at 14.9606 -73.17105)
		(size 0.508)
		(drill 0.254)
		(layers "F.Cu" "B.Cu")
		(net "SMB_DEBUG_AUX_LVC3_USB_SDA")
	)
	(via
		(at 35.3568 -94.61754)
		(size 0.508)
		(drill 0.254)
		(layers "F.Cu" "B.Cu")
		(net "SMB_DEBUG_AUX_LVC3_USB_SDA")
	)
	(via
		(at 50.1396 -94.0435)
		(size 0.508)
		(drill 0.254)
		(layers "F.Cu" "B.Cu")
		(net "SMB_DEBUG_AUX_LVC3_USB_SDA")
	)
	(segment
		(start 35.8648 -97.0534)
		(end 35.8648 -95.12554)
		(width 0.11684)
		(layer "B.Cu")
		(net "SMB_DEBUG_AUX_LVC3_USB_SDA")
	)
	(segment
		(start 35.8648 -95.12554)
		(end 35.3568 -94.61754)
		(width 0.11684)
		(layer "B.Cu")
		(net "SMB_DEBUG_AUX_LVC3_USB_SDA")
	)
	(segment
		(start 36.03244 -97.22104)
		(end 35.8648 -97.0534)
		(width 0.11684)
		(layer "B.Cu")
		(net "SMB_DEBUG_AUX_LVC3_USB_SDA")
	)
	(segment
		(start 50.71745 -94.0435)
		(end 50.1396 -94.0435)
		(width 0.11684)
		(layer "B.Cu")
		(net "SMB_DEBUG_AUX_LVC3_USB_SDA")
	)
	(segment
		(start 16.764 -73.17105)
		(end 14.9606 -73.17105)
		(width 0.11684)
		(layer "B.Cu")
		(net "SMB_DEBUG_AUX_LVC3_USB_SDA")
	)
	(segment
		(start 36.37407 -97.22104)
		(end 36.03244 -97.22104)
		(width 0.11684)
		(layer "B.Cu")
		(net "SMB_DEBUG_AUX_LVC3_USB_SDA")
	)
	(segment
		(start 50.84445 -94.1705)
		(end 50.71745 -94.0435)
		(width 0.11684)
		(layer "B.Cu")
		(net "SMB_DEBUG_AUX_LVC3_USB_SDA")
	)
	(segment
		(start 49.66081 -94.52229)
		(end 50.1396 -94.0435)
		(width 0.08382)
		(layer "In2.Cu")
		(net "SMB_DEBUG_AUX_LVC3_USB_SDA")
	)
	(segment
		(start 16.162528 -70.08622)
		(end 14.78407 -71.464678)
		(width 0.08382)
		(layer "In2.Cu")
		(net "SMB_DEBUG_AUX_LVC3_USB_SDA")
	)
	(segment
		(start 35.3568 -94.61754)
		(end 37.18306 -94.61754)
		(width 0.08382)
		(layer "In2.Cu")
		(net "SMB_DEBUG_AUX_LVC3_USB_SDA")
	)
	(segment
		(start 18.156174 -70.08622)
		(end 16.162528 -70.08622)
		(width 0.08382)
		(layer "In2.Cu")
		(net "SMB_DEBUG_AUX_LVC3_USB_SDA")
	)
	(segment
		(start 37.5158 -94.2848)
		(end 44.099988 -94.2848)
		(width 0.08382)
		(layer "In2.Cu")
		(net "SMB_DEBUG_AUX_LVC3_USB_SDA")
	)
	(segment
		(start 14.78407 -71.464678)
		(end 14.78407 -72.99452)
		(width 0.08382)
		(layer "In2.Cu")
		(net "SMB_DEBUG_AUX_LVC3_USB_SDA")
	)
	(segment
		(start 27.571954 -74.104754)
		(end 24.257 -70.7898)
		(width 0.08382)
		(layer "In2.Cu")
		(net "SMB_DEBUG_AUX_LVC3_USB_SDA")
	)
	(segment
		(start 24.257 -70.7898)
		(end 22.733 -70.7898)
		(width 0.08382)
		(layer "In2.Cu")
		(net "SMB_DEBUG_AUX_LVC3_USB_SDA")
	)
	(segment
		(start 27.571954 -74.737214)
		(end 27.571954 -74.104754)
		(width 0.08382)
		(layer "In2.Cu")
		(net "SMB_DEBUG_AUX_LVC3_USB_SDA")
	)
	(segment
		(start 37.18306 -94.61754)
		(end 37.5158 -94.2848)
		(width 0.08382)
		(layer "In2.Cu")
		(net "SMB_DEBUG_AUX_LVC3_USB_SDA")
	)
	(segment
		(start 14.78407 -72.99452)
		(end 14.9606 -73.17105)
		(width 0.08382)
		(layer "In2.Cu")
		(net "SMB_DEBUG_AUX_LVC3_USB_SDA")
	)
	(segment
		(start 49.026572 -94.52229)
		(end 49.66081 -94.52229)
		(width 0.08382)
		(layer "In2.Cu")
		(net "SMB_DEBUG_AUX_LVC3_USB_SDA")
	)
	(segment
		(start 44.778168 -94.96298)
		(end 48.585882 -94.96298)
		(width 0.08382)
		(layer "In2.Cu")
		(net "SMB_DEBUG_AUX_LVC3_USB_SDA")
	)
	(segment
		(start 22.18563 -70.24243)
		(end 18.312384 -70.24243)
		(width 0.08382)
		(layer "In2.Cu")
		(net "SMB_DEBUG_AUX_LVC3_USB_SDA")
	)
	(segment
		(start 48.585882 -94.96298)
		(end 49.026572 -94.52229)
		(width 0.08382)
		(layer "In2.Cu")
		(net "SMB_DEBUG_AUX_LVC3_USB_SDA")
	)
	(segment
		(start 18.312384 -70.24243)
		(end 18.156174 -70.08622)
		(width 0.08382)
		(layer "In2.Cu")
		(net "SMB_DEBUG_AUX_LVC3_USB_SDA")
	)
	(segment
		(start 44.099988 -94.2848)
		(end 44.778168 -94.96298)
		(width 0.08382)
		(layer "In2.Cu")
		(net "SMB_DEBUG_AUX_LVC3_USB_SDA")
	)
	(segment
		(start 22.733 -70.7898)
		(end 22.18563 -70.24243)
		(width 0.08382)
		(layer "In2.Cu")
		(net "SMB_DEBUG_AUX_LVC3_USB_SDA")
	)
	(segment
		(start 29.4259 -80.065372)
		(end 30.734 -81.373472)
		(width 0.10668)
		(layer "In7.Cu")
		(net "SMB_DEBUG_AUX_LVC3_USB_SDA")
	)
	(segment
		(start 29.4259 -77.43063)
		(end 29.4259 -80.065372)
		(width 0.10668)
		(layer "In7.Cu")
		(net "SMB_DEBUG_AUX_LVC3_USB_SDA")
	)
	(segment
		(start 33.04286 -85.443314)
		(end 33.65754 -86.057994)
		(width 0.10668)
		(layer "In7.Cu")
		(net "SMB_DEBUG_AUX_LVC3_USB_SDA")
	)
	(segment
		(start 38.543738 -89.70772)
		(end 39.071296 -90.235278)
		(width 0.10668)
		(layer "In7.Cu")
		(net "SMB_DEBUG_AUX_LVC3_USB_SDA")
	)
	(segment
		(start 30.734 -82.451194)
		(end 33.04286 -84.760054)
		(width 0.10668)
		(layer "In7.Cu")
		(net "SMB_DEBUG_AUX_LVC3_USB_SDA")
	)
	(segment
		(start 39.071296 -93.931486)
		(end 38.385242 -94.61754)
		(width 0.10668)
		(layer "In7.Cu")
		(net "SMB_DEBUG_AUX_LVC3_USB_SDA")
	)
	(segment
		(start 27.571954 -74.737214)
		(end 27.571954 -75.576684)
		(width 0.10668)
		(layer "In7.Cu")
		(net "SMB_DEBUG_AUX_LVC3_USB_SDA")
	)
	(segment
		(start 38.385242 -94.61754)
		(end 35.3568 -94.61754)
		(width 0.10668)
		(layer "In7.Cu")
		(net "SMB_DEBUG_AUX_LVC3_USB_SDA")
	)
	(segment
		(start 27.571954 -75.576684)
		(end 29.4259 -77.43063)
		(width 0.10668)
		(layer "In7.Cu")
		(net "SMB_DEBUG_AUX_LVC3_USB_SDA")
	)
	(segment
		(start 37.10178 -88.88984)
		(end 37.91966 -89.70772)
		(width 0.10668)
		(layer "In7.Cu")
		(net "SMB_DEBUG_AUX_LVC3_USB_SDA")
	)
	(segment
		(start 33.65754 -87.775542)
		(end 34.771838 -88.88984)
		(width 0.10668)
		(layer "In7.Cu")
		(net "SMB_DEBUG_AUX_LVC3_USB_SDA")
	)
	(segment
		(start 34.771838 -88.88984)
		(end 37.10178 -88.88984)
		(width 0.10668)
		(layer "In7.Cu")
		(net "SMB_DEBUG_AUX_LVC3_USB_SDA")
	)
	(segment
		(start 37.91966 -89.70772)
		(end 38.543738 -89.70772)
		(width 0.10668)
		(layer "In7.Cu")
		(net "SMB_DEBUG_AUX_LVC3_USB_SDA")
	)
	(segment
		(start 39.071296 -90.235278)
		(end 39.071296 -93.931486)
		(width 0.10668)
		(layer "In7.Cu")
		(net "SMB_DEBUG_AUX_LVC3_USB_SDA")
	)
	(segment
		(start 33.65754 -86.057994)
		(end 33.65754 -87.775542)
		(width 0.10668)
		(layer "In7.Cu")
		(net "SMB_DEBUG_AUX_LVC3_USB_SDA")
	)
	(segment
		(start 30.734 -81.373472)
		(end 30.734 -82.451194)
		(width 0.10668)
		(layer "In7.Cu")
		(net "SMB_DEBUG_AUX_LVC3_USB_SDA")
	)
	(segment
		(start 33.04286 -84.760054)
		(end 33.04286 -85.443314)
		(width 0.10668)
		(layer "In7.Cu")
		(net "SMB_DEBUG_AUX_LVC3_USB_SDA")
	)
	(segment
		(start 37.008562 -94.1578)
		(end 37.008562 -95.681038)
		(width 0.11684)
		(layer "F.Cu")
		(net "SMB_DEBUG_AUX_LVC3_USB_SCL")
	)
	(segment
		(start 37.008562 -95.681038)
		(end 35.4838 -97.2058)
		(width 0.11684)
		(layer "F.Cu")
		(net "SMB_DEBUG_AUX_LVC3_USB_SCL")
	)
	(segment
		(start 35.4838 -97.2058)
		(end 32.09036 -97.2058)
		(width 0.11684)
		(layer "F.Cu")
		(net "SMB_DEBUG_AUX_LVC3_USB_SCL")
	)
	(via
		(at 19.29384 -72.148446)
		(size 0.508)
		(drill 0.254)
		(layers "F.Cu" "B.Cu")
		(net "SMB_DEBUG_AUX_LVC3_USB_SCL")
	)
	(via
		(at 50.1396 -93.3704)
		(size 0.508)
		(drill 0.254)
		(layers "F.Cu" "B.Cu")
		(net "SMB_DEBUG_AUX_LVC3_USB_SCL")
	)
	(via
		(at 32.09036 -97.2058)
		(size 0.508)
		(drill 0.254)
		(layers "F.Cu" "B.Cu")
		(net "SMB_DEBUG_AUX_LVC3_USB_SCL")
	)
	(via
		(at 37.008562 -94.1578)
		(size 0.508)
		(drill 0.254)
		(layers "F.Cu" "B.Cu")
		(net "SMB_DEBUG_AUX_LVC3_USB_SCL")
	)
	(segment
		(start 18.972022 -72.542146)
		(end 18.61185 -72.902318)
		(width 0.11684)
		(layer "B.Cu")
		(net "SMB_DEBUG_AUX_LVC3_USB_SCL")
	)
	(segment
		(start 18.972022 -72.470264)
		(end 18.972022 -72.542146)
		(width 0.11684)
		(layer "B.Cu")
		(net "SMB_DEBUG_AUX_LVC3_USB_SCL")
	)
	(segment
		(start 36.37407 -96.20504)
		(end 36.37407 -94.792292)
		(width 0.11684)
		(layer "B.Cu")
		(net "SMB_DEBUG_AUX_LVC3_USB_SCL")
	)
	(segment
		(start 50.84445 -93.2815)
		(end 50.75555 -93.3704)
		(width 0.11684)
		(layer "B.Cu")
		(net "SMB_DEBUG_AUX_LVC3_USB_SCL")
	)
	(segment
		(start 36.37407 -94.792292)
		(end 37.008562 -94.1578)
		(width 0.11684)
		(layer "B.Cu")
		(net "SMB_DEBUG_AUX_LVC3_USB_SCL")
	)
	(segment
		(start 18.61185 -72.902318)
		(end 18.61185 -72.9234)
		(width 0.11684)
		(layer "B.Cu")
		(net "SMB_DEBUG_AUX_LVC3_USB_SCL")
	)
	(segment
		(start 19.29384 -72.148446)
		(end 18.972022 -72.470264)
		(width 0.11684)
		(layer "B.Cu")
		(net "SMB_DEBUG_AUX_LVC3_USB_SCL")
	)
	(segment
		(start 50.75555 -93.3704)
		(end 50.1396 -93.3704)
		(width 0.11684)
		(layer "B.Cu")
		(net "SMB_DEBUG_AUX_LVC3_USB_SCL")
	)
	(segment
		(start 49.30013 -94.20987)
		(end 50.1396 -93.3704)
		(width 0.08382)
		(layer "In2.Cu")
		(net "SMB_DEBUG_AUX_LVC3_USB_SCL")
	)
	(segment
		(start 37.262562 -93.9038)
		(end 44.160948 -93.9038)
		(width 0.08382)
		(layer "In2.Cu")
		(net "SMB_DEBUG_AUX_LVC3_USB_SCL")
	)
	(segment
		(start 44.907708 -94.65056)
		(end 48.456342 -94.65056)
		(width 0.08382)
		(layer "In2.Cu")
		(net "SMB_DEBUG_AUX_LVC3_USB_SCL")
	)
	(segment
		(start 48.456342 -94.65056)
		(end 48.897032 -94.20987)
		(width 0.08382)
		(layer "In2.Cu")
		(net "SMB_DEBUG_AUX_LVC3_USB_SCL")
	)
	(segment
		(start 37.008562 -94.1578)
		(end 37.262562 -93.9038)
		(width 0.08382)
		(layer "In2.Cu")
		(net "SMB_DEBUG_AUX_LVC3_USB_SCL")
	)
	(segment
		(start 48.897032 -94.20987)
		(end 49.30013 -94.20987)
		(width 0.08382)
		(layer "In2.Cu")
		(net "SMB_DEBUG_AUX_LVC3_USB_SCL")
	)
	(segment
		(start 44.160948 -93.9038)
		(end 44.907708 -94.65056)
		(width 0.08382)
		(layer "In2.Cu")
		(net "SMB_DEBUG_AUX_LVC3_USB_SCL")
	)
	(segment
		(start 23.34768 -75.524614)
		(end 23.34768 -80.31988)
		(width 0.10668)
		(layer "In7.Cu")
		(net "SMB_DEBUG_AUX_LVC3_USB_SCL")
	)
	(segment
		(start 29.337 -96.056958)
		(end 29.337 -97.92462)
		(width 0.10668)
		(layer "In7.Cu")
		(net "SMB_DEBUG_AUX_LVC3_USB_SCL")
	)
	(segment
		(start 20.086574 -72.58812)
		(end 22.267164 -74.76871)
		(width 0.10668)
		(layer "In7.Cu")
		(net "SMB_DEBUG_AUX_LVC3_USB_SCL")
	)
	(segment
		(start 31.145734 -95.950278)
		(end 29.44368 -95.950278)
		(width 0.10668)
		(layer "In7.Cu")
		(net "SMB_DEBUG_AUX_LVC3_USB_SCL")
	)
	(segment
		(start 27.1272 -86.2838)
		(end 28.321 -87.4776)
		(width 0.10668)
		(layer "In7.Cu")
		(net "SMB_DEBUG_AUX_LVC3_USB_SCL")
	)
	(segment
		(start 29.44368 -95.335598)
		(end 31.145734 -95.335598)
		(width 0.10668)
		(layer "In7.Cu")
		(net "SMB_DEBUG_AUX_LVC3_USB_SCL")
	)
	(segment
		(start 25.3492 -81.8388)
		(end 25.3492 -82.556858)
		(width 0.10668)
		(layer "In7.Cu")
		(net "SMB_DEBUG_AUX_LVC3_USB_SCL")
	)
	(segment
		(start 29.337 -97.92462)
		(end 29.83738 -98.425)
		(width 0.10668)
		(layer "In7.Cu")
		(net "SMB_DEBUG_AUX_LVC3_USB_SCL")
	)
	(segment
		(start 24.3078 -81.28)
		(end 24.7904 -81.28)
		(width 0.10668)
		(layer "In7.Cu")
		(net "SMB_DEBUG_AUX_LVC3_USB_SCL")
	)
	(segment
		(start 25.99182 -83.199478)
		(end 25.99182 -83.534504)
		(width 0.10668)
		(layer "In7.Cu")
		(net "SMB_DEBUG_AUX_LVC3_USB_SCL")
	)
	(segment
		(start 29.1592 -92.14358)
		(end 29.2481 -92.23248)
		(width 0.10668)
		(layer "In7.Cu")
		(net "SMB_DEBUG_AUX_LVC3_USB_SCL")
	)
	(segment
		(start 30.51302 -94.389702)
		(end 30.332934 -94.569788)
		(width 0.10668)
		(layer "In7.Cu")
		(net "SMB_DEBUG_AUX_LVC3_USB_SCL")
	)
	(segment
		(start 22.591776 -74.76871)
		(end 23.34768 -75.524614)
		(width 0.10668)
		(layer "In7.Cu")
		(net "SMB_DEBUG_AUX_LVC3_USB_SCL")
	)
	(segment
		(start 25.99182 -83.534504)
		(end 27.1272 -84.669884)
		(width 0.10668)
		(layer "In7.Cu")
		(net "SMB_DEBUG_AUX_LVC3_USB_SCL")
	)
	(segment
		(start 29.1592 -90.42654)
		(end 29.1592 -92.14358)
		(width 0.10668)
		(layer "In7.Cu")
		(net "SMB_DEBUG_AUX_LVC3_USB_SCL")
	)
	(segment
		(start 22.267164 -74.76871)
		(end 22.591776 -74.76871)
		(width 0.10668)
		(layer "In7.Cu")
		(net "SMB_DEBUG_AUX_LVC3_USB_SCL")
	)
	(segment
		(start 28.321 -89.58834)
		(end 29.1592 -90.42654)
		(width 0.10668)
		(layer "In7.Cu")
		(net "SMB_DEBUG_AUX_LVC3_USB_SCL")
	)
	(segment
		(start 29.83738 -98.425)
		(end 31.61284 -98.425)
		(width 0.10668)
		(layer "In7.Cu")
		(net "SMB_DEBUG_AUX_LVC3_USB_SCL")
	)
	(segment
		(start 31.32582 -95.770192)
		(end 31.145734 -95.950278)
		(width 0.10668)
		(layer "In7.Cu")
		(net "SMB_DEBUG_AUX_LVC3_USB_SCL")
	)
	(segment
		(start 27.1272 -84.669884)
		(end 27.1272 -86.2838)
		(width 0.10668)
		(layer "In7.Cu")
		(net "SMB_DEBUG_AUX_LVC3_USB_SCL")
	)
	(segment
		(start 29.337 -95.228918)
		(end 29.44368 -95.335598)
		(width 0.10668)
		(layer "In7.Cu")
		(net "SMB_DEBUG_AUX_LVC3_USB_SCL")
	)
	(segment
		(start 32.09036 -97.94748)
		(end 32.09036 -97.2058)
		(width 0.10668)
		(layer "In7.Cu")
		(net "SMB_DEBUG_AUX_LVC3_USB_SCL")
	)
	(segment
		(start 25.3492 -82.556858)
		(end 25.99182 -83.199478)
		(width 0.10668)
		(layer "In7.Cu")
		(net "SMB_DEBUG_AUX_LVC3_USB_SCL")
	)
	(segment
		(start 29.44368 -94.569788)
		(end 29.337 -94.676468)
		(width 0.10668)
		(layer "In7.Cu")
		(net "SMB_DEBUG_AUX_LVC3_USB_SCL")
	)
	(segment
		(start 29.44368 -95.950278)
		(end 29.337 -96.056958)
		(width 0.10668)
		(layer "In7.Cu")
		(net "SMB_DEBUG_AUX_LVC3_USB_SCL")
	)
	(segment
		(start 28.321 -87.4776)
		(end 28.321 -89.58834)
		(width 0.10668)
		(layer "In7.Cu")
		(net "SMB_DEBUG_AUX_LVC3_USB_SCL")
	)
	(segment
		(start 30.51302 -94.135194)
		(end 30.51302 -94.389702)
		(width 0.10668)
		(layer "In7.Cu")
		(net "SMB_DEBUG_AUX_LVC3_USB_SCL")
	)
	(segment
		(start 29.2481 -92.23248)
		(end 29.2481 -93.194378)
		(width 0.10668)
		(layer "In7.Cu")
		(net "SMB_DEBUG_AUX_LVC3_USB_SCL")
	)
	(segment
		(start 29.2481 -93.194378)
		(end 30.00883 -93.955108)
		(width 0.10668)
		(layer "In7.Cu")
		(net "SMB_DEBUG_AUX_LVC3_USB_SCL")
	)
	(segment
		(start 31.145734 -95.335598)
		(end 31.32582 -95.515684)
		(width 0.10668)
		(layer "In7.Cu")
		(net "SMB_DEBUG_AUX_LVC3_USB_SCL")
	)
	(segment
		(start 19.733514 -72.58812)
		(end 20.086574 -72.58812)
		(width 0.10668)
		(layer "In7.Cu")
		(net "SMB_DEBUG_AUX_LVC3_USB_SCL")
	)
	(segment
		(start 30.332934 -94.569788)
		(end 29.44368 -94.569788)
		(width 0.10668)
		(layer "In7.Cu")
		(net "SMB_DEBUG_AUX_LVC3_USB_SCL")
	)
	(segment
		(start 19.29384 -72.148446)
		(end 19.733514 -72.58812)
		(width 0.10668)
		(layer "In7.Cu")
		(net "SMB_DEBUG_AUX_LVC3_USB_SCL")
	)
	(segment
		(start 31.61284 -98.425)
		(end 32.09036 -97.94748)
		(width 0.10668)
		(layer "In7.Cu")
		(net "SMB_DEBUG_AUX_LVC3_USB_SCL")
	)
	(segment
		(start 29.337 -94.676468)
		(end 29.337 -95.228918)
		(width 0.10668)
		(layer "In7.Cu")
		(net "SMB_DEBUG_AUX_LVC3_USB_SCL")
	)
	(segment
		(start 23.34768 -80.31988)
		(end 24.3078 -81.28)
		(width 0.10668)
		(layer "In7.Cu")
		(net "SMB_DEBUG_AUX_LVC3_USB_SCL")
	)
	(segment
		(start 31.32582 -95.515684)
		(end 31.32582 -95.770192)
		(width 0.10668)
		(layer "In7.Cu")
		(net "SMB_DEBUG_AUX_LVC3_USB_SCL")
	)
	(segment
		(start 24.7904 -81.28)
		(end 25.3492 -81.8388)
		(width 0.10668)
		(layer "In7.Cu")
		(net "SMB_DEBUG_AUX_LVC3_USB_SCL")
	)
	(segment
		(start 30.00883 -93.955108)
		(end 30.332934 -93.955108)
		(width 0.10668)
		(layer "In7.Cu")
		(net "SMB_DEBUG_AUX_LVC3_USB_SCL")
	)
	(segment
		(start 30.332934 -93.955108)
		(end 30.51302 -94.135194)
		(width 0.10668)
		(layer "In7.Cu")
		(net "SMB_DEBUG_AUX_LVC3_USB_SCL")
	)
	(via
		(at 15.5448 -70.2056)
		(size 0.6604)
		(drill 0.3302)
		(layers "F.Cu" "B.Cu")
		(net "SMB_DEBUG_AUX_LVC3_USB_R1_SDA")
	)
	(segment
		(start 16.764 -69.70395)
		(end 16.04645 -69.70395)
		(width 0.11684)
		(layer "B.Cu")
		(net "SMB_DEBUG_AUX_LVC3_USB_R1_SDA")
	)
	(segment
		(start 16.764 -68.822316)
		(end 16.31188 -68.370196)
		(width 0.11684)
		(layer "B.Cu")
		(net "SMB_DEBUG_AUX_LVC3_USB_R1_SDA")
	)
	(segment
		(start 16.764 -72.37095)
		(end 17.08785 -72.37095)
		(width 0.11684)
		(layer "B.Cu")
		(net "SMB_DEBUG_AUX_LVC3_USB_R1_SDA")
	)
	(segment
		(start 16.764 -69.70395)
		(end 16.764 -68.822316)
		(width 0.11684)
		(layer "B.Cu")
		(net "SMB_DEBUG_AUX_LVC3_USB_R1_SDA")
	)
	(segment
		(start 17.08785 -72.37095)
		(end 17.272 -72.1868)
		(width 0.11684)
		(layer "B.Cu")
		(net "SMB_DEBUG_AUX_LVC3_USB_R1_SDA")
	)
	(segment
		(start 17.272 -71.4248)
		(end 17.0688 -71.2216)
		(width 0.11684)
		(layer "B.Cu")
		(net "SMB_DEBUG_AUX_LVC3_USB_R1_SDA")
	)
	(segment
		(start 16.3068 -71.2216)
		(end 16.0274 -70.9422)
		(width 0.11684)
		(layer "B.Cu")
		(net "SMB_DEBUG_AUX_LVC3_USB_R1_SDA")
	)
	(segment
		(start 16.31188 -68.370196)
		(end 16.31188 -67.385946)
		(width 0.11684)
		(layer "B.Cu")
		(net "SMB_DEBUG_AUX_LVC3_USB_R1_SDA")
	)
	(segment
		(start 16.0274 -70.9422)
		(end 16.0274 -70.6882)
		(width 0.11684)
		(layer "B.Cu")
		(net "SMB_DEBUG_AUX_LVC3_USB_R1_SDA")
	)
	(segment
		(start 17.0688 -71.2216)
		(end 16.3068 -71.2216)
		(width 0.11684)
		(layer "B.Cu")
		(net "SMB_DEBUG_AUX_LVC3_USB_R1_SDA")
	)
	(segment
		(start 16.04645 -69.70395)
		(end 15.5448 -70.2056)
		(width 0.11684)
		(layer "B.Cu")
		(net "SMB_DEBUG_AUX_LVC3_USB_R1_SDA")
	)
	(segment
		(start 16.0274 -70.6882)
		(end 15.5448 -70.2056)
		(width 0.11684)
		(layer "B.Cu")
		(net "SMB_DEBUG_AUX_LVC3_USB_R1_SDA")
	)
	(segment
		(start 17.272 -72.1868)
		(end 17.272 -71.4248)
		(width 0.11684)
		(layer "B.Cu")
		(net "SMB_DEBUG_AUX_LVC3_USB_R1_SDA")
	)
	(via
		(at 18.3642 -71.755)
		(size 0.6604)
		(drill 0.3302)
		(layers "F.Cu" "B.Cu")
		(net "SMB_DEBUG_AUX_LVC3_USB_R1_SCL")
	)
	(segment
		(start 17.989296 -69.70395)
		(end 18.3642 -70.078854)
		(width 0.11684)
		(layer "B.Cu")
		(net "SMB_DEBUG_AUX_LVC3_USB_R1_SCL")
	)
	(segment
		(start 17.81175 -72.30745)
		(end 17.81175 -72.9234)
		(width 0.11684)
		(layer "B.Cu")
		(net "SMB_DEBUG_AUX_LVC3_USB_R1_SCL")
	)
	(segment
		(start 17.16024 -69.08419)
		(end 17.78 -69.70395)
		(width 0.11684)
		(layer "B.Cu")
		(net "SMB_DEBUG_AUX_LVC3_USB_R1_SCL")
	)
	(segment
		(start 16.96212 -68.459858)
		(end 17.16024 -68.657978)
		(width 0.11684)
		(layer "B.Cu")
		(net "SMB_DEBUG_AUX_LVC3_USB_R1_SCL")
	)
	(segment
		(start 16.96212 -67.385946)
		(end 16.96212 -68.459858)
		(width 0.11684)
		(layer "B.Cu")
		(net "SMB_DEBUG_AUX_LVC3_USB_R1_SCL")
	)
	(segment
		(start 18.3642 -71.755)
		(end 17.81175 -72.30745)
		(width 0.11684)
		(layer "B.Cu")
		(net "SMB_DEBUG_AUX_LVC3_USB_R1_SCL")
	)
	(segment
		(start 17.16024 -68.657978)
		(end 17.16024 -69.08419)
		(width 0.11684)
		(layer "B.Cu")
		(net "SMB_DEBUG_AUX_LVC3_USB_R1_SCL")
	)
	(segment
		(start 18.3642 -70.078854)
		(end 18.3642 -71.755)
		(width 0.11684)
		(layer "B.Cu")
		(net "SMB_DEBUG_AUX_LVC3_USB_R1_SCL")
	)
	(segment
		(start 17.78 -69.70395)
		(end 17.989296 -69.70395)
		(width 0.11684)
		(layer "B.Cu")
		(net "SMB_DEBUG_AUX_LVC3_USB_R1_SCL")
	)
	(segment
		(start 80.307434 -97.77222)
		(end 81.312004 -97.356168)
		(width 0.11684)
		(layer "F.Cu")
		(net "SMB_BMC_TPM_MM16_SDA")
	)
	(segment
		(start 74.727054 -99.4664)
		(end 75.97775 -98.215704)
		(width 0.11684)
		(layer "F.Cu")
		(net "SMB_BMC_TPM_MM16_SDA")
	)
	(segment
		(start 75.97775 -98.215704)
		(end 77.049122 -97.77222)
		(width 0.11684)
		(layer "F.Cu")
		(net "SMB_BMC_TPM_MM16_SDA")
	)
	(segment
		(start 77.049122 -97.77222)
		(end 80.307434 -97.77222)
		(width 0.11684)
		(layer "F.Cu")
		(net "SMB_BMC_TPM_MM16_SDA")
	)
	(segment
		(start 74.380344 -99.4664)
		(end 74.727054 -99.4664)
		(width 0.11684)
		(layer "F.Cu")
		(net "SMB_BMC_TPM_MM16_SDA")
	)
	(segment
		(start 74.380344 -97.809304)
		(end 74.380344 -98.425)
		(width 0.11684)
		(layer "F.Cu")
		(net "SMB_BMC_TPM_MM16_SCL")
	)
	(segment
		(start 76.076556 -95.856044)
		(end 74.72934 -97.20326)
		(width 0.11684)
		(layer "F.Cu")
		(net "SMB_BMC_TPM_MM16_SCL")
	)
	(segment
		(start 74.72934 -97.20326)
		(end 73.7743 -97.20326)
		(width 0.11684)
		(layer "F.Cu")
		(net "SMB_BMC_TPM_MM16_SCL")
	)
	(segment
		(start 73.7743 -97.20326)
		(end 74.380344 -97.809304)
		(width 0.11684)
		(layer "F.Cu")
		(net "SMB_BMC_TPM_MM16_SCL")
	)
	(segment
		(start 77.092048 -95.856044)
		(end 76.076556 -95.856044)
		(width 0.11684)
		(layer "F.Cu")
		(net "SMB_BMC_TPM_MM16_SCL")
	)
	(via
		(at 73.7743 -97.20326)
		(size 0.762)
		(drill 0.381)
		(layers "F.Cu" "B.Cu")
		(net "SMB_BMC_TPM_MM16_SCL")
	)
	(segment
		(start 20.66417 -88.791796)
		(end 21.059394 -89.18702)
		(width 0.11684)
		(layer "F.Cu")
		(net "SMB_BMC_MM16_R3_SDA")
	)
	(via
		(at 18.923 -85.2678)
		(size 0.6604)
		(drill 0.3302)
		(layers "F.Cu" "B.Cu")
		(net "SMB_BMC_MM16_R3_SDA")
	)
	(via
		(at 20.66417 -88.791796)
		(size 0.4572)
		(drill 0.254)
		(layers "F.Cu" "B.Cu")
		(net "SMB_BMC_MM16_R3_SDA")
	)
	(segment
		(start 18.923 -85.2678)
		(end 18.923 -86.106)
		(width 0.11684)
		(layer "B.Cu")
		(net "SMB_BMC_MM16_R3_SDA")
	)
	(segment
		(start 19.0754 -86.2584)
		(end 19.0754 -86.6648)
		(width 0.11684)
		(layer "B.Cu")
		(net "SMB_BMC_MM16_R3_SDA")
	)
	(segment
		(start 18.288 -84.09305)
		(end 18.47596 -84.28101)
		(width 0.11684)
		(layer "B.Cu")
		(net "SMB_BMC_MM16_R3_SDA")
	)
	(segment
		(start 20.2692 -88.396826)
		(end 20.66417 -88.791796)
		(width 0.11684)
		(layer "B.Cu")
		(net "SMB_BMC_MM16_R3_SDA")
	)
	(segment
		(start 18.47596 -84.28101)
		(end 18.47596 -84.4931)
		(width 0.11684)
		(layer "B.Cu")
		(net "SMB_BMC_MM16_R3_SDA")
	)
	(segment
		(start 18.47596 -84.4931)
		(end 18.923 -84.94014)
		(width 0.11684)
		(layer "B.Cu")
		(net "SMB_BMC_MM16_R3_SDA")
	)
	(segment
		(start 20.2692 -87.8586)
		(end 20.2692 -88.396826)
		(width 0.11684)
		(layer "B.Cu")
		(net "SMB_BMC_MM16_R3_SDA")
	)
	(segment
		(start 19.0754 -86.6648)
		(end 20.2692 -87.8586)
		(width 0.11684)
		(layer "B.Cu")
		(net "SMB_BMC_MM16_R3_SDA")
	)
	(segment
		(start 18.923 -84.94014)
		(end 18.923 -85.2678)
		(width 0.11684)
		(layer "B.Cu")
		(net "SMB_BMC_MM16_R3_SDA")
	)
	(segment
		(start 18.923 -86.106)
		(end 19.0754 -86.2584)
		(width 0.11684)
		(layer "B.Cu")
		(net "SMB_BMC_MM16_R3_SDA")
	)
	(segment
		(start 21.059394 -87.327994)
		(end 21.059394 -87.587074)
		(width 0.11684)
		(layer "F.Cu")
		(net "SMB_BMC_MM16_R3_SCL")
	)
	(segment
		(start 20.7518 -87.0204)
		(end 21.059394 -87.327994)
		(width 0.11684)
		(layer "F.Cu")
		(net "SMB_BMC_MM16_R3_SCL")
	)
	(via
		(at 20.7518 -87.0204)
		(size 0.508)
		(drill 0.254)
		(layers "F.Cu" "B.Cu")
		(net "SMB_BMC_MM16_R3_SCL")
	)
	(via
		(at 18.618454 -81.17205)
		(size 0.6604)
		(drill 0.3302)
		(layers "F.Cu" "B.Cu")
		(net "SMB_BMC_MM16_R3_SCL")
	)
	(segment
		(start 19.0246 -82.425794)
		(end 19.0246 -81.578196)
		(width 0.11684)
		(layer "B.Cu")
		(net "SMB_BMC_MM16_R3_SCL")
	)
	(segment
		(start 19.9136 -87.0204)
		(end 19.5072 -86.614)
		(width 0.11684)
		(layer "B.Cu")
		(net "SMB_BMC_MM16_R3_SCL")
	)
	(segment
		(start 19.0246 -81.578196)
		(end 18.618454 -81.17205)
		(width 0.11684)
		(layer "B.Cu")
		(net "SMB_BMC_MM16_R3_SCL")
	)
	(segment
		(start 19.5072 -86.614)
		(end 19.5072 -84.963)
		(width 0.11684)
		(layer "B.Cu")
		(net "SMB_BMC_MM16_R3_SCL")
	)
	(segment
		(start 18.96618 -84.42198)
		(end 18.96618 -82.484214)
		(width 0.11684)
		(layer "B.Cu")
		(net "SMB_BMC_MM16_R3_SCL")
	)
	(segment
		(start 17.272 -81.17205)
		(end 18.618454 -81.17205)
		(width 0.11684)
		(layer "B.Cu")
		(net "SMB_BMC_MM16_R3_SCL")
	)
	(segment
		(start 20.7518 -87.0204)
		(end 19.9136 -87.0204)
		(width 0.11684)
		(layer "B.Cu")
		(net "SMB_BMC_MM16_R3_SCL")
	)
	(segment
		(start 19.5072 -84.963)
		(end 18.96618 -84.42198)
		(width 0.11684)
		(layer "B.Cu")
		(net "SMB_BMC_MM16_R3_SCL")
	)
	(segment
		(start 18.96618 -82.484214)
		(end 19.0246 -82.425794)
		(width 0.11684)
		(layer "B.Cu")
		(net "SMB_BMC_MM16_R3_SCL")
	)
	(segment
		(start 36.1061 -46.736)
		(end 35.4076 -46.736)
		(width 0.11684)
		(layer "F.Cu")
		(net "SMB_BMC_MM14_SDA")
	)
	(segment
		(start 37.7952 -45.16628)
		(end 37.7952 -45.180504)
		(width 0.11684)
		(layer "F.Cu")
		(net "SMB_BMC_MM14_SDA")
	)
	(segment
		(start 37.99332 -44.96816)
		(end 37.7952 -45.16628)
		(width 0.11684)
		(layer "F.Cu")
		(net "SMB_BMC_MM14_SDA")
	)
	(segment
		(start 37.792406 -45.183298)
		(end 37.792406 -45.684948)
		(width 0.11684)
		(layer "F.Cu")
		(net "SMB_BMC_MM14_SDA")
	)
	(segment
		(start 37.792406 -45.684948)
		(end 37.565838 -45.911516)
		(width 0.11684)
		(layer "F.Cu")
		(net "SMB_BMC_MM14_SDA")
	)
	(segment
		(start 33.55086 -48.59274)
		(end 32.97174 -48.59274)
		(width 0.11684)
		(layer "F.Cu")
		(net "SMB_BMC_MM14_SDA")
	)
	(segment
		(start 35.4076 -46.736)
		(end 33.55086 -48.59274)
		(width 0.11684)
		(layer "F.Cu")
		(net "SMB_BMC_MM14_SDA")
	)
	(segment
		(start 37.7952 -45.180504)
		(end 37.792406 -45.183298)
		(width 0.11684)
		(layer "F.Cu")
		(net "SMB_BMC_MM14_SDA")
	)
	(segment
		(start 38.767004 -44.3992)
		(end 38.342824 -44.82338)
		(width 0.11684)
		(layer "F.Cu")
		(net "SMB_BMC_MM14_SDA")
	)
	(segment
		(start 36.483798 -46.358302)
		(end 36.1061 -46.736)
		(width 0.11684)
		(layer "F.Cu")
		(net "SMB_BMC_MM14_SDA")
	)
	(segment
		(start 39.52875 -44.3992)
		(end 38.767004 -44.3992)
		(width 0.11684)
		(layer "F.Cu")
		(net "SMB_BMC_MM14_SDA")
	)
	(segment
		(start 38.342824 -44.82338)
		(end 37.99332 -44.96816)
		(width 0.11684)
		(layer "F.Cu")
		(net "SMB_BMC_MM14_SDA")
	)
	(segment
		(start 37.565838 -45.911516)
		(end 36.483798 -46.358302)
		(width 0.11684)
		(layer "F.Cu")
		(net "SMB_BMC_MM14_SDA")
	)
	(via
		(at 62.972442 -81.026)
		(size 0.508)
		(drill 0.254)
		(layers "F.Cu" "B.Cu")
		(net "SMB_BMC_MM14_SDA")
	)
	(via
		(at 70.5358 -103.1494)
		(size 0.508)
		(drill 0.254)
		(layers "F.Cu" "B.Cu")
		(net "SMB_BMC_MM14_SDA")
	)
	(via
		(at 23.9776 -78.0288)
		(size 0.508)
		(drill 0.254)
		(layers "F.Cu" "B.Cu")
		(net "SMB_BMC_MM14_SDA")
	)
	(via
		(at 32.97174 -48.59274)
		(size 0.762)
		(drill 0.254)
		(layers "F.Cu" "B.Cu")
		(net "SMB_BMC_MM14_SDA")
	)
	(segment
		(start 66.3956 -105.4862)
		(end 66.3956 -106.03865)
		(width 0.11684)
		(layer "B.Cu")
		(net "SMB_BMC_MM14_SDA")
	)
	(segment
		(start 70.5358 -103.1494)
		(end 68.7324 -103.1494)
		(width 0.11684)
		(layer "B.Cu")
		(net "SMB_BMC_MM14_SDA")
	)
	(segment
		(start 68.7324 -103.1494)
		(end 66.3956 -105.4862)
		(width 0.11684)
		(layer "B.Cu")
		(net "SMB_BMC_MM14_SDA")
	)
	(segment
		(start 48.270414 -80.570324)
		(end 44.451524 -80.570324)
		(width 0.08382)
		(layer "In2.Cu")
		(net "SMB_BMC_MM14_SDA")
	)
	(segment
		(start 52.98694 -79.852774)
		(end 51.135534 -81.70418)
		(width 0.08382)
		(layer "In2.Cu")
		(net "SMB_BMC_MM14_SDA")
	)
	(segment
		(start 24.5872 -78.6384)
		(end 23.9776 -78.0288)
		(width 0.08382)
		(layer "In2.Cu")
		(net "SMB_BMC_MM14_SDA")
	)
	(segment
		(start 55.84698 -79.852774)
		(end 52.98694 -79.852774)
		(width 0.08382)
		(layer "In2.Cu")
		(net "SMB_BMC_MM14_SDA")
	)
	(segment
		(start 38.36035 -80.583532)
		(end 37.988494 -80.583532)
		(width 0.08382)
		(layer "In2.Cu")
		(net "SMB_BMC_MM14_SDA")
	)
	(segment
		(start 43.155362 -80.12049)
		(end 42.243502 -81.03235)
		(width 0.08382)
		(layer "In2.Cu")
		(net "SMB_BMC_MM14_SDA")
	)
	(segment
		(start 37.292026 -80.58404)
		(end 35.35172 -80.58404)
		(width 0.08382)
		(layer "In2.Cu")
		(net "SMB_BMC_MM14_SDA")
	)
	(segment
		(start 24.5872 -79.177134)
		(end 24.5872 -78.6384)
		(width 0.08382)
		(layer "In2.Cu")
		(net "SMB_BMC_MM14_SDA")
	)
	(segment
		(start 44.451524 -80.570324)
		(end 44.00169 -80.12049)
		(width 0.08382)
		(layer "In2.Cu")
		(net "SMB_BMC_MM14_SDA")
	)
	(segment
		(start 59.43092 -81.15808)
		(end 57.152286 -81.15808)
		(width 0.08382)
		(layer "In2.Cu")
		(net "SMB_BMC_MM14_SDA")
	)
	(segment
		(start 39.852854 -80.37322)
		(end 39.37762 -80.37322)
		(width 0.08382)
		(layer "In2.Cu")
		(net "SMB_BMC_MM14_SDA")
	)
	(segment
		(start 51.135534 -81.70418)
		(end 49.40427 -81.70418)
		(width 0.08382)
		(layer "In2.Cu")
		(net "SMB_BMC_MM14_SDA")
	)
	(segment
		(start 39.3192 -80.3148)
		(end 38.629082 -80.3148)
		(width 0.08382)
		(layer "In2.Cu")
		(net "SMB_BMC_MM14_SDA")
	)
	(segment
		(start 44.00169 -80.12049)
		(end 43.155362 -80.12049)
		(width 0.08382)
		(layer "In2.Cu")
		(net "SMB_BMC_MM14_SDA")
	)
	(segment
		(start 42.243502 -81.03235)
		(end 40.511984 -81.03235)
		(width 0.08382)
		(layer "In2.Cu")
		(net "SMB_BMC_MM14_SDA")
	)
	(segment
		(start 49.40427 -81.70418)
		(end 48.270414 -80.570324)
		(width 0.08382)
		(layer "In2.Cu")
		(net "SMB_BMC_MM14_SDA")
	)
	(segment
		(start 37.719762 -80.3148)
		(end 37.601906 -80.3148)
		(width 0.08382)
		(layer "In2.Cu")
		(net "SMB_BMC_MM14_SDA")
	)
	(segment
		(start 26.2255 -80.3148)
		(end 25.724866 -80.3148)
		(width 0.08382)
		(layer "In2.Cu")
		(net "SMB_BMC_MM14_SDA")
	)
	(segment
		(start 39.37762 -80.37322)
		(end 39.3192 -80.3148)
		(width 0.08382)
		(layer "In2.Cu")
		(net "SMB_BMC_MM14_SDA")
	)
	(segment
		(start 62.303152 -81.69529)
		(end 59.96813 -81.69529)
		(width 0.08382)
		(layer "In2.Cu")
		(net "SMB_BMC_MM14_SDA")
	)
	(segment
		(start 37.601906 -80.3148)
		(end 37.441886 -80.47482)
		(width 0.08382)
		(layer "In2.Cu")
		(net "SMB_BMC_MM14_SDA")
	)
	(segment
		(start 37.988494 -80.583532)
		(end 37.719762 -80.3148)
		(width 0.08382)
		(layer "In2.Cu")
		(net "SMB_BMC_MM14_SDA")
	)
	(segment
		(start 37.401246 -80.47482)
		(end 37.292026 -80.58404)
		(width 0.08382)
		(layer "In2.Cu")
		(net "SMB_BMC_MM14_SDA")
	)
	(segment
		(start 35.2425 -80.47482)
		(end 26.38552 -80.47482)
		(width 0.08382)
		(layer "In2.Cu")
		(net "SMB_BMC_MM14_SDA")
	)
	(segment
		(start 62.972442 -81.026)
		(end 62.303152 -81.69529)
		(width 0.08382)
		(layer "In2.Cu")
		(net "SMB_BMC_MM14_SDA")
	)
	(segment
		(start 37.441886 -80.47482)
		(end 37.401246 -80.47482)
		(width 0.08382)
		(layer "In2.Cu")
		(net "SMB_BMC_MM14_SDA")
	)
	(segment
		(start 40.511984 -81.03235)
		(end 39.852854 -80.37322)
		(width 0.08382)
		(layer "In2.Cu")
		(net "SMB_BMC_MM14_SDA")
	)
	(segment
		(start 57.152286 -81.15808)
		(end 55.84698 -79.852774)
		(width 0.08382)
		(layer "In2.Cu")
		(net "SMB_BMC_MM14_SDA")
	)
	(segment
		(start 25.724866 -80.3148)
		(end 24.5872 -79.177134)
		(width 0.08382)
		(layer "In2.Cu")
		(net "SMB_BMC_MM14_SDA")
	)
	(segment
		(start 38.629082 -80.3148)
		(end 38.36035 -80.583532)
		(width 0.08382)
		(layer "In2.Cu")
		(net "SMB_BMC_MM14_SDA")
	)
	(segment
		(start 35.35172 -80.58404)
		(end 35.2425 -80.47482)
		(width 0.08382)
		(layer "In2.Cu")
		(net "SMB_BMC_MM14_SDA")
	)
	(segment
		(start 26.38552 -80.47482)
		(end 26.2255 -80.3148)
		(width 0.08382)
		(layer "In2.Cu")
		(net "SMB_BMC_MM14_SDA")
	)
	(segment
		(start 59.96813 -81.69529)
		(end 59.43092 -81.15808)
		(width 0.08382)
		(layer "In2.Cu")
		(net "SMB_BMC_MM14_SDA")
	)
	(segment
		(start 62.909704 -82.785712)
		(end 62.99708 -82.99577)
		(width 0.10668)
		(layer "In7.Cu")
		(net "SMB_BMC_MM14_SDA")
	)
	(segment
		(start 63.589916 -83.588606)
		(end 63.589916 -89.656412)
		(width 0.10668)
		(layer "In7.Cu")
		(net "SMB_BMC_MM14_SDA")
	)
	(segment
		(start 69.539358 -99.308412)
		(end 69.64934 -99.573842)
		(width 0.10668)
		(layer "In7.Cu")
		(net "SMB_BMC_MM14_SDA")
	)
	(segment
		(start 69.64934 -101.06914)
		(end 70.77202 -102.19182)
		(width 0.10668)
		(layer "In7.Cu")
		(net "SMB_BMC_MM14_SDA")
	)
	(segment
		(start 63.589916 -89.656412)
		(end 67.76974 -93.836236)
		(width 0.10668)
		(layer "In7.Cu")
		(net "SMB_BMC_MM14_SDA")
	)
	(segment
		(start 70.77202 -102.19182)
		(end 70.77202 -102.91318)
		(width 0.10668)
		(layer "In7.Cu")
		(net "SMB_BMC_MM14_SDA")
	)
	(segment
		(start 70.77202 -102.91318)
		(end 70.5358 -103.1494)
		(width 0.10668)
		(layer "In7.Cu")
		(net "SMB_BMC_MM14_SDA")
	)
	(segment
		(start 62.972442 -81.026)
		(end 62.7761 -81.222342)
		(width 0.10668)
		(layer "In7.Cu")
		(net "SMB_BMC_MM14_SDA")
	)
	(segment
		(start 62.7761 -82.46237)
		(end 62.909704 -82.785712)
		(width 0.10668)
		(layer "In7.Cu")
		(net "SMB_BMC_MM14_SDA")
	)
	(segment
		(start 62.99708 -82.99577)
		(end 63.589916 -83.588606)
		(width 0.10668)
		(layer "In7.Cu")
		(net "SMB_BMC_MM14_SDA")
	)
	(segment
		(start 62.7761 -81.222342)
		(end 62.7761 -82.46237)
		(width 0.10668)
		(layer "In7.Cu")
		(net "SMB_BMC_MM14_SDA")
	)
	(segment
		(start 69.64934 -99.573842)
		(end 69.64934 -101.06914)
		(width 0.10668)
		(layer "In7.Cu")
		(net "SMB_BMC_MM14_SDA")
	)
	(segment
		(start 67.76974 -93.836236)
		(end 67.76974 -97.538794)
		(width 0.10668)
		(layer "In7.Cu")
		(net "SMB_BMC_MM14_SDA")
	)
	(segment
		(start 67.76974 -97.538794)
		(end 69.539358 -99.308412)
		(width 0.10668)
		(layer "In7.Cu")
		(net "SMB_BMC_MM14_SDA")
	)
	(segment
		(start 27.871928 -73.24471)
		(end 29.7307 -71.385938)
		(width 0.08382)
		(layer "In9.Cu")
		(net "SMB_BMC_MM14_SDA")
	)
	(segment
		(start 31.63189 -64.58839)
		(end 31.979108 -64.241172)
		(width 0.08382)
		(layer "In9.Cu")
		(net "SMB_BMC_MM14_SDA")
	)
	(segment
		(start 32.5882 -56.813958)
		(end 32.34182 -56.567578)
		(width 0.08382)
		(layer "In9.Cu")
		(net "SMB_BMC_MM14_SDA")
	)
	(segment
		(start 31.979108 -59.079892)
		(end 32.5882 -58.4708)
		(width 0.08382)
		(layer "In9.Cu")
		(net "SMB_BMC_MM14_SDA")
	)
	(segment
		(start 33.909 -51.34229)
		(end 33.909 -49.53)
		(width 0.08382)
		(layer "In9.Cu")
		(net "SMB_BMC_MM14_SDA")
	)
	(segment
		(start 29.7307 -69.1261)
		(end 30.2768 -68.58)
		(width 0.08382)
		(layer "In9.Cu")
		(net "SMB_BMC_MM14_SDA")
	)
	(segment
		(start 32.5882 -58.4708)
		(end 32.5882 -56.813958)
		(width 0.08382)
		(layer "In9.Cu")
		(net "SMB_BMC_MM14_SDA")
	)
	(segment
		(start 23.9776 -76.809854)
		(end 27.542744 -73.24471)
		(width 0.08382)
		(layer "In9.Cu")
		(net "SMB_BMC_MM14_SDA")
	)
	(segment
		(start 23.9776 -78.0288)
		(end 23.9776 -76.809854)
		(width 0.08382)
		(layer "In9.Cu")
		(net "SMB_BMC_MM14_SDA")
	)
	(segment
		(start 33.27908 -51.97221)
		(end 33.909 -51.34229)
		(width 0.08382)
		(layer "In9.Cu")
		(net "SMB_BMC_MM14_SDA")
	)
	(segment
		(start 32.34182 -55.287164)
		(end 33.27908 -54.349904)
		(width 0.08382)
		(layer "In9.Cu")
		(net "SMB_BMC_MM14_SDA")
	)
	(segment
		(start 27.542744 -73.24471)
		(end 27.871928 -73.24471)
		(width 0.08382)
		(layer "In9.Cu")
		(net "SMB_BMC_MM14_SDA")
	)
	(segment
		(start 31.979108 -64.241172)
		(end 31.979108 -59.079892)
		(width 0.08382)
		(layer "In9.Cu")
		(net "SMB_BMC_MM14_SDA")
	)
	(segment
		(start 30.2768 -68.58)
		(end 30.64256 -68.58)
		(width 0.08382)
		(layer "In9.Cu")
		(net "SMB_BMC_MM14_SDA")
	)
	(segment
		(start 29.7307 -71.385938)
		(end 29.7307 -69.1261)
		(width 0.08382)
		(layer "In9.Cu")
		(net "SMB_BMC_MM14_SDA")
	)
	(segment
		(start 33.27908 -54.349904)
		(end 33.27908 -51.97221)
		(width 0.08382)
		(layer "In9.Cu")
		(net "SMB_BMC_MM14_SDA")
	)
	(segment
		(start 33.909 -49.53)
		(end 32.97174 -48.59274)
		(width 0.08382)
		(layer "In9.Cu")
		(net "SMB_BMC_MM14_SDA")
	)
	(segment
		(start 32.34182 -56.567578)
		(end 32.34182 -55.287164)
		(width 0.08382)
		(layer "In9.Cu")
		(net "SMB_BMC_MM14_SDA")
	)
	(segment
		(start 31.63189 -67.59067)
		(end 31.63189 -64.58839)
		(width 0.08382)
		(layer "In9.Cu")
		(net "SMB_BMC_MM14_SDA")
	)
	(segment
		(start 30.64256 -68.58)
		(end 31.63189 -67.59067)
		(width 0.08382)
		(layer "In9.Cu")
		(net "SMB_BMC_MM14_SDA")
	)
	(via
		(at 61.72454 -82.1436)
		(size 0.508)
		(drill 0.254)
		(layers "F.Cu" "B.Cu")
		(net "SMB_BMC_MM14_SCL")
	)
	(via
		(at 23.9776 -79.0194)
		(size 0.508)
		(drill 0.254)
		(layers "F.Cu" "B.Cu")
		(net "SMB_BMC_MM14_SCL")
	)
	(via
		(at 70.5358 -104.79532)
		(size 0.508)
		(drill 0.254)
		(layers "F.Cu" "B.Cu")
		(net "SMB_BMC_MM14_SCL")
	)
	(via
		(at 37.8714 -48.250602)
		(size 0.508)
		(drill 0.254)
		(layers "F.Cu" "B.Cu")
		(net "SMB_BMC_MM14_SCL")
	)
	(segment
		(start 67.96405 -105.4862)
		(end 67.4116 -106.03865)
		(width 0.11684)
		(layer "B.Cu")
		(net "SMB_BMC_MM14_SCL")
	)
	(segment
		(start 38.261798 -48.485298)
		(end 38.261798 -48.925988)
		(width 0.11684)
		(layer "B.Cu")
		(net "SMB_BMC_MM14_SCL")
	)
	(segment
		(start 38.261798 -48.925988)
		(end 38.267386 -48.9204)
		(width 0.11684)
		(layer "B.Cu")
		(net "SMB_BMC_MM14_SCL")
	)
	(segment
		(start 38.027102 -48.250602)
		(end 38.261798 -48.485298)
		(width 0.11684)
		(layer "B.Cu")
		(net "SMB_BMC_MM14_SCL")
	)
	(segment
		(start 37.8714 -48.250602)
		(end 38.027102 -48.250602)
		(width 0.11684)
		(layer "B.Cu")
		(net "SMB_BMC_MM14_SCL")
	)
	(segment
		(start 39.530782 -48.915828)
		(end 39.117524 -48.915828)
		(width 0.11684)
		(layer "B.Cu")
		(net "SMB_BMC_MM14_SCL")
	)
	(segment
		(start 39.117524 -48.915828)
		(end 39.112952 -48.9204)
		(width 0.11684)
		(layer "B.Cu")
		(net "SMB_BMC_MM14_SCL")
	)
	(segment
		(start 69.84492 -105.4862)
		(end 67.96405 -105.4862)
		(width 0.11684)
		(layer "B.Cu")
		(net "SMB_BMC_MM14_SCL")
	)
	(segment
		(start 39.112952 -48.9204)
		(end 38.267386 -48.9204)
		(width 0.11684)
		(layer "B.Cu")
		(net "SMB_BMC_MM14_SCL")
	)
	(segment
		(start 70.5358 -104.79532)
		(end 69.84492 -105.4862)
		(width 0.11684)
		(layer "B.Cu")
		(net "SMB_BMC_MM14_SCL")
	)
	(segment
		(start 59.2963 -81.4705)
		(end 59.9694 -82.1436)
		(width 0.08382)
		(layer "In2.Cu")
		(net "SMB_BMC_MM14_SCL")
	)
	(segment
		(start 44.889928 -81.47431)
		(end 45.481494 -80.882744)
		(width 0.08382)
		(layer "In2.Cu")
		(net "SMB_BMC_MM14_SCL")
	)
	(segment
		(start 38.48989 -80.895952)
		(end 38.758622 -80.62722)
		(width 0.08382)
		(layer "In2.Cu")
		(net "SMB_BMC_MM14_SCL")
	)
	(segment
		(start 23.987506 -79.0194)
		(end 25.595326 -80.62722)
		(width 0.08382)
		(layer "In2.Cu")
		(net "SMB_BMC_MM14_SCL")
	)
	(segment
		(start 54.175152 -80.91551)
		(end 56.04891 -80.91551)
		(width 0.08382)
		(layer "In2.Cu")
		(net "SMB_BMC_MM14_SCL")
	)
	(segment
		(start 37.858954 -80.895952)
		(end 38.48989 -80.895952)
		(width 0.08382)
		(layer "In2.Cu")
		(net "SMB_BMC_MM14_SCL")
	)
	(segment
		(start 37.660834 -80.697832)
		(end 37.858954 -80.895952)
		(width 0.08382)
		(layer "In2.Cu")
		(net "SMB_BMC_MM14_SCL")
	)
	(segment
		(start 45.481494 -80.882744)
		(end 48.140874 -80.882744)
		(width 0.08382)
		(layer "In2.Cu")
		(net "SMB_BMC_MM14_SCL")
	)
	(segment
		(start 56.6039 -81.4705)
		(end 59.2963 -81.4705)
		(width 0.08382)
		(layer "In2.Cu")
		(net "SMB_BMC_MM14_SCL")
	)
	(segment
		(start 51.265074 -82.0166)
		(end 52.568094 -80.71358)
		(width 0.08382)
		(layer "In2.Cu")
		(net "SMB_BMC_MM14_SCL")
	)
	(segment
		(start 23.9776 -79.0194)
		(end 23.987506 -79.0194)
		(width 0.08382)
		(layer "In2.Cu")
		(net "SMB_BMC_MM14_SCL")
	)
	(segment
		(start 35.11296 -80.78724)
		(end 35.22218 -80.89646)
		(width 0.08382)
		(layer "In2.Cu")
		(net "SMB_BMC_MM14_SCL")
	)
	(segment
		(start 26.25598 -80.78724)
		(end 35.11296 -80.78724)
		(width 0.08382)
		(layer "In2.Cu")
		(net "SMB_BMC_MM14_SCL")
	)
	(segment
		(start 52.568094 -80.71358)
		(end 53.973222 -80.71358)
		(width 0.08382)
		(layer "In2.Cu")
		(net "SMB_BMC_MM14_SCL")
	)
	(segment
		(start 37.530786 -80.78724)
		(end 37.571426 -80.78724)
		(width 0.08382)
		(layer "In2.Cu")
		(net "SMB_BMC_MM14_SCL")
	)
	(segment
		(start 39.24808 -80.68564)
		(end 39.723314 -80.68564)
		(width 0.08382)
		(layer "In2.Cu")
		(net "SMB_BMC_MM14_SCL")
	)
	(segment
		(start 53.973222 -80.71358)
		(end 54.175152 -80.91551)
		(width 0.08382)
		(layer "In2.Cu")
		(net "SMB_BMC_MM14_SCL")
	)
	(segment
		(start 56.04891 -80.91551)
		(end 56.6039 -81.4705)
		(width 0.08382)
		(layer "In2.Cu")
		(net "SMB_BMC_MM14_SCL")
	)
	(segment
		(start 39.723314 -80.68564)
		(end 40.511984 -81.47431)
		(width 0.08382)
		(layer "In2.Cu")
		(net "SMB_BMC_MM14_SCL")
	)
	(segment
		(start 59.9694 -82.1436)
		(end 61.72454 -82.1436)
		(width 0.08382)
		(layer "In2.Cu")
		(net "SMB_BMC_MM14_SCL")
	)
	(segment
		(start 35.22218 -80.89646)
		(end 37.421566 -80.89646)
		(width 0.08382)
		(layer "In2.Cu")
		(net "SMB_BMC_MM14_SCL")
	)
	(segment
		(start 48.140874 -80.882744)
		(end 49.27473 -82.0166)
		(width 0.08382)
		(layer "In2.Cu")
		(net "SMB_BMC_MM14_SCL")
	)
	(segment
		(start 38.758622 -80.62722)
		(end 39.18966 -80.62722)
		(width 0.08382)
		(layer "In2.Cu")
		(net "SMB_BMC_MM14_SCL")
	)
	(segment
		(start 49.27473 -82.0166)
		(end 51.265074 -82.0166)
		(width 0.08382)
		(layer "In2.Cu")
		(net "SMB_BMC_MM14_SCL")
	)
	(segment
		(start 39.18966 -80.62722)
		(end 39.24808 -80.68564)
		(width 0.08382)
		(layer "In2.Cu")
		(net "SMB_BMC_MM14_SCL")
	)
	(segment
		(start 25.595326 -80.62722)
		(end 26.09596 -80.62722)
		(width 0.08382)
		(layer "In2.Cu")
		(net "SMB_BMC_MM14_SCL")
	)
	(segment
		(start 40.511984 -81.47431)
		(end 44.889928 -81.47431)
		(width 0.08382)
		(layer "In2.Cu")
		(net "SMB_BMC_MM14_SCL")
	)
	(segment
		(start 37.571426 -80.78724)
		(end 37.660834 -80.697832)
		(width 0.08382)
		(layer "In2.Cu")
		(net "SMB_BMC_MM14_SCL")
	)
	(segment
		(start 26.09596 -80.62722)
		(end 26.25598 -80.78724)
		(width 0.08382)
		(layer "In2.Cu")
		(net "SMB_BMC_MM14_SCL")
	)
	(segment
		(start 37.421566 -80.89646)
		(end 37.530786 -80.78724)
		(width 0.08382)
		(layer "In2.Cu")
		(net "SMB_BMC_MM14_SCL")
	)
	(segment
		(start 61.72454 -82.1436)
		(end 62.04204 -82.4611)
		(width 0.10668)
		(layer "In7.Cu")
		(net "SMB_BMC_MM14_SCL")
	)
	(segment
		(start 62.04204 -82.4611)
		(end 62.43574 -83.411314)
		(width 0.10668)
		(layer "In7.Cu")
		(net "SMB_BMC_MM14_SCL")
	)
	(segment
		(start 62.919356 -85.543136)
		(end 62.9158 -85.546692)
		(width 0.10668)
		(layer "In7.Cu")
		(net "SMB_BMC_MM14_SCL")
	)
	(segment
		(start 62.919356 -89.944448)
		(end 67.09918 -94.124272)
		(width 0.10668)
		(layer "In7.Cu")
		(net "SMB_BMC_MM14_SCL")
	)
	(segment
		(start 62.9158 -85.740494)
		(end 62.919356 -85.74405)
		(width 0.10668)
		(layer "In7.Cu")
		(net "SMB_BMC_MM14_SCL")
	)
	(segment
		(start 69.56806 -101.80066)
		(end 69.56806 -102.8319)
		(width 0.10668)
		(layer "In7.Cu")
		(net "SMB_BMC_MM14_SCL")
	)
	(segment
		(start 70.20306 -104.46258)
		(end 70.5358 -104.79532)
		(width 0.10668)
		(layer "In7.Cu")
		(net "SMB_BMC_MM14_SCL")
	)
	(segment
		(start 68.65366 -100.88626)
		(end 69.56806 -101.80066)
		(width 0.10668)
		(layer "In7.Cu")
		(net "SMB_BMC_MM14_SCL")
	)
	(segment
		(start 67.09918 -94.124272)
		(end 67.09918 -97.816924)
		(width 0.10668)
		(layer "In7.Cu")
		(net "SMB_BMC_MM14_SCL")
	)
	(segment
		(start 69.56806 -102.8319)
		(end 70.20306 -103.4669)
		(width 0.10668)
		(layer "In7.Cu")
		(net "SMB_BMC_MM14_SCL")
	)
	(segment
		(start 62.9158 -83.891628)
		(end 62.919356 -83.895184)
		(width 0.10668)
		(layer "In7.Cu")
		(net "SMB_BMC_MM14_SCL")
	)
	(segment
		(start 62.919356 -85.74405)
		(end 62.919356 -89.944448)
		(width 0.10668)
		(layer "In7.Cu")
		(net "SMB_BMC_MM14_SCL")
	)
	(segment
		(start 62.9158 -83.891374)
		(end 62.9158 -83.891628)
		(width 0.10668)
		(layer "In7.Cu")
		(net "SMB_BMC_MM14_SCL")
	)
	(segment
		(start 62.9158 -85.546692)
		(end 62.9158 -85.740494)
		(width 0.10668)
		(layer "In7.Cu")
		(net "SMB_BMC_MM14_SCL")
	)
	(segment
		(start 62.43574 -83.411314)
		(end 62.9158 -83.891374)
		(width 0.10668)
		(layer "In7.Cu")
		(net "SMB_BMC_MM14_SCL")
	)
	(segment
		(start 62.919356 -83.895184)
		(end 62.919356 -85.543136)
		(width 0.10668)
		(layer "In7.Cu")
		(net "SMB_BMC_MM14_SCL")
	)
	(segment
		(start 70.20306 -103.4669)
		(end 70.20306 -104.46258)
		(width 0.10668)
		(layer "In7.Cu")
		(net "SMB_BMC_MM14_SCL")
	)
	(segment
		(start 68.65366 -99.371404)
		(end 68.65366 -100.88626)
		(width 0.10668)
		(layer "In7.Cu")
		(net "SMB_BMC_MM14_SCL")
	)
	(segment
		(start 67.09918 -97.816924)
		(end 68.65366 -99.371404)
		(width 0.10668)
		(layer "In7.Cu")
		(net "SMB_BMC_MM14_SCL")
	)
	(segment
		(start 23.9776 -79.0194)
		(end 24.22906 -79.0194)
		(width 0.08382)
		(layer "In9.Cu")
		(net "SMB_BMC_MM14_SCL")
	)
	(segment
		(start 32.25673 -67.84975)
		(end 32.25673 -67.18427)
		(width 0.08382)
		(layer "In9.Cu")
		(net "SMB_BMC_MM14_SCL")
	)
	(segment
		(start 37.180012 -48.7172)
		(end 37.64661 -48.250602)
		(width 0.08382)
		(layer "In9.Cu")
		(net "SMB_BMC_MM14_SCL")
	)
	(segment
		(start 32.96666 -56.308498)
		(end 32.96666 -55.546244)
		(width 0.08382)
		(layer "In9.Cu")
		(net "SMB_BMC_MM14_SCL")
	)
	(segment
		(start 37.64661 -48.250602)
		(end 37.8714 -48.250602)
		(width 0.08382)
		(layer "In9.Cu")
		(net "SMB_BMC_MM14_SCL")
	)
	(segment
		(start 32.603948 -61.226192)
		(end 33.510728 -59.869324)
		(width 0.08382)
		(layer "In9.Cu")
		(net "SMB_BMC_MM14_SCL")
	)
	(segment
		(start 35.4584 -48.3616)
		(end 35.941 -48.3616)
		(width 0.08382)
		(layer "In9.Cu")
		(net "SMB_BMC_MM14_SCL")
	)
	(segment
		(start 36.2966 -48.7172)
		(end 37.180012 -48.7172)
		(width 0.08382)
		(layer "In9.Cu")
		(net "SMB_BMC_MM14_SCL")
	)
	(segment
		(start 32.27324 -64.83096)
		(end 32.603948 -64.500252)
		(width 0.08382)
		(layer "In9.Cu")
		(net "SMB_BMC_MM14_SCL")
	)
	(segment
		(start 35.1536 -48.6664)
		(end 35.4584 -48.3616)
		(width 0.08382)
		(layer "In9.Cu")
		(net "SMB_BMC_MM14_SCL")
	)
	(segment
		(start 32.895286 -66.545714)
		(end 32.895286 -65.813686)
		(width 0.08382)
		(layer "In9.Cu")
		(net "SMB_BMC_MM14_SCL")
	)
	(segment
		(start 33.510728 -59.869324)
		(end 33.510728 -56.852566)
		(width 0.08382)
		(layer "In9.Cu")
		(net "SMB_BMC_MM14_SCL")
	)
	(segment
		(start 30.94609 -71.054468)
		(end 30.94609 -69.16039)
		(width 0.08382)
		(layer "In9.Cu")
		(net "SMB_BMC_MM14_SCL")
	)
	(segment
		(start 24.75484 -76.916534)
		(end 27.801824 -73.86955)
		(width 0.08382)
		(layer "In9.Cu")
		(net "SMB_BMC_MM14_SCL")
	)
	(segment
		(start 35.941 -48.3616)
		(end 36.2966 -48.7172)
		(width 0.08382)
		(layer "In9.Cu")
		(net "SMB_BMC_MM14_SCL")
	)
	(segment
		(start 35.1536 -53.359304)
		(end 35.1536 -48.6664)
		(width 0.08382)
		(layer "In9.Cu")
		(net "SMB_BMC_MM14_SCL")
	)
	(segment
		(start 33.510728 -56.852566)
		(end 32.96666 -56.308498)
		(width 0.08382)
		(layer "In9.Cu")
		(net "SMB_BMC_MM14_SCL")
	)
	(segment
		(start 24.75484 -78.338426)
		(end 24.75484 -76.916534)
		(width 0.08382)
		(layer "In9.Cu")
		(net "SMB_BMC_MM14_SCL")
	)
	(segment
		(start 28.131008 -73.86955)
		(end 30.94609 -71.054468)
		(width 0.08382)
		(layer "In9.Cu")
		(net "SMB_BMC_MM14_SCL")
	)
	(segment
		(start 24.645112 -78.603348)
		(end 24.75484 -78.338426)
		(width 0.08382)
		(layer "In9.Cu")
		(net "SMB_BMC_MM14_SCL")
	)
	(segment
		(start 27.801824 -73.86955)
		(end 28.131008 -73.86955)
		(width 0.08382)
		(layer "In9.Cu")
		(net "SMB_BMC_MM14_SCL")
	)
	(segment
		(start 32.603948 -64.500252)
		(end 32.603948 -61.226192)
		(width 0.08382)
		(layer "In9.Cu")
		(net "SMB_BMC_MM14_SCL")
	)
	(segment
		(start 32.25673 -67.18427)
		(end 32.895286 -66.545714)
		(width 0.08382)
		(layer "In9.Cu")
		(net "SMB_BMC_MM14_SCL")
	)
	(segment
		(start 24.22906 -79.0194)
		(end 24.645112 -78.603348)
		(width 0.08382)
		(layer "In9.Cu")
		(net "SMB_BMC_MM14_SCL")
	)
	(segment
		(start 32.27324 -65.19164)
		(end 32.27324 -64.83096)
		(width 0.08382)
		(layer "In9.Cu")
		(net "SMB_BMC_MM14_SCL")
	)
	(segment
		(start 30.94609 -69.16039)
		(end 32.25673 -67.84975)
		(width 0.08382)
		(layer "In9.Cu")
		(net "SMB_BMC_MM14_SCL")
	)
	(segment
		(start 32.96666 -55.546244)
		(end 35.1536 -53.359304)
		(width 0.08382)
		(layer "In9.Cu")
		(net "SMB_BMC_MM14_SCL")
	)
	(segment
		(start 32.895286 -65.813686)
		(end 32.27324 -65.19164)
		(width 0.08382)
		(layer "In9.Cu")
		(net "SMB_BMC_MM14_SCL")
	)
	(via
		(at 65.30213 -108.914184)
		(size 0.6604)
		(drill 0.3302)
		(layers "F.Cu" "B.Cu")
		(net "SMB_BMC_MM14_R1_SDA")
	)
	(segment
		(start 65.5955 -108.620814)
		(end 65.30213 -108.914184)
		(width 0.11684)
		(layer "B.Cu")
		(net "SMB_BMC_MM14_R1_SDA")
	)
	(segment
		(start 63.215012 -111.001302)
		(end 63.215012 -116.718588)
		(width 0.11684)
		(layer "B.Cu")
		(net "SMB_BMC_MM14_R1_SDA")
	)
	(segment
		(start 65.5955 -107.63885)
		(end 65.5955 -108.620814)
		(width 0.11684)
		(layer "B.Cu")
		(net "SMB_BMC_MM14_R1_SDA")
	)
	(segment
		(start 65.30213 -108.914184)
		(end 63.215012 -111.001302)
		(width 0.11684)
		(layer "B.Cu")
		(net "SMB_BMC_MM14_R1_SDA")
	)
	(segment
		(start 62.865 -117.0686)
		(end 62.865 -118.460012)
		(width 0.11684)
		(layer "B.Cu")
		(net "SMB_BMC_MM14_R1_SDA")
	)
	(segment
		(start 66.3956 -106.83875)
		(end 65.5955 -107.63885)
		(width 0.11684)
		(layer "B.Cu")
		(net "SMB_BMC_MM14_R1_SDA")
	)
	(segment
		(start 63.215012 -116.718588)
		(end 62.865 -117.0686)
		(width 0.11684)
		(layer "B.Cu")
		(net "SMB_BMC_MM14_R1_SDA")
	)
	(via
		(at 66.59626 -108.0262)
		(size 0.6604)
		(drill 0.3302)
		(layers "F.Cu" "B.Cu")
		(net "SMB_BMC_MM14_R1_SCL")
	)
	(segment
		(start 66.59626 -108.40466)
		(end 63.61684 -111.38408)
		(width 0.11684)
		(layer "B.Cu")
		(net "SMB_BMC_MM14_R1_SCL")
	)
	(segment
		(start 63.61684 -111.38408)
		(end 63.61684 -117.00764)
		(width 0.11684)
		(layer "B.Cu")
		(net "SMB_BMC_MM14_R1_SCL")
	)
	(segment
		(start 67.4116 -106.83875)
		(end 66.59626 -107.65409)
		(width 0.11684)
		(layer "B.Cu")
		(net "SMB_BMC_MM14_R1_SCL")
	)
	(segment
		(start 66.59626 -107.65409)
		(end 66.59626 -108.0262)
		(width 0.11684)
		(layer "B.Cu")
		(net "SMB_BMC_MM14_R1_SCL")
	)
	(segment
		(start 63.464948 -117.159532)
		(end 63.464948 -118.460012)
		(width 0.11684)
		(layer "B.Cu")
		(net "SMB_BMC_MM14_R1_SCL")
	)
	(segment
		(start 63.61684 -117.00764)
		(end 63.464948 -117.159532)
		(width 0.11684)
		(layer "B.Cu")
		(net "SMB_BMC_MM14_R1_SCL")
	)
	(segment
		(start 66.59626 -108.0262)
		(end 66.59626 -108.40466)
		(width 0.11684)
		(layer "B.Cu")
		(net "SMB_BMC_MM14_R1_SCL")
	)
	(via
		(at 38.10127 -46.983142)
		(size 0.508)
		(drill 0.254)
		(layers "F.Cu" "B.Cu")
		(net "SMB_BMC_MM13_SDA")
	)
	(via
		(at 35.2425 -115.443)
		(size 0.508)
		(drill 0.254)
		(layers "F.Cu" "B.Cu")
		(net "SMB_BMC_MM13_SDA")
	)
	(via
		(at 19.685 -80.2894)
		(size 0.508)
		(drill 0.254)
		(layers "F.Cu" "B.Cu")
		(net "SMB_BMC_MM13_SDA")
	)
	(segment
		(start 38.10127 -47.432976)
		(end 38.10127 -46.983142)
		(width 0.11684)
		(layer "B.Cu")
		(net "SMB_BMC_MM13_SDA")
	)
	(segment
		(start 39.530782 -48.026828)
		(end 39.117524 -48.026828)
		(width 0.11684)
		(layer "B.Cu")
		(net "SMB_BMC_MM13_SDA")
	)
	(segment
		(start 38.42385 -46.660562)
		(end 38.10127 -46.983142)
		(width 0.11684)
		(layer "B.Cu")
		(net "SMB_BMC_MM13_SDA")
	)
	(segment
		(start 38.261798 -47.914052)
		(end 38.261798 -47.593504)
		(width 0.11684)
		(layer "B.Cu")
		(net "SMB_BMC_MM13_SDA")
	)
	(segment
		(start 38.261798 -47.593504)
		(end 38.10127 -47.432976)
		(width 0.11684)
		(layer "B.Cu")
		(net "SMB_BMC_MM13_SDA")
	)
	(segment
		(start 38.42385 -46.25594)
		(end 38.42385 -46.660562)
		(width 0.11684)
		(layer "B.Cu")
		(net "SMB_BMC_MM13_SDA")
	)
	(segment
		(start 38.506146 -48.1584)
		(end 38.261798 -47.914052)
		(width 0.11684)
		(layer "B.Cu")
		(net "SMB_BMC_MM13_SDA")
	)
	(segment
		(start 39.117524 -48.026828)
		(end 38.985952 -48.1584)
		(width 0.11684)
		(layer "B.Cu")
		(net "SMB_BMC_MM13_SDA")
	)
	(segment
		(start 36.055046 -118.460012)
		(end 36.055046 -116.255546)
		(width 0.11684)
		(layer "B.Cu")
		(net "SMB_BMC_MM13_SDA")
	)
	(segment
		(start 38.985952 -48.1584)
		(end 38.506146 -48.1584)
		(width 0.11684)
		(layer "B.Cu")
		(net "SMB_BMC_MM13_SDA")
	)
	(segment
		(start 36.055046 -116.255546)
		(end 35.2425 -115.443)
		(width 0.11684)
		(layer "B.Cu")
		(net "SMB_BMC_MM13_SDA")
	)
	(segment
		(start 8.92302 -84.23402)
		(end 8.92302 -82.00898)
		(width 0.10668)
		(layer "In7.Cu")
		(net "SMB_BMC_MM13_SDA")
	)
	(segment
		(start 9.722612 -81.209388)
		(end 10.155428 -81.209388)
		(width 0.10668)
		(layer "In7.Cu")
		(net "SMB_BMC_MM13_SDA")
	)
	(segment
		(start 9.08812 -109.86516)
		(end 9.08812 -108.650786)
		(width 0.10668)
		(layer "In7.Cu")
		(net "SMB_BMC_MM13_SDA")
	)
	(segment
		(start 35.9664 -114.7191)
		(end 35.9664 -113.792254)
		(width 0.10668)
		(layer "In7.Cu")
		(net "SMB_BMC_MM13_SDA")
	)
	(segment
		(start 34.589466 -112.41532)
		(end 31.3055 -112.41532)
		(width 0.10668)
		(layer "In7.Cu")
		(net "SMB_BMC_MM13_SDA")
	)
	(segment
		(start 18.81632 -113.10112)
		(end 17.882616 -113.10112)
		(width 0.10668)
		(layer "In7.Cu")
		(net "SMB_BMC_MM13_SDA")
	)
	(segment
		(start 35.9664 -113.792254)
		(end 34.589466 -112.41532)
		(width 0.10668)
		(layer "In7.Cu")
		(net "SMB_BMC_MM13_SDA")
	)
	(segment
		(start 10.155428 -81.209388)
		(end 10.351516 -81.0133)
		(width 0.10668)
		(layer "In7.Cu")
		(net "SMB_BMC_MM13_SDA")
	)
	(segment
		(start 16.585184 -111.803688)
		(end 11.026648 -111.803688)
		(width 0.10668)
		(layer "In7.Cu")
		(net "SMB_BMC_MM13_SDA")
	)
	(segment
		(start 9.08812 -108.650786)
		(end 5.04444 -104.607106)
		(width 0.10668)
		(layer "In7.Cu")
		(net "SMB_BMC_MM13_SDA")
	)
	(segment
		(start 19.42338 -80.55102)
		(end 19.685 -80.2894)
		(width 0.10668)
		(layer "In7.Cu")
		(net "SMB_BMC_MM13_SDA")
	)
	(segment
		(start 14.04112 -79.6544)
		(end 14.935962 -78.759558)
		(width 0.10668)
		(layer "In7.Cu")
		(net "SMB_BMC_MM13_SDA")
	)
	(segment
		(start 11.026648 -111.803688)
		(end 9.08812 -109.86516)
		(width 0.10668)
		(layer "In7.Cu")
		(net "SMB_BMC_MM13_SDA")
	)
	(segment
		(start 8.92302 -82.00898)
		(end 9.722612 -81.209388)
		(width 0.10668)
		(layer "In7.Cu")
		(net "SMB_BMC_MM13_SDA")
	)
	(segment
		(start 9.525 -86.918546)
		(end 9.525 -84.836)
		(width 0.10668)
		(layer "In7.Cu")
		(net "SMB_BMC_MM13_SDA")
	)
	(segment
		(start 11.470132 -81.0133)
		(end 12.829032 -79.6544)
		(width 0.10668)
		(layer "In7.Cu")
		(net "SMB_BMC_MM13_SDA")
	)
	(segment
		(start 6.690106 -89.75344)
		(end 9.525 -86.918546)
		(width 0.10668)
		(layer "In7.Cu")
		(net "SMB_BMC_MM13_SDA")
	)
	(segment
		(start 14.935962 -78.759558)
		(end 16.38554 -78.759558)
		(width 0.10668)
		(layer "In7.Cu")
		(net "SMB_BMC_MM13_SDA")
	)
	(segment
		(start 10.351516 -81.0133)
		(end 11.470132 -81.0133)
		(width 0.10668)
		(layer "In7.Cu")
		(net "SMB_BMC_MM13_SDA")
	)
	(segment
		(start 9.525 -84.836)
		(end 8.92302 -84.23402)
		(width 0.10668)
		(layer "In7.Cu")
		(net "SMB_BMC_MM13_SDA")
	)
	(segment
		(start 28.17622 -115.5446)
		(end 21.2598 -115.5446)
		(width 0.10668)
		(layer "In7.Cu")
		(net "SMB_BMC_MM13_SDA")
	)
	(segment
		(start 35.2425 -115.443)
		(end 35.9664 -114.7191)
		(width 0.10668)
		(layer "In7.Cu")
		(net "SMB_BMC_MM13_SDA")
	)
	(segment
		(start 17.882616 -113.10112)
		(end 16.585184 -111.803688)
		(width 0.10668)
		(layer "In7.Cu")
		(net "SMB_BMC_MM13_SDA")
	)
	(segment
		(start 5.04444 -104.607106)
		(end 5.04444 -89.86012)
		(width 0.10668)
		(layer "In7.Cu")
		(net "SMB_BMC_MM13_SDA")
	)
	(segment
		(start 12.829032 -79.6544)
		(end 14.04112 -79.6544)
		(width 0.10668)
		(layer "In7.Cu")
		(net "SMB_BMC_MM13_SDA")
	)
	(segment
		(start 5.15112 -89.75344)
		(end 6.690106 -89.75344)
		(width 0.10668)
		(layer "In7.Cu")
		(net "SMB_BMC_MM13_SDA")
	)
	(segment
		(start 5.04444 -89.86012)
		(end 5.15112 -89.75344)
		(width 0.10668)
		(layer "In7.Cu")
		(net "SMB_BMC_MM13_SDA")
	)
	(segment
		(start 16.38554 -78.759558)
		(end 18.177002 -80.55102)
		(width 0.10668)
		(layer "In7.Cu")
		(net "SMB_BMC_MM13_SDA")
	)
	(segment
		(start 31.3055 -112.41532)
		(end 28.17622 -115.5446)
		(width 0.10668)
		(layer "In7.Cu")
		(net "SMB_BMC_MM13_SDA")
	)
	(segment
		(start 21.2598 -115.5446)
		(end 18.81632 -113.10112)
		(width 0.10668)
		(layer "In7.Cu")
		(net "SMB_BMC_MM13_SDA")
	)
	(segment
		(start 18.177002 -80.55102)
		(end 19.42338 -80.55102)
		(width 0.10668)
		(layer "In7.Cu")
		(net "SMB_BMC_MM13_SDA")
	)
	(segment
		(start 30.59303 -69.07149)
		(end 30.242256 -69.07149)
		(width 0.08382)
		(layer "In9.Cu")
		(net "SMB_BMC_MM13_SDA")
	)
	(segment
		(start 34.84118 -48.53686)
		(end 34.84118 -50.85207)
		(width 0.08382)
		(layer "In9.Cu")
		(net "SMB_BMC_MM13_SDA")
	)
	(segment
		(start 30.04566 -70.97014)
		(end 30.04312 -70.97268)
		(width 0.08382)
		(layer "In9.Cu")
		(net "SMB_BMC_MM13_SDA")
	)
	(segment
		(start 24.383238 -78.331822)
		(end 24.22398 -78.49108)
		(width 0.08382)
		(layer "In9.Cu")
		(net "SMB_BMC_MM13_SDA")
	)
	(segment
		(start 24.22398 -78.49108)
		(end 23.83028 -78.49108)
		(width 0.08382)
		(layer "In9.Cu")
		(net "SMB_BMC_MM13_SDA")
	)
	(segment
		(start 24.43734 -76.792074)
		(end 24.43734 -78.201266)
		(width 0.08382)
		(layer "In9.Cu")
		(net "SMB_BMC_MM13_SDA")
	)
	(segment
		(start 32.90062 -56.684418)
		(end 32.90062 -58.60034)
		(width 0.08382)
		(layer "In9.Cu")
		(net "SMB_BMC_MM13_SDA")
	)
	(segment
		(start 34.84118 -50.85207)
		(end 33.5915 -52.10175)
		(width 0.08382)
		(layer "In9.Cu")
		(net "SMB_BMC_MM13_SDA")
	)
	(segment
		(start 34.8488 -48.219614)
		(end 34.8488 -48.52924)
		(width 0.08382)
		(layer "In9.Cu")
		(net "SMB_BMC_MM13_SDA")
	)
	(segment
		(start 27.672284 -73.55713)
		(end 24.43734 -76.792074)
		(width 0.08382)
		(layer "In9.Cu")
		(net "SMB_BMC_MM13_SDA")
	)
	(segment
		(start 32.849566 -58.651394)
		(end 32.291528 -59.486546)
		(width 0.08382)
		(layer "In9.Cu")
		(net "SMB_BMC_MM13_SDA")
	)
	(segment
		(start 32.291528 -64.370712)
		(end 31.94431 -64.71793)
		(width 0.08382)
		(layer "In9.Cu")
		(net "SMB_BMC_MM13_SDA")
	)
	(segment
		(start 32.90062 -58.60034)
		(end 32.849566 -58.651394)
		(width 0.08382)
		(layer "In9.Cu")
		(net "SMB_BMC_MM13_SDA")
	)
	(segment
		(start 36.215574 -46.85284)
		(end 34.8488 -48.219614)
		(width 0.08382)
		(layer "In9.Cu")
		(net "SMB_BMC_MM13_SDA")
	)
	(segment
		(start 24.43734 -78.201266)
		(end 24.383238 -78.331822)
		(width 0.08382)
		(layer "In9.Cu")
		(net "SMB_BMC_MM13_SDA")
	)
	(segment
		(start 37.970968 -46.85284)
		(end 36.215574 -46.85284)
		(width 0.08382)
		(layer "In9.Cu")
		(net "SMB_BMC_MM13_SDA")
	)
	(segment
		(start 32.291528 -59.486546)
		(end 32.291528 -64.370712)
		(width 0.08382)
		(layer "In9.Cu")
		(net "SMB_BMC_MM13_SDA")
	)
	(segment
		(start 30.04312 -70.97268)
		(end 30.04312 -71.515478)
		(width 0.08382)
		(layer "In9.Cu")
		(net "SMB_BMC_MM13_SDA")
	)
	(segment
		(start 33.5915 -52.10175)
		(end 33.5915 -54.479444)
		(width 0.08382)
		(layer "In9.Cu")
		(net "SMB_BMC_MM13_SDA")
	)
	(segment
		(start 32.65424 -55.416704)
		(end 32.65424 -56.438038)
		(width 0.08382)
		(layer "In9.Cu")
		(net "SMB_BMC_MM13_SDA")
	)
	(segment
		(start 30.04566 -69.268086)
		(end 30.04566 -70.97014)
		(width 0.08382)
		(layer "In9.Cu")
		(net "SMB_BMC_MM13_SDA")
	)
	(segment
		(start 22.6568 -80.2894)
		(end 19.685 -80.2894)
		(width 0.08382)
		(layer "In9.Cu")
		(net "SMB_BMC_MM13_SDA")
	)
	(segment
		(start 23.46706 -79.47914)
		(end 22.6568 -80.2894)
		(width 0.08382)
		(layer "In9.Cu")
		(net "SMB_BMC_MM13_SDA")
	)
	(segment
		(start 23.83028 -78.49108)
		(end 23.46706 -78.8543)
		(width 0.08382)
		(layer "In9.Cu")
		(net "SMB_BMC_MM13_SDA")
	)
	(segment
		(start 30.04312 -71.515478)
		(end 28.001468 -73.55713)
		(width 0.08382)
		(layer "In9.Cu")
		(net "SMB_BMC_MM13_SDA")
	)
	(segment
		(start 33.5915 -54.479444)
		(end 32.65424 -55.416704)
		(width 0.08382)
		(layer "In9.Cu")
		(net "SMB_BMC_MM13_SDA")
	)
	(segment
		(start 28.001468 -73.55713)
		(end 27.672284 -73.55713)
		(width 0.08382)
		(layer "In9.Cu")
		(net "SMB_BMC_MM13_SDA")
	)
	(segment
		(start 30.242256 -69.07149)
		(end 30.04566 -69.268086)
		(width 0.08382)
		(layer "In9.Cu")
		(net "SMB_BMC_MM13_SDA")
	)
	(segment
		(start 32.65424 -56.438038)
		(end 32.90062 -56.684418)
		(width 0.08382)
		(layer "In9.Cu")
		(net "SMB_BMC_MM13_SDA")
	)
	(segment
		(start 31.94431 -67.72021)
		(end 30.59303 -69.07149)
		(width 0.08382)
		(layer "In9.Cu")
		(net "SMB_BMC_MM13_SDA")
	)
	(segment
		(start 38.10127 -46.983142)
		(end 37.970968 -46.85284)
		(width 0.08382)
		(layer "In9.Cu")
		(net "SMB_BMC_MM13_SDA")
	)
	(segment
		(start 23.46706 -78.8543)
		(end 23.46706 -79.47914)
		(width 0.08382)
		(layer "In9.Cu")
		(net "SMB_BMC_MM13_SDA")
	)
	(segment
		(start 34.8488 -48.52924)
		(end 34.84118 -48.53686)
		(width 0.08382)
		(layer "In9.Cu")
		(net "SMB_BMC_MM13_SDA")
	)
	(segment
		(start 31.94431 -64.71793)
		(end 31.94431 -67.72021)
		(width 0.08382)
		(layer "In9.Cu")
		(net "SMB_BMC_MM13_SDA")
	)
	(segment
		(start 37.77361 -46.378876)
		(end 37.723826 -46.378876)
		(width 0.11684)
		(layer "F.Cu")
		(net "SMB_BMC_MM13_SCL")
	)
	(segment
		(start 38.257226 -45.376084)
		(end 38.257226 -45.89526)
		(width 0.11684)
		(layer "F.Cu")
		(net "SMB_BMC_MM13_SCL")
	)
	(segment
		(start 38.257226 -45.89526)
		(end 37.77361 -46.378876)
		(width 0.11684)
		(layer "F.Cu")
		(net "SMB_BMC_MM13_SCL")
	)
	(via
		(at 35.2425 -114.681)
		(size 0.508)
		(drill 0.254)
		(layers "F.Cu" "B.Cu")
		(net "SMB_BMC_MM13_SCL")
	)
	(via
		(at 38.257226 -45.376084)
		(size 0.508)
		(drill 0.254)
		(layers "F.Cu" "B.Cu")
		(net "SMB_BMC_MM13_SCL")
	)
	(via
		(at 18.6436 -79.6798)
		(size 0.508)
		(drill 0.254)
		(layers "F.Cu" "B.Cu")
		(net "SMB_BMC_MM13_SCL")
	)
	(via
		(at 37.837618 -44.051982)
		(size 0.6604)
		(drill 0.3302)
		(layers "F.Cu" "B.Cu")
		(net "SMB_BMC_MM13_SCL")
	)
	(segment
		(start 36.5633 -117.1448)
		(end 36.5633 -116.0018)
		(width 0.11684)
		(layer "B.Cu")
		(net "SMB_BMC_MM13_SCL")
	)
	(segment
		(start 36.654994 -118.25986)
		(end 36.654994 -117.236494)
		(width 0.11684)
		(layer "B.Cu")
		(net "SMB_BMC_MM13_SCL")
	)
	(segment
		(start 36.654994 -117.236494)
		(end 36.5633 -117.1448)
		(width 0.11684)
		(layer "B.Cu")
		(net "SMB_BMC_MM13_SCL")
	)
	(segment
		(start 36.5633 -116.0018)
		(end 35.2425 -114.681)
		(width 0.11684)
		(layer "B.Cu")
		(net "SMB_BMC_MM13_SCL")
	)
	(segment
		(start 38.97503 -44.63288)
		(end 38.418516 -44.63288)
		(width 0.11684)
		(layer "B.Cu")
		(net "SMB_BMC_MM13_SCL")
	)
	(segment
		(start 38.257226 -45.140372)
		(end 38.257226 -45.376084)
		(width 0.11684)
		(layer "B.Cu")
		(net "SMB_BMC_MM13_SCL")
	)
	(segment
		(start 37.837618 -44.051982)
		(end 37.837618 -44.720764)
		(width 0.11684)
		(layer "B.Cu")
		(net "SMB_BMC_MM13_SCL")
	)
	(segment
		(start 37.837618 -44.720764)
		(end 38.257226 -45.140372)
		(width 0.11684)
		(layer "B.Cu")
		(net "SMB_BMC_MM13_SCL")
	)
	(segment
		(start 38.418516 -44.63288)
		(end 37.837618 -44.051982)
		(width 0.11684)
		(layer "B.Cu")
		(net "SMB_BMC_MM13_SCL")
	)
	(segment
		(start 5.6388 -87.6554)
		(end 4.70916 -88.58504)
		(width 0.10668)
		(layer "In7.Cu")
		(net "SMB_BMC_MM13_SCL")
	)
	(segment
		(start 20.962874 -115.9002)
		(end 28.519374 -115.9002)
		(width 0.10668)
		(layer "In7.Cu")
		(net "SMB_BMC_MM13_SCL")
	)
	(segment
		(start 18.136362 -80.036162)
		(end 16.507968 -78.407768)
		(width 0.10668)
		(layer "In7.Cu")
		(net "SMB_BMC_MM13_SCL")
	)
	(segment
		(start 10.88771 -112.138968)
		(end 16.446246 -112.138968)
		(width 0.10668)
		(layer "In7.Cu")
		(net "SMB_BMC_MM13_SCL")
	)
	(segment
		(start 18.287238 -80.036162)
		(end 18.136362 -80.036162)
		(width 0.10668)
		(layer "In7.Cu")
		(net "SMB_BMC_MM13_SCL")
	)
	(segment
		(start 8.450834 -87.51824)
		(end 8.31342 -87.655654)
		(width 0.10668)
		(layer "In7.Cu")
		(net "SMB_BMC_MM13_SCL")
	)
	(segment
		(start 18.6436 -79.6798)
		(end 18.287238 -80.036162)
		(width 0.10668)
		(layer "In7.Cu")
		(net "SMB_BMC_MM13_SCL")
	)
	(segment
		(start 35.5346 -114.3889)
		(end 35.2425 -114.681)
		(width 0.10668)
		(layer "In7.Cu")
		(net "SMB_BMC_MM13_SCL")
	)
	(segment
		(start 4.70916 -104.746044)
		(end 8.752586 -108.78947)
		(width 0.10668)
		(layer "In7.Cu")
		(net "SMB_BMC_MM13_SCL")
	)
	(segment
		(start 11.007598 -79.883)
		(end 10.01649 -80.874108)
		(width 0.10668)
		(layer "In7.Cu")
		(net "SMB_BMC_MM13_SCL")
	)
	(segment
		(start 17.819878 -113.5126)
		(end 18.575274 -113.5126)
		(width 0.10668)
		(layer "In7.Cu")
		(net "SMB_BMC_MM13_SCL")
	)
	(segment
		(start 13.565378 -78.407768)
		(end 12.090146 -79.883)
		(width 0.10668)
		(layer "In7.Cu")
		(net "SMB_BMC_MM13_SCL")
	)
	(segment
		(start 8.58774 -84.503514)
		(end 8.450834 -84.64042)
		(width 0.10668)
		(layer "In7.Cu")
		(net "SMB_BMC_MM13_SCL")
	)
	(segment
		(start 10.01649 -80.874108)
		(end 9.219692 -80.874108)
		(width 0.10668)
		(layer "In7.Cu")
		(net "SMB_BMC_MM13_SCL")
	)
	(segment
		(start 6.402832 -87.655654)
		(end 6.402578 -87.6554)
		(width 0.10668)
		(layer "In7.Cu")
		(net "SMB_BMC_MM13_SCL")
	)
	(segment
		(start 16.446246 -112.138968)
		(end 17.819878 -113.5126)
		(width 0.10668)
		(layer "In7.Cu")
		(net "SMB_BMC_MM13_SCL")
	)
	(segment
		(start 8.31342 -87.655654)
		(end 6.402832 -87.655654)
		(width 0.10668)
		(layer "In7.Cu")
		(net "SMB_BMC_MM13_SCL")
	)
	(segment
		(start 8.752586 -110.003844)
		(end 10.88771 -112.138968)
		(width 0.10668)
		(layer "In7.Cu")
		(net "SMB_BMC_MM13_SCL")
	)
	(segment
		(start 8.58774 -81.50606)
		(end 8.58774 -84.503514)
		(width 0.10668)
		(layer "In7.Cu")
		(net "SMB_BMC_MM13_SCL")
	)
	(segment
		(start 9.219692 -80.874108)
		(end 8.58774 -81.50606)
		(width 0.10668)
		(layer "In7.Cu")
		(net "SMB_BMC_MM13_SCL")
	)
	(segment
		(start 18.575274 -113.5126)
		(end 20.962874 -115.9002)
		(width 0.10668)
		(layer "In7.Cu")
		(net "SMB_BMC_MM13_SCL")
	)
	(segment
		(start 16.507968 -78.407768)
		(end 13.565378 -78.407768)
		(width 0.10668)
		(layer "In7.Cu")
		(net "SMB_BMC_MM13_SCL")
	)
	(segment
		(start 4.70916 -88.58504)
		(end 4.70916 -104.746044)
		(width 0.10668)
		(layer "In7.Cu")
		(net "SMB_BMC_MM13_SCL")
	)
	(segment
		(start 8.752586 -108.78947)
		(end 8.752586 -110.003844)
		(width 0.10668)
		(layer "In7.Cu")
		(net "SMB_BMC_MM13_SCL")
	)
	(segment
		(start 8.450834 -84.64042)
		(end 8.450834 -87.51824)
		(width 0.10668)
		(layer "In7.Cu")
		(net "SMB_BMC_MM13_SCL")
	)
	(segment
		(start 28.519374 -115.9002)
		(end 31.618174 -112.8014)
		(width 0.10668)
		(layer "In7.Cu")
		(net "SMB_BMC_MM13_SCL")
	)
	(segment
		(start 35.5346 -113.919)
		(end 35.5346 -114.3889)
		(width 0.10668)
		(layer "In7.Cu")
		(net "SMB_BMC_MM13_SCL")
	)
	(segment
		(start 12.090146 -79.883)
		(end 11.007598 -79.883)
		(width 0.10668)
		(layer "In7.Cu")
		(net "SMB_BMC_MM13_SCL")
	)
	(segment
		(start 31.618174 -112.8014)
		(end 34.417 -112.8014)
		(width 0.10668)
		(layer "In7.Cu")
		(net "SMB_BMC_MM13_SCL")
	)
	(segment
		(start 34.417 -112.8014)
		(end 35.5346 -113.919)
		(width 0.10668)
		(layer "In7.Cu")
		(net "SMB_BMC_MM13_SCL")
	)
	(segment
		(start 6.402578 -87.6554)
		(end 5.6388 -87.6554)
		(width 0.10668)
		(layer "In7.Cu")
		(net "SMB_BMC_MM13_SCL")
	)
	(segment
		(start 32.1818 -58.3692)
		(end 31.666688 -58.884312)
		(width 0.08382)
		(layer "In9.Cu")
		(net "SMB_BMC_MM13_SCL")
	)
	(segment
		(start 32.52343 -48.29683)
		(end 32.52343 -48.778668)
		(width 0.08382)
		(layer "In9.Cu")
		(net "SMB_BMC_MM13_SCL")
	)
	(segment
		(start 30.3784 -67.938396)
		(end 29.508196 -68.8086)
		(width 0.08382)
		(layer "In9.Cu")
		(net "SMB_BMC_MM13_SCL")
	)
	(segment
		(start 38.257226 -45.376084)
		(end 37.16147 -46.47184)
		(width 0.08382)
		(layer "In9.Cu")
		(net "SMB_BMC_MM13_SCL")
	)
	(segment
		(start 32.96666 -54.220364)
		(end 32.0294 -55.157624)
		(width 0.08382)
		(layer "In9.Cu")
		(net "SMB_BMC_MM13_SCL")
	)
	(segment
		(start 31.666688 -64.111632)
		(end 31.31947 -64.45885)
		(width 0.08382)
		(layer "In9.Cu")
		(net "SMB_BMC_MM13_SCL")
	)
	(segment
		(start 37.16147 -46.47184)
		(end 34.34842 -46.47184)
		(width 0.08382)
		(layer "In9.Cu")
		(net "SMB_BMC_MM13_SCL")
	)
	(segment
		(start 31.31947 -66.16573)
		(end 30.3784 -67.1068)
		(width 0.08382)
		(layer "In9.Cu")
		(net "SMB_BMC_MM13_SCL")
	)
	(segment
		(start 28.6766 -70.409054)
		(end 27.89809 -71.187564)
		(width 0.08382)
		(layer "In9.Cu")
		(net "SMB_BMC_MM13_SCL")
	)
	(segment
		(start 32.0294 -55.157624)
		(end 32.0294 -56.697118)
		(width 0.08382)
		(layer "In9.Cu")
		(net "SMB_BMC_MM13_SCL")
	)
	(segment
		(start 31.666688 -58.884312)
		(end 31.666688 -64.111632)
		(width 0.08382)
		(layer "In9.Cu")
		(net "SMB_BMC_MM13_SCL")
	)
	(segment
		(start 27.89809 -71.187564)
		(end 27.89809 -72.152764)
		(width 0.08382)
		(layer "In9.Cu")
		(net "SMB_BMC_MM13_SCL")
	)
	(segment
		(start 27.89809 -72.152764)
		(end 26.162254 -73.8886)
		(width 0.08382)
		(layer "In9.Cu")
		(net "SMB_BMC_MM13_SCL")
	)
	(segment
		(start 32.0294 -56.697118)
		(end 32.1818 -56.849518)
		(width 0.08382)
		(layer "In9.Cu")
		(net "SMB_BMC_MM13_SCL")
	)
	(segment
		(start 29.1084 -68.8086)
		(end 28.6766 -69.2404)
		(width 0.08382)
		(layer "In9.Cu")
		(net "SMB_BMC_MM13_SCL")
	)
	(segment
		(start 32.1818 -56.849518)
		(end 32.1818 -58.3692)
		(width 0.08382)
		(layer "In9.Cu")
		(net "SMB_BMC_MM13_SCL")
	)
	(segment
		(start 33.59658 -49.851818)
		(end 33.59658 -51.21275)
		(width 0.08382)
		(layer "In9.Cu")
		(net "SMB_BMC_MM13_SCL")
	)
	(segment
		(start 25.2984 -73.8886)
		(end 23.04034 -76.14666)
		(width 0.08382)
		(layer "In9.Cu")
		(net "SMB_BMC_MM13_SCL")
	)
	(segment
		(start 31.31947 -64.45885)
		(end 31.31947 -66.16573)
		(width 0.08382)
		(layer "In9.Cu")
		(net "SMB_BMC_MM13_SCL")
	)
	(segment
		(start 26.162254 -73.8886)
		(end 25.2984 -73.8886)
		(width 0.08382)
		(layer "In9.Cu")
		(net "SMB_BMC_MM13_SCL")
	)
	(segment
		(start 33.59658 -51.21275)
		(end 32.96666 -51.84267)
		(width 0.08382)
		(layer "In9.Cu")
		(net "SMB_BMC_MM13_SCL")
	)
	(segment
		(start 29.508196 -68.8086)
		(end 29.1084 -68.8086)
		(width 0.08382)
		(layer "In9.Cu")
		(net "SMB_BMC_MM13_SCL")
	)
	(segment
		(start 32.96666 -51.84267)
		(end 32.96666 -54.220364)
		(width 0.08382)
		(layer "In9.Cu")
		(net "SMB_BMC_MM13_SCL")
	)
	(segment
		(start 34.34842 -46.47184)
		(end 32.52343 -48.29683)
		(width 0.08382)
		(layer "In9.Cu")
		(net "SMB_BMC_MM13_SCL")
	)
	(segment
		(start 28.6766 -69.2404)
		(end 28.6766 -70.409054)
		(width 0.08382)
		(layer "In9.Cu")
		(net "SMB_BMC_MM13_SCL")
	)
	(segment
		(start 32.52343 -48.778668)
		(end 33.59658 -49.851818)
		(width 0.08382)
		(layer "In9.Cu")
		(net "SMB_BMC_MM13_SCL")
	)
	(segment
		(start 23.04034 -76.14666)
		(end 23.04034 -79.4639)
		(width 0.08382)
		(layer "In9.Cu")
		(net "SMB_BMC_MM13_SCL")
	)
	(segment
		(start 23.04034 -79.4639)
		(end 22.67204 -79.8322)
		(width 0.08382)
		(layer "In9.Cu")
		(net "SMB_BMC_MM13_SCL")
	)
	(segment
		(start 18.796 -79.8322)
		(end 18.6436 -79.6798)
		(width 0.08382)
		(layer "In9.Cu")
		(net "SMB_BMC_MM13_SCL")
	)
	(segment
		(start 22.67204 -79.8322)
		(end 18.796 -79.8322)
		(width 0.08382)
		(layer "In9.Cu")
		(net "SMB_BMC_MM13_SCL")
	)
	(segment
		(start 30.3784 -67.1068)
		(end 30.3784 -67.938396)
		(width 0.08382)
		(layer "In9.Cu")
		(net "SMB_BMC_MM13_SCL")
	)
	(segment
		(start 52.894992 -56.171338)
		(end 52.499768 -56.566562)
		(width 0.11684)
		(layer "F.Cu")
		(net "SMB_BMC_ALERT9_R_N")
	)
	(via
		(at 52.499768 -56.566562)
		(size 0.4572)
		(drill 0.254)
		(layers "F.Cu" "B.Cu")
		(net "SMB_BMC_ALERT9_R_N")
	)
	(segment
		(start 47.81804 -61.927994)
		(end 47.81804 -59.890914)
		(width 0.11684)
		(layer "B.Cu")
		(net "SMB_BMC_ALERT9_R_N")
	)
	(segment
		(start 48.912526 -58.796428)
		(end 48.912526 -58.693558)
		(width 0.11684)
		(layer "B.Cu")
		(net "SMB_BMC_ALERT9_R_N")
	)
	(segment
		(start 49.699926 -57.967118)
		(end 49.901856 -57.765188)
		(width 0.11684)
		(layer "B.Cu")
		(net "SMB_BMC_ALERT9_R_N")
	)
	(segment
		(start 47.907702 -62.73546)
		(end 47.907702 -62.017656)
		(width 0.11684)
		(layer "B.Cu")
		(net "SMB_BMC_ALERT9_R_N")
	)
	(segment
		(start 51.308 -56.82234)
		(end 51.308 -56.388254)
		(width 0.11684)
		(layer "B.Cu")
		(net "SMB_BMC_ALERT9_R_N")
	)
	(segment
		(start 51.308 -56.388254)
		(end 51.519582 -56.176672)
		(width 0.11684)
		(layer "B.Cu")
		(net "SMB_BMC_ALERT9_R_N")
	)
	(segment
		(start 49.033684 -58.5724)
		(end 49.519078 -58.5724)
		(width 0.11684)
		(layer "B.Cu")
		(net "SMB_BMC_ALERT9_R_N")
	)
	(segment
		(start 50.499518 -57.124854)
		(end 50.660554 -56.963818)
		(width 0.11684)
		(layer "B.Cu")
		(net "SMB_BMC_ALERT9_R_N")
	)
	(segment
		(start 51.166522 -56.963818)
		(end 51.308 -56.82234)
		(width 0.11684)
		(layer "B.Cu")
		(net "SMB_BMC_ALERT9_R_N")
	)
	(segment
		(start 48.393858 -63.044832)
		(end 48.217074 -63.044832)
		(width 0.11684)
		(layer "B.Cu")
		(net "SMB_BMC_ALERT9_R_N")
	)
	(segment
		(start 48.217074 -63.044832)
		(end 47.907702 -62.73546)
		(width 0.11684)
		(layer "B.Cu")
		(net "SMB_BMC_ALERT9_R_N")
	)
	(segment
		(start 49.901856 -57.765188)
		(end 50.28819 -57.765188)
		(width 0.11684)
		(layer "B.Cu")
		(net "SMB_BMC_ALERT9_R_N")
	)
	(segment
		(start 51.519582 -56.176672)
		(end 52.109878 -56.176672)
		(width 0.11684)
		(layer "B.Cu")
		(net "SMB_BMC_ALERT9_R_N")
	)
	(segment
		(start 52.109878 -56.176672)
		(end 52.499768 -56.566562)
		(width 0.11684)
		(layer "B.Cu")
		(net "SMB_BMC_ALERT9_R_N")
	)
	(segment
		(start 47.81804 -59.890914)
		(end 48.912526 -58.796428)
		(width 0.11684)
		(layer "B.Cu")
		(net "SMB_BMC_ALERT9_R_N")
	)
	(segment
		(start 50.660554 -56.963818)
		(end 51.166522 -56.963818)
		(width 0.11684)
		(layer "B.Cu")
		(net "SMB_BMC_ALERT9_R_N")
	)
	(segment
		(start 50.28819 -57.765188)
		(end 50.499518 -57.55386)
		(width 0.11684)
		(layer "B.Cu")
		(net "SMB_BMC_ALERT9_R_N")
	)
	(segment
		(start 48.895254 -63.546228)
		(end 48.393858 -63.044832)
		(width 0.11684)
		(layer "B.Cu")
		(net "SMB_BMC_ALERT9_R_N")
	)
	(segment
		(start 48.912526 -58.693558)
		(end 49.033684 -58.5724)
		(width 0.11684)
		(layer "B.Cu")
		(net "SMB_BMC_ALERT9_R_N")
	)
	(segment
		(start 49.699926 -58.391552)
		(end 49.699926 -57.967118)
		(width 0.11684)
		(layer "B.Cu")
		(net "SMB_BMC_ALERT9_R_N")
	)
	(segment
		(start 47.907702 -62.017656)
		(end 47.81804 -61.927994)
		(width 0.11684)
		(layer "B.Cu")
		(net "SMB_BMC_ALERT9_R_N")
	)
	(segment
		(start 50.499518 -57.55386)
		(end 50.499518 -57.124854)
		(width 0.11684)
		(layer "B.Cu")
		(net "SMB_BMC_ALERT9_R_N")
	)
	(segment
		(start 49.519078 -58.5724)
		(end 49.699926 -58.391552)
		(width 0.11684)
		(layer "B.Cu")
		(net "SMB_BMC_ALERT9_R_N")
	)
	(segment
		(start 17.464278 -91.191842)
		(end 17.859502 -91.587066)
		(width 0.11684)
		(layer "F.Cu")
		(net "SMB_BMC_ALERT9_R1_N")
	)
	(via
		(at 13.85062 -88.4428)
		(size 0.6604)
		(drill 0.3302)
		(layers "F.Cu" "B.Cu")
		(net "SMB_BMC_ALERT9_R1_N")
	)
	(via
		(at 17.464278 -91.191842)
		(size 0.4572)
		(drill 0.254)
		(layers "F.Cu" "B.Cu")
		(net "SMB_BMC_ALERT9_R1_N")
	)
	(segment
		(start 17.075658 -90.803222)
		(end 17.464278 -91.191842)
		(width 0.11684)
		(layer "B.Cu")
		(net "SMB_BMC_ALERT9_R1_N")
	)
	(segment
		(start 15.263876 -90.340942)
		(end 15.726156 -90.803222)
		(width 0.11684)
		(layer "B.Cu")
		(net "SMB_BMC_ALERT9_R1_N")
	)
	(segment
		(start 13.360654 -87.376)
		(end 13.85062 -87.865966)
		(width 0.11684)
		(layer "B.Cu")
		(net "SMB_BMC_ALERT9_R1_N")
	)
	(segment
		(start 14.8336 -89.281)
		(end 15.263876 -89.711276)
		(width 0.11684)
		(layer "B.Cu")
		(net "SMB_BMC_ALERT9_R1_N")
	)
	(segment
		(start 15.263876 -89.711276)
		(end 15.263876 -90.340942)
		(width 0.11684)
		(layer "B.Cu")
		(net "SMB_BMC_ALERT9_R1_N")
	)
	(segment
		(start 13.85062 -87.865966)
		(end 13.85062 -88.4428)
		(width 0.11684)
		(layer "B.Cu")
		(net "SMB_BMC_ALERT9_R1_N")
	)
	(segment
		(start 13.85062 -88.4428)
		(end 14.68882 -89.281)
		(width 0.11684)
		(layer "B.Cu")
		(net "SMB_BMC_ALERT9_R1_N")
	)
	(segment
		(start 14.68882 -89.281)
		(end 14.8336 -89.281)
		(width 0.11684)
		(layer "B.Cu")
		(net "SMB_BMC_ALERT9_R1_N")
	)
	(segment
		(start 12.71905 -87.376)
		(end 13.360654 -87.376)
		(width 0.11684)
		(layer "B.Cu")
		(net "SMB_BMC_ALERT9_R1_N")
	)
	(segment
		(start 15.726156 -90.803222)
		(end 17.075658 -90.803222)
		(width 0.11684)
		(layer "B.Cu")
		(net "SMB_BMC_ALERT9_R1_N")
	)
	(segment
		(start 41.775888 -43.155108)
		(end 42.356532 -43.155108)
		(width 0.11684)
		(layer "F.Cu")
		(net "SMB_BMC_ALERT4_R_N")
	)
	(segment
		(start 42.356532 -43.155108)
		(end 44.577508 -45.376084)
		(width 0.11684)
		(layer "F.Cu")
		(net "SMB_BMC_ALERT4_R_N")
	)
	(segment
		(start 41.11498 -42.4942)
		(end 40.920924 -42.4942)
		(width 0.11684)
		(layer "F.Cu")
		(net "SMB_BMC_ALERT4_R_N")
	)
	(segment
		(start 40.920924 -42.4942)
		(end 40.870124 -42.4434)
		(width 0.11684)
		(layer "F.Cu")
		(net "SMB_BMC_ALERT4_R_N")
	)
	(segment
		(start 45.299884 -45.376084)
		(end 45.695108 -45.771308)
		(width 0.11684)
		(layer "F.Cu")
		(net "SMB_BMC_ALERT4_R_N")
	)
	(segment
		(start 40.870124 -42.4434)
		(end 40.45585 -42.4434)
		(width 0.11684)
		(layer "F.Cu")
		(net "SMB_BMC_ALERT4_R_N")
	)
	(segment
		(start 44.577508 -45.376084)
		(end 45.299884 -45.376084)
		(width 0.11684)
		(layer "F.Cu")
		(net "SMB_BMC_ALERT4_R_N")
	)
	(segment
		(start 41.775888 -43.155108)
		(end 41.11498 -42.4942)
		(width 0.11684)
		(layer "F.Cu")
		(net "SMB_BMC_ALERT4_R_N")
	)
	(via
		(at 41.775888 -43.155108)
		(size 0.762)
		(drill 0.381)
		(layers "F.Cu" "B.Cu")
		(net "SMB_BMC_ALERT4_R_N")
	)
	(segment
		(start 13.80744 -87.903812)
		(end 13.80744 -88.08466)
		(width 0.11684)
		(layer "F.Cu")
		(net "SMB_BMC_ALERT4_R1_N")
	)
	(segment
		(start 13.335 -86.97595)
		(end 13.335 -87.431372)
		(width 0.11684)
		(layer "F.Cu")
		(net "SMB_BMC_ALERT4_R1_N")
	)
	(segment
		(start 12.71905 -86.36)
		(end 13.335 -86.97595)
		(width 0.11684)
		(layer "F.Cu")
		(net "SMB_BMC_ALERT4_R1_N")
	)
	(segment
		(start 15.864332 -89.591896)
		(end 16.259556 -89.98712)
		(width 0.11684)
		(layer "F.Cu")
		(net "SMB_BMC_ALERT4_R1_N")
	)
	(segment
		(start 13.335 -87.431372)
		(end 13.80744 -87.903812)
		(width 0.11684)
		(layer "F.Cu")
		(net "SMB_BMC_ALERT4_R1_N")
	)
	(segment
		(start 15.314676 -89.591896)
		(end 15.864332 -89.591896)
		(width 0.11684)
		(layer "F.Cu")
		(net "SMB_BMC_ALERT4_R1_N")
	)
	(segment
		(start 13.80744 -88.08466)
		(end 15.314676 -89.591896)
		(width 0.11684)
		(layer "F.Cu")
		(net "SMB_BMC_ALERT4_R1_N")
	)
	(segment
		(start 40.743124 -41.5036)
		(end 40.30345 -41.5036)
		(width 0.11684)
		(layer "F.Cu")
		(net "SMB_BMC_ALERT3_R_N")
	)
	(segment
		(start 42.468038 -41.869868)
		(end 41.905428 -41.869868)
		(width 0.11684)
		(layer "F.Cu")
		(net "SMB_BMC_ALERT3_R_N")
	)
	(segment
		(start 41.112186 -41.872662)
		(end 40.743124 -41.5036)
		(width 0.11684)
		(layer "F.Cu")
		(net "SMB_BMC_ALERT3_R_N")
	)
	(segment
		(start 41.905428 -41.869868)
		(end 41.295828 -41.869868)
		(width 0.11684)
		(layer "F.Cu")
		(net "SMB_BMC_ALERT3_R_N")
	)
	(segment
		(start 41.293034 -41.872662)
		(end 41.112186 -41.872662)
		(width 0.11684)
		(layer "F.Cu")
		(net "SMB_BMC_ALERT3_R_N")
	)
	(segment
		(start 42.963084 -42.364914)
		(end 42.468038 -41.869868)
		(width 0.11684)
		(layer "F.Cu")
		(net "SMB_BMC_ALERT3_R_N")
	)
	(segment
		(start 41.295828 -41.869868)
		(end 41.293034 -41.872662)
		(width 0.11684)
		(layer "F.Cu")
		(net "SMB_BMC_ALERT3_R_N")
	)
	(segment
		(start 44.895008 -44.971208)
		(end 42.963084 -43.039284)
		(width 0.11684)
		(layer "F.Cu")
		(net "SMB_BMC_ALERT3_R_N")
	)
	(segment
		(start 42.963084 -43.039284)
		(end 42.963084 -42.364914)
		(width 0.11684)
		(layer "F.Cu")
		(net "SMB_BMC_ALERT3_R_N")
	)
	(via
		(at 41.905428 -41.869868)
		(size 0.762)
		(drill 0.381)
		(layers "F.Cu" "B.Cu")
		(net "SMB_BMC_ALERT3_R_N")
	)
	(segment
		(start 13.133324 -86.20887)
		(end 13.60424 -86.679786)
		(width 0.11684)
		(layer "F.Cu")
		(net "SMB_BMC_ALERT3_R1_N")
	)
	(segment
		(start 13.60424 -86.679786)
		(end 13.60424 -87.319612)
		(width 0.11684)
		(layer "F.Cu")
		(net "SMB_BMC_ALERT3_R1_N")
	)
	(segment
		(start 13.133324 -85.758274)
		(end 13.133324 -86.20887)
		(width 0.11684)
		(layer "F.Cu")
		(net "SMB_BMC_ALERT3_R1_N")
	)
	(segment
		(start 13.60424 -87.319612)
		(end 14.08684 -87.802212)
		(width 0.11684)
		(layer "F.Cu")
		(net "SMB_BMC_ALERT3_R1_N")
	)
	(segment
		(start 12.71905 -85.344)
		(end 13.133324 -85.758274)
		(width 0.11684)
		(layer "F.Cu")
		(net "SMB_BMC_ALERT3_R1_N")
	)
	(segment
		(start 14.08684 -87.92464)
		(end 15.12697 -88.96477)
		(width 0.11684)
		(layer "F.Cu")
		(net "SMB_BMC_ALERT3_R1_N")
	)
	(segment
		(start 15.12697 -88.96477)
		(end 15.459456 -89.18702)
		(width 0.11684)
		(layer "F.Cu")
		(net "SMB_BMC_ALERT3_R1_N")
	)
	(segment
		(start 14.08684 -87.802212)
		(end 14.08684 -87.92464)
		(width 0.11684)
		(layer "F.Cu")
		(net "SMB_BMC_ALERT3_R1_N")
	)
	(segment
		(start 52.094892 -55.371238)
		(end 51.699668 -55.766462)
		(width 0.11684)
		(layer "F.Cu")
		(net "SMB_BMC_ALERT10_R_N")
	)
	(via
		(at 51.699668 -55.766462)
		(size 0.4572)
		(drill 0.254)
		(layers "F.Cu" "B.Cu")
		(net "SMB_BMC_ALERT10_R_N")
	)
	(segment
		(start 50.494946 -56.73598)
		(end 50.267108 -56.963818)
		(width 0.11684)
		(layer "B.Cu")
		(net "SMB_BMC_ALERT10_R_N")
	)
	(segment
		(start 51.232054 -56.155082)
		(end 50.730404 -56.155082)
		(width 0.11684)
		(layer "B.Cu")
		(net "SMB_BMC_ALERT10_R_N")
	)
	(segment
		(start 48.6664 -58.14314)
		(end 48.6664 -58.733436)
		(width 0.11684)
		(layer "B.Cu")
		(net "SMB_BMC_ALERT10_R_N")
	)
	(segment
		(start 47.4218 -62.092332)
		(end 47.511462 -62.181994)
		(width 0.11684)
		(layer "B.Cu")
		(net "SMB_BMC_ALERT10_R_N")
	)
	(segment
		(start 47.4218 -59.978036)
		(end 47.4218 -62.092332)
		(width 0.11684)
		(layer "B.Cu")
		(net "SMB_BMC_ALERT10_R_N")
	)
	(segment
		(start 47.511462 -62.181994)
		(end 47.511462 -62.899798)
		(width 0.11684)
		(layer "B.Cu")
		(net "SMB_BMC_ALERT10_R_N")
	)
	(segment
		(start 50.267108 -56.963818)
		(end 49.814226 -56.963818)
		(width 0.11684)
		(layer "B.Cu")
		(net "SMB_BMC_ALERT10_R_N")
	)
	(segment
		(start 47.511462 -62.899798)
		(end 47.879 -63.267336)
		(width 0.11684)
		(layer "B.Cu")
		(net "SMB_BMC_ALERT10_R_N")
	)
	(segment
		(start 50.730404 -56.155082)
		(end 50.494946 -56.39054)
		(width 0.11684)
		(layer "B.Cu")
		(net "SMB_BMC_ALERT10_R_N")
	)
	(segment
		(start 49.054512 -57.755028)
		(end 48.6664 -58.14314)
		(width 0.11684)
		(layer "B.Cu")
		(net "SMB_BMC_ALERT10_R_N")
	)
	(segment
		(start 49.699926 -57.078118)
		(end 49.699926 -57.582054)
		(width 0.11684)
		(layer "B.Cu")
		(net "SMB_BMC_ALERT10_R_N")
	)
	(segment
		(start 51.507898 -55.958232)
		(end 51.428904 -55.958232)
		(width 0.11684)
		(layer "B.Cu")
		(net "SMB_BMC_ALERT10_R_N")
	)
	(segment
		(start 50.494946 -56.39054)
		(end 50.494946 -56.73598)
		(width 0.11684)
		(layer "B.Cu")
		(net "SMB_BMC_ALERT10_R_N")
	)
	(segment
		(start 51.428904 -55.958232)
		(end 51.232054 -56.155082)
		(width 0.11684)
		(layer "B.Cu")
		(net "SMB_BMC_ALERT10_R_N")
	)
	(segment
		(start 48.6664 -58.733436)
		(end 47.4218 -59.978036)
		(width 0.11684)
		(layer "B.Cu")
		(net "SMB_BMC_ALERT10_R_N")
	)
	(segment
		(start 49.814226 -56.963818)
		(end 49.699926 -57.078118)
		(width 0.11684)
		(layer "B.Cu")
		(net "SMB_BMC_ALERT10_R_N")
	)
	(segment
		(start 49.526952 -57.755028)
		(end 49.054512 -57.755028)
		(width 0.11684)
		(layer "B.Cu")
		(net "SMB_BMC_ALERT10_R_N")
	)
	(segment
		(start 47.879 -63.267336)
		(end 47.879 -63.54445)
		(width 0.11684)
		(layer "B.Cu")
		(net "SMB_BMC_ALERT10_R_N")
	)
	(segment
		(start 49.699926 -57.582054)
		(end 49.526952 -57.755028)
		(width 0.11684)
		(layer "B.Cu")
		(net "SMB_BMC_ALERT10_R_N")
	)
	(segment
		(start 51.699668 -55.766462)
		(end 51.507898 -55.958232)
		(width 0.11684)
		(layer "B.Cu")
		(net "SMB_BMC_ALERT10_R_N")
	)
	(segment
		(start 18.264124 -91.991942)
		(end 18.659348 -92.387166)
		(width 0.11684)
		(layer "F.Cu")
		(net "SMB_BMC_ALERT10_R1_N")
	)
	(via
		(at 15.1384 -92.2274)
		(size 0.6604)
		(drill 0.3302)
		(layers "F.Cu" "B.Cu")
		(net "SMB_BMC_ALERT10_R1_N")
	)
	(via
		(at 18.264124 -91.991942)
		(size 0.4572)
		(drill 0.254)
		(layers "F.Cu" "B.Cu")
		(net "SMB_BMC_ALERT10_R1_N")
	)
	(segment
		(start 18.1864 -93.4466)
		(end 18.669 -92.964)
		(width 0.11684)
		(layer "B.Cu")
		(net "SMB_BMC_ALERT10_R1_N")
	)
	(segment
		(start 18.669 -92.396818)
		(end 18.264124 -91.991942)
		(width 0.11684)
		(layer "B.Cu")
		(net "SMB_BMC_ALERT10_R1_N")
	)
	(segment
		(start 13.335 -93.87205)
		(end 13.335 -93.598746)
		(width 0.11684)
		(layer "B.Cu")
		(net "SMB_BMC_ALERT10_R1_N")
	)
	(segment
		(start 15.7988 -92.2274)
		(end 17.018 -93.4466)
		(width 0.11684)
		(layer "B.Cu")
		(net "SMB_BMC_ALERT10_R1_N")
	)
	(segment
		(start 12.71905 -94.488)
		(end 13.335 -93.87205)
		(width 0.11684)
		(layer "B.Cu")
		(net "SMB_BMC_ALERT10_R1_N")
	)
	(segment
		(start 13.335 -93.598746)
		(end 14.706346 -92.2274)
		(width 0.11684)
		(layer "B.Cu")
		(net "SMB_BMC_ALERT10_R1_N")
	)
	(segment
		(start 18.669 -92.964)
		(end 18.669 -92.396818)
		(width 0.11684)
		(layer "B.Cu")
		(net "SMB_BMC_ALERT10_R1_N")
	)
	(segment
		(start 17.018 -93.4466)
		(end 18.1864 -93.4466)
		(width 0.11684)
		(layer "B.Cu")
		(net "SMB_BMC_ALERT10_R1_N")
	)
	(segment
		(start 14.706346 -92.2274)
		(end 15.1384 -92.2274)
		(width 0.11684)
		(layer "B.Cu")
		(net "SMB_BMC_ALERT10_R1_N")
	)
	(segment
		(start 15.1384 -92.2274)
		(end 15.7988 -92.2274)
		(width 0.11684)
		(layer "B.Cu")
		(net "SMB_BMC_ALERT10_R1_N")
	)
	(segment
		(start 9.35355 -80.867504)
		(end 8.7884 -81.432654)
		(width 0.11684)
		(layer "F.Cu")
		(net "RST_SRST_PLD_BMC_BUF_N")
	)
	(segment
		(start 8.7884 -81.7372)
		(end 8.951214 -81.900014)
		(width 0.11684)
		(layer "F.Cu")
		(net "RST_SRST_PLD_BMC_BUF_N")
	)
	(segment
		(start 9.35355 -80.5434)
		(end 9.35355 -80.867504)
		(width 0.11684)
		(layer "F.Cu")
		(net "RST_SRST_PLD_BMC_BUF_N")
	)
	(segment
		(start 8.951214 -81.900014)
		(end 9.07796 -81.900014)
		(width 0.11684)
		(layer "F.Cu")
		(net "RST_SRST_PLD_BMC_BUF_N")
	)
	(segment
		(start 8.7884 -81.432654)
		(end 8.7884 -81.7372)
		(width 0.11684)
		(layer "F.Cu")
		(net "RST_SRST_PLD_BMC_BUF_N")
	)
	(segment
		(start 37.1856 -90.551)
		(end 37.1856 -91.645994)
		(width 0.11684)
		(layer "F.Cu")
		(net "RST_SPI_PCH_FLASH_R1_N")
	)
	(segment
		(start 37.1856 -91.645994)
		(end 37.595302 -92.055696)
		(width 0.11684)
		(layer "F.Cu")
		(net "RST_SPI_PCH_FLASH_R1_N")
	)
	(segment
		(start 38.862 -88.5444)
		(end 38.3032 -89.1032)
		(width 0.11684)
		(layer "F.Cu")
		(net "RST_SPI_PCH_FLASH_R1_N")
	)
	(segment
		(start 40.11295 -89.027)
		(end 39.63035 -88.5444)
		(width 0.11684)
		(layer "F.Cu")
		(net "RST_SPI_PCH_FLASH_R1_N")
	)
	(segment
		(start 37.595302 -92.055696)
		(end 37.595302 -92.760038)
		(width 0.11684)
		(layer "F.Cu")
		(net "RST_SPI_PCH_FLASH_R1_N")
	)
	(segment
		(start 38.3032 -89.1032)
		(end 38.3032 -89.4334)
		(width 0.11684)
		(layer "F.Cu")
		(net "RST_SPI_PCH_FLASH_R1_N")
	)
	(segment
		(start 38.3032 -89.4334)
		(end 37.1856 -90.551)
		(width 0.11684)
		(layer "F.Cu")
		(net "RST_SPI_PCH_FLASH_R1_N")
	)
	(segment
		(start 39.63035 -88.5444)
		(end 38.862 -88.5444)
		(width 0.11684)
		(layer "F.Cu")
		(net "RST_SPI_PCH_FLASH_R1_N")
	)
	(via
		(at 38.862 -88.5444)
		(size 0.762)
		(drill 0.381)
		(layers "F.Cu" "B.Cu")
		(net "RST_SPI_PCH_FLASH_R1_N")
	)
	(segment
		(start 21.209 -69.221604)
		(end 20.77339 -68.785994)
		(width 0.11684)
		(layer "F.Cu")
		(net "RST_SPI_BMC_FLASH_R2_N")
	)
	(segment
		(start 23.06574 -75.848718)
		(end 22.289262 -75.07224)
		(width 0.11684)
		(layer "F.Cu")
		(net "RST_SPI_BMC_FLASH_R2_N")
	)
	(segment
		(start 20.580604 -68.43395)
		(end 20.193 -68.43395)
		(width 0.11684)
		(layer "F.Cu")
		(net "RST_SPI_BMC_FLASH_R2_N")
	)
	(segment
		(start 20.77339 -68.785994)
		(end 20.77339 -68.626736)
		(width 0.11684)
		(layer "F.Cu")
		(net "RST_SPI_BMC_FLASH_R2_N")
	)
	(segment
		(start 20.475194 -71.887588)
		(end 20.966176 -70.70217)
		(width 0.11684)
		(layer "F.Cu")
		(net "RST_SPI_BMC_FLASH_R2_N")
	)
	(segment
		(start 21.209 -69.23405)
		(end 21.209 -69.221604)
		(width 0.11684)
		(layer "F.Cu")
		(net "RST_SPI_BMC_FLASH_R2_N")
	)
	(segment
		(start 22.289262 -75.07224)
		(end 20.968462 -75.07224)
		(width 0.11684)
		(layer "F.Cu")
		(net "RST_SPI_BMC_FLASH_R2_N")
	)
	(segment
		(start 21.999956 -80.080866)
		(end 23.06574 -79.015082)
		(width 0.11684)
		(layer "F.Cu")
		(net "RST_SPI_BMC_FLASH_R2_N")
	)
	(segment
		(start 20.966176 -70.70217)
		(end 21.209 -70.459346)
		(width 0.11684)
		(layer "F.Cu")
		(net "RST_SPI_BMC_FLASH_R2_N")
	)
	(segment
		(start 21.209 -70.459346)
		(end 21.209 -69.23405)
		(width 0.11684)
		(layer "F.Cu")
		(net "RST_SPI_BMC_FLASH_R2_N")
	)
	(segment
		(start 21.999956 -80.910176)
		(end 21.999956 -80.080866)
		(width 0.11684)
		(layer "F.Cu")
		(net "RST_SPI_BMC_FLASH_R2_N")
	)
	(segment
		(start 20.475194 -74.578972)
		(end 20.475194 -71.887588)
		(width 0.11684)
		(layer "F.Cu")
		(net "RST_SPI_BMC_FLASH_R2_N")
	)
	(segment
		(start 23.06574 -79.015082)
		(end 23.06574 -75.848718)
		(width 0.11684)
		(layer "F.Cu")
		(net "RST_SPI_BMC_FLASH_R2_N")
	)
	(segment
		(start 20.77339 -68.626736)
		(end 20.580604 -68.43395)
		(width 0.11684)
		(layer "F.Cu")
		(net "RST_SPI_BMC_FLASH_R2_N")
	)
	(segment
		(start 20.968462 -75.07224)
		(end 20.475194 -74.578972)
		(width 0.11684)
		(layer "F.Cu")
		(net "RST_SPI_BMC_FLASH_R2_N")
	)
	(segment
		(start 20.871434 -74.414634)
		(end 21.1328 -74.676)
		(width 0.11684)
		(layer "F.Cu")
		(net "RST_SPI_BMC_FLASH_R1_N")
	)
	(segment
		(start 22.225 -69.23405)
		(end 22.225 -70.0786)
		(width 0.11684)
		(layer "F.Cu")
		(net "RST_SPI_BMC_FLASH_R1_N")
	)
	(segment
		(start 22.225 -70.0786)
		(end 21.264626 -71.038974)
		(width 0.11684)
		(layer "F.Cu")
		(net "RST_SPI_BMC_FLASH_R1_N")
	)
	(segment
		(start 22.4536 -74.676)
		(end 23.46198 -75.68438)
		(width 0.11684)
		(layer "F.Cu")
		(net "RST_SPI_BMC_FLASH_R1_N")
	)
	(segment
		(start 23.46198 -79.17942)
		(end 22.500082 -80.141318)
		(width 0.11684)
		(layer "F.Cu")
		(net "RST_SPI_BMC_FLASH_R1_N")
	)
	(segment
		(start 22.500082 -80.141318)
		(end 22.500082 -80.910176)
		(width 0.11684)
		(layer "F.Cu")
		(net "RST_SPI_BMC_FLASH_R1_N")
	)
	(segment
		(start 20.871434 -71.988172)
		(end 20.871434 -74.414634)
		(width 0.11684)
		(layer "F.Cu")
		(net "RST_SPI_BMC_FLASH_R1_N")
	)
	(segment
		(start 23.46198 -75.68438)
		(end 23.46198 -79.17942)
		(width 0.11684)
		(layer "F.Cu")
		(net "RST_SPI_BMC_FLASH_R1_N")
	)
	(segment
		(start 21.1328 -74.676)
		(end 22.4536 -74.676)
		(width 0.11684)
		(layer "F.Cu")
		(net "RST_SPI_BMC_FLASH_R1_N")
	)
	(segment
		(start 21.264626 -71.038974)
		(end 20.871434 -71.988172)
		(width 0.11684)
		(layer "F.Cu")
		(net "RST_SPI_BMC_FLASH_R1_N")
	)
	(segment
		(start 13.4112 -88.264746)
		(end 14.435836 -89.289382)
		(width 0.11684)
		(layer "F.Cu")
		(net "RST_SGPIO_RESET_R_N")
	)
	(segment
		(start 14.923262 -90.786966)
		(end 15.459456 -90.786966)
		(width 0.11684)
		(layer "F.Cu")
		(net "RST_SGPIO_RESET_R_N")
	)
	(segment
		(start 14.435836 -89.289382)
		(end 14.435836 -90.29954)
		(width 0.11684)
		(layer "F.Cu")
		(net "RST_SGPIO_RESET_R_N")
	)
	(segment
		(start 13.4112 -88.06815)
		(end 13.4112 -88.264746)
		(width 0.11684)
		(layer "F.Cu")
		(net "RST_SGPIO_RESET_R_N")
	)
	(segment
		(start 12.71905 -87.376)
		(end 13.4112 -88.06815)
		(width 0.11684)
		(layer "F.Cu")
		(net "RST_SGPIO_RESET_R_N")
	)
	(segment
		(start 14.435836 -90.29954)
		(end 14.923262 -90.786966)
		(width 0.11684)
		(layer "F.Cu")
		(net "RST_SGPIO_RESET_R_N")
	)
	(segment
		(start 17.4752 -85.013546)
		(end 18.7198 -86.258146)
		(width 0.11684)
		(layer "F.Cu")
		(net "RST_EXTRST_R_N")
	)
	(segment
		(start 17.4752 -84.16925)
		(end 17.4752 -85.013546)
		(width 0.11684)
		(layer "F.Cu")
		(net "RST_EXTRST_R_N")
	)
	(segment
		(start 18.7198 -86.258146)
		(end 18.7198 -86.847426)
		(width 0.11684)
		(layer "F.Cu")
		(net "RST_EXTRST_R_N")
	)
	(segment
		(start 18.7198 -86.847426)
		(end 19.459448 -87.587074)
		(width 0.11684)
		(layer "F.Cu")
		(net "RST_EXTRST_R_N")
	)
	(segment
		(start 15.5194 -81.8134)
		(end 14.478 -80.772)
		(width 0.11684)
		(layer "F.Cu")
		(net "RST_EXTRST_N")
	)
	(segment
		(start 53.76545 -99.2886)
		(end 54.229 -98.82505)
		(width 0.11684)
		(layer "F.Cu")
		(net "RST_EXTRST_N")
	)
	(segment
		(start 14.478 -80.772)
		(end 14.3764 -80.772)
		(width 0.11684)
		(layer "F.Cu")
		(net "RST_EXTRST_N")
	)
	(segment
		(start 16.637 -82.53095)
		(end 16.637 -82.270346)
		(width 0.11684)
		(layer "F.Cu")
		(net "RST_EXTRST_N")
	)
	(segment
		(start 17.4752 -83.36915)
		(end 16.637 -82.53095)
		(width 0.11684)
		(layer "F.Cu")
		(net "RST_EXTRST_N")
	)
	(segment
		(start 57.8358 -38.5826)
		(end 58.0898 -38.8366)
		(width 0.11684)
		(layer "F.Cu")
		(net "RST_EXTRST_N")
	)
	(segment
		(start 35.5854 -98.4758)
		(end 37.439346 -98.4758)
		(width 0.11684)
		(layer "F.Cu")
		(net "RST_EXTRST_N")
	)
	(segment
		(start 58.0898 -39.776654)
		(end 57.695084 -40.17137)
		(width 0.11684)
		(layer "F.Cu")
		(net "RST_EXTRST_N")
	)
	(segment
		(start 39.166546 -100.203)
		(end 48.716946 -100.203)
		(width 0.11684)
		(layer "F.Cu")
		(net "RST_EXTRST_N")
	)
	(segment
		(start 33.41116 -100.25126)
		(end 33.80994 -100.25126)
		(width 0.11684)
		(layer "F.Cu")
		(net "RST_EXTRST_N")
	)
	(segment
		(start 49.036986 -99.88296)
		(end 50.45964 -99.88296)
		(width 0.11684)
		(layer "F.Cu")
		(net "RST_EXTRST_N")
	)
	(segment
		(start 16.180054 -81.8134)
		(end 15.5194 -81.8134)
		(width 0.11684)
		(layer "F.Cu")
		(net "RST_EXTRST_N")
	)
	(segment
		(start 51.054 -99.2886)
		(end 53.76545 -99.2886)
		(width 0.11684)
		(layer "F.Cu")
		(net "RST_EXTRST_N")
	)
	(segment
		(start 50.45964 -99.88296)
		(end 51.054 -99.2886)
		(width 0.11684)
		(layer "F.Cu")
		(net "RST_EXTRST_N")
	)
	(segment
		(start 59.311794 -36.317682)
		(end 58.994548 -37.083238)
		(width 0.11684)
		(layer "F.Cu")
		(net "RST_EXTRST_N")
	)
	(segment
		(start 37.439346 -98.4758)
		(end 39.166546 -100.203)
		(width 0.11684)
		(layer "F.Cu")
		(net "RST_EXTRST_N")
	)
	(segment
		(start 59.311794 -35.088576)
		(end 59.311794 -36.317682)
		(width 0.11684)
		(layer "F.Cu")
		(net "RST_EXTRST_N")
	)
	(segment
		(start 16.637 -82.270346)
		(end 16.180054 -81.8134)
		(width 0.11684)
		(layer "F.Cu")
		(net "RST_EXTRST_N")
	)
	(segment
		(start 33.80994 -100.25126)
		(end 35.5854 -98.4758)
		(width 0.11684)
		(layer "F.Cu")
		(net "RST_EXTRST_N")
	)
	(segment
		(start 58.994548 -37.083238)
		(end 57.8358 -38.241986)
		(width 0.11684)
		(layer "F.Cu")
		(net "RST_EXTRST_N")
	)
	(segment
		(start 57.8358 -38.241986)
		(end 57.8358 -38.5826)
		(width 0.11684)
		(layer "F.Cu")
		(net "RST_EXTRST_N")
	)
	(segment
		(start 48.716946 -100.203)
		(end 49.036986 -99.88296)
		(width 0.11684)
		(layer "F.Cu")
		(net "RST_EXTRST_N")
	)
	(segment
		(start 58.0898 -38.8366)
		(end 58.0898 -39.776654)
		(width 0.11684)
		(layer "F.Cu")
		(net "RST_EXTRST_N")
	)
	(via
		(at 57.8358 -38.5826)
		(size 0.508)
		(drill 0.254)
		(layers "F.Cu" "B.Cu")
		(net "RST_EXTRST_N")
	)
	(via
		(at 23.094442 -74.55408)
		(size 0.508)
		(drill 0.254)
		(layers "F.Cu" "B.Cu")
		(net "RST_EXTRST_N")
	)
	(via
		(at 59.311794 -36.317682)
		(size 0.762)
		(drill 0.381)
		(layers "F.Cu" "B.Cu")
		(net "RST_EXTRST_N")
	)
	(via
		(at 14.3764 -80.772)
		(size 0.508)
		(drill 0.254)
		(layers "F.Cu" "B.Cu")
		(net "RST_EXTRST_N")
	)
	(via
		(at 33.41116 -100.25126)
		(size 0.508)
		(drill 0.254)
		(layers "F.Cu" "B.Cu")
		(net "RST_EXTRST_N")
	)
	(segment
		(start 22.860762 -74.3204)
		(end 16.078454 -74.3204)
		(width 0.11684)
		(layer "B.Cu")
		(net "RST_EXTRST_N")
	)
	(segment
		(start 23.094442 -74.55408)
		(end 22.860762 -74.3204)
		(width 0.11684)
		(layer "B.Cu")
		(net "RST_EXTRST_N")
	)
	(segment
		(start 14.816836 -78.807564)
		(end 14.816836 -80.331564)
		(width 0.11684)
		(layer "B.Cu")
		(net "RST_EXTRST_N")
	)
	(segment
		(start 15.24 -75.158854)
		(end 15.24 -78.3844)
		(width 0.11684)
		(layer "B.Cu")
		(net "RST_EXTRST_N")
	)
	(segment
		(start 14.816836 -80.331564)
		(end 14.3764 -80.772)
		(width 0.11684)
		(layer "B.Cu")
		(net "RST_EXTRST_N")
	)
	(segment
		(start 16.078454 -74.3204)
		(end 15.24 -75.158854)
		(width 0.11684)
		(layer "B.Cu")
		(net "RST_EXTRST_N")
	)
	(segment
		(start 15.24 -78.3844)
		(end 14.816836 -78.807564)
		(width 0.11684)
		(layer "B.Cu")
		(net "RST_EXTRST_N")
	)
	(segment
		(start 57.813702 -36.33597)
		(end 57.813702 -38.560502)
		(width 0.10668)
		(layer "In7.Cu")
		(net "RST_EXTRST_N")
	)
	(segment
		(start 60.66536 -25.1206)
		(end 60.66536 -25.85974)
		(width 0.10668)
		(layer "In7.Cu")
		(net "RST_EXTRST_N")
	)
	(segment
		(start 26.107644 -24.511)
		(end 25.654 -24.057356)
		(width 0.10668)
		(layer "In7.Cu")
		(net "RST_EXTRST_N")
	)
	(segment
		(start 25.654 -23.020528)
		(end 26.449528 -22.225)
		(width 0.10668)
		(layer "In7.Cu")
		(net "RST_EXTRST_N")
	)
	(segment
		(start 17.412462 -53.111654)
		(end 17.8308 -52.693316)
		(width 0.10668)
		(layer "In7.Cu")
		(net "RST_EXTRST_N")
	)
	(segment
		(start 59.39028 -26.457148)
		(end 59.39028 -27.07894)
		(width 0.10668)
		(layer "In7.Cu")
		(net "RST_EXTRST_N")
	)
	(segment
		(start 20.128738 -66.624708)
		(end 20.1168 -66.595752)
		(width 0.10668)
		(layer "In7.Cu")
		(net "RST_EXTRST_N")
	)
	(segment
		(start 20.55114 -72.570086)
		(end 20.55114 -71.36257)
		(width 0.10668)
		(layer "In7.Cu")
		(net "RST_EXTRST_N")
	)
	(segment
		(start 28.6512 -87.30234)
		(end 27.59202 -86.24316)
		(width 0.10668)
		(layer "In7.Cu")
		(net "RST_EXTRST_N")
	)
	(segment
		(start 19.9136 -64.06515)
		(end 19.9136 -62.229746)
		(width 0.10668)
		(layer "In7.Cu")
		(net "RST_EXTRST_N")
	)
	(segment
		(start 26.449528 -22.225)
		(end 27.051 -22.225)
		(width 0.10668)
		(layer "In7.Cu")
		(net "RST_EXTRST_N")
	)
	(segment
		(start 27.59202 -84.660486)
		(end 26.3271 -83.395566)
		(width 0.10668)
		(layer "In7.Cu")
		(net "RST_EXTRST_N")
	)
	(segment
		(start 25.70226 -82.4357)
		(end 25.70226 -81.658206)
		(width 0.10668)
		(layer "In7.Cu")
		(net "RST_EXTRST_N")
	)
	(segment
		(start 27.051 -22.225)
		(end 27.686 -21.59)
		(width 0.10668)
		(layer "In7.Cu")
		(net "RST_EXTRST_N")
	)
	(segment
		(start 48.297846 -20.09648)
		(end 53.568854 -20.09648)
		(width 0.10668)
		(layer "In7.Cu")
		(net "RST_EXTRST_N")
	)
	(segment
		(start 58.3819 -23.75154)
		(end 59.2963 -23.75154)
		(width 0.10668)
		(layer "In7.Cu")
		(net "RST_EXTRST_N")
	)
	(segment
		(start 60.0456 -27.73426)
		(end 60.0456 -31.76016)
		(width 0.10668)
		(layer "In7.Cu")
		(net "RST_EXTRST_N")
	)
	(segment
		(start 59.39028 -27.07894)
		(end 60.0456 -27.73426)
		(width 0.10668)
		(layer "In7.Cu")
		(net "RST_EXTRST_N")
	)
	(segment
		(start 46.809914 -19.47926)
		(end 47.680626 -19.47926)
		(width 0.10668)
		(layer "In7.Cu")
		(net "RST_EXTRST_N")
	)
	(segment
		(start 57.64276 -23.0124)
		(end 58.3819 -23.75154)
		(width 0.10668)
		(layer "In7.Cu")
		(net "RST_EXTRST_N")
	)
	(segment
		(start 17.8308 -52.693316)
		(end 17.8308 -51.562)
		(width 0.10668)
		(layer "In7.Cu")
		(net "RST_EXTRST_N")
	)
	(segment
		(start 23.68296 -76.43876)
		(end 23.68296 -75.142598)
		(width 0.10668)
		(layer "In7.Cu")
		(net "RST_EXTRST_N")
	)
	(segment
		(start 19.214338 -61.530484)
		(end 19.214338 -59.643518)
		(width 0.10668)
		(layer "In7.Cu")
		(net "RST_EXTRST_N")
	)
	(segment
		(start 19.214338 -59.643518)
		(end 17.412462 -57.841642)
		(width 0.10668)
		(layer "In7.Cu")
		(net "RST_EXTRST_N")
	)
	(segment
		(start 30.71622 -93.619828)
		(end 30.147768 -93.619828)
		(width 0.10668)
		(layer "In7.Cu")
		(net "RST_EXTRST_N")
	)
	(segment
		(start 31.6611 -96.038416)
		(end 31.6611 -94.564708)
		(width 0.10668)
		(layer "In7.Cu")
		(net "RST_EXTRST_N")
	)
	(segment
		(start 53.568854 -20.09648)
		(end 56.486806 -23.0124)
		(width 0.10668)
		(layer "In7.Cu")
		(net "RST_EXTRST_N")
	)
	(segment
		(start 45.519594 -18.18894)
		(end 46.809914 -19.47926)
		(width 0.10668)
		(layer "In7.Cu")
		(net "RST_EXTRST_N")
	)
	(segment
		(start 20.24634 -69.5833)
		(end 19.9136 -69.25056)
		(width 0.10668)
		(layer "In7.Cu")
		(net "RST_EXTRST_N")
	)
	(segment
		(start 25.70226 -81.658206)
		(end 24.4602 -80.416146)
		(width 0.10668)
		(layer "In7.Cu")
		(net "RST_EXTRST_N")
	)
	(segment
		(start 29.51226 -91.952318)
		(end 29.51226 -90.233754)
		(width 0.10668)
		(layer "In7.Cu")
		(net "RST_EXTRST_N")
	)
	(segment
		(start 16.83512 -49.12106)
		(end 16.126714 -48.412654)
		(width 0.10668)
		(layer "In7.Cu")
		(net "RST_EXTRST_N")
	)
	(segment
		(start 29.6926 -92.132658)
		(end 29.51226 -91.952318)
		(width 0.10668)
		(layer "In7.Cu")
		(net "RST_EXTRST_N")
	)
	(segment
		(start 19.616166 -43.18)
		(end 23.32482 -39.471346)
		(width 0.10668)
		(layer "In7.Cu")
		(net "RST_EXTRST_N")
	)
	(segment
		(start 23.094442 -74.55408)
		(end 22.973792 -74.43343)
		(width 0.10668)
		(layer "In7.Cu")
		(net "RST_EXTRST_N")
	)
	(segment
		(start 29.59354 -17.01546)
		(end 36.064444 -17.01546)
		(width 0.10668)
		(layer "In7.Cu")
		(net "RST_EXTRST_N")
	)
	(segment
		(start 23.32482 -35.32378)
		(end 24.91232 -33.73628)
		(width 0.10668)
		(layer "In7.Cu")
		(net "RST_EXTRST_N")
	)
	(segment
		(start 29.51226 -90.233754)
		(end 28.6512 -89.372694)
		(width 0.10668)
		(layer "In7.Cu")
		(net "RST_EXTRST_N")
	)
	(segment
		(start 57.813702 -38.560502)
		(end 57.8358 -38.5826)
		(width 0.10668)
		(layer "In7.Cu")
		(net "RST_EXTRST_N")
	)
	(segment
		(start 56.486806 -23.0124)
		(end 57.64276 -23.0124)
		(width 0.10668)
		(layer "In7.Cu")
		(net "RST_EXTRST_N")
	)
	(segment
		(start 31.6611 -94.564708)
		(end 30.71622 -93.619828)
		(width 0.10668)
		(layer "In7.Cu")
		(net "RST_EXTRST_N")
	)
	(segment
		(start 23.68296 -75.142598)
		(end 23.094442 -74.55408)
		(width 0.10668)
		(layer "In7.Cu")
		(net "RST_EXTRST_N")
	)
	(segment
		(start 17.526 -51.2572)
		(end 17.526 -50.6222)
		(width 0.10668)
		(layer "In7.Cu")
		(net "RST_EXTRST_N")
	)
	(segment
		(start 17.21104 -46.416468)
		(end 17.21104 -45.019214)
		(width 0.10668)
		(layer "In7.Cu")
		(net "RST_EXTRST_N")
	)
	(segment
		(start 26.3271 -83.06054)
		(end 25.70226 -82.4357)
		(width 0.10668)
		(layer "In7.Cu")
		(net "RST_EXTRST_N")
	)
	(segment
		(start 33.41116 -98.513392)
		(end 32.5501 -97.652332)
		(width 0.10668)
		(layer "In7.Cu")
		(net "RST_EXTRST_N")
	)
	(segment
		(start 30.147768 -93.619828)
		(end 29.6926 -93.16466)
		(width 0.10668)
		(layer "In7.Cu")
		(net "RST_EXTRST_N")
	)
	(segment
		(start 26.3271 -83.395566)
		(end 26.3271 -83.06054)
		(width 0.10668)
		(layer "In7.Cu")
		(net "RST_EXTRST_N")
	)
	(segment
		(start 60.12434 -34.025332)
		(end 57.813702 -36.33597)
		(width 0.10668)
		(layer "In7.Cu")
		(net "RST_EXTRST_N")
	)
	(segment
		(start 29.6926 -93.16466)
		(end 29.6926 -92.132658)
		(width 0.10668)
		(layer "In7.Cu")
		(net "RST_EXTRST_N")
	)
	(segment
		(start 20.1168 -66.595752)
		(end 20.115276 -66.594228)
		(width 0.10668)
		(layer "In7.Cu")
		(net "RST_EXTRST_N")
	)
	(segment
		(start 32.5501 -97.652332)
		(end 32.5501 -97.113598)
		(width 0.10668)
		(layer "In7.Cu")
		(net "RST_EXTRST_N")
	)
	(segment
		(start 24.91232 -33.73628)
		(end 24.91232 -31.458662)
		(width 0.10668)
		(layer "In7.Cu")
		(net "RST_EXTRST_N")
	)
	(segment
		(start 25.654 -24.057356)
		(end 25.654 -23.020528)
		(width 0.10668)
		(layer "In7.Cu")
		(net "RST_EXTRST_N")
	)
	(segment
		(start 19.9136 -62.229746)
		(end 19.214338 -61.530484)
		(width 0.10668)
		(layer "In7.Cu")
		(net "RST_EXTRST_N")
	)
	(segment
		(start 27.686 -18.923)
		(end 29.59354 -17.01546)
		(width 0.10668)
		(layer "In7.Cu")
		(net "RST_EXTRST_N")
	)
	(segment
		(start 23.32482 -39.471346)
		(end 23.32482 -35.32378)
		(width 0.10668)
		(layer "In7.Cu")
		(net "RST_EXTRST_N")
	)
	(segment
		(start 59.2963 -23.75154)
		(end 60.66536 -25.1206)
		(width 0.10668)
		(layer "In7.Cu")
		(net "RST_EXTRST_N")
	)
	(segment
		(start 37.237924 -18.18894)
		(end 45.519594 -18.18894)
		(width 0.10668)
		(layer "In7.Cu")
		(net "RST_EXTRST_N")
	)
	(segment
		(start 17.526 -50.6222)
		(end 16.83512 -49.93132)
		(width 0.10668)
		(layer "In7.Cu")
		(net "RST_EXTRST_N")
	)
	(segment
		(start 17.21104 -45.019214)
		(end 19.050254 -43.18)
		(width 0.10668)
		(layer "In7.Cu")
		(net "RST_EXTRST_N")
	)
	(segment
		(start 24.4602 -80.416146)
		(end 24.4602 -77.216)
		(width 0.10668)
		(layer "In7.Cu")
		(net "RST_EXTRST_N")
	)
	(segment
		(start 59.728608 -26.11882)
		(end 59.39028 -26.457148)
		(width 0.10668)
		(layer "In7.Cu")
		(net "RST_EXTRST_N")
	)
	(segment
		(start 22.973792 -74.43343)
		(end 22.414484 -74.43343)
		(width 0.10668)
		(layer "In7.Cu")
		(net "RST_EXTRST_N")
	)
	(segment
		(start 20.115276 -64.266826)
		(end 19.9136 -64.06515)
		(width 0.10668)
		(layer "In7.Cu")
		(net "RST_EXTRST_N")
	)
	(segment
		(start 20.55114 -71.36257)
		(end 20.24634 -70.626732)
		(width 0.10668)
		(layer "In7.Cu")
		(net "RST_EXTRST_N")
	)
	(segment
		(start 36.064444 -17.01546)
		(end 37.237924 -18.18894)
		(width 0.10668)
		(layer "In7.Cu")
		(net "RST_EXTRST_N")
	)
	(segment
		(start 17.412462 -57.841642)
		(end 17.412462 -53.111654)
		(width 0.10668)
		(layer "In7.Cu")
		(net "RST_EXTRST_N")
	)
	(segment
		(start 60.12434 -31.8389)
		(end 60.12434 -34.025332)
		(width 0.10668)
		(layer "In7.Cu")
		(net "RST_EXTRST_N")
	)
	(segment
		(start 22.414484 -74.43343)
		(end 20.55114 -72.570086)
		(width 0.10668)
		(layer "In7.Cu")
		(net "RST_EXTRST_N")
	)
	(segment
		(start 60.0456 -31.76016)
		(end 60.12434 -31.8389)
		(width 0.10668)
		(layer "In7.Cu")
		(net "RST_EXTRST_N")
	)
	(segment
		(start 16.126714 -48.412654)
		(end 16.126714 -47.500794)
		(width 0.10668)
		(layer "In7.Cu")
		(net "RST_EXTRST_N")
	)
	(segment
		(start 26.107644 -30.263338)
		(end 26.107644 -24.511)
		(width 0.10668)
		(layer "In7.Cu")
		(net "RST_EXTRST_N")
	)
	(segment
		(start 19.9136 -67.146678)
		(end 20.128738 -66.93154)
		(width 0.10668)
		(layer "In7.Cu")
		(net "RST_EXTRST_N")
	)
	(segment
		(start 20.24634 -70.626732)
		(end 20.24634 -69.5833)
		(width 0.10668)
		(layer "In7.Cu")
		(net "RST_EXTRST_N")
	)
	(segment
		(start 27.59202 -86.24316)
		(end 27.59202 -84.660486)
		(width 0.10668)
		(layer "In7.Cu")
		(net "RST_EXTRST_N")
	)
	(segment
		(start 16.126714 -47.500794)
		(end 17.21104 -46.416468)
		(width 0.10668)
		(layer "In7.Cu")
		(net "RST_EXTRST_N")
	)
	(segment
		(start 24.4602 -77.216)
		(end 23.68296 -76.43876)
		(width 0.10668)
		(layer "In7.Cu")
		(net "RST_EXTRST_N")
	)
	(segment
		(start 20.115276 -66.594228)
		(end 20.115276 -64.266826)
		(width 0.10668)
		(layer "In7.Cu")
		(net "RST_EXTRST_N")
	)
	(segment
		(start 28.6512 -89.372694)
		(end 28.6512 -87.30234)
		(width 0.10668)
		(layer "In7.Cu")
		(net "RST_EXTRST_N")
	)
	(segment
		(start 19.9136 -69.25056)
		(end 19.9136 -67.146678)
		(width 0.10668)
		(layer "In7.Cu")
		(net "RST_EXTRST_N")
	)
	(segment
		(start 17.8308 -51.562)
		(end 17.526 -51.2572)
		(width 0.10668)
		(layer "In7.Cu")
		(net "RST_EXTRST_N")
	)
	(segment
		(start 32.5501 -97.113598)
		(end 32.418528 -96.795844)
		(width 0.10668)
		(layer "In7.Cu")
		(net "RST_EXTRST_N")
	)
	(segment
		(start 24.91232 -31.458662)
		(end 26.107644 -30.263338)
		(width 0.10668)
		(layer "In7.Cu")
		(net "RST_EXTRST_N")
	)
	(segment
		(start 47.680626 -19.47926)
		(end 48.297846 -20.09648)
		(width 0.10668)
		(layer "In7.Cu")
		(net "RST_EXTRST_N")
	)
	(segment
		(start 27.686 -21.59)
		(end 27.686 -18.923)
		(width 0.10668)
		(layer "In7.Cu")
		(net "RST_EXTRST_N")
	)
	(segment
		(start 20.128738 -66.93154)
		(end 20.128738 -66.624708)
		(width 0.10668)
		(layer "In7.Cu")
		(net "RST_EXTRST_N")
	)
	(segment
		(start 19.050254 -43.18)
		(end 19.616166 -43.18)
		(width 0.10668)
		(layer "In7.Cu")
		(net "RST_EXTRST_N")
	)
	(segment
		(start 33.41116 -100.25126)
		(end 33.41116 -98.513392)
		(width 0.10668)
		(layer "In7.Cu")
		(net "RST_EXTRST_N")
	)
	(segment
		(start 32.418528 -96.795844)
		(end 31.6611 -96.038416)
		(width 0.10668)
		(layer "In7.Cu")
		(net "RST_EXTRST_N")
	)
	(segment
		(start 60.40628 -26.11882)
		(end 59.728608 -26.11882)
		(width 0.10668)
		(layer "In7.Cu")
		(net "RST_EXTRST_N")
	)
	(segment
		(start 16.83512 -49.93132)
		(end 16.83512 -49.12106)
		(width 0.10668)
		(layer "In7.Cu")
		(net "RST_EXTRST_N")
	)
	(segment
		(start 60.66536 -25.85974)
		(end 60.40628 -26.11882)
		(width 0.10668)
		(layer "In7.Cu")
		(net "RST_EXTRST_N")
	)
	(segment
		(start 10.3378 -107.57535)
		(end 10.15365 -107.57535)
		(width 0.11684)
		(layer "F.Cu")
		(net "RST_BMC_SRST_BUF_R_N")
	)
	(segment
		(start 10.15365 -107.57535)
		(end 9.652 -108.077)
		(width 0.11684)
		(layer "F.Cu")
		(net "RST_BMC_SRST_BUF_R_N")
	)
	(segment
		(start 10.414 -107.49915)
		(end 10.3632 -107.54995)
		(width 0.11684)
		(layer "F.Cu")
		(net "RST_BMC_SRST_BUF_R_N")
	)
	(segment
		(start 9.652 -108.077)
		(end 9.652 -108.9152)
		(width 0.11684)
		(layer "F.Cu")
		(net "RST_BMC_SRST_BUF_R_N")
	)
	(segment
		(start 10.414 -107.161076)
		(end 10.414 -107.49915)
		(width 0.11684)
		(layer "F.Cu")
		(net "RST_BMC_SRST_BUF_R_N")
	)
	(segment
		(start 10.3632 -107.54995)
		(end 10.3378 -107.57535)
		(width 0.11684)
		(layer "F.Cu")
		(net "RST_BMC_SRST_BUF_R_N")
	)
	(segment
		(start 9.53135 -89.5096)
		(end 8.9154 -89.5096)
		(width 0.11684)
		(layer "F.Cu")
		(net "RST_BMC_SRST_BUF_R_N")
	)
	(segment
		(start 10.52195 -106.6038)
		(end 10.52195 -107.053126)
		(width 0.11684)
		(layer "F.Cu")
		(net "RST_BMC_SRST_BUF_R_N")
	)
	(segment
		(start 10.43305 -88.519)
		(end 9.656318 -89.295732)
		(width 0.11684)
		(layer "F.Cu")
		(net "RST_BMC_SRST_BUF_R_N")
	)
	(segment
		(start 9.63295 -89.408)
		(end 9.53135 -89.5096)
		(width 0.11684)
		(layer "F.Cu")
		(net "RST_BMC_SRST_BUF_R_N")
	)
	(segment
		(start 10.15365 -80.5434)
		(end 11.049 -80.5434)
		(width 0.11684)
		(layer "F.Cu")
		(net "RST_BMC_SRST_BUF_R_N")
	)
	(segment
		(start 10.52195 -107.053126)
		(end 10.414 -107.161076)
		(width 0.11684)
		(layer "F.Cu")
		(net "RST_BMC_SRST_BUF_R_N")
	)
	(segment
		(start 9.656318 -89.295732)
		(end 9.656318 -89.384632)
		(width 0.11684)
		(layer "F.Cu")
		(net "RST_BMC_SRST_BUF_R_N")
	)
	(segment
		(start 9.656318 -89.384632)
		(end 9.63295 -89.408)
		(width 0.11684)
		(layer "F.Cu")
		(net "RST_BMC_SRST_BUF_R_N")
	)
	(segment
		(start 10.52195 -105.5878)
		(end 10.52195 -106.6038)
		(width 0.11684)
		(layer "F.Cu")
		(net "RST_BMC_SRST_BUF_R_N")
	)
	(via
		(at 9.652 -108.9152)
		(size 0.508)
		(drill 0.254)
		(layers "F.Cu" "B.Cu")
		(net "RST_BMC_SRST_BUF_R_N")
	)
	(via
		(at 11.049 -80.5434)
		(size 0.508)
		(drill 0.254)
		(layers "F.Cu" "B.Cu")
		(net "RST_BMC_SRST_BUF_R_N")
	)
	(via
		(at 8.9154 -89.5096)
		(size 0.508)
		(drill 0.254)
		(layers "F.Cu" "B.Cu")
		(net "RST_BMC_SRST_BUF_R_N")
	)
	(segment
		(start 10.35558 -82.76082)
		(end 10.850372 -82.266028)
		(width 0.10668)
		(layer "In4.Cu")
		(net "RST_BMC_SRST_BUF_R_N")
	)
	(segment
		(start 8.9154 -89.5096)
		(end 10.35558 -88.06942)
		(width 0.10668)
		(layer "In4.Cu")
		(net "RST_BMC_SRST_BUF_R_N")
	)
	(segment
		(start 8.9154 -89.5096)
		(end 8.018272 -89.5096)
		(width 0.10668)
		(layer "In4.Cu")
		(net "RST_BMC_SRST_BUF_R_N")
	)
	(segment
		(start 7.0866 -90.441272)
		(end 7.0866 -91.539568)
		(width 0.10668)
		(layer "In4.Cu")
		(net "RST_BMC_SRST_BUF_R_N")
	)
	(segment
		(start 9.824212 -106.126788)
		(end 9.824212 -108.742988)
		(width 0.10668)
		(layer "In4.Cu")
		(net "RST_BMC_SRST_BUF_R_N")
	)
	(segment
		(start 10.35558 -88.06942)
		(end 10.35558 -82.76082)
		(width 0.10668)
		(layer "In4.Cu")
		(net "RST_BMC_SRST_BUF_R_N")
	)
	(segment
		(start 5.392166 -92.272866)
		(end 4.61772 -93.047312)
		(width 0.10668)
		(layer "In4.Cu")
		(net "RST_BMC_SRST_BUF_R_N")
	)
	(segment
		(start 5.0292 -102.0572)
		(end 5.4864 -102.5144)
		(width 0.10668)
		(layer "In4.Cu")
		(net "RST_BMC_SRST_BUF_R_N")
	)
	(segment
		(start 8.0137 -103.0986)
		(end 8.0137 -104.316276)
		(width 0.10668)
		(layer "In4.Cu")
		(net "RST_BMC_SRST_BUF_R_N")
	)
	(segment
		(start 4.61772 -99.865688)
		(end 5.0292 -100.277168)
		(width 0.10668)
		(layer "In4.Cu")
		(net "RST_BMC_SRST_BUF_R_N")
	)
	(segment
		(start 10.977372 -80.5434)
		(end 11.049 -80.5434)
		(width 0.10668)
		(layer "In4.Cu")
		(net "RST_BMC_SRST_BUF_R_N")
	)
	(segment
		(start 5.4864 -102.5144)
		(end 7.4295 -102.5144)
		(width 0.10668)
		(layer "In4.Cu")
		(net "RST_BMC_SRST_BUF_R_N")
	)
	(segment
		(start 9.824212 -108.742988)
		(end 9.652 -108.9152)
		(width 0.10668)
		(layer "In4.Cu")
		(net "RST_BMC_SRST_BUF_R_N")
	)
	(segment
		(start 4.61772 -93.047312)
		(end 4.61772 -99.865688)
		(width 0.10668)
		(layer "In4.Cu")
		(net "RST_BMC_SRST_BUF_R_N")
	)
	(segment
		(start 10.850372 -82.266028)
		(end 10.850372 -80.6704)
		(width 0.10668)
		(layer "In4.Cu")
		(net "RST_BMC_SRST_BUF_R_N")
	)
	(segment
		(start 7.4295 -102.5144)
		(end 8.0137 -103.0986)
		(width 0.10668)
		(layer "In4.Cu")
		(net "RST_BMC_SRST_BUF_R_N")
	)
	(segment
		(start 5.0292 -100.277168)
		(end 5.0292 -102.0572)
		(width 0.10668)
		(layer "In4.Cu")
		(net "RST_BMC_SRST_BUF_R_N")
	)
	(segment
		(start 8.018272 -89.5096)
		(end 7.0866 -90.441272)
		(width 0.10668)
		(layer "In4.Cu")
		(net "RST_BMC_SRST_BUF_R_N")
	)
	(segment
		(start 10.850372 -80.6704)
		(end 10.977372 -80.5434)
		(width 0.10668)
		(layer "In4.Cu")
		(net "RST_BMC_SRST_BUF_R_N")
	)
	(segment
		(start 7.0866 -91.539568)
		(end 6.353302 -92.272866)
		(width 0.10668)
		(layer "In4.Cu")
		(net "RST_BMC_SRST_BUF_R_N")
	)
	(segment
		(start 8.0137 -104.316276)
		(end 9.824212 -106.126788)
		(width 0.10668)
		(layer "In4.Cu")
		(net "RST_BMC_SRST_BUF_R_N")
	)
	(segment
		(start 6.353302 -92.272866)
		(end 5.392166 -92.272866)
		(width 0.10668)
		(layer "In4.Cu")
		(net "RST_BMC_SRST_BUF_R_N")
	)
	(segment
		(start 12.4968 -106.1212)
		(end 12.4968 -105.2068)
		(width 0.11684)
		(layer "F.Cu")
		(net "RST_BMC_SRST_BUF_R1_N")
	)
	(segment
		(start 11.7094 -104.8258)
		(end 11.32205 -105.21315)
		(width 0.11684)
		(layer "F.Cu")
		(net "RST_BMC_SRST_BUF_R1_N")
	)
	(segment
		(start 12.4968 -105.2068)
		(end 12.1158 -104.8258)
		(width 0.11684)
		(layer "F.Cu")
		(net "RST_BMC_SRST_BUF_R1_N")
	)
	(segment
		(start 11.32205 -105.21315)
		(end 11.32205 -105.5878)
		(width 0.11684)
		(layer "F.Cu")
		(net "RST_BMC_SRST_BUF_R1_N")
	)
	(segment
		(start 12.71397 -106.33837)
		(end 12.4968 -106.1212)
		(width 0.11684)
		(layer "F.Cu")
		(net "RST_BMC_SRST_BUF_R1_N")
	)
	(segment
		(start 13.163042 -106.33837)
		(end 12.71397 -106.33837)
		(width 0.11684)
		(layer "F.Cu")
		(net "RST_BMC_SRST_BUF_R1_N")
	)
	(segment
		(start 12.1158 -104.8258)
		(end 11.7094 -104.8258)
		(width 0.11684)
		(layer "F.Cu")
		(net "RST_BMC_SRST_BUF_R1_N")
	)
	(via
		(at 11.7094 -104.8258)
		(size 0.508)
		(drill 0.254)
		(layers "F.Cu" "B.Cu")
		(net "RST_BMC_SRST_BUF_R1_N")
	)
	(via
		(at 32.4993 -100.5205)
		(size 0.6604)
		(drill 0.3302)
		(layers "F.Cu" "B.Cu")
		(net "RST_BMC_SELF_HW_R3")
	)
	(segment
		(start 32.4993 -100.5205)
		(end 32.004 -101.0158)
		(width 0.11684)
		(layer "B.Cu")
		(net "RST_BMC_SELF_HW_R3")
	)
	(segment
		(start 32.8676 -100.1522)
		(end 32.4993 -100.5205)
		(width 0.11684)
		(layer "B.Cu")
		(net "RST_BMC_SELF_HW_R3")
	)
	(segment
		(start 32.8676 -99.5426)
		(end 32.8676 -100.1522)
		(width 0.11684)
		(layer "B.Cu")
		(net "RST_BMC_SELF_HW_R3")
	)
	(segment
		(start 32.512 -99.187)
		(end 32.8676 -99.5426)
		(width 0.11684)
		(layer "B.Cu")
		(net "RST_BMC_SELF_HW_R3")
	)
	(segment
		(start 32.15894 -98.304096)
		(end 32.15894 -99.06254)
		(width 0.11684)
		(layer "B.Cu")
		(net "RST_BMC_SELF_HW_R3")
	)
	(segment
		(start 32.004 -101.0158)
		(end 32.004 -101.45395)
		(width 0.11684)
		(layer "B.Cu")
		(net "RST_BMC_SELF_HW_R3")
	)
	(segment
		(start 32.2834 -99.187)
		(end 32.512 -99.187)
		(width 0.11684)
		(layer "B.Cu")
		(net "RST_BMC_SELF_HW_R3")
	)
	(segment
		(start 32.15894 -99.06254)
		(end 32.2834 -99.187)
		(width 0.11684)
		(layer "B.Cu")
		(net "RST_BMC_SELF_HW_R3")
	)
	(segment
		(start 17.464278 -91.991942)
		(end 17.859502 -92.387166)
		(width 0.11684)
		(layer "F.Cu")
		(net "RST_BMC_SELF_HW_R2")
	)
	(via
		(at 17.464278 -91.991942)
		(size 0.4572)
		(drill 0.254)
		(layers "F.Cu" "B.Cu")
		(net "RST_BMC_SELF_HW_R2")
	)
	(segment
		(start 16.401542 -91.991942)
		(end 17.464278 -91.991942)
		(width 0.11684)
		(layer "B.Cu")
		(net "RST_BMC_SELF_HW_R2")
	)
	(segment
		(start 15.7988 -91.3892)
		(end 16.401542 -91.991942)
		(width 0.11684)
		(layer "B.Cu")
		(net "RST_BMC_SELF_HW_R2")
	)
	(segment
		(start 13.22705 -91.948)
		(end 13.843 -91.948)
		(width 0.11684)
		(layer "B.Cu")
		(net "RST_BMC_SELF_HW_R2")
	)
	(segment
		(start 12.59205 -89.64295)
		(end 12.131294 -90.103706)
		(width 0.11684)
		(layer "B.Cu")
		(net "RST_BMC_SELF_HW_R2")
	)
	(segment
		(start 14.4018 -91.3892)
		(end 15.7988 -91.3892)
		(width 0.11684)
		(layer "B.Cu")
		(net "RST_BMC_SELF_HW_R2")
	)
	(segment
		(start 12.131294 -90.103706)
		(end 12.131294 -90.852244)
		(width 0.11684)
		(layer "B.Cu")
		(net "RST_BMC_SELF_HW_R2")
	)
	(segment
		(start 12.7 -89.64295)
		(end 12.59205 -89.64295)
		(width 0.11684)
		(layer "B.Cu")
		(net "RST_BMC_SELF_HW_R2")
	)
	(segment
		(start 12.131294 -90.852244)
		(end 12.71905 -91.44)
		(width 0.11684)
		(layer "B.Cu")
		(net "RST_BMC_SELF_HW_R2")
	)
	(segment
		(start 12.71905 -91.44)
		(end 13.22705 -91.948)
		(width 0.11684)
		(layer "B.Cu")
		(net "RST_BMC_SELF_HW_R2")
	)
	(segment
		(start 13.843 -91.948)
		(end 14.4018 -91.3892)
		(width 0.11684)
		(layer "B.Cu")
		(net "RST_BMC_SELF_HW_R2")
	)
	(segment
		(start 64.2874 -70.44309)
		(end 64.310768 -70.466458)
		(width 0.11684)
		(layer "F.Cu")
		(net "BMC_EMMC_RST_R_N")
	)
	(segment
		(start 64.1096 -70.44309)
		(end 64.2874 -70.44309)
		(width 0.11684)
		(layer "F.Cu")
		(net "BMC_EMMC_RST_R_N")
	)
	(segment
		(start 56.094884 -55.371238)
		(end 56.490108 -55.766462)
		(width 0.11684)
		(layer "F.Cu")
		(net "BMC_EMMC_RST_R_N")
	)
	(segment
		(start 64.737488 -70.466458)
		(end 65.31483 -71.0438)
		(width 0.11684)
		(layer "F.Cu")
		(net "BMC_EMMC_RST_R_N")
	)
	(segment
		(start 64.310768 -70.466458)
		(end 64.737488 -70.466458)
		(width 0.11684)
		(layer "F.Cu")
		(net "BMC_EMMC_RST_R_N")
	)
	(via
		(at 65.31483 -71.0438)
		(size 0.762)
		(drill 0.254)
		(layers "F.Cu" "B.Cu")
		(net "BMC_EMMC_RST_R_N")
	)
	(via
		(at 56.490108 -55.766462)
		(size 0.4572)
		(drill 0.254)
		(layers "F.Cu" "B.Cu")
		(net "BMC_EMMC_RST_R_N")
	)
	(segment
		(start 62.16904 -65.92824)
		(end 65.31483 -69.07403)
		(width 0.08382)
		(layer "In9.Cu")
		(net "BMC_EMMC_RST_R_N")
	)
	(segment
		(start 58.4962 -61.3156)
		(end 59.0042 -61.8236)
		(width 0.08382)
		(layer "In9.Cu")
		(net "BMC_EMMC_RST_R_N")
	)
	(segment
		(start 56.490108 -55.766462)
		(end 56.490108 -55.778908)
		(width 0.08382)
		(layer "In9.Cu")
		(net "BMC_EMMC_RST_R_N")
	)
	(segment
		(start 59.817 -64.1604)
		(end 59.817 -65.70218)
		(width 0.08382)
		(layer "In9.Cu")
		(net "BMC_EMMC_RST_R_N")
	)
	(segment
		(start 58.4962 -57.2262)
		(end 58.4962 -61.3156)
		(width 0.08382)
		(layer "In9.Cu")
		(net "BMC_EMMC_RST_R_N")
	)
	(segment
		(start 57.6834 -56.7182)
		(end 57.9374 -56.9722)
		(width 0.08382)
		(layer "In9.Cu")
		(net "BMC_EMMC_RST_R_N")
	)
	(segment
		(start 59.0042 -61.8236)
		(end 59.0042 -63.3476)
		(width 0.08382)
		(layer "In9.Cu")
		(net "BMC_EMMC_RST_R_N")
	)
	(segment
		(start 59.0042 -63.3476)
		(end 59.817 -64.1604)
		(width 0.08382)
		(layer "In9.Cu")
		(net "BMC_EMMC_RST_R_N")
	)
	(segment
		(start 59.817 -65.70218)
		(end 60.04306 -65.92824)
		(width 0.08382)
		(layer "In9.Cu")
		(net "BMC_EMMC_RST_R_N")
	)
	(segment
		(start 58.2422 -56.9722)
		(end 58.4962 -57.2262)
		(width 0.08382)
		(layer "In9.Cu")
		(net "BMC_EMMC_RST_R_N")
	)
	(segment
		(start 56.490108 -55.778908)
		(end 56.896 -56.1848)
		(width 0.08382)
		(layer "In9.Cu")
		(net "BMC_EMMC_RST_R_N")
	)
	(segment
		(start 57.6834 -56.388)
		(end 57.6834 -56.7182)
		(width 0.08382)
		(layer "In9.Cu")
		(net "BMC_EMMC_RST_R_N")
	)
	(segment
		(start 60.04306 -65.92824)
		(end 62.16904 -65.92824)
		(width 0.08382)
		(layer "In9.Cu")
		(net "BMC_EMMC_RST_R_N")
	)
	(segment
		(start 65.31483 -69.07403)
		(end 65.31483 -71.0438)
		(width 0.08382)
		(layer "In9.Cu")
		(net "BMC_EMMC_RST_R_N")
	)
	(segment
		(start 57.4802 -56.1848)
		(end 57.6834 -56.388)
		(width 0.08382)
		(layer "In9.Cu")
		(net "BMC_EMMC_RST_R_N")
	)
	(segment
		(start 56.896 -56.1848)
		(end 57.4802 -56.1848)
		(width 0.08382)
		(layer "In9.Cu")
		(net "BMC_EMMC_RST_R_N")
	)
	(segment
		(start 57.9374 -56.9722)
		(end 58.2422 -56.9722)
		(width 0.08382)
		(layer "In9.Cu")
		(net "BMC_EMMC_RST_R_N")
	)
	(segment
		(start 22.77745 -105.918)
		(end 22.77745 -107.17276)
		(width 0.11684)
		(layer "F.Cu")
		(net "RST_BMC_SELF_HW_D_C")
	)
	(segment
		(start 21.371814 -104.775)
		(end 22.77745 -104.775)
		(width 0.11684)
		(layer "F.Cu")
		(net "RST_BMC_SELF_HW_D_C")
	)
	(segment
		(start 23.21941 -108.25861)
		(end 23.21941 -108.71708)
		(width 0.11684)
		(layer "F.Cu")
		(net "RST_BMC_SELF_HW_D_C")
	)
	(segment
		(start 21.102574 -105.04424)
		(end 21.371814 -104.775)
		(width 0.11684)
		(layer "F.Cu")
		(net "RST_BMC_SELF_HW_D_C")
	)
	(segment
		(start 22.77745 -107.17276)
		(end 22.77745 -107.81665)
		(width 0.11684)
		(layer "F.Cu")
		(net "RST_BMC_SELF_HW_D_C")
	)
	(segment
		(start 22.77745 -104.775)
		(end 22.77745 -105.918)
		(width 0.11684)
		(layer "F.Cu")
		(net "RST_BMC_SELF_HW_D_C")
	)
	(segment
		(start 22.77745 -107.81665)
		(end 23.21941 -108.25861)
		(width 0.11684)
		(layer "F.Cu")
		(net "RST_BMC_SELF_HW_D_C")
	)
	(via
		(at 22.77745 -107.17276)
		(size 0.762)
		(drill 0.381)
		(layers "F.Cu" "B.Cu")
		(net "RST_BMC_SELF_HW_D_C")
	)
	(segment
		(start 25.06472 -105.535984)
		(end 25.06472 -108.04525)
		(width 0.11684)
		(layer "F.Cu")
		(net "RST_BMC_SELF_HW_D")
	)
	(segment
		(start 25.139904 -105.4608)
		(end 25.06472 -105.535984)
		(width 0.11684)
		(layer "F.Cu")
		(net "RST_BMC_SELF_HW_D")
	)
	(segment
		(start 24.01951 -108.71708)
		(end 24.30907 -108.42752)
		(width 0.11684)
		(layer "F.Cu")
		(net "RST_BMC_SELF_HW_D")
	)
	(segment
		(start 24.68245 -108.42752)
		(end 25.06472 -108.04525)
		(width 0.11684)
		(layer "F.Cu")
		(net "RST_BMC_SELF_HW_D")
	)
	(segment
		(start 24.30907 -108.42752)
		(end 24.68245 -108.42752)
		(width 0.11684)
		(layer "F.Cu")
		(net "RST_BMC_SELF_HW_D")
	)
	(segment
		(start 58.68924 -68.95084)
		(end 57.9882 -68.2498)
		(width 0.11684)
		(layer "F.Cu")
		(net "RST_BMC_SELF_HW")
	)
	(segment
		(start 56.3372 -64.516254)
		(end 56.3372 -64.05245)
		(width 0.11684)
		(layer "F.Cu")
		(net "RST_BMC_SELF_HW")
	)
	(segment
		(start 11.91895 -91.44)
		(end 11.30935 -91.44)
		(width 0.11684)
		(layer "F.Cu")
		(net "RST_BMC_SELF_HW")
	)
	(segment
		(start 57.189116 -68.2498)
		(end 55.5752 -66.635884)
		(width 0.11684)
		(layer "F.Cu")
		(net "RST_BMC_SELF_HW")
	)
	(segment
		(start 58.9026 -69.2658)
		(end 58.68924 -69.05244)
		(width 0.11684)
		(layer "F.Cu")
		(net "RST_BMC_SELF_HW")
	)
	(segment
		(start 55.5752 -66.635884)
		(end 55.5752 -65.278254)
		(width 0.11684)
		(layer "F.Cu")
		(net "RST_BMC_SELF_HW")
	)
	(segment
		(start 58.68924 -69.05244)
		(end 58.68924 -68.95084)
		(width 0.11684)
		(layer "F.Cu")
		(net "RST_BMC_SELF_HW")
	)
	(segment
		(start 57.9882 -68.2498)
		(end 57.189116 -68.2498)
		(width 0.11684)
		(layer "F.Cu")
		(net "RST_BMC_SELF_HW")
	)
	(segment
		(start 55.5752 -65.278254)
		(end 56.3372 -64.516254)
		(width 0.11684)
		(layer "F.Cu")
		(net "RST_BMC_SELF_HW")
	)
	(via
		(at 30.9118 -107.69727)
		(size 0.508)
		(drill 0.254)
		(layers "F.Cu" "B.Cu")
		(net "RST_BMC_SELF_HW")
	)
	(via
		(at 11.30935 -91.44)
		(size 0.508)
		(drill 0.254)
		(layers "F.Cu" "B.Cu")
		(net "RST_BMC_SELF_HW")
	)
	(via
		(at 55.914036 -101.79812)
		(size 0.508)
		(drill 0.254)
		(layers "F.Cu" "B.Cu")
		(net "RST_BMC_SELF_HW")
	)
	(via
		(at 58.9026 -69.2658)
		(size 0.508)
		(drill 0.254)
		(layers "F.Cu" "B.Cu")
		(net "RST_BMC_SELF_HW")
	)
	(segment
		(start 30.48 -105.918)
		(end 31.3055 -105.0925)
		(width 0.11684)
		(layer "B.Cu")
		(net "RST_BMC_SELF_HW")
	)
	(segment
		(start 31.3055 -105.0925)
		(end 31.3055 -104.2035)
		(width 0.11684)
		(layer "B.Cu")
		(net "RST_BMC_SELF_HW")
	)
	(segment
		(start 11.91895 -91.44)
		(end 11.30935 -91.44)
		(width 0.11684)
		(layer "B.Cu")
		(net "RST_BMC_SELF_HW")
	)
	(segment
		(start 32.131 -103.378)
		(end 32.131 -102.87)
		(width 0.11684)
		(layer "B.Cu")
		(net "RST_BMC_SELF_HW")
	)
	(segment
		(start 30.48 -107.26547)
		(end 30.48 -105.918)
		(width 0.11684)
		(layer "B.Cu")
		(net "RST_BMC_SELF_HW")
	)
	(segment
		(start 32.004 -102.743)
		(end 32.004 -102.25405)
		(width 0.11684)
		(layer "B.Cu")
		(net "RST_BMC_SELF_HW")
	)
	(segment
		(start 30.9118 -107.69727)
		(end 30.48 -107.26547)
		(width 0.11684)
		(layer "B.Cu")
		(net "RST_BMC_SELF_HW")
	)
	(segment
		(start 32.131 -102.87)
		(end 32.004 -102.743)
		(width 0.11684)
		(layer "B.Cu")
		(net "RST_BMC_SELF_HW")
	)
	(segment
		(start 31.3055 -104.2035)
		(end 32.131 -103.378)
		(width 0.11684)
		(layer "B.Cu")
		(net "RST_BMC_SELF_HW")
	)
	(segment
		(start 55.244746 -102.7684)
		(end 55.914036 -102.09911)
		(width 0.08382)
		(layer "In2.Cu")
		(net "RST_BMC_SELF_HW")
	)
	(segment
		(start 46.00575 -107.07751)
		(end 47.79645 -107.07751)
		(width 0.08382)
		(layer "In2.Cu")
		(net "RST_BMC_SELF_HW")
	)
	(segment
		(start 50.266346 -106.299)
		(end 52.29479 -104.270556)
		(width 0.08382)
		(layer "In2.Cu")
		(net "RST_BMC_SELF_HW")
	)
	(segment
		(start 31.36011 -108.14558)
		(end 35.4711 -108.14558)
		(width 0.08382)
		(layer "In2.Cu")
		(net "RST_BMC_SELF_HW")
	)
	(segment
		(start 30.9118 -107.69727)
		(end 31.36011 -108.14558)
		(width 0.08382)
		(layer "In2.Cu")
		(net "RST_BMC_SELF_HW")
	)
	(segment
		(start 35.4711 -108.14558)
		(end 37.086794 -106.529886)
		(width 0.08382)
		(layer "In2.Cu")
		(net "RST_BMC_SELF_HW")
	)
	(segment
		(start 45.20184 -106.2736)
		(end 46.00575 -107.07751)
		(width 0.08382)
		(layer "In2.Cu")
		(net "RST_BMC_SELF_HW")
	)
	(segment
		(start 37.086794 -106.529886)
		(end 40.815768 -106.529886)
		(width 0.08382)
		(layer "In2.Cu")
		(net "RST_BMC_SELF_HW")
	)
	(segment
		(start 55.914036 -102.09911)
		(end 55.914036 -101.79812)
		(width 0.08382)
		(layer "In2.Cu")
		(net "RST_BMC_SELF_HW")
	)
	(segment
		(start 48.57496 -106.299)
		(end 50.266346 -106.299)
		(width 0.08382)
		(layer "In2.Cu")
		(net "RST_BMC_SELF_HW")
	)
	(segment
		(start 52.29479 -104.270556)
		(end 53.260244 -104.270556)
		(width 0.08382)
		(layer "In2.Cu")
		(net "RST_BMC_SELF_HW")
	)
	(segment
		(start 41.434766 -106.2736)
		(end 45.20184 -106.2736)
		(width 0.08382)
		(layer "In2.Cu")
		(net "RST_BMC_SELF_HW")
	)
	(segment
		(start 53.260244 -104.270556)
		(end 54.7624 -102.7684)
		(width 0.08382)
		(layer "In2.Cu")
		(net "RST_BMC_SELF_HW")
	)
	(segment
		(start 40.815768 -106.529886)
		(end 41.434766 -106.2736)
		(width 0.08382)
		(layer "In2.Cu")
		(net "RST_BMC_SELF_HW")
	)
	(segment
		(start 47.79645 -107.07751)
		(end 48.57496 -106.299)
		(width 0.08382)
		(layer "In2.Cu")
		(net "RST_BMC_SELF_HW")
	)
	(segment
		(start 54.7624 -102.7684)
		(end 55.244746 -102.7684)
		(width 0.08382)
		(layer "In2.Cu")
		(net "RST_BMC_SELF_HW")
	)
	(segment
		(start 10.67308 -105.81132)
		(end 14.708124 -105.81132)
		(width 0.10668)
		(layer "In4.Cu")
		(net "RST_BMC_SELF_HW")
	)
	(segment
		(start 56.75376 -84.543646)
		(end 56.75376 -85.96376)
		(width 0.10668)
		(layer "In4.Cu")
		(net "RST_BMC_SELF_HW")
	)
	(segment
		(start 59.79668 -94.54896)
		(end 57.55767 -96.78797)
		(width 0.10668)
		(layer "In4.Cu")
		(net "RST_BMC_SELF_HW")
	)
	(segment
		(start 8.83666 -102.529132)
		(end 8.83666 -103.9749)
		(width 0.10668)
		(layer "In4.Cu")
		(net "RST_BMC_SELF_HW")
	)
	(segment
		(start 8.223758 -101.91623)
		(end 8.83666 -102.529132)
		(width 0.10668)
		(layer "In4.Cu")
		(net "RST_BMC_SELF_HW")
	)
	(segment
		(start 58.79846 -90.745564)
		(end 58.79846 -91.447112)
		(width 0.10668)
		(layer "In4.Cu")
		(net "RST_BMC_SELF_HW")
	)
	(segment
		(start 57.9374 -87.1474)
		(end 57.9374 -89.884504)
		(width 0.10668)
		(layer "In4.Cu")
		(net "RST_BMC_SELF_HW")
	)
	(segment
		(start 14.708124 -105.81132)
		(end 16.2306 -107.333796)
		(width 0.10668)
		(layer "In4.Cu")
		(net "RST_BMC_SELF_HW")
	)
	(segment
		(start 57.250584 -99.18827)
		(end 57.250584 -101.935788)
		(width 0.10668)
		(layer "In4.Cu")
		(net "RST_BMC_SELF_HW")
	)
	(segment
		(start 57.55767 -98.881184)
		(end 57.250584 -99.18827)
		(width 0.10668)
		(layer "In4.Cu")
		(net "RST_BMC_SELF_HW")
	)
	(segment
		(start 8.244332 -90.45702)
		(end 7.9756 -90.725752)
		(width 0.10668)
		(layer "In4.Cu")
		(net "RST_BMC_SELF_HW")
	)
	(segment
		(start 21.056346 -108.478066)
		(end 21.397214 -108.478066)
		(width 0.10668)
		(layer "In4.Cu")
		(net "RST_BMC_SELF_HW")
	)
	(segment
		(start 11.30935 -91.44)
		(end 10.32637 -90.45702)
		(width 0.10668)
		(layer "In4.Cu")
		(net "RST_BMC_SELF_HW")
	)
	(segment
		(start 25.77211 -109.21492)
		(end 26.778712 -109.21492)
		(width 0.10668)
		(layer "In4.Cu")
		(net "RST_BMC_SELF_HW")
	)
	(segment
		(start 57.250584 -101.935788)
		(end 56.89219 -102.294182)
		(width 0.10668)
		(layer "In4.Cu")
		(net "RST_BMC_SELF_HW")
	)
	(segment
		(start 25.48509 -108.9279)
		(end 25.77211 -109.21492)
		(width 0.10668)
		(layer "In4.Cu")
		(net "RST_BMC_SELF_HW")
	)
	(segment
		(start 7.13994 -100.385372)
		(end 8.223758 -101.46919)
		(width 0.10668)
		(layer "In4.Cu")
		(net "RST_BMC_SELF_HW")
	)
	(segment
		(start 27.446478 -107.706922)
		(end 30.902148 -107.706922)
		(width 0.10668)
		(layer "In4.Cu")
		(net "RST_BMC_SELF_HW")
	)
	(segment
		(start 57.55767 -96.78797)
		(end 57.55767 -98.881184)
		(width 0.10668)
		(layer "In4.Cu")
		(net "RST_BMC_SELF_HW")
	)
	(segment
		(start 26.778712 -109.21492)
		(end 27.2034 -108.790232)
		(width 0.10668)
		(layer "In4.Cu")
		(net "RST_BMC_SELF_HW")
	)
	(segment
		(start 56.75376 -85.96376)
		(end 57.9374 -87.1474)
		(width 0.10668)
		(layer "In4.Cu")
		(net "RST_BMC_SELF_HW")
	)
	(segment
		(start 56.384698 -102.294182)
		(end 55.914036 -101.82352)
		(width 0.10668)
		(layer "In4.Cu")
		(net "RST_BMC_SELF_HW")
	)
	(segment
		(start 30.902148 -107.706922)
		(end 30.9118 -107.69727)
		(width 0.10668)
		(layer "In4.Cu")
		(net "RST_BMC_SELF_HW")
	)
	(segment
		(start 59.79668 -92.445332)
		(end 59.79668 -94.54896)
		(width 0.10668)
		(layer "In4.Cu")
		(net "RST_BMC_SELF_HW")
	)
	(segment
		(start 16.2306 -107.63504)
		(end 17.45996 -108.8644)
		(width 0.10668)
		(layer "In4.Cu")
		(net "RST_BMC_SELF_HW")
	)
	(segment
		(start 55.914036 -101.82352)
		(end 55.914036 -101.79812)
		(width 0.10668)
		(layer "In4.Cu")
		(net "RST_BMC_SELF_HW")
	)
	(segment
		(start 27.2034 -108.790232)
		(end 27.2034 -107.95)
		(width 0.10668)
		(layer "In4.Cu")
		(net "RST_BMC_SELF_HW")
	)
	(segment
		(start 56.24068 -84.030566)
		(end 56.75376 -84.543646)
		(width 0.10668)
		(layer "In4.Cu")
		(net "RST_BMC_SELF_HW")
	)
	(segment
		(start 21.397468 -108.47832)
		(end 21.778468 -108.47832)
		(width 0.10668)
		(layer "In4.Cu")
		(net "RST_BMC_SELF_HW")
	)
	(segment
		(start 57.9374 -89.884504)
		(end 58.79846 -90.745564)
		(width 0.10668)
		(layer "In4.Cu")
		(net "RST_BMC_SELF_HW")
	)
	(segment
		(start 27.2034 -107.95)
		(end 27.446478 -107.706922)
		(width 0.10668)
		(layer "In4.Cu")
		(net "RST_BMC_SELF_HW")
	)
	(segment
		(start 8.83666 -103.9749)
		(end 10.67308 -105.81132)
		(width 0.10668)
		(layer "In4.Cu")
		(net "RST_BMC_SELF_HW")
	)
	(segment
		(start 20.670012 -108.8644)
		(end 21.056346 -108.478066)
		(width 0.10668)
		(layer "In4.Cu")
		(net "RST_BMC_SELF_HW")
	)
	(segment
		(start 7.13994 -92.650818)
		(end 7.13994 -100.385372)
		(width 0.10668)
		(layer "In4.Cu")
		(net "RST_BMC_SELF_HW")
	)
	(segment
		(start 8.223758 -101.46919)
		(end 8.223758 -101.91623)
		(width 0.10668)
		(layer "In4.Cu")
		(net "RST_BMC_SELF_HW")
	)
	(segment
		(start 58.47588 -75.788774)
		(end 57.404 -76.860654)
		(width 0.10668)
		(layer "In4.Cu")
		(net "RST_BMC_SELF_HW")
	)
	(segment
		(start 58.79846 -91.447112)
		(end 59.79668 -92.445332)
		(width 0.10668)
		(layer "In4.Cu")
		(net "RST_BMC_SELF_HW")
	)
	(segment
		(start 17.45996 -108.8644)
		(end 20.670012 -108.8644)
		(width 0.10668)
		(layer "In4.Cu")
		(net "RST_BMC_SELF_HW")
	)
	(segment
		(start 56.24068 -81.24952)
		(end 56.24068 -84.030566)
		(width 0.10668)
		(layer "In4.Cu")
		(net "RST_BMC_SELF_HW")
	)
	(segment
		(start 10.32637 -90.45702)
		(end 8.244332 -90.45702)
		(width 0.10668)
		(layer "In4.Cu")
		(net "RST_BMC_SELF_HW")
	)
	(segment
		(start 57.404 -76.860654)
		(end 57.404 -80.0862)
		(width 0.10668)
		(layer "In4.Cu")
		(net "RST_BMC_SELF_HW")
	)
	(segment
		(start 7.9756 -91.815158)
		(end 7.13994 -92.650818)
		(width 0.10668)
		(layer "In4.Cu")
		(net "RST_BMC_SELF_HW")
	)
	(segment
		(start 21.778468 -108.47832)
		(end 22.228048 -108.9279)
		(width 0.10668)
		(layer "In4.Cu")
		(net "RST_BMC_SELF_HW")
	)
	(segment
		(start 58.9026 -69.2658)
		(end 58.9026 -73.338182)
		(width 0.10668)
		(layer "In4.Cu")
		(net "RST_BMC_SELF_HW")
	)
	(segment
		(start 58.9026 -73.338182)
		(end 58.47588 -73.764902)
		(width 0.10668)
		(layer "In4.Cu")
		(net "RST_BMC_SELF_HW")
	)
	(segment
		(start 57.404 -80.0862)
		(end 56.24068 -81.24952)
		(width 0.10668)
		(layer "In4.Cu")
		(net "RST_BMC_SELF_HW")
	)
	(segment
		(start 21.397214 -108.478066)
		(end 21.397468 -108.47832)
		(width 0.10668)
		(layer "In4.Cu")
		(net "RST_BMC_SELF_HW")
	)
	(segment
		(start 22.228048 -108.9279)
		(end 25.48509 -108.9279)
		(width 0.10668)
		(layer "In4.Cu")
		(net "RST_BMC_SELF_HW")
	)
	(segment
		(start 56.89219 -102.294182)
		(end 56.384698 -102.294182)
		(width 0.10668)
		(layer "In4.Cu")
		(net "RST_BMC_SELF_HW")
	)
	(segment
		(start 7.9756 -90.725752)
		(end 7.9756 -91.815158)
		(width 0.10668)
		(layer "In4.Cu")
		(net "RST_BMC_SELF_HW")
	)
	(segment
		(start 16.2306 -107.333796)
		(end 16.2306 -107.63504)
		(width 0.10668)
		(layer "In4.Cu")
		(net "RST_BMC_SELF_HW")
	)
	(segment
		(start 58.47588 -73.764902)
		(end 58.47588 -75.788774)
		(width 0.10668)
		(layer "In4.Cu")
		(net "RST_BMC_SELF_HW")
	)
	(segment
		(start 81.312004 -93.355922)
		(end 82.296 -93.355922)
		(width 0.11684)
		(layer "F.Cu")
		(net "RST_BMC_EXTRST_R3_N")
	)
	(segment
		(start 83.329272 -92.873322)
		(end 82.7786 -92.873322)
		(width 0.11684)
		(layer "F.Cu")
		(net "RST_BMC_EXTRST_R3_N")
	)
	(segment
		(start 82.296 -93.355922)
		(end 82.7786 -92.873322)
		(width 0.11684)
		(layer "F.Cu")
		(net "RST_BMC_EXTRST_R3_N")
	)
	(segment
		(start 83.80095 -93.345)
		(end 83.329272 -92.873322)
		(width 0.11684)
		(layer "F.Cu")
		(net "RST_BMC_EXTRST_R3_N")
	)
	(via
		(at 82.7786 -92.873322)
		(size 0.508)
		(drill 0.254)
		(layers "F.Cu" "B.Cu")
		(net "RST_BMC_EXTRST_R3_N")
	)
	(segment
		(start 53.94325 -96.41205)
		(end 53.6956 -96.1644)
		(width 0.11684)
		(layer "F.Cu")
		(net "RST_BMC_EXTRST_R2_N")
	)
	(segment
		(start 53.2003 -94.80296)
		(end 52.832 -94.80296)
		(width 0.11684)
		(layer "F.Cu")
		(net "RST_BMC_EXTRST_R2_N")
	)
	(segment
		(start 51.301396 -98.69805)
		(end 49.2125 -98.69805)
		(width 0.11684)
		(layer "F.Cu")
		(net "RST_BMC_EXTRST_R2_N")
	)
	(segment
		(start 51.71313 -98.286316)
		(end 51.301396 -98.69805)
		(width 0.11684)
		(layer "F.Cu")
		(net "RST_BMC_EXTRST_R2_N")
	)
	(segment
		(start 85.21065 -93.345)
		(end 84.60105 -93.345)
		(width 0.11684)
		(layer "F.Cu")
		(net "RST_BMC_EXTRST_R2_N")
	)
	(segment
		(start 53.722016 -98.02495)
		(end 53.46065 -98.286316)
		(width 0.11684)
		(layer "F.Cu")
		(net "RST_BMC_EXTRST_R2_N")
	)
	(segment
		(start 53.6956 -95.29826)
		(end 53.2003 -94.80296)
		(width 0.11684)
		(layer "F.Cu")
		(net "RST_BMC_EXTRST_R2_N")
	)
	(segment
		(start 53.6956 -96.1644)
		(end 53.6956 -95.29826)
		(width 0.11684)
		(layer "F.Cu")
		(net "RST_BMC_EXTRST_R2_N")
	)
	(segment
		(start 53.46065 -98.286316)
		(end 51.71313 -98.286316)
		(width 0.11684)
		(layer "F.Cu")
		(net "RST_BMC_EXTRST_R2_N")
	)
	(segment
		(start 54.229 -98.02495)
		(end 53.722016 -98.02495)
		(width 0.11684)
		(layer "F.Cu")
		(net "RST_BMC_EXTRST_R2_N")
	)
	(segment
		(start 54.229 -96.41205)
		(end 53.94325 -96.41205)
		(width 0.11684)
		(layer "F.Cu")
		(net "RST_BMC_EXTRST_R2_N")
	)
	(segment
		(start 54.229 -98.02495)
		(end 54.229 -96.41205)
		(width 0.11684)
		(layer "F.Cu")
		(net "RST_BMC_EXTRST_R2_N")
	)
	(via
		(at 85.21065 -93.345)
		(size 0.508)
		(drill 0.254)
		(layers "F.Cu" "B.Cu")
		(net "RST_BMC_EXTRST_R2_N")
	)
	(via
		(at 52.832 -94.80296)
		(size 0.508)
		(drill 0.254)
		(layers "F.Cu" "B.Cu")
		(net "RST_BMC_EXTRST_R2_N")
	)
	(segment
		(start 65.92824 -93.4466)
		(end 68.48602 -96.00438)
		(width 0.08382)
		(layer "In2.Cu")
		(net "RST_BMC_EXTRST_R2_N")
	)
	(segment
		(start 59.817 -95.123)
		(end 61.4934 -93.4466)
		(width 0.08382)
		(layer "In2.Cu")
		(net "RST_BMC_EXTRST_R2_N")
	)
	(segment
		(start 82.42808 -92.194634)
		(end 84.060284 -92.194634)
		(width 0.08382)
		(layer "In2.Cu")
		(net "RST_BMC_EXTRST_R2_N")
	)
	(segment
		(start 71.541386 -95.26524)
		(end 73.31456 -95.26524)
		(width 0.08382)
		(layer "In2.Cu")
		(net "RST_BMC_EXTRST_R2_N")
	)
	(segment
		(start 59.2582 -95.123)
		(end 59.817 -95.123)
		(width 0.08382)
		(layer "In2.Cu")
		(net "RST_BMC_EXTRST_R2_N")
	)
	(segment
		(start 77.22489 -91.35491)
		(end 81.588356 -91.35491)
		(width 0.08382)
		(layer "In2.Cu")
		(net "RST_BMC_EXTRST_R2_N")
	)
	(segment
		(start 55.17134 -94.43974)
		(end 55.94731 -95.21571)
		(width 0.08382)
		(layer "In2.Cu")
		(net "RST_BMC_EXTRST_R2_N")
	)
	(segment
		(start 68.48602 -96.00438)
		(end 70.802246 -96.00438)
		(width 0.08382)
		(layer "In2.Cu")
		(net "RST_BMC_EXTRST_R2_N")
	)
	(segment
		(start 52.832 -94.80296)
		(end 53.19522 -94.43974)
		(width 0.08382)
		(layer "In2.Cu")
		(net "RST_BMC_EXTRST_R2_N")
	)
	(segment
		(start 53.19522 -94.43974)
		(end 55.17134 -94.43974)
		(width 0.08382)
		(layer "In2.Cu")
		(net "RST_BMC_EXTRST_R2_N")
	)
	(segment
		(start 61.4934 -93.4466)
		(end 65.92824 -93.4466)
		(width 0.08382)
		(layer "In2.Cu")
		(net "RST_BMC_EXTRST_R2_N")
	)
	(segment
		(start 84.060284 -92.194634)
		(end 85.21065 -93.345)
		(width 0.08382)
		(layer "In2.Cu")
		(net "RST_BMC_EXTRST_R2_N")
	)
	(segment
		(start 55.94731 -95.21571)
		(end 59.16549 -95.21571)
		(width 0.08382)
		(layer "In2.Cu")
		(net "RST_BMC_EXTRST_R2_N")
	)
	(segment
		(start 73.31456 -95.26524)
		(end 77.22489 -91.35491)
		(width 0.08382)
		(layer "In2.Cu")
		(net "RST_BMC_EXTRST_R2_N")
	)
	(segment
		(start 70.802246 -96.00438)
		(end 71.541386 -95.26524)
		(width 0.08382)
		(layer "In2.Cu")
		(net "RST_BMC_EXTRST_R2_N")
	)
	(segment
		(start 81.588356 -91.35491)
		(end 82.42808 -92.194634)
		(width 0.08382)
		(layer "In2.Cu")
		(net "RST_BMC_EXTRST_R2_N")
	)
	(segment
		(start 59.16549 -95.21571)
		(end 59.2582 -95.123)
		(width 0.08382)
		(layer "In2.Cu")
		(net "RST_BMC_EXTRST_R2_N")
	)
	(segment
		(start 48.979836 -93.51645)
		(end 48.641 -93.855286)
		(width 0.11684)
		(layer "F.Cu")
		(net "RST_BMC_EXTRST_R1_N")
	)
	(segment
		(start 49.2125 -93.51645)
		(end 48.979836 -93.51645)
		(width 0.11684)
		(layer "F.Cu")
		(net "RST_BMC_EXTRST_R1_N")
	)
	(segment
		(start 18.005806 -105.9942)
		(end 18.902426 -105.9942)
		(width 0.11684)
		(layer "F.Cu")
		(net "RST_BMC_EXTRST_R1_N")
	)
	(segment
		(start 15.062962 -105.688384)
		(end 17.44853 -105.688384)
		(width 0.11684)
		(layer "F.Cu")
		(net "RST_BMC_EXTRST_R1_N")
	)
	(segment
		(start 48.2727 -98.04654)
		(end 48.2727 -98.84156)
		(width 0.11684)
		(layer "F.Cu")
		(net "RST_BMC_EXTRST_R1_N")
	)
	(segment
		(start 17.929606 -105.918)
		(end 18.005806 -105.9942)
		(width 0.11684)
		(layer "F.Cu")
		(net "RST_BMC_EXTRST_R1_N")
	)
	(segment
		(start 48.641 -97.67824)
		(end 48.2727 -98.04654)
		(width 0.11684)
		(layer "F.Cu")
		(net "RST_BMC_EXTRST_R1_N")
	)
	(segment
		(start 48.641 -93.855286)
		(end 48.641 -97.67824)
		(width 0.11684)
		(layer "F.Cu")
		(net "RST_BMC_EXTRST_R1_N")
	)
	(segment
		(start 17.44853 -105.688384)
		(end 17.678146 -105.918)
		(width 0.11684)
		(layer "F.Cu")
		(net "RST_BMC_EXTRST_R1_N")
	)
	(segment
		(start 17.678146 -105.918)
		(end 17.929606 -105.918)
		(width 0.11684)
		(layer "F.Cu")
		(net "RST_BMC_EXTRST_R1_N")
	)
	(segment
		(start 18.902426 -105.197402)
		(end 18.994628 -105.1052)
		(width 0.11684)
		(layer "F.Cu")
		(net "RST_BMC_EXTRST_R1_N")
	)
	(segment
		(start 49.2125 -93.51645)
		(end 49.2125 -92.41155)
		(width 0.11684)
		(layer "F.Cu")
		(net "RST_BMC_EXTRST_R1_N")
	)
	(segment
		(start 18.902426 -105.9942)
		(end 18.902426 -105.197402)
		(width 0.11684)
		(layer "F.Cu")
		(net "RST_BMC_EXTRST_R1_N")
	)
	(via
		(at 18.994628 -105.1052)
		(size 0.508)
		(drill 0.254)
		(layers "F.Cu" "B.Cu")
		(net "RST_BMC_EXTRST_R1_N")
	)
	(via
		(at 48.2727 -98.84156)
		(size 0.508)
		(drill 0.254)
		(layers "F.Cu" "B.Cu")
		(net "RST_BMC_EXTRST_R1_N")
	)
	(segment
		(start 29.855922 -101.61397)
		(end 29.09062 -102.379272)
		(width 0.08382)
		(layer "In2.Cu")
		(net "RST_BMC_EXTRST_R1_N")
	)
	(segment
		(start 48.2727 -98.871532)
		(end 44.811442 -102.33279)
		(width 0.08382)
		(layer "In2.Cu")
		(net "RST_BMC_EXTRST_R1_N")
	)
	(segment
		(start 48.2727 -98.84156)
		(end 48.2727 -98.871532)
		(width 0.08382)
		(layer "In2.Cu")
		(net "RST_BMC_EXTRST_R1_N")
	)
	(segment
		(start 19.304 -103.453946)
		(end 19.304 -104.4194)
		(width 0.08382)
		(layer "In2.Cu")
		(net "RST_BMC_EXTRST_R1_N")
	)
	(segment
		(start 34.293556 -100.99802)
		(end 33.967166 -101.32441)
		(width 0.08382)
		(layer "In2.Cu")
		(net "RST_BMC_EXTRST_R1_N")
	)
	(segment
		(start 18.994628 -104.728772)
		(end 18.994628 -105.1052)
		(width 0.08382)
		(layer "In2.Cu")
		(net "RST_BMC_EXTRST_R1_N")
	)
	(segment
		(start 32.195008 -101.61397)
		(end 29.855922 -101.61397)
		(width 0.08382)
		(layer "In2.Cu")
		(net "RST_BMC_EXTRST_R1_N")
	)
	(segment
		(start 24.508968 -102.379272)
		(end 23.73884 -103.1494)
		(width 0.08382)
		(layer "In2.Cu")
		(net "RST_BMC_EXTRST_R1_N")
	)
	(segment
		(start 38.928548 -101.6)
		(end 38.508178 -102.02037)
		(width 0.08382)
		(layer "In2.Cu")
		(net "RST_BMC_EXTRST_R1_N")
	)
	(segment
		(start 23.73884 -103.1494)
		(end 21.79447 -103.1494)
		(width 0.08382)
		(layer "In2.Cu")
		(net "RST_BMC_EXTRST_R1_N")
	)
	(segment
		(start 35.47491 -101.686868)
		(end 35.47491 -101.287072)
		(width 0.08382)
		(layer "In2.Cu")
		(net "RST_BMC_EXTRST_R1_N")
	)
	(segment
		(start 35.185858 -100.99802)
		(end 34.293556 -100.99802)
		(width 0.08382)
		(layer "In2.Cu")
		(net "RST_BMC_EXTRST_R1_N")
	)
	(segment
		(start 38.508178 -102.02037)
		(end 35.808412 -102.02037)
		(width 0.08382)
		(layer "In2.Cu")
		(net "RST_BMC_EXTRST_R1_N")
	)
	(segment
		(start 41.732454 -101.2952)
		(end 39.233602 -101.2952)
		(width 0.08382)
		(layer "In2.Cu")
		(net "RST_BMC_EXTRST_R1_N")
	)
	(segment
		(start 35.47491 -101.287072)
		(end 35.185858 -100.99802)
		(width 0.08382)
		(layer "In2.Cu")
		(net "RST_BMC_EXTRST_R1_N")
	)
	(segment
		(start 29.09062 -102.379272)
		(end 24.508968 -102.379272)
		(width 0.08382)
		(layer "In2.Cu")
		(net "RST_BMC_EXTRST_R1_N")
	)
	(segment
		(start 38.928802 -101.6)
		(end 38.928548 -101.6)
		(width 0.08382)
		(layer "In2.Cu")
		(net "RST_BMC_EXTRST_R1_N")
	)
	(segment
		(start 39.233602 -101.2952)
		(end 38.928802 -101.6)
		(width 0.08382)
		(layer "In2.Cu")
		(net "RST_BMC_EXTRST_R1_N")
	)
	(segment
		(start 33.967166 -101.32441)
		(end 32.484568 -101.32441)
		(width 0.08382)
		(layer "In2.Cu")
		(net "RST_BMC_EXTRST_R1_N")
	)
	(segment
		(start 21.79447 -103.1494)
		(end 21.718016 -103.225854)
		(width 0.08382)
		(layer "In2.Cu")
		(net "RST_BMC_EXTRST_R1_N")
	)
	(segment
		(start 42.770044 -102.33279)
		(end 41.732454 -101.2952)
		(width 0.08382)
		(layer "In2.Cu")
		(net "RST_BMC_EXTRST_R1_N")
	)
	(segment
		(start 19.304 -104.4194)
		(end 18.994628 -104.728772)
		(width 0.08382)
		(layer "In2.Cu")
		(net "RST_BMC_EXTRST_R1_N")
	)
	(segment
		(start 32.484568 -101.32441)
		(end 32.195008 -101.61397)
		(width 0.08382)
		(layer "In2.Cu")
		(net "RST_BMC_EXTRST_R1_N")
	)
	(segment
		(start 21.718016 -103.225854)
		(end 19.532092 -103.225854)
		(width 0.08382)
		(layer "In2.Cu")
		(net "RST_BMC_EXTRST_R1_N")
	)
	(segment
		(start 19.532092 -103.225854)
		(end 19.304 -103.453946)
		(width 0.08382)
		(layer "In2.Cu")
		(net "RST_BMC_EXTRST_R1_N")
	)
	(segment
		(start 44.811442 -102.33279)
		(end 42.770044 -102.33279)
		(width 0.08382)
		(layer "In2.Cu")
		(net "RST_BMC_EXTRST_R1_N")
	)
	(segment
		(start 35.808412 -102.02037)
		(end 35.47491 -101.686868)
		(width 0.08382)
		(layer "In2.Cu")
		(net "RST_BMC_EXTRST_R1_N")
	)
	(segment
		(start 17.454626 -96.782382)
		(end 17.059402 -96.387158)
		(width 0.11684)
		(layer "F.Cu")
		(net "PWR_LED_CPLD")
	)
	(via
		(at 17.454626 -96.782382)
		(size 0.4572)
		(drill 0.254)
		(layers "F.Cu" "B.Cu")
		(net "PWR_LED_CPLD")
	)
	(via
		(at 15.728696 -97.402904)
		(size 0.6604)
		(drill 0.3302)
		(layers "F.Cu" "B.Cu")
		(net "PWR_LED_CPLD")
	)
	(segment
		(start 12.92225 -97.7392)
		(end 15.3924 -97.7392)
		(width 0.11684)
		(layer "B.Cu")
		(net "PWR_LED_CPLD")
	)
	(segment
		(start 15.3924 -97.7392)
		(end 15.728696 -97.402904)
		(width 0.11684)
		(layer "B.Cu")
		(net "PWR_LED_CPLD")
	)
	(segment
		(start 12.71905 -97.536)
		(end 12.92225 -97.7392)
		(width 0.11684)
		(layer "B.Cu")
		(net "PWR_LED_CPLD")
	)
	(segment
		(start 15.9512 -97.1804)
		(end 15.728696 -97.402904)
		(width 0.11684)
		(layer "B.Cu")
		(net "PWR_LED_CPLD")
	)
	(segment
		(start 17.056608 -97.1804)
		(end 15.9512 -97.1804)
		(width 0.11684)
		(layer "B.Cu")
		(net "PWR_LED_CPLD")
	)
	(segment
		(start 17.454626 -96.782382)
		(end 17.056608 -97.1804)
		(width 0.11684)
		(layer "B.Cu")
		(net "PWR_LED_CPLD")
	)
	(segment
		(start 13.23848 -19.07159)
		(end 13.335 -18.97507)
		(width 0.11684)
		(layer "F.Cu")
		(net "PWR_LED")
	)
	(segment
		(start 32.042862 -50.566066)
		(end 32.657796 -51.181)
		(width 0.11684)
		(layer "F.Cu")
		(net "PWR_LED")
	)
	(segment
		(start 11.43 -19.05)
		(end 11.303 -18.923)
		(width 0.11684)
		(layer "F.Cu")
		(net "PWR_LED")
	)
	(segment
		(start 13.335 -18.97507)
		(end 13.335 -18.56105)
		(width 0.11684)
		(layer "F.Cu")
		(net "PWR_LED")
	)
	(segment
		(start 13.335 -18.56105)
		(end 12.84605 -19.05)
		(width 0.11684)
		(layer "F.Cu")
		(net "PWR_LED")
	)
	(segment
		(start 13.23848 -19.906742)
		(end 13.23848 -19.07159)
		(width 0.11684)
		(layer "F.Cu")
		(net "PWR_LED")
	)
	(segment
		(start 32.657796 -51.181)
		(end 34.01695 -51.181)
		(width 0.11684)
		(layer "F.Cu")
		(net "PWR_LED")
	)
	(segment
		(start 12.84605 -19.05)
		(end 11.43 -19.05)
		(width 0.11684)
		(layer "F.Cu")
		(net "PWR_LED")
	)
	(segment
		(start 11.303 -18.923)
		(end 11.303 -18.34896)
		(width 0.11684)
		(layer "F.Cu")
		(net "PWR_LED")
	)
	(via
		(at 13.23848 -19.906742)
		(size 0.508)
		(drill 0.254)
		(layers "F.Cu" "B.Cu")
		(net "PWR_LED")
	)
	(via
		(at 30.6324 -74.541634)
		(size 0.508)
		(drill 0.254)
		(layers "F.Cu" "B.Cu")
		(net "PWR_LED")
	)
	(via
		(at 7.9502 -83.7946)
		(size 0.508)
		(drill 0.254)
		(layers "F.Cu" "B.Cu")
		(net "PWR_LED")
	)
	(via
		(at 8.001 -108.839)
		(size 0.508)
		(drill 0.254)
		(layers "F.Cu" "B.Cu")
		(net "PWR_LED")
	)
	(via
		(at 32.042862 -50.566066)
		(size 0.508)
		(drill 0.254)
		(layers "F.Cu" "B.Cu")
		(net "PWR_LED")
	)
	(segment
		(start 11.65098 -98.00082)
		(end 11.91895 -97.73285)
		(width 0.11684)
		(layer "B.Cu")
		(net "PWR_LED")
	)
	(segment
		(start 8.001 -104.012746)
		(end 10.34796 -101.665786)
		(width 0.11684)
		(layer "B.Cu")
		(net "PWR_LED")
	)
	(segment
		(start 11.11758 -98.00082)
		(end 11.65098 -98.00082)
		(width 0.11684)
		(layer "B.Cu")
		(net "PWR_LED")
	)
	(segment
		(start 11.91895 -97.73285)
		(end 11.91895 -97.536)
		(width 0.11684)
		(layer "B.Cu")
		(net "PWR_LED")
	)
	(segment
		(start 10.34796 -98.77044)
		(end 11.11758 -98.00082)
		(width 0.11684)
		(layer "B.Cu")
		(net "PWR_LED")
	)
	(segment
		(start 10.34796 -101.665786)
		(end 10.34796 -98.77044)
		(width 0.11684)
		(layer "B.Cu")
		(net "PWR_LED")
	)
	(segment
		(start 8.001 -108.839)
		(end 8.001 -104.012746)
		(width 0.11684)
		(layer "B.Cu")
		(net "PWR_LED")
	)
	(segment
		(start 22.31517 -69.93001)
		(end 22.70252 -70.31736)
		(width 0.08382)
		(layer "In2.Cu")
		(net "PWR_LED")
	)
	(segment
		(start 11.9634 -80.0608)
		(end 14.337284 -77.686916)
		(width 0.08382)
		(layer "In2.Cu")
		(net "PWR_LED")
	)
	(segment
		(start 14.337284 -77.686916)
		(end 14.44752 -77.420724)
		(width 0.08382)
		(layer "In2.Cu")
		(net "PWR_LED")
	)
	(segment
		(start 7.6454 -83.4898)
		(end 7.6454 -82.728562)
		(width 0.08382)
		(layer "In2.Cu")
		(net "PWR_LED")
	)
	(segment
		(start 19.57197 -68.21297)
		(end 21.28901 -69.93001)
		(width 0.08382)
		(layer "In2.Cu")
		(net "PWR_LED")
	)
	(segment
		(start 29.790644 -73.699878)
		(end 30.6324 -74.541634)
		(width 0.08382)
		(layer "In2.Cu")
		(net "PWR_LED")
	)
	(segment
		(start 14.44752 -77.420724)
		(end 14.44752 -71.30288)
		(width 0.08382)
		(layer "In2.Cu")
		(net "PWR_LED")
	)
	(segment
		(start 7.6454 -82.728562)
		(end 8.611362 -81.7626)
		(width 0.08382)
		(layer "In2.Cu")
		(net "PWR_LED")
	)
	(segment
		(start 9.79932 -80.72628)
		(end 10.23112 -80.72628)
		(width 0.08382)
		(layer "In2.Cu")
		(net "PWR_LED")
	)
	(segment
		(start 8.611362 -81.7626)
		(end 8.763 -81.7626)
		(width 0.08382)
		(layer "In2.Cu")
		(net "PWR_LED")
	)
	(segment
		(start 17.53743 -68.21297)
		(end 19.57197 -68.21297)
		(width 0.08382)
		(layer "In2.Cu")
		(net "PWR_LED")
	)
	(segment
		(start 27.675078 -73.699878)
		(end 29.790644 -73.699878)
		(width 0.08382)
		(layer "In2.Cu")
		(net "PWR_LED")
	)
	(segment
		(start 8.763 -81.7626)
		(end 9.79932 -80.72628)
		(width 0.08382)
		(layer "In2.Cu")
		(net "PWR_LED")
	)
	(segment
		(start 22.70252 -70.31736)
		(end 24.29256 -70.31736)
		(width 0.08382)
		(layer "In2.Cu")
		(net "PWR_LED")
	)
	(segment
		(start 14.44752 -71.30288)
		(end 17.53743 -68.21297)
		(width 0.08382)
		(layer "In2.Cu")
		(net "PWR_LED")
	)
	(segment
		(start 10.8966 -80.0608)
		(end 11.9634 -80.0608)
		(width 0.08382)
		(layer "In2.Cu")
		(net "PWR_LED")
	)
	(segment
		(start 7.9502 -83.7946)
		(end 7.6454 -83.4898)
		(width 0.08382)
		(layer "In2.Cu")
		(net "PWR_LED")
	)
	(segment
		(start 21.28901 -69.93001)
		(end 22.31517 -69.93001)
		(width 0.08382)
		(layer "In2.Cu")
		(net "PWR_LED")
	)
	(segment
		(start 10.23112 -80.72628)
		(end 10.8966 -80.0608)
		(width 0.08382)
		(layer "In2.Cu")
		(net "PWR_LED")
	)
	(segment
		(start 24.29256 -70.31736)
		(end 27.675078 -73.699878)
		(width 0.08382)
		(layer "In2.Cu")
		(net "PWR_LED")
	)
	(segment
		(start 30.546548 -57.75071)
		(end 30.546548 -59.073034)
		(width 0.10668)
		(layer "In4.Cu")
		(net "PWR_LED")
	)
	(segment
		(start 30.303978 -59.315604)
		(end 30.303978 -59.861958)
		(width 0.10668)
		(layer "In4.Cu")
		(net "PWR_LED")
	)
	(segment
		(start 30.546548 -59.073034)
		(end 30.303978 -59.315604)
		(width 0.10668)
		(layer "In4.Cu")
		(net "PWR_LED")
	)
	(segment
		(start 31.02864 -69.31152)
		(end 31.02864 -74.145394)
		(width 0.10668)
		(layer "In4.Cu")
		(net "PWR_LED")
	)
	(segment
		(start 32.153606 -53.870098)
		(end 30.546548 -57.75071)
		(width 0.10668)
		(layer "In4.Cu")
		(net "PWR_LED")
	)
	(segment
		(start 30.303978 -59.861958)
		(end 30.5943 -60.15228)
		(width 0.10668)
		(layer "In4.Cu")
		(net "PWR_LED")
	)
	(segment
		(start 30.5943 -60.15228)
		(end 30.5943 -62.667896)
		(width 0.10668)
		(layer "In4.Cu")
		(net "PWR_LED")
	)
	(segment
		(start 32.153606 -50.67681)
		(end 32.153606 -53.870098)
		(width 0.10668)
		(layer "In4.Cu")
		(net "PWR_LED")
	)
	(segment
		(start 31.02864 -74.145394)
		(end 30.6324 -74.541634)
		(width 0.10668)
		(layer "In4.Cu")
		(net "PWR_LED")
	)
	(segment
		(start 32.042862 -50.566066)
		(end 32.153606 -50.67681)
		(width 0.10668)
		(layer "In4.Cu")
		(net "PWR_LED")
	)
	(segment
		(start 30.5943 -62.667896)
		(end 29.736796 -63.5254)
		(width 0.10668)
		(layer "In4.Cu")
		(net "PWR_LED")
	)
	(segment
		(start 29.736796 -64.527176)
		(end 31.4706 -66.26098)
		(width 0.10668)
		(layer "In4.Cu")
		(net "PWR_LED")
	)
	(segment
		(start 31.4706 -66.26098)
		(end 31.4706 -68.86956)
		(width 0.10668)
		(layer "In4.Cu")
		(net "PWR_LED")
	)
	(segment
		(start 31.4706 -68.86956)
		(end 31.02864 -69.31152)
		(width 0.10668)
		(layer "In4.Cu")
		(net "PWR_LED")
	)
	(segment
		(start 29.736796 -63.5254)
		(end 29.736796 -64.527176)
		(width 0.10668)
		(layer "In4.Cu")
		(net "PWR_LED")
	)
	(segment
		(start 13.23848 -19.906742)
		(end 11.208258 -19.906742)
		(width 0.10668)
		(layer "In7.Cu")
		(net "PWR_LED")
	)
	(segment
		(start 5.82168 -81.21777)
		(end 5.997956 -81.394046)
		(width 0.10668)
		(layer "In7.Cu")
		(net "PWR_LED")
	)
	(segment
		(start 4.37388 -104.910636)
		(end 4.37388 -88.446102)
		(width 0.10668)
		(layer "In7.Cu")
		(net "PWR_LED")
	)
	(segment
		(start 5.499862 -87.32012)
		(end 6.541516 -87.32012)
		(width 0.10668)
		(layer "In7.Cu")
		(net "PWR_LED")
	)
	(segment
		(start 5.997956 -81.394046)
		(end 6.4643 -81.58734)
		(width 0.10668)
		(layer "In7.Cu")
		(net "PWR_LED")
	)
	(segment
		(start 5.82168 -80.75168)
		(end 5.82168 -81.21777)
		(width 0.10668)
		(layer "In7.Cu")
		(net "PWR_LED")
	)
	(segment
		(start 7.0866 -86.775036)
		(end 7.0866 -84.6582)
		(width 0.10668)
		(layer "In7.Cu")
		(net "PWR_LED")
	)
	(segment
		(start 8.001 -108.537756)
		(end 4.37388 -104.910636)
		(width 0.10668)
		(layer "In7.Cu")
		(net "PWR_LED")
	)
	(segment
		(start 10.287 -20.828)
		(end 10.287 -24.003)
		(width 0.10668)
		(layer "In7.Cu")
		(net "PWR_LED")
	)
	(segment
		(start 7.62 -83.4644)
		(end 7.9502 -83.7946)
		(width 0.10668)
		(layer "In7.Cu")
		(net "PWR_LED")
	)
	(segment
		(start 2.770632 -77.700632)
		(end 5.82168 -80.75168)
		(width 0.10668)
		(layer "In7.Cu")
		(net "PWR_LED")
	)
	(segment
		(start 6.541516 -87.32012)
		(end 7.0866 -86.775036)
		(width 0.10668)
		(layer "In7.Cu")
		(net "PWR_LED")
	)
	(segment
		(start 10.287 -24.003)
		(end 8.21182 -26.07818)
		(width 0.10668)
		(layer "In7.Cu")
		(net "PWR_LED")
	)
	(segment
		(start 8.21182 -26.07818)
		(end 7.440422 -26.07818)
		(width 0.10668)
		(layer "In7.Cu")
		(net "PWR_LED")
	)
	(segment
		(start 7.440422 -26.07818)
		(end 2.770632 -30.74797)
		(width 0.10668)
		(layer "In7.Cu")
		(net "PWR_LED")
	)
	(segment
		(start 7.0866 -84.6582)
		(end 7.9502 -83.7946)
		(width 0.10668)
		(layer "In7.Cu")
		(net "PWR_LED")
	)
	(segment
		(start 6.4643 -81.58734)
		(end 6.60654 -81.58734)
		(width 0.10668)
		(layer "In7.Cu")
		(net "PWR_LED")
	)
	(segment
		(start 7.62 -82.6008)
		(end 7.62 -83.4644)
		(width 0.10668)
		(layer "In7.Cu")
		(net "PWR_LED")
	)
	(segment
		(start 4.37388 -88.446102)
		(end 5.499862 -87.32012)
		(width 0.10668)
		(layer "In7.Cu")
		(net "PWR_LED")
	)
	(segment
		(start 6.60654 -81.58734)
		(end 7.62 -82.6008)
		(width 0.10668)
		(layer "In7.Cu")
		(net "PWR_LED")
	)
	(segment
		(start 8.001 -108.839)
		(end 8.001 -108.537756)
		(width 0.10668)
		(layer "In7.Cu")
		(net "PWR_LED")
	)
	(segment
		(start 11.208258 -19.906742)
		(end 10.287 -20.828)
		(width 0.10668)
		(layer "In7.Cu")
		(net "PWR_LED")
	)
	(segment
		(start 2.770632 -30.74797)
		(end 2.770632 -77.700632)
		(width 0.10668)
		(layer "In7.Cu")
		(net "PWR_LED")
	)
	(segment
		(start 11.05535 -62.2046)
		(end 11.25855 -62.4078)
		(width 0.11684)
		(layer "F.Cu")
		(net "PWRGD_EN_P3V3_R")
	)
	(segment
		(start 8.799068 -63.429134)
		(end 8.799068 -63.837058)
		(width 0.11684)
		(layer "F.Cu")
		(net "PWRGD_EN_P3V3_R")
	)
	(segment
		(start 11.25855 -62.4078)
		(end 11.25855 -63.1952)
		(width 0.11684)
		(layer "F.Cu")
		(net "PWRGD_EN_P3V3_R")
	)
	(segment
		(start 10.4394 -63.2206)
		(end 9.007602 -63.2206)
		(width 0.11684)
		(layer "F.Cu")
		(net "PWRGD_EN_P3V3_R")
	)
	(segment
		(start 11.23315 -63.2206)
		(end 10.4394 -63.2206)
		(width 0.11684)
		(layer "F.Cu")
		(net "PWRGD_EN_P3V3_R")
	)
	(segment
		(start 9.007602 -63.2206)
		(end 8.799068 -63.429134)
		(width 0.11684)
		(layer "F.Cu")
		(net "PWRGD_EN_P3V3_R")
	)
	(segment
		(start 11.25855 -63.1952)
		(end 11.23315 -63.2206)
		(width 0.11684)
		(layer "F.Cu")
		(net "PWRGD_EN_P3V3_R")
	)
	(via
		(at 10.4394 -63.2206)
		(size 0.508)
		(drill 0.254)
		(layers "F.Cu" "B.Cu")
		(net "PWRGD_EN_P3V3_R")
	)
	(segment
		(start 12.71905 -98.4758)
		(end 13.299948 -98.4758)
		(width 0.11684)
		(layer "F.Cu")
		(net "PWRGD_P5V_AUX_R1")
	)
	(segment
		(start 12.71905 -98.73742)
		(end 12.71905 -98.4758)
		(width 0.11684)
		(layer "F.Cu")
		(net "PWRGD_P5V_AUX_R1")
	)
	(segment
		(start 14.984984 -96.790764)
		(end 15.85595 -96.790764)
		(width 0.11684)
		(layer "F.Cu")
		(net "PWRGD_P5V_AUX_R1")
	)
	(segment
		(start 13.299948 -98.4758)
		(end 14.984984 -96.790764)
		(width 0.11684)
		(layer "F.Cu")
		(net "PWRGD_P5V_AUX_R1")
	)
	(segment
		(start 11.95705 -99.49942)
		(end 12.71905 -98.73742)
		(width 0.11684)
		(layer "F.Cu")
		(net "PWRGD_P5V_AUX_R1")
	)
	(segment
		(start 15.85595 -96.790764)
		(end 16.259556 -96.387158)
		(width 0.11684)
		(layer "F.Cu")
		(net "PWRGD_P5V_AUX_R1")
	)
	(via
		(at 11.95705 -99.49942)
		(size 0.508)
		(drill 0.254)
		(layers "F.Cu" "B.Cu")
		(net "PWRGD_P5V_AUX_R1")
	)
	(segment
		(start 12.319 -100.654104)
		(end 12.319 -99.86137)
		(width 0.11684)
		(layer "B.Cu")
		(net "PWRGD_P5V_AUX_R1")
	)
	(segment
		(start 12.319 -99.86137)
		(end 11.95705 -99.49942)
		(width 0.11684)
		(layer "B.Cu")
		(net "PWRGD_P5V_AUX_R1")
	)
	(segment
		(start 9.218168 -52.982368)
		(end 9.36498 -53.12918)
		(width 0.11684)
		(layer "F.Cu")
		(net "PWRGD_P5V_AUX_R")
	)
	(segment
		(start 10.1092 -54.3052)
		(end 10.342372 -54.538372)
		(width 0.11684)
		(layer "F.Cu")
		(net "PWRGD_P5V_AUX_R")
	)
	(segment
		(start 10.771886 -54.538372)
		(end 10.771886 -53.518054)
		(width 0.11684)
		(layer "F.Cu")
		(net "PWRGD_P5V_AUX_R")
	)
	(segment
		(start 10.71626 -53.518054)
		(end 10.771886 -53.518054)
		(width 0.11684)
		(layer "F.Cu")
		(net "PWRGD_P5V_AUX_R")
	)
	(segment
		(start 9.59485 -54.3052)
		(end 10.1092 -54.3052)
		(width 0.11684)
		(layer "F.Cu")
		(net "PWRGD_P5V_AUX_R")
	)
	(segment
		(start 10.342372 -54.538372)
		(end 10.771886 -54.538372)
		(width 0.11684)
		(layer "F.Cu")
		(net "PWRGD_P5V_AUX_R")
	)
	(segment
		(start 9.36625 -54.5338)
		(end 9.59485 -54.3052)
		(width 0.11684)
		(layer "F.Cu")
		(net "PWRGD_P5V_AUX_R")
	)
	(segment
		(start 8.728456 -51.679856)
		(end 8.9916 -51.943)
		(width 0.11684)
		(layer "F.Cu")
		(net "PWRGD_P5V_AUX_R")
	)
	(segment
		(start 10.327386 -53.12918)
		(end 10.71626 -53.518054)
		(width 0.11684)
		(layer "F.Cu")
		(net "PWRGD_P5V_AUX_R")
	)
	(segment
		(start 8.459724 -51.679856)
		(end 8.728456 -51.679856)
		(width 0.11684)
		(layer "F.Cu")
		(net "PWRGD_P5V_AUX_R")
	)
	(segment
		(start 8.9916 -51.943)
		(end 8.9916 -52.7558)
		(width 0.11684)
		(layer "F.Cu")
		(net "PWRGD_P5V_AUX_R")
	)
	(segment
		(start 8.9916 -52.7558)
		(end 9.218168 -52.982368)
		(width 0.11684)
		(layer "F.Cu")
		(net "PWRGD_P5V_AUX_R")
	)
	(segment
		(start 9.36498 -53.12918)
		(end 10.327386 -53.12918)
		(width 0.11684)
		(layer "F.Cu")
		(net "PWRGD_P5V_AUX_R")
	)
	(via
		(at 10.1092 -54.3052)
		(size 0.508)
		(drill 0.254)
		(layers "F.Cu" "B.Cu")
		(net "PWRGD_P5V_AUX_R")
	)
	(via
		(at 9.218168 -52.982368)
		(size 0.762)
		(drill 0.381)
		(layers "F.Cu" "B.Cu")
		(net "PWRGD_P5V_AUX_R")
	)
	(segment
		(start 10.4902 -54.3052)
		(end 10.94105 -54.75605)
		(width 0.11684)
		(layer "B.Cu")
		(net "PWRGD_P5V_AUX_R")
	)
	(segment
		(start 10.1092 -54.3052)
		(end 10.4902 -54.3052)
		(width 0.11684)
		(layer "B.Cu")
		(net "PWRGD_P5V_AUX_R")
	)
	(segment
		(start 11.684 -55.13705)
		(end 11.684 -55.75935)
		(width 0.11684)
		(layer "B.Cu")
		(net "PWRGD_P5V_AUX_R")
	)
	(segment
		(start 11.684 -55.75935)
		(end 11.92657 -56.00192)
		(width 0.11684)
		(layer "B.Cu")
		(net "PWRGD_P5V_AUX_R")
	)
	(segment
		(start 11.303 -54.75605)
		(end 11.684 -55.13705)
		(width 0.11684)
		(layer "B.Cu")
		(net "PWRGD_P5V_AUX_R")
	)
	(segment
		(start 10.94105 -54.75605)
		(end 11.303 -54.75605)
		(width 0.11684)
		(layer "B.Cu")
		(net "PWRGD_P5V_AUX_R")
	)
	(segment
		(start 20.66417 -97.582228)
		(end 21.059394 -97.187004)
		(width 0.11684)
		(layer "F.Cu")
		(net "PWRGD_P3V3_RGM_R1")
	)
	(via
		(at 21.3106 -97.9678)
		(size 0.6604)
		(drill 0.3302)
		(layers "F.Cu" "B.Cu")
		(net "PWRGD_P3V3_RGM_R1")
	)
	(via
		(at 20.66417 -97.582228)
		(size 0.4572)
		(drill 0.254)
		(layers "F.Cu" "B.Cu")
		(net "PWRGD_P3V3_RGM_R1")
	)
	(segment
		(start 21.19376 -97.582228)
		(end 21.3106 -97.699068)
		(width 0.11684)
		(layer "B.Cu")
		(net "PWRGD_P3V3_RGM_R1")
	)
	(segment
		(start 21.3106 -97.699068)
		(end 21.3106 -97.9678)
		(width 0.11684)
		(layer "B.Cu")
		(net "PWRGD_P3V3_RGM_R1")
	)
	(segment
		(start 18.923 -100.906326)
		(end 20.134326 -99.695)
		(width 0.11684)
		(layer "B.Cu")
		(net "PWRGD_P3V3_RGM_R1")
	)
	(segment
		(start 21.3106 -99.462082)
		(end 21.3106 -97.9678)
		(width 0.11684)
		(layer "B.Cu")
		(net "PWRGD_P3V3_RGM_R1")
	)
	(segment
		(start 18.923 -101.58095)
		(end 18.923 -100.906326)
		(width 0.11684)
		(layer "B.Cu")
		(net "PWRGD_P3V3_RGM_R1")
	)
	(segment
		(start 21.077682 -99.695)
		(end 21.3106 -99.462082)
		(width 0.11684)
		(layer "B.Cu")
		(net "PWRGD_P3V3_RGM_R1")
	)
	(segment
		(start 20.66417 -97.582228)
		(end 21.19376 -97.582228)
		(width 0.11684)
		(layer "B.Cu")
		(net "PWRGD_P3V3_RGM_R1")
	)
	(segment
		(start 20.134326 -99.695)
		(end 21.077682 -99.695)
		(width 0.11684)
		(layer "B.Cu")
		(net "PWRGD_P3V3_RGM_R1")
	)
	(segment
		(start 70.146926 -28.8798)
		(end 70.0278 -28.8798)
		(width 0.254)
		(layer "F.Cu")
		(net "PWRGD_P3V3_RGM_R")
	)
	(segment
		(start 70.04685 -30.24505)
		(end 70.4088 -30.24505)
		(width 0.254)
		(layer "F.Cu")
		(net "PWRGD_P3V3_RGM_R")
	)
	(segment
		(start 69.7738 -29.972)
		(end 70.04685 -30.24505)
		(width 0.254)
		(layer "F.Cu")
		(net "PWRGD_P3V3_RGM_R")
	)
	(segment
		(start 70.0278 -28.8798)
		(end 69.8373 -29.0703)
		(width 0.254)
		(layer "F.Cu")
		(net "PWRGD_P3V3_RGM_R")
	)
	(segment
		(start 71.4502 -28.31465)
		(end 70.712076 -28.31465)
		(width 0.254)
		(layer "F.Cu")
		(net "PWRGD_P3V3_RGM_R")
	)
	(segment
		(start 69.8373 -29.115258)
		(end 69.7738 -29.178758)
		(width 0.254)
		(layer "F.Cu")
		(net "PWRGD_P3V3_RGM_R")
	)
	(segment
		(start 69.8373 -29.0703)
		(end 69.8373 -29.115258)
		(width 0.254)
		(layer "F.Cu")
		(net "PWRGD_P3V3_RGM_R")
	)
	(segment
		(start 69.7738 -29.178758)
		(end 69.7738 -29.972)
		(width 0.254)
		(layer "F.Cu")
		(net "PWRGD_P3V3_RGM_R")
	)
	(segment
		(start 70.712076 -28.31465)
		(end 70.146926 -28.8798)
		(width 0.254)
		(layer "F.Cu")
		(net "PWRGD_P3V3_RGM_R")
	)
	(via
		(at 71.2216 -32.004)
		(size 0.508)
		(drill 0.254)
		(layers "F.Cu" "B.Cu")
		(net "PWRGD_P3V3_RGM_R")
	)
	(via
		(at 81.518252 -31.159958)
		(size 0.508)
		(drill 0.254)
		(layers "F.Cu" "B.Cu")
		(net "PWRGD_P3V3_AUX_R2")
	)
	(segment
		(start 14.6812 -98.475546)
		(end 14.6812 -97.655126)
		(width 0.11684)
		(layer "F.Cu")
		(net "PWRGD_P3V3_AUX_R1")
	)
	(segment
		(start 14.6812 -97.655126)
		(end 15.149322 -97.187004)
		(width 0.11684)
		(layer "F.Cu")
		(net "PWRGD_P3V3_AUX_R1")
	)
	(segment
		(start 15.149322 -97.187004)
		(end 15.459456 -97.187004)
		(width 0.11684)
		(layer "F.Cu")
		(net "PWRGD_P3V3_AUX_R1")
	)
	(segment
		(start 12.991846 -100.1649)
		(end 14.6812 -98.475546)
		(width 0.11684)
		(layer "F.Cu")
		(net "PWRGD_P3V3_AUX_R1")
	)
	(segment
		(start 12.82065 -100.1649)
		(end 12.991846 -100.1649)
		(width 0.11684)
		(layer "F.Cu")
		(net "PWRGD_P3V3_AUX_R1")
	)
	(segment
		(start 10.6172 -67.2592)
		(end 9.63041 -66.27241)
		(width 0.11684)
		(layer "F.Cu")
		(net "PWRGD_P3V3_AUX_R")
	)
	(segment
		(start 11.29538 -67.81165)
		(end 11.7729 -67.81165)
		(width 0.11684)
		(layer "F.Cu")
		(net "PWRGD_P3V3_AUX_R")
	)
	(segment
		(start 12.37615 -66.2432)
		(end 12.37615 -67.2084)
		(width 0.11684)
		(layer "F.Cu")
		(net "PWRGD_P3V3_AUX_R")
	)
	(segment
		(start 9.63041 -66.27241)
		(end 8.56361 -66.27241)
		(width 0.11684)
		(layer "F.Cu")
		(net "PWRGD_P3V3_AUX_R")
	)
	(segment
		(start 10.6172 -67.5132)
		(end 10.6172 -67.2592)
		(width 0.11684)
		(layer "F.Cu")
		(net "PWRGD_P3V3_AUX_R")
	)
	(segment
		(start 8.56361 -66.27241)
		(end 8.298942 -66.007742)
		(width 0.11684)
		(layer "F.Cu")
		(net "PWRGD_P3V3_AUX_R")
	)
	(segment
		(start 11.29538 -67.81165)
		(end 10.91565 -67.81165)
		(width 0.11684)
		(layer "F.Cu")
		(net "PWRGD_P3V3_AUX_R")
	)
	(segment
		(start 8.298942 -66.007742)
		(end 8.298942 -65.636902)
		(width 0.11684)
		(layer "F.Cu")
		(net "PWRGD_P3V3_AUX_R")
	)
	(segment
		(start 10.91565 -67.81165)
		(end 10.6172 -67.5132)
		(width 0.11684)
		(layer "F.Cu")
		(net "PWRGD_P3V3_AUX_R")
	)
	(segment
		(start 11.7729 -67.81165)
		(end 12.37615 -67.2084)
		(width 0.11684)
		(layer "F.Cu")
		(net "PWRGD_P3V3_AUX_R")
	)
	(via
		(at 34.262314 -57.193434)
		(size 0.508)
		(drill 0.254)
		(layers "F.Cu" "B.Cu")
		(net "EN_P1V8_R")
	)
	(segment
		(start 16.664178 -97.582228)
		(end 17.059402 -97.187004)
		(width 0.11684)
		(layer "F.Cu")
		(net "PWRGD_P2V5_AUX_R1")
	)
	(via
		(at 16.664178 -97.582228)
		(size 0.4572)
		(drill 0.254)
		(layers "F.Cu" "B.Cu")
		(net "PWRGD_P2V5_AUX_R1")
	)
	(via
		(at 13.8684 -98.552)
		(size 0.6604)
		(drill 0.3302)
		(layers "F.Cu" "B.Cu")
		(net "PWRGD_P2V5_AUX_R1")
	)
	(segment
		(start 15.0622 -97.9932)
		(end 16.253206 -97.9932)
		(width 0.11684)
		(layer "B.Cu")
		(net "PWRGD_P2V5_AUX_R1")
	)
	(segment
		(start 16.253206 -97.9932)
		(end 16.664178 -97.582228)
		(width 0.11684)
		(layer "B.Cu")
		(net "PWRGD_P2V5_AUX_R1")
	)
	(segment
		(start 14.5034 -98.552)
		(end 15.0622 -97.9932)
		(width 0.11684)
		(layer "B.Cu")
		(net "PWRGD_P2V5_AUX_R1")
	)
	(segment
		(start 13.8684 -98.552)
		(end 14.5034 -98.552)
		(width 0.11684)
		(layer "B.Cu")
		(net "PWRGD_P2V5_AUX_R1")
	)
	(segment
		(start 13.8684 -98.552)
		(end 12.71905 -98.552)
		(width 0.11684)
		(layer "B.Cu")
		(net "PWRGD_P2V5_AUX_R1")
	)
	(segment
		(start 81.788 -36.81095)
		(end 81.6864 -36.70935)
		(width 0.11684)
		(layer "F.Cu")
		(net "PWRGD_P2V5_AUX_R")
	)
	(segment
		(start 81.6864 -36.70935)
		(end 81.6864 -36.0934)
		(width 0.11684)
		(layer "F.Cu")
		(net "PWRGD_P2V5_AUX_R")
	)
	(segment
		(start 81.639664 -35.130486)
		(end 81.639664 -36.046664)
		(width 0.11684)
		(layer "F.Cu")
		(net "PWRGD_P2V5_AUX_R")
	)
	(segment
		(start 81.639664 -36.046664)
		(end 81.6864 -36.0934)
		(width 0.11684)
		(layer "F.Cu")
		(net "PWRGD_P2V5_AUX_R")
	)
	(via
		(at 81.92262 -35.2933)
		(size 0.6604)
		(drill 0.3302)
		(layers "F.Cu" "B.Cu")
		(net "PWRGD_P2V5_AUX_R")
	)
	(via
		(at 81.6864 -36.0934)
		(size 0.508)
		(drill 0.254)
		(layers "F.Cu" "B.Cu")
		(net "PWRGD_P2V5_AUX_R")
	)
	(segment
		(start 80.772 -34.229548)
		(end 81.313528 -34.771076)
		(width 0.11684)
		(layer "B.Cu")
		(net "PWRGD_P2V5_AUX_R")
	)
	(segment
		(start 81.313528 -34.771076)
		(end 81.400396 -34.771076)
		(width 0.11684)
		(layer "B.Cu")
		(net "PWRGD_P2V5_AUX_R")
	)
	(segment
		(start 81.92262 -35.85718)
		(end 81.92262 -35.2933)
		(width 0.11684)
		(layer "B.Cu")
		(net "PWRGD_P2V5_AUX_R")
	)
	(segment
		(start 80.772 -33.86455)
		(end 80.772 -34.229548)
		(width 0.11684)
		(layer "B.Cu")
		(net "PWRGD_P2V5_AUX_R")
	)
	(segment
		(start 81.400396 -34.771076)
		(end 81.92262 -35.2933)
		(width 0.11684)
		(layer "B.Cu")
		(net "PWRGD_P2V5_AUX_R")
	)
	(segment
		(start 81.6864 -36.0934)
		(end 81.92262 -35.85718)
		(width 0.11684)
		(layer "B.Cu")
		(net "PWRGD_P2V5_AUX_R")
	)
	(segment
		(start 79.756 -33.86455)
		(end 80.772 -33.86455)
		(width 0.11684)
		(layer "B.Cu")
		(net "PWRGD_P2V5_AUX_R")
	)
	(segment
		(start 70.4342 -27.838146)
		(end 69.925946 -28.3464)
		(width 0.254)
		(layer "F.Cu")
		(net "EN_P3V3_RGM_R")
	)
	(segment
		(start 70.4342 -27.67965)
		(end 70.4342 -27.838146)
		(width 0.254)
		(layer "F.Cu")
		(net "EN_P3V3_RGM_R")
	)
	(segment
		(start 69.925946 -28.3464)
		(end 68.961 -28.3464)
		(width 0.254)
		(layer "F.Cu")
		(net "EN_P3V3_RGM_R")
	)
	(via
		(at 68.961 -28.3464)
		(size 0.762)
		(drill 0.381)
		(layers "F.Cu" "B.Cu")
		(net "EN_P3V3_RGM_R")
	)
	(segment
		(start 21.470874 -96.775778)
		(end 21.859494 -96.387158)
		(width 0.11684)
		(layer "F.Cu")
		(net "PWRGD_P1V8_AUX_R1")
	)
	(segment
		(start 19.870928 -100.261928)
		(end 19.870928 -99.426014)
		(width 0.11684)
		(layer "F.Cu")
		(net "PWRGD_P1V8_AUX_R1")
	)
	(segment
		(start 20.098512 -99.19843)
		(end 21.19757 -99.19843)
		(width 0.11684)
		(layer "F.Cu")
		(net "PWRGD_P1V8_AUX_R1")
	)
	(segment
		(start 19.870928 -99.426014)
		(end 20.098512 -99.19843)
		(width 0.11684)
		(layer "F.Cu")
		(net "PWRGD_P1V8_AUX_R1")
	)
	(segment
		(start 20.066 -100.457)
		(end 19.870928 -100.261928)
		(width 0.11684)
		(layer "F.Cu")
		(net "PWRGD_P1V8_AUX_R1")
	)
	(segment
		(start 21.19757 -99.19843)
		(end 21.470874 -98.925126)
		(width 0.11684)
		(layer "F.Cu")
		(net "PWRGD_P1V8_AUX_R1")
	)
	(segment
		(start 21.470874 -98.925126)
		(end 21.470874 -96.775778)
		(width 0.11684)
		(layer "F.Cu")
		(net "PWRGD_P1V8_AUX_R1")
	)
	(via
		(at 20.066 -100.457)
		(size 0.508)
		(drill 0.254)
		(layers "F.Cu" "B.Cu")
		(net "PWRGD_P1V8_AUX_R1")
	)
	(segment
		(start 19.939 -100.584)
		(end 20.066 -100.457)
		(width 0.11684)
		(layer "B.Cu")
		(net "PWRGD_P1V8_AUX_R1")
	)
	(segment
		(start 19.939 -101.58095)
		(end 19.939 -100.584)
		(width 0.11684)
		(layer "B.Cu")
		(net "PWRGD_P1V8_AUX_R1")
	)
	(segment
		(start 17.281652 -31.8262)
		(end 16.9926 -31.8262)
		(width 0.254)
		(layer "F.Cu")
		(net "EN_P1V0_AUX_R")
	)
	(segment
		(start 17.517872 -32.06242)
		(end 17.281652 -31.8262)
		(width 0.254)
		(layer "F.Cu")
		(net "EN_P1V0_AUX_R")
	)
	(segment
		(start 16.68018 -32.06242)
		(end 16.235172 -32.06242)
		(width 0.254)
		(layer "F.Cu")
		(net "EN_P1V0_AUX_R")
	)
	(segment
		(start 15.26286 -32.06369)
		(end 15.26413 -32.06242)
		(width 0.254)
		(layer "F.Cu")
		(net "EN_P1V0_AUX_R")
	)
	(segment
		(start 16.9164 -31.8262)
		(end 16.68018 -32.06242)
		(width 0.254)
		(layer "F.Cu")
		(net "EN_P1V0_AUX_R")
	)
	(segment
		(start 17.869916 -32.06242)
		(end 17.517872 -32.06242)
		(width 0.254)
		(layer "F.Cu")
		(net "EN_P1V0_AUX_R")
	)
	(segment
		(start 16.9926 -31.8262)
		(end 16.9164 -31.8262)
		(width 0.254)
		(layer "F.Cu")
		(net "EN_P1V0_AUX_R")
	)
	(segment
		(start 15.26413 -32.06242)
		(end 16.235172 -32.06242)
		(width 0.254)
		(layer "F.Cu")
		(net "EN_P1V0_AUX_R")
	)
	(via
		(at 16.9926 -31.8262)
		(size 0.508)
		(drill 0.254)
		(layers "F.Cu" "B.Cu")
		(net "EN_P1V0_AUX_R")
	)
	(segment
		(start 20.066 -101.167946)
		(end 20.6248 -100.609146)
		(width 0.11684)
		(layer "F.Cu")
		(net "PWRGD_P1V2_AUX_R1")
	)
	(segment
		(start 20.6248 -100.021644)
		(end 21.059394 -99.58705)
		(width 0.11684)
		(layer "F.Cu")
		(net "PWRGD_P1V2_AUX_R1")
	)
	(segment
		(start 20.066 -102.34295)
		(end 20.066 -101.167946)
		(width 0.11684)
		(layer "F.Cu")
		(net "PWRGD_P1V2_AUX_R1")
	)
	(segment
		(start 20.6248 -100.609146)
		(end 20.6248 -100.021644)
		(width 0.11684)
		(layer "F.Cu")
		(net "PWRGD_P1V2_AUX_R1")
	)
	(segment
		(start 83.194144 -73.430638)
		(end 83.412838 -73.430638)
		(width 0.11684)
		(layer "F.Cu")
		(net "PWRGD_P1V2_AUX_R")
	)
	(segment
		(start 84.76615 -75.1586)
		(end 84.455 -75.46975)
		(width 0.11684)
		(layer "F.Cu")
		(net "PWRGD_P1V2_AUX_R")
	)
	(segment
		(start 83.412838 -73.430638)
		(end 84.17179 -74.18959)
		(width 0.11684)
		(layer "F.Cu")
		(net "PWRGD_P1V2_AUX_R")
	)
	(segment
		(start 85.471 -76.25715)
		(end 84.455 -76.25715)
		(width 0.11684)
		(layer "F.Cu")
		(net "PWRGD_P1V2_AUX_R")
	)
	(segment
		(start 84.772246 -74.18959)
		(end 84.76615 -74.195686)
		(width 0.11684)
		(layer "F.Cu")
		(net "PWRGD_P1V2_AUX_R")
	)
	(segment
		(start 84.76615 -74.195686)
		(end 84.76615 -75.1586)
		(width 0.11684)
		(layer "F.Cu")
		(net "PWRGD_P1V2_AUX_R")
	)
	(segment
		(start 84.455 -75.46975)
		(end 84.455 -76.25715)
		(width 0.11684)
		(layer "F.Cu")
		(net "PWRGD_P1V2_AUX_R")
	)
	(segment
		(start 84.17179 -74.18959)
		(end 84.772246 -74.18959)
		(width 0.11684)
		(layer "F.Cu")
		(net "PWRGD_P1V2_AUX_R")
	)
	(segment
		(start 34.55416 -36.928298)
		(end 34.93135 -36.551108)
		(width 0.11684)
		(layer "F.Cu")
		(net "PWRGD_P1V0_AUX_R2")
	)
	(segment
		(start 34.55416 -38.288214)
		(end 34.55416 -36.928298)
		(width 0.11684)
		(layer "F.Cu")
		(net "PWRGD_P1V0_AUX_R2")
	)
	(segment
		(start 34.85896 -38.593014)
		(end 34.55416 -38.288214)
		(width 0.11684)
		(layer "F.Cu")
		(net "PWRGD_P1V0_AUX_R2")
	)
	(segment
		(start 34.85896 -38.85819)
		(end 34.85896 -38.593014)
		(width 0.11684)
		(layer "F.Cu")
		(net "PWRGD_P1V0_AUX_R2")
	)
	(segment
		(start 20.66417 -98.382328)
		(end 21.059394 -97.987104)
		(width 0.11684)
		(layer "F.Cu")
		(net "PWRGD_P1V0_AUX_R1")
	)
	(via
		(at 20.66417 -99.1362)
		(size 0.6604)
		(drill 0.3302)
		(layers "F.Cu" "B.Cu")
		(net "PWRGD_P1V0_AUX_R1")
	)
	(via
		(at 20.66417 -98.382328)
		(size 0.4572)
		(drill 0.254)
		(layers "F.Cu" "B.Cu")
		(net "PWRGD_P1V0_AUX_R1")
	)
	(segment
		(start 17.907 -101.58095)
		(end 20.35175 -99.1362)
		(width 0.11684)
		(layer "B.Cu")
		(net "PWRGD_P1V0_AUX_R1")
	)
	(segment
		(start 20.35175 -99.1362)
		(end 20.66417 -99.1362)
		(width 0.11684)
		(layer "B.Cu")
		(net "PWRGD_P1V0_AUX_R1")
	)
	(segment
		(start 20.66417 -99.1362)
		(end 20.66417 -98.382328)
		(width 0.11684)
		(layer "B.Cu")
		(net "PWRGD_P1V0_AUX_R1")
	)
	(segment
		(start 25.5016 -33.50895)
		(end 24.4856 -33.50895)
		(width 0.11684)
		(layer "F.Cu")
		(net "PWRGD_P1V0_AUX_R")
	)
	(segment
		(start 24.480774 -33.504124)
		(end 24.4856 -33.50895)
		(width 0.11684)
		(layer "F.Cu")
		(net "PWRGD_P1V0_AUX_R")
	)
	(segment
		(start 21.9075 -34.2773)
		(end 21.3233 -34.2773)
		(width 0.11684)
		(layer "F.Cu")
		(net "PWRGD_P1V0_AUX_R")
	)
	(segment
		(start 23.071836 -33.504124)
		(end 22.40407 -33.78073)
		(width 0.11684)
		(layer "F.Cu")
		(net "PWRGD_P1V0_AUX_R")
	)
	(segment
		(start 23.47087 -33.504124)
		(end 23.071836 -33.504124)
		(width 0.11684)
		(layer "F.Cu")
		(net "PWRGD_P1V0_AUX_R")
	)
	(segment
		(start 22.40407 -33.78073)
		(end 21.9075 -34.2773)
		(width 0.11684)
		(layer "F.Cu")
		(net "PWRGD_P1V0_AUX_R")
	)
	(segment
		(start 21.3233 -34.2773)
		(end 21.3233 -33.388046)
		(width 0.11684)
		(layer "F.Cu")
		(net "PWRGD_P1V0_AUX_R")
	)
	(segment
		(start 21.3233 -33.388046)
		(end 20.997672 -33.062418)
		(width 0.11684)
		(layer "F.Cu")
		(net "PWRGD_P1V0_AUX_R")
	)
	(segment
		(start 23.47087 -33.504124)
		(end 24.480774 -33.504124)
		(width 0.11684)
		(layer "F.Cu")
		(net "PWRGD_P1V0_AUX_R")
	)
	(segment
		(start 20.997672 -33.062418)
		(end 20.770088 -33.062418)
		(width 0.11684)
		(layer "F.Cu")
		(net "PWRGD_P1V0_AUX_R")
	)
	(via
		(at 21.3233 -34.2773)
		(size 0.762)
		(drill 0.381)
		(layers "F.Cu" "B.Cu")
		(net "PWRGD_P1V0_AUX_R")
	)
	(segment
		(start 31.699454 -37.561774)
		(end 31.699454 -37.62502)
		(width 0.11684)
		(layer "F.Cu")
		(net "PWRGD_P1V0_AUX_DELAY_R1")
	)
	(segment
		(start 32.893 -36.59505)
		(end 33.909 -36.59505)
		(width 0.11684)
		(layer "F.Cu")
		(net "PWRGD_P1V0_AUX_DELAY_R1")
	)
	(segment
		(start 32.95904 -38.17366)
		(end 32.95904 -38.85819)
		(width 0.11684)
		(layer "F.Cu")
		(net "PWRGD_P1V0_AUX_DELAY_R1")
	)
	(segment
		(start 31.699454 -37.62502)
		(end 32.042354 -37.96792)
		(width 0.11684)
		(layer "F.Cu")
		(net "PWRGD_P1V0_AUX_DELAY_R1")
	)
	(segment
		(start 32.666178 -36.59505)
		(end 31.699454 -37.561774)
		(width 0.11684)
		(layer "F.Cu")
		(net "PWRGD_P1V0_AUX_DELAY_R1")
	)
	(segment
		(start 32.7533 -37.96792)
		(end 32.95904 -38.17366)
		(width 0.11684)
		(layer "F.Cu")
		(net "PWRGD_P1V0_AUX_DELAY_R1")
	)
	(segment
		(start 32.042354 -37.96792)
		(end 32.7533 -37.96792)
		(width 0.11684)
		(layer "F.Cu")
		(net "PWRGD_P1V0_AUX_DELAY_R1")
	)
	(segment
		(start 32.893 -36.59505)
		(end 32.666178 -36.59505)
		(width 0.11684)
		(layer "F.Cu")
		(net "PWRGD_P1V0_AUX_DELAY_R1")
	)
	(via
		(at 31.699454 -37.62502)
		(size 0.762)
		(drill 0.381)
		(layers "F.Cu" "B.Cu")
		(net "PWRGD_P1V0_AUX_DELAY_R1")
	)
	(segment
		(start 10.287 -85.344)
		(end 10.287 -87.86495)
		(width 0.11684)
		(layer "F.Cu")
		(net "PWRGD_P1V0_AUX_DELAY_BUF")
	)
	(segment
		(start 9.79424 -83.753706)
		(end 9.24052 -83.199986)
		(width 0.11684)
		(layer "F.Cu")
		(net "PWRGD_P1V0_AUX_DELAY_BUF")
	)
	(segment
		(start 9.79424 -83.753706)
		(end 9.79424 -84.25561)
		(width 0.11684)
		(layer "F.Cu")
		(net "PWRGD_P1V0_AUX_DELAY_BUF")
	)
	(segment
		(start 9.24052 -83.199986)
		(end 9.07796 -83.199986)
		(width 0.11684)
		(layer "F.Cu")
		(net "PWRGD_P1V0_AUX_DELAY_BUF")
	)
	(segment
		(start 9.9314 -84.9884)
		(end 10.287 -85.344)
		(width 0.11684)
		(layer "F.Cu")
		(net "PWRGD_P1V0_AUX_DELAY_BUF")
	)
	(segment
		(start 9.79424 -84.25561)
		(end 9.9314 -84.39277)
		(width 0.11684)
		(layer "F.Cu")
		(net "PWRGD_P1V0_AUX_DELAY_BUF")
	)
	(segment
		(start 10.287 -87.86495)
		(end 9.63295 -88.519)
		(width 0.11684)
		(layer "F.Cu")
		(net "PWRGD_P1V0_AUX_DELAY_BUF")
	)
	(segment
		(start 9.9314 -84.39277)
		(end 9.9314 -84.9884)
		(width 0.11684)
		(layer "F.Cu")
		(net "PWRGD_P1V0_AUX_DELAY_BUF")
	)
	(via
		(at 9.79424 -83.753706)
		(size 0.508)
		(drill 0.254)
		(layers "F.Cu" "B.Cu")
		(net "PWRGD_P1V0_AUX_DELAY_BUF")
	)
	(segment
		(start 36.47059 -45.50664)
		(end 36.891976 -45.085254)
		(width 0.11684)
		(layer "F.Cu")
		(net "PD_BIOS_MUX_EN_R_N")
	)
	(segment
		(start 43.6118 -39.8526)
		(end 44.0182 -40.259)
		(width 0.11684)
		(layer "F.Cu")
		(net "PD_BIOS_MUX_EN_R_N")
	)
	(segment
		(start 36.891976 -45.085254)
		(end 37.308028 -45.085254)
		(width 0.11684)
		(layer "F.Cu")
		(net "PD_BIOS_MUX_EN_R_N")
	)
	(segment
		(start 44.0182 -40.259)
		(end 44.0182 -40.496236)
		(width 0.11684)
		(layer "F.Cu")
		(net "PD_BIOS_MUX_EN_R_N")
	)
	(segment
		(start 44.0182 -40.496236)
		(end 44.299886 -41.176194)
		(width 0.11684)
		(layer "F.Cu")
		(net "PD_BIOS_MUX_EN_R_N")
	)
	(segment
		(start 44.299886 -41.176194)
		(end 44.895008 -41.771316)
		(width 0.11684)
		(layer "F.Cu")
		(net "PD_BIOS_MUX_EN_R_N")
	)
	(via
		(at 43.6118 -39.8526)
		(size 0.508)
		(drill 0.254)
		(layers "F.Cu" "B.Cu")
		(net "PD_BIOS_MUX_EN_R_N")
	)
	(via
		(at 37.308028 -45.085254)
		(size 0.508)
		(drill 0.254)
		(layers "F.Cu" "B.Cu")
		(net "PD_BIOS_MUX_EN_R_N")
	)
	(segment
		(start 39.10965 -44.89704)
		(end 37.496242 -44.89704)
		(width 0.10668)
		(layer "In4.Cu")
		(net "PD_BIOS_MUX_EN_R_N")
	)
	(segment
		(start 43.49496 -40.51173)
		(end 39.10965 -44.89704)
		(width 0.10668)
		(layer "In4.Cu")
		(net "PD_BIOS_MUX_EN_R_N")
	)
	(segment
		(start 43.6118 -39.8526)
		(end 43.49496 -39.96944)
		(width 0.10668)
		(layer "In4.Cu")
		(net "PD_BIOS_MUX_EN_R_N")
	)
	(segment
		(start 43.49496 -39.96944)
		(end 43.49496 -40.51173)
		(width 0.10668)
		(layer "In4.Cu")
		(net "PD_BIOS_MUX_EN_R_N")
	)
	(segment
		(start 37.496242 -44.89704)
		(end 37.308028 -45.085254)
		(width 0.10668)
		(layer "In4.Cu")
		(net "PD_BIOS_MUX_EN_R_N")
	)
	(segment
		(start 35.0266 -45.50664)
		(end 35.67049 -45.50664)
		(width 0.11684)
		(layer "F.Cu")
		(net "PD_BIOS_MUX_EN_N")
	)
	(via
		(at 38.42131 -101.473)
		(size 0.508)
		(drill 0.254)
		(layers "F.Cu" "B.Cu")
		(net "PD_BIOS_MUX_EN_N")
	)
	(via
		(at 31.5214 -79.0194)
		(size 0.508)
		(drill 0.254)
		(layers "F.Cu" "B.Cu")
		(net "PD_BIOS_MUX_EN_N")
	)
	(via
		(at 35.0266 -45.50664)
		(size 0.508)
		(drill 0.254)
		(layers "F.Cu" "B.Cu")
		(net "PD_BIOS_MUX_EN_N")
	)
	(via
		(at 50.07737 -79.812642)
		(size 0.508)
		(drill 0.254)
		(layers "F.Cu" "B.Cu")
		(net "PD_BIOS_MUX_EN_N")
	)
	(via
		(at 39.14394 -102.63886)
		(size 0.6604)
		(drill 0.3302)
		(layers "F.Cu" "B.Cu")
		(net "PD_BIOS_MUX_EN_N")
	)
	(segment
		(start 40.969184 -103.327962)
		(end 39.827962 -103.327962)
		(width 0.11684)
		(layer "B.Cu")
		(net "PD_BIOS_MUX_EN_N")
	)
	(segment
		(start 38.9382 -101.289866)
		(end 38.613334 -100.965)
		(width 0.11684)
		(layer "B.Cu")
		(net "PD_BIOS_MUX_EN_N")
	)
	(segment
		(start 38.9382 -102.43312)
		(end 38.9382 -101.289866)
		(width 0.11684)
		(layer "B.Cu")
		(net "PD_BIOS_MUX_EN_N")
	)
	(segment
		(start 38.4048 -101.48951)
		(end 38.4048 -101.92766)
		(width 0.11684)
		(layer "B.Cu")
		(net "PD_BIOS_MUX_EN_N")
	)
	(segment
		(start 38.28796 -102.0445)
		(end 37.80155 -102.0445)
		(width 0.11684)
		(layer "B.Cu")
		(net "PD_BIOS_MUX_EN_N")
	)
	(segment
		(start 39.507922 -103.007922)
		(end 39.507922 -103.002842)
		(width 0.11684)
		(layer "B.Cu")
		(net "PD_BIOS_MUX_EN_N")
	)
	(segment
		(start 50.07737 -79.812642)
		(end 50.7238 -79.166212)
		(width 0.11684)
		(layer "B.Cu")
		(net "PD_BIOS_MUX_EN_N")
	)
	(segment
		(start 38.613334 -100.965)
		(end 37.80155 -100.965)
		(width 0.11684)
		(layer "B.Cu")
		(net "PD_BIOS_MUX_EN_N")
	)
	(segment
		(start 51.05273 -78.335124)
		(end 51.861466 -78.335124)
		(width 0.11684)
		(layer "B.Cu")
		(net "PD_BIOS_MUX_EN_N")
	)
	(segment
		(start 38.4048 -101.92766)
		(end 38.28796 -102.0445)
		(width 0.11684)
		(layer "B.Cu")
		(net "PD_BIOS_MUX_EN_N")
	)
	(segment
		(start 50.7238 -78.664054)
		(end 51.05273 -78.335124)
		(width 0.11684)
		(layer "B.Cu")
		(net "PD_BIOS_MUX_EN_N")
	)
	(segment
		(start 50.7238 -79.166212)
		(end 50.7238 -78.664054)
		(width 0.11684)
		(layer "B.Cu")
		(net "PD_BIOS_MUX_EN_N")
	)
	(segment
		(start 38.42131 -101.473)
		(end 38.4048 -101.48951)
		(width 0.11684)
		(layer "B.Cu")
		(net "PD_BIOS_MUX_EN_N")
	)
	(segment
		(start 39.14394 -102.63886)
		(end 38.9382 -102.43312)
		(width 0.11684)
		(layer "B.Cu")
		(net "PD_BIOS_MUX_EN_N")
	)
	(segment
		(start 39.507922 -103.002842)
		(end 39.14394 -102.63886)
		(width 0.11684)
		(layer "B.Cu")
		(net "PD_BIOS_MUX_EN_N")
	)
	(segment
		(start 39.827962 -103.327962)
		(end 39.507922 -103.007922)
		(width 0.11684)
		(layer "B.Cu")
		(net "PD_BIOS_MUX_EN_N")
	)
	(segment
		(start 37.80155 -100.965)
		(end 37.80155 -102.0445)
		(width 0.11684)
		(layer "B.Cu")
		(net "PD_BIOS_MUX_EN_N")
	)
	(segment
		(start 42.930572 -79.49565)
		(end 42.896282 -79.49565)
		(width 0.08382)
		(layer "In2.Cu")
		(net "PD_BIOS_MUX_EN_N")
	)
	(segment
		(start 37.726366 -79.26578)
		(end 37.032946 -79.9592)
		(width 0.08382)
		(layer "In2.Cu")
		(net "PD_BIOS_MUX_EN_N")
	)
	(segment
		(start 46.489112 -79.31912)
		(end 45.552614 -78.382622)
		(width 0.08382)
		(layer "In2.Cu")
		(net "PD_BIOS_MUX_EN_N")
	)
	(segment
		(start 49.132998 -80.0354)
		(end 48.416718 -79.31912)
		(width 0.08382)
		(layer "In2.Cu")
		(net "PD_BIOS_MUX_EN_N")
	)
	(segment
		(start 48.416718 -79.31912)
		(end 46.489112 -79.31912)
		(width 0.08382)
		(layer "In2.Cu")
		(net "PD_BIOS_MUX_EN_N")
	)
	(segment
		(start 31.997396 -79.11846)
		(end 31.898336 -79.0194)
		(width 0.08382)
		(layer "In2.Cu")
		(net "PD_BIOS_MUX_EN_N")
	)
	(segment
		(start 35.6108 -79.9592)
		(end 34.77006 -79.11846)
		(width 0.08382)
		(layer "In2.Cu")
		(net "PD_BIOS_MUX_EN_N")
	)
	(segment
		(start 45.55236 -78.382114)
		(end 45.465238 -78.294992)
		(width 0.08382)
		(layer "In2.Cu")
		(net "PD_BIOS_MUX_EN_N")
	)
	(segment
		(start 31.898336 -79.0194)
		(end 31.5214 -79.0194)
		(width 0.08382)
		(layer "In2.Cu")
		(net "PD_BIOS_MUX_EN_N")
	)
	(segment
		(start 37.032946 -79.9592)
		(end 35.6108 -79.9592)
		(width 0.08382)
		(layer "In2.Cu")
		(net "PD_BIOS_MUX_EN_N")
	)
	(segment
		(start 34.77006 -79.11846)
		(end 31.997396 -79.11846)
		(width 0.08382)
		(layer "In2.Cu")
		(net "PD_BIOS_MUX_EN_N")
	)
	(segment
		(start 45.552614 -78.382622)
		(end 45.55236 -78.382114)
		(width 0.08382)
		(layer "In2.Cu")
		(net "PD_BIOS_MUX_EN_N")
	)
	(segment
		(start 40.214296 -79.74838)
		(end 39.6367 -79.74838)
		(width 0.08382)
		(layer "In2.Cu")
		(net "PD_BIOS_MUX_EN_N")
	)
	(segment
		(start 45.02023 -78.110588)
		(end 44.315634 -78.110588)
		(width 0.08382)
		(layer "In2.Cu")
		(net "PD_BIOS_MUX_EN_N")
	)
	(segment
		(start 49.854612 -80.0354)
		(end 49.132998 -80.0354)
		(width 0.08382)
		(layer "In2.Cu")
		(net "PD_BIOS_MUX_EN_N")
	)
	(segment
		(start 40.873426 -80.40751)
		(end 40.214296 -79.74838)
		(width 0.08382)
		(layer "In2.Cu")
		(net "PD_BIOS_MUX_EN_N")
	)
	(segment
		(start 39.6367 -79.74838)
		(end 39.1541 -79.26578)
		(width 0.08382)
		(layer "In2.Cu")
		(net "PD_BIOS_MUX_EN_N")
	)
	(segment
		(start 45.465238 -78.294992)
		(end 45.46473 -78.294738)
		(width 0.08382)
		(layer "In2.Cu")
		(net "PD_BIOS_MUX_EN_N")
	)
	(segment
		(start 41.984422 -80.40751)
		(end 40.873426 -80.40751)
		(width 0.08382)
		(layer "In2.Cu")
		(net "PD_BIOS_MUX_EN_N")
	)
	(segment
		(start 39.1541 -79.26578)
		(end 37.726366 -79.26578)
		(width 0.08382)
		(layer "In2.Cu")
		(net "PD_BIOS_MUX_EN_N")
	)
	(segment
		(start 45.46473 -78.294738)
		(end 45.02023 -78.110588)
		(width 0.08382)
		(layer "In2.Cu")
		(net "PD_BIOS_MUX_EN_N")
	)
	(segment
		(start 44.315634 -78.110588)
		(end 42.930572 -79.49565)
		(width 0.08382)
		(layer "In2.Cu")
		(net "PD_BIOS_MUX_EN_N")
	)
	(segment
		(start 50.07737 -79.812642)
		(end 49.854612 -80.0354)
		(width 0.08382)
		(layer "In2.Cu")
		(net "PD_BIOS_MUX_EN_N")
	)
	(segment
		(start 42.896282 -79.49565)
		(end 41.984422 -80.40751)
		(width 0.08382)
		(layer "In2.Cu")
		(net "PD_BIOS_MUX_EN_N")
	)
	(segment
		(start 34.58718 -67.861434)
		(end 35.816032 -69.090286)
		(width 0.10668)
		(layer "In4.Cu")
		(net "PD_BIOS_MUX_EN_N")
	)
	(segment
		(start 34.798 -45.73524)
		(end 34.798 -47.15764)
		(width 0.10668)
		(layer "In4.Cu")
		(net "PD_BIOS_MUX_EN_N")
	)
	(segment
		(start 32.68726 -56.307736)
		(end 32.68726 -57.513474)
		(width 0.10668)
		(layer "In4.Cu")
		(net "PD_BIOS_MUX_EN_N")
	)
	(segment
		(start 33.44672 -50.420016)
		(end 33.44672 -54.472586)
		(width 0.10668)
		(layer "In4.Cu")
		(net "PD_BIOS_MUX_EN_N")
	)
	(segment
		(start 34.798 -47.15764)
		(end 33.44672 -50.420016)
		(width 0.10668)
		(layer "In4.Cu")
		(net "PD_BIOS_MUX_EN_N")
	)
	(segment
		(start 32.68726 -57.513474)
		(end 33.66643 -59.878468)
		(width 0.10668)
		(layer "In4.Cu")
		(net "PD_BIOS_MUX_EN_N")
	)
	(segment
		(start 35.816032 -69.090286)
		(end 35.978084 -69.481954)
		(width 0.10668)
		(layer "In4.Cu")
		(net "PD_BIOS_MUX_EN_N")
	)
	(segment
		(start 33.66643 -63.3349)
		(end 34.58718 -64.25565)
		(width 0.10668)
		(layer "In4.Cu")
		(net "PD_BIOS_MUX_EN_N")
	)
	(segment
		(start 31.5214 -78.124558)
		(end 31.5214 -79.0194)
		(width 0.10668)
		(layer "In4.Cu")
		(net "PD_BIOS_MUX_EN_N")
	)
	(segment
		(start 33.66643 -59.878468)
		(end 33.66643 -63.3349)
		(width 0.10668)
		(layer "In4.Cu")
		(net "PD_BIOS_MUX_EN_N")
	)
	(segment
		(start 35.978084 -71.09079)
		(end 35.909758 -71.236332)
		(width 0.10668)
		(layer "In4.Cu")
		(net "PD_BIOS_MUX_EN_N")
	)
	(segment
		(start 32.3977 -77.248258)
		(end 31.5214 -78.124558)
		(width 0.10668)
		(layer "In4.Cu")
		(net "PD_BIOS_MUX_EN_N")
	)
	(segment
		(start 35.909758 -71.236332)
		(end 34.943034 -72.202802)
		(width 0.10668)
		(layer "In4.Cu")
		(net "PD_BIOS_MUX_EN_N")
	)
	(segment
		(start 35.978084 -69.481954)
		(end 35.978084 -71.09079)
		(width 0.10668)
		(layer "In4.Cu")
		(net "PD_BIOS_MUX_EN_N")
	)
	(segment
		(start 34.58718 -64.25565)
		(end 34.58718 -67.861434)
		(width 0.10668)
		(layer "In4.Cu")
		(net "PD_BIOS_MUX_EN_N")
	)
	(segment
		(start 33.901634 -72.202802)
		(end 32.3977 -73.706736)
		(width 0.10668)
		(layer "In4.Cu")
		(net "PD_BIOS_MUX_EN_N")
	)
	(segment
		(start 33.44672 -54.472586)
		(end 32.68726 -56.307736)
		(width 0.10668)
		(layer "In4.Cu")
		(net "PD_BIOS_MUX_EN_N")
	)
	(segment
		(start 32.3977 -73.706736)
		(end 32.3977 -77.248258)
		(width 0.10668)
		(layer "In4.Cu")
		(net "PD_BIOS_MUX_EN_N")
	)
	(segment
		(start 35.0266 -45.50664)
		(end 34.798 -45.73524)
		(width 0.10668)
		(layer "In4.Cu")
		(net "PD_BIOS_MUX_EN_N")
	)
	(segment
		(start 34.943034 -72.202802)
		(end 33.901634 -72.202802)
		(width 0.10668)
		(layer "In4.Cu")
		(net "PD_BIOS_MUX_EN_N")
	)
	(segment
		(start 46.4312 -95.4278)
		(end 45.72 -94.7166)
		(width 0.08382)
		(layer "In9.Cu")
		(net "PD_BIOS_MUX_EN_N")
	)
	(segment
		(start 45.72 -94.7166)
		(end 38.928802 -94.7166)
		(width 0.08382)
		(layer "In9.Cu")
		(net "PD_BIOS_MUX_EN_N")
	)
	(segment
		(start 50.034444 -95.100648)
		(end 49.707292 -95.4278)
		(width 0.08382)
		(layer "In9.Cu")
		(net "PD_BIOS_MUX_EN_N")
	)
	(segment
		(start 50.07737 -79.812642)
		(end 50.07737 -79.92618)
		(width 0.08382)
		(layer "In9.Cu")
		(net "PD_BIOS_MUX_EN_N")
	)
	(segment
		(start 47.6758 -92.3036)
		(end 50.034444 -94.662244)
		(width 0.08382)
		(layer "In9.Cu")
		(net "PD_BIOS_MUX_EN_N")
	)
	(segment
		(start 37.3888 -98.628454)
		(end 38.42131 -99.660964)
		(width 0.08382)
		(layer "In9.Cu")
		(net "PD_BIOS_MUX_EN_N")
	)
	(segment
		(start 47.9044 -87.1982)
		(end 47.9044 -88.7476)
		(width 0.08382)
		(layer "In9.Cu")
		(net "PD_BIOS_MUX_EN_N")
	)
	(segment
		(start 37.3888 -96.256602)
		(end 37.3888 -98.628454)
		(width 0.08382)
		(layer "In9.Cu")
		(net "PD_BIOS_MUX_EN_N")
	)
	(segment
		(start 50.07737 -79.92618)
		(end 50.0126 -79.99095)
		(width 0.08382)
		(layer "In9.Cu")
		(net "PD_BIOS_MUX_EN_N")
	)
	(segment
		(start 50.0126 -79.99095)
		(end 50.0126 -85.09)
		(width 0.08382)
		(layer "In9.Cu")
		(net "PD_BIOS_MUX_EN_N")
	)
	(segment
		(start 38.928802 -94.7166)
		(end 37.3888 -96.256602)
		(width 0.08382)
		(layer "In9.Cu")
		(net "PD_BIOS_MUX_EN_N")
	)
	(segment
		(start 47.9044 -88.7476)
		(end 47.6758 -88.9762)
		(width 0.08382)
		(layer "In9.Cu")
		(net "PD_BIOS_MUX_EN_N")
	)
	(segment
		(start 50.0126 -85.09)
		(end 47.9044 -87.1982)
		(width 0.08382)
		(layer "In9.Cu")
		(net "PD_BIOS_MUX_EN_N")
	)
	(segment
		(start 49.707292 -95.4278)
		(end 46.4312 -95.4278)
		(width 0.08382)
		(layer "In9.Cu")
		(net "PD_BIOS_MUX_EN_N")
	)
	(segment
		(start 38.42131 -99.660964)
		(end 38.42131 -101.473)
		(width 0.08382)
		(layer "In9.Cu")
		(net "PD_BIOS_MUX_EN_N")
	)
	(segment
		(start 47.6758 -88.9762)
		(end 47.6758 -92.3036)
		(width 0.08382)
		(layer "In9.Cu")
		(net "PD_BIOS_MUX_EN_N")
	)
	(segment
		(start 50.034444 -94.662244)
		(end 50.034444 -95.100648)
		(width 0.08382)
		(layer "In9.Cu")
		(net "PD_BIOS_MUX_EN_N")
	)
	(segment
		(start 17.059402 -90.786966)
		(end 16.664178 -90.391742)
		(width 0.11684)
		(layer "F.Cu")
		(net "IRQ_SGPIO_R_N")
	)
	(via
		(at 13.843 -86.71306)
		(size 0.6604)
		(drill 0.3302)
		(layers "F.Cu" "B.Cu")
		(net "IRQ_SGPIO_R_N")
	)
	(via
		(at 16.664178 -90.391742)
		(size 0.4572)
		(drill 0.254)
		(layers "F.Cu" "B.Cu")
		(net "IRQ_SGPIO_R_N")
	)
	(segment
		(start 16.086836 -89.8144)
		(end 16.664178 -90.391742)
		(width 0.11684)
		(layer "B.Cu")
		(net "IRQ_SGPIO_R_N")
	)
	(segment
		(start 13.843 -86.5124)
		(end 13.843 -86.71306)
		(width 0.11684)
		(layer "B.Cu")
		(net "IRQ_SGPIO_R_N")
	)
	(segment
		(start 14.1224 -87.4776)
		(end 14.1224 -87.817706)
		(width 0.11684)
		(layer "B.Cu")
		(net "IRQ_SGPIO_R_N")
	)
	(segment
		(start 14.00175 -84.836)
		(end 14.3002 -84.836)
		(width 0.11684)
		(layer "B.Cu")
		(net "IRQ_SGPIO_R_N")
	)
	(segment
		(start 14.3002 -84.836)
		(end 14.72184 -85.25764)
		(width 0.11684)
		(layer "B.Cu")
		(net "IRQ_SGPIO_R_N")
	)
	(segment
		(start 13.2588 -84.09305)
		(end 14.00175 -84.836)
		(width 0.11684)
		(layer "B.Cu")
		(net "IRQ_SGPIO_R_N")
	)
	(segment
		(start 13.843 -87.1982)
		(end 14.1224 -87.4776)
		(width 0.11684)
		(layer "B.Cu")
		(net "IRQ_SGPIO_R_N")
	)
	(segment
		(start 14.72184 -85.63356)
		(end 13.843 -86.5124)
		(width 0.11684)
		(layer "B.Cu")
		(net "IRQ_SGPIO_R_N")
	)
	(segment
		(start 14.72184 -85.25764)
		(end 14.72184 -85.63356)
		(width 0.11684)
		(layer "B.Cu")
		(net "IRQ_SGPIO_R_N")
	)
	(segment
		(start 15.8496 -89.8144)
		(end 16.086836 -89.8144)
		(width 0.11684)
		(layer "B.Cu")
		(net "IRQ_SGPIO_R_N")
	)
	(segment
		(start 14.313154 -88.277954)
		(end 15.8496 -89.8144)
		(width 0.11684)
		(layer "B.Cu")
		(net "IRQ_SGPIO_R_N")
	)
	(segment
		(start 14.1224 -87.817706)
		(end 14.313154 -88.277954)
		(width 0.11684)
		(layer "B.Cu")
		(net "IRQ_SGPIO_R_N")
	)
	(segment
		(start 13.843 -86.71306)
		(end 13.843 -87.1982)
		(width 0.11684)
		(layer "B.Cu")
		(net "IRQ_SGPIO_R_N")
	)
	(segment
		(start 73.787254 -94.938596)
		(end 73.787254 -95.8596)
		(width 0.11684)
		(layer "F.Cu")
		(net "IRQ_BMC_TPM_SPI_R_N")
	)
	(segment
		(start 74.06005 -94.6658)
		(end 73.787254 -94.938596)
		(width 0.11684)
		(layer "F.Cu")
		(net "IRQ_BMC_TPM_SPI_R_N")
	)
	(segment
		(start 75.577954 -94.856046)
		(end 77.092048 -94.856046)
		(width 0.11684)
		(layer "F.Cu")
		(net "IRQ_BMC_TPM_SPI_R_N")
	)
	(segment
		(start 73.787254 -95.8596)
		(end 74.5744 -95.8596)
		(width 0.11684)
		(layer "F.Cu")
		(net "IRQ_BMC_TPM_SPI_R_N")
	)
	(segment
		(start 74.5744 -95.8596)
		(end 75.577954 -94.856046)
		(width 0.11684)
		(layer "F.Cu")
		(net "IRQ_BMC_TPM_SPI_R_N")
	)
	(via
		(at 73.787254 -95.8596)
		(size 0.762)
		(drill 0.381)
		(layers "F.Cu" "B.Cu")
		(net "IRQ_BMC_TPM_SPI_R_N")
	)
	(segment
		(start 30.081728 -104.0638)
		(end 29.624528 -104.521)
		(width 0.11684)
		(layer "F.Cu")
		(net "FM_TPM_PRSNT_1_N")
	)
	(segment
		(start 34.1122 -100.9396)
		(end 33.7947 -101.2571)
		(width 0.11684)
		(layer "F.Cu")
		(net "FM_TPM_PRSNT_1_N")
	)
	(segment
		(start 39.484808 -101.854)
		(end 38.570408 -100.9396)
		(width 0.11684)
		(layer "F.Cu")
		(net "FM_TPM_PRSNT_1_N")
	)
	(segment
		(start 33.9598 -102.9716)
		(end 32.9438 -102.9716)
		(width 0.11684)
		(layer "F.Cu")
		(net "FM_TPM_PRSNT_1_N")
	)
	(segment
		(start 32.9438 -102.9716)
		(end 31.8516 -104.0638)
		(width 0.11684)
		(layer "F.Cu")
		(net "FM_TPM_PRSNT_1_N")
	)
	(segment
		(start 34.2392 -102.1334)
		(end 34.2392 -102.6922)
		(width 0.11684)
		(layer "F.Cu")
		(net "FM_TPM_PRSNT_1_N")
	)
	(segment
		(start 75.999848 -93.856048)
		(end 75.490832 -93.347032)
		(width 0.11684)
		(layer "F.Cu")
		(net "FM_TPM_PRSNT_1_N")
	)
	(segment
		(start 33.7947 -101.2571)
		(end 33.7947 -101.6889)
		(width 0.11684)
		(layer "F.Cu")
		(net "FM_TPM_PRSNT_1_N")
	)
	(segment
		(start 24.892 -82.7786)
		(end 24.8412 -82.7278)
		(width 0.11684)
		(layer "F.Cu")
		(net "FM_TPM_PRSNT_1_N")
	)
	(segment
		(start 46.09973 -50.166524)
		(end 46.494954 -50.571146)
		(width 0.11684)
		(layer "F.Cu")
		(net "FM_TPM_PRSNT_1_N")
	)
	(segment
		(start 37.2872 -100.9396)
		(end 37.0586 -101.1682)
		(width 0.11684)
		(layer "F.Cu")
		(net "FM_TPM_PRSNT_1_N")
	)
	(segment
		(start 24.892 -83.34375)
		(end 24.892 -82.7786)
		(width 0.11684)
		(layer "F.Cu")
		(net "FM_TPM_PRSNT_1_N")
	)
	(segment
		(start 35.761422 -100.9396)
		(end 34.1122 -100.9396)
		(width 0.11684)
		(layer "F.Cu")
		(net "FM_TPM_PRSNT_1_N")
	)
	(segment
		(start 36.313364 -101.1682)
		(end 35.761422 -100.9396)
		(width 0.11684)
		(layer "F.Cu")
		(net "FM_TPM_PRSNT_1_N")
	)
	(segment
		(start 33.7947 -101.6889)
		(end 34.2392 -102.1334)
		(width 0.11684)
		(layer "F.Cu")
		(net "FM_TPM_PRSNT_1_N")
	)
	(segment
		(start 37.0586 -101.1682)
		(end 36.313364 -101.1682)
		(width 0.11684)
		(layer "F.Cu")
		(net "FM_TPM_PRSNT_1_N")
	)
	(segment
		(start 74.4982 -93.347032)
		(end 74.4982 -93.47708)
		(width 0.11684)
		(layer "F.Cu")
		(net "FM_TPM_PRSNT_1_N")
	)
	(segment
		(start 31.8516 -104.0638)
		(end 30.081728 -104.0638)
		(width 0.11684)
		(layer "F.Cu")
		(net "FM_TPM_PRSNT_1_N")
	)
	(segment
		(start 34.2392 -102.6922)
		(end 33.9598 -102.9716)
		(width 0.11684)
		(layer "F.Cu")
		(net "FM_TPM_PRSNT_1_N")
	)
	(segment
		(start 74.4982 -93.47708)
		(end 75.38212 -94.361)
		(width 0.11684)
		(layer "F.Cu")
		(net "FM_TPM_PRSNT_1_N")
	)
	(segment
		(start 75.490832 -93.347032)
		(end 74.4982 -93.347032)
		(width 0.11684)
		(layer "F.Cu")
		(net "FM_TPM_PRSNT_1_N")
	)
	(segment
		(start 38.570408 -100.9396)
		(end 37.2872 -100.9396)
		(width 0.11684)
		(layer "F.Cu")
		(net "FM_TPM_PRSNT_1_N")
	)
	(segment
		(start 77.092048 -93.856048)
		(end 75.999848 -93.856048)
		(width 0.11684)
		(layer "F.Cu")
		(net "FM_TPM_PRSNT_1_N")
	)
	(via
		(at 29.624528 -104.521)
		(size 0.508)
		(drill 0.254)
		(layers "F.Cu" "B.Cu")
		(net "FM_TPM_PRSNT_1_N")
	)
	(via
		(at 75.38212 -94.361)
		(size 0.508)
		(drill 0.254)
		(layers "F.Cu" "B.Cu")
		(net "FM_TPM_PRSNT_1_N")
	)
	(via
		(at 24.8412 -82.7278)
		(size 0.508)
		(drill 0.254)
		(layers "F.Cu" "B.Cu")
		(net "FM_TPM_PRSNT_1_N")
	)
	(via
		(at 39.484808 -101.854)
		(size 0.508)
		(drill 0.254)
		(layers "F.Cu" "B.Cu")
		(net "FM_TPM_PRSNT_1_N")
	)
	(via
		(at 46.09973 -50.166524)
		(size 0.4572)
		(drill 0.254)
		(layers "F.Cu" "B.Cu")
		(net "FM_TPM_PRSNT_1_N")
	)
	(segment
		(start 61.77026 -101.60508)
		(end 64.6557 -98.71964)
		(width 0.08382)
		(layer "In2.Cu")
		(net "FM_TPM_PRSNT_1_N")
	)
	(segment
		(start 34.094928 -103.46563)
		(end 34.135568 -103.50627)
		(width 0.08382)
		(layer "In2.Cu")
		(net "FM_TPM_PRSNT_1_N")
	)
	(segment
		(start 70.94728 -98.71964)
		(end 71.982838 -99.755198)
		(width 0.08382)
		(layer "In2.Cu")
		(net "FM_TPM_PRSNT_1_N")
	)
	(segment
		(start 53.474874 -101.938074)
		(end 54.380638 -101.938074)
		(width 0.08382)
		(layer "In2.Cu")
		(net "FM_TPM_PRSNT_1_N")
	)
	(segment
		(start 32.614108 -103.75519)
		(end 33.433512 -103.75519)
		(width 0.08382)
		(layer "In2.Cu")
		(net "FM_TPM_PRSNT_1_N")
	)
	(segment
		(start 29.7942 -105.21188)
		(end 31.157418 -105.21188)
		(width 0.08382)
		(layer "In2.Cu")
		(net "FM_TPM_PRSNT_1_N")
	)
	(segment
		(start 71.982838 -99.755198)
		(end 73.095104 -99.755198)
		(width 0.08382)
		(layer "In2.Cu")
		(net "FM_TPM_PRSNT_1_N")
	)
	(segment
		(start 48.848264 -101.7016)
		(end 53.2384 -101.7016)
		(width 0.08382)
		(layer "In2.Cu")
		(net "FM_TPM_PRSNT_1_N")
	)
	(segment
		(start 29.624528 -105.042208)
		(end 29.7942 -105.21188)
		(width 0.08382)
		(layer "In2.Cu")
		(net "FM_TPM_PRSNT_1_N")
	)
	(segment
		(start 54.380638 -101.938074)
		(end 55.292752 -101.02596)
		(width 0.08382)
		(layer "In2.Cu")
		(net "FM_TPM_PRSNT_1_N")
	)
	(segment
		(start 47.043594 -103.50627)
		(end 48.848264 -101.7016)
		(width 0.08382)
		(layer "In2.Cu")
		(net "FM_TPM_PRSNT_1_N")
	)
	(segment
		(start 31.157418 -105.21188)
		(end 32.614108 -103.75519)
		(width 0.08382)
		(layer "In2.Cu")
		(net "FM_TPM_PRSNT_1_N")
	)
	(segment
		(start 64.6557 -98.71964)
		(end 70.94728 -98.71964)
		(width 0.08382)
		(layer "In2.Cu")
		(net "FM_TPM_PRSNT_1_N")
	)
	(segment
		(start 75.396598 -94.375478)
		(end 75.38212 -94.361)
		(width 0.08382)
		(layer "In2.Cu")
		(net "FM_TPM_PRSNT_1_N")
	)
	(segment
		(start 58.92292 -101.02596)
		(end 59.50204 -101.60508)
		(width 0.08382)
		(layer "In2.Cu")
		(net "FM_TPM_PRSNT_1_N")
	)
	(segment
		(start 55.292752 -101.02596)
		(end 58.92292 -101.02596)
		(width 0.08382)
		(layer "In2.Cu")
		(net "FM_TPM_PRSNT_1_N")
	)
	(segment
		(start 73.095104 -99.755198)
		(end 75.396598 -97.453704)
		(width 0.08382)
		(layer "In2.Cu")
		(net "FM_TPM_PRSNT_1_N")
	)
	(segment
		(start 75.396598 -97.453704)
		(end 75.396598 -94.375478)
		(width 0.08382)
		(layer "In2.Cu")
		(net "FM_TPM_PRSNT_1_N")
	)
	(segment
		(start 53.2384 -101.7016)
		(end 53.474874 -101.938074)
		(width 0.08382)
		(layer "In2.Cu")
		(net "FM_TPM_PRSNT_1_N")
	)
	(segment
		(start 33.723072 -103.46563)
		(end 34.094928 -103.46563)
		(width 0.08382)
		(layer "In2.Cu")
		(net "FM_TPM_PRSNT_1_N")
	)
	(segment
		(start 29.624528 -104.521)
		(end 29.624528 -105.042208)
		(width 0.08382)
		(layer "In2.Cu")
		(net "FM_TPM_PRSNT_1_N")
	)
	(segment
		(start 34.135568 -103.50627)
		(end 47.043594 -103.50627)
		(width 0.08382)
		(layer "In2.Cu")
		(net "FM_TPM_PRSNT_1_N")
	)
	(segment
		(start 33.433512 -103.75519)
		(end 33.723072 -103.46563)
		(width 0.08382)
		(layer "In2.Cu")
		(net "FM_TPM_PRSNT_1_N")
	)
	(segment
		(start 59.50204 -101.60508)
		(end 61.77026 -101.60508)
		(width 0.08382)
		(layer "In2.Cu")
		(net "FM_TPM_PRSNT_1_N")
	)
	(segment
		(start 41.71188 -77.230986)
		(end 41.496742 -77.446124)
		(width 0.10668)
		(layer "In4.Cu")
		(net "FM_TPM_PRSNT_1_N")
	)
	(segment
		(start 45.581824 -53.782976)
		(end 45.073824 -53.782976)
		(width 0.10668)
		(layer "In4.Cu")
		(net "FM_TPM_PRSNT_1_N")
	)
	(segment
		(start 42.88282 -65.933066)
		(end 42.865548 -65.950338)
		(width 0.10668)
		(layer "In4.Cu")
		(net "FM_TPM_PRSNT_1_N")
	)
	(segment
		(start 41.12514 -80.59674)
		(end 41.12514 -82.28711)
		(width 0.10668)
		(layer "In4.Cu")
		(net "FM_TPM_PRSNT_1_N")
	)
	(segment
		(start 38.76802 -100.59162)
		(end 39.484808 -101.308408)
		(width 0.10668)
		(layer "In4.Cu")
		(net "FM_TPM_PRSNT_1_N")
	)
	(segment
		(start 40.3098 -92.035122)
		(end 40.3098 -95.6564)
		(width 0.10668)
		(layer "In4.Cu")
		(net "FM_TPM_PRSNT_1_N")
	)
	(segment
		(start 44.883324 -54.532276)
		(end 44.6786 -54.737)
		(width 0.10668)
		(layer "In4.Cu")
		(net "FM_TPM_PRSNT_1_N")
	)
	(segment
		(start 41.11752 -82.29473)
		(end 41.11752 -88.650826)
		(width 0.10668)
		(layer "In4.Cu")
		(net "FM_TPM_PRSNT_1_N")
	)
	(segment
		(start 38.76802 -98.21164)
		(end 38.76802 -100.59162)
		(width 0.10668)
		(layer "In4.Cu")
		(net "FM_TPM_PRSNT_1_N")
	)
	(segment
		(start 45.972476 -50.166524)
		(end 45.6946 -50.4444)
		(width 0.10668)
		(layer "In4.Cu")
		(net "FM_TPM_PRSNT_1_N")
	)
	(segment
		(start 41.12514 -82.28711)
		(end 41.11752 -82.29473)
		(width 0.10668)
		(layer "In4.Cu")
		(net "FM_TPM_PRSNT_1_N")
	)
	(segment
		(start 40.3098 -95.6564)
		(end 39.72306 -96.24314)
		(width 0.10668)
		(layer "In4.Cu")
		(net "FM_TPM_PRSNT_1_N")
	)
	(segment
		(start 44.6786 -54.737)
		(end 44.007278 -54.737)
		(width 0.10668)
		(layer "In4.Cu")
		(net "FM_TPM_PRSNT_1_N")
	)
	(segment
		(start 42.50944 -74.696066)
		(end 41.71188 -75.493626)
		(width 0.10668)
		(layer "In4.Cu")
		(net "FM_TPM_PRSNT_1_N")
	)
	(segment
		(start 45.073824 -53.782976)
		(end 44.883324 -53.973476)
		(width 0.10668)
		(layer "In4.Cu")
		(net "FM_TPM_PRSNT_1_N")
	)
	(segment
		(start 42.378884 -68.95846)
		(end 42.378884 -71.338186)
		(width 0.10668)
		(layer "In4.Cu")
		(net "FM_TPM_PRSNT_1_N")
	)
	(segment
		(start 40.31488 -89.453466)
		(end 40.31488 -92.030042)
		(width 0.10668)
		(layer "In4.Cu")
		(net "FM_TPM_PRSNT_1_N")
	)
	(segment
		(start 45.6946 -53.6702)
		(end 45.581824 -53.782976)
		(width 0.10668)
		(layer "In4.Cu")
		(net "FM_TPM_PRSNT_1_N")
	)
	(segment
		(start 41.11752 -88.650826)
		(end 40.31488 -89.453466)
		(width 0.10668)
		(layer "In4.Cu")
		(net "FM_TPM_PRSNT_1_N")
	)
	(segment
		(start 44.007278 -54.737)
		(end 43.307 -55.437278)
		(width 0.10668)
		(layer "In4.Cu")
		(net "FM_TPM_PRSNT_1_N")
	)
	(segment
		(start 41.496742 -77.446124)
		(end 41.496742 -78.518258)
		(width 0.10668)
		(layer "In4.Cu")
		(net "FM_TPM_PRSNT_1_N")
	)
	(segment
		(start 43.307 -55.437278)
		(end 43.307 -56.706008)
		(width 0.10668)
		(layer "In4.Cu")
		(net "FM_TPM_PRSNT_1_N")
	)
	(segment
		(start 43.307 -56.706008)
		(end 43.206924 -56.806084)
		(width 0.10668)
		(layer "In4.Cu")
		(net "FM_TPM_PRSNT_1_N")
	)
	(segment
		(start 39.72306 -96.24314)
		(end 39.72306 -97.2566)
		(width 0.10668)
		(layer "In4.Cu")
		(net "FM_TPM_PRSNT_1_N")
	)
	(segment
		(start 42.865548 -65.950338)
		(end 42.865548 -68.471796)
		(width 0.10668)
		(layer "In4.Cu")
		(net "FM_TPM_PRSNT_1_N")
	)
	(segment
		(start 44.883324 -53.973476)
		(end 44.883324 -54.532276)
		(width 0.10668)
		(layer "In4.Cu")
		(net "FM_TPM_PRSNT_1_N")
	)
	(segment
		(start 39.484808 -101.308408)
		(end 39.484808 -101.854)
		(width 0.10668)
		(layer "In4.Cu")
		(net "FM_TPM_PRSNT_1_N")
	)
	(segment
		(start 39.72306 -97.2566)
		(end 38.76802 -98.21164)
		(width 0.10668)
		(layer "In4.Cu")
		(net "FM_TPM_PRSNT_1_N")
	)
	(segment
		(start 40.64 -80.1116)
		(end 41.12514 -80.59674)
		(width 0.10668)
		(layer "In4.Cu")
		(net "FM_TPM_PRSNT_1_N")
	)
	(segment
		(start 43.206924 -56.806084)
		(end 42.88282 -57.589928)
		(width 0.10668)
		(layer "In4.Cu")
		(net "FM_TPM_PRSNT_1_N")
	)
	(segment
		(start 40.31488 -92.030042)
		(end 40.3098 -92.035122)
		(width 0.10668)
		(layer "In4.Cu")
		(net "FM_TPM_PRSNT_1_N")
	)
	(segment
		(start 42.50944 -71.468742)
		(end 42.50944 -74.696066)
		(width 0.10668)
		(layer "In4.Cu")
		(net "FM_TPM_PRSNT_1_N")
	)
	(segment
		(start 42.88282 -57.589928)
		(end 42.88282 -65.933066)
		(width 0.10668)
		(layer "In4.Cu")
		(net "FM_TPM_PRSNT_1_N")
	)
	(segment
		(start 41.71188 -75.493626)
		(end 41.71188 -77.230986)
		(width 0.10668)
		(layer "In4.Cu")
		(net "FM_TPM_PRSNT_1_N")
	)
	(segment
		(start 40.64 -79.375)
		(end 40.64 -80.1116)
		(width 0.10668)
		(layer "In4.Cu")
		(net "FM_TPM_PRSNT_1_N")
	)
	(segment
		(start 42.865548 -68.471796)
		(end 42.378884 -68.95846)
		(width 0.10668)
		(layer "In4.Cu")
		(net "FM_TPM_PRSNT_1_N")
	)
	(segment
		(start 42.378884 -71.338186)
		(end 42.50944 -71.468742)
		(width 0.10668)
		(layer "In4.Cu")
		(net "FM_TPM_PRSNT_1_N")
	)
	(segment
		(start 41.496742 -78.518258)
		(end 40.64 -79.375)
		(width 0.10668)
		(layer "In4.Cu")
		(net "FM_TPM_PRSNT_1_N")
	)
	(segment
		(start 46.09973 -50.166524)
		(end 45.972476 -50.166524)
		(width 0.10668)
		(layer "In4.Cu")
		(net "FM_TPM_PRSNT_1_N")
	)
	(segment
		(start 45.6946 -50.4444)
		(end 45.6946 -53.6702)
		(width 0.10668)
		(layer "In4.Cu")
		(net "FM_TPM_PRSNT_1_N")
	)
	(segment
		(start 27.8384 -87.996268)
		(end 27.8384 -90.6018)
		(width 0.10668)
		(layer "In7.Cu")
		(net "FM_TPM_PRSNT_1_N")
	)
	(segment
		(start 30.5816 -103.9368)
		(end 30.208728 -103.9368)
		(width 0.10668)
		(layer "In7.Cu")
		(net "FM_TPM_PRSNT_1_N")
	)
	(segment
		(start 25.540208 -85.698076)
		(end 27.8384 -87.996268)
		(width 0.10668)
		(layer "In7.Cu")
		(net "FM_TPM_PRSNT_1_N")
	)
	(segment
		(start 30.9118 -103.6066)
		(end 30.5816 -103.9368)
		(width 0.10668)
		(layer "In7.Cu")
		(net "FM_TPM_PRSNT_1_N")
	)
	(segment
		(start 24.8412 -82.7278)
		(end 24.8412 -84.328)
		(width 0.10668)
		(layer "In7.Cu")
		(net "FM_TPM_PRSNT_1_N")
	)
	(segment
		(start 27.8384 -90.6018)
		(end 27.56408 -90.87612)
		(width 0.10668)
		(layer "In7.Cu")
		(net "FM_TPM_PRSNT_1_N")
	)
	(segment
		(start 25.540208 -85.027008)
		(end 25.540208 -85.698076)
		(width 0.10668)
		(layer "In7.Cu")
		(net "FM_TPM_PRSNT_1_N")
	)
	(segment
		(start 30.9118 -102.1842)
		(end 30.9118 -103.6066)
		(width 0.10668)
		(layer "In7.Cu")
		(net "FM_TPM_PRSNT_1_N")
	)
	(segment
		(start 30.208728 -103.9368)
		(end 29.624528 -104.521)
		(width 0.10668)
		(layer "In7.Cu")
		(net "FM_TPM_PRSNT_1_N")
	)
	(segment
		(start 27.56408 -90.87612)
		(end 27.56408 -98.83648)
		(width 0.10668)
		(layer "In7.Cu")
		(net "FM_TPM_PRSNT_1_N")
	)
	(segment
		(start 24.8412 -84.328)
		(end 25.540208 -85.027008)
		(width 0.10668)
		(layer "In7.Cu")
		(net "FM_TPM_PRSNT_1_N")
	)
	(segment
		(start 27.56408 -98.83648)
		(end 30.9118 -102.1842)
		(width 0.10668)
		(layer "In7.Cu")
		(net "FM_TPM_PRSNT_1_N")
	)
	(segment
		(start 16.664178 -95.182182)
		(end 17.059402 -94.786958)
		(width 0.11684)
		(layer "F.Cu")
		(net "FM_PWR_R_BTN")
	)
	(via
		(at 13.9192 -96.9772)
		(size 0.6604)
		(drill 0.3302)
		(layers "F.Cu" "B.Cu")
		(net "FM_PWR_R_BTN")
	)
	(via
		(at 16.664178 -95.182182)
		(size 0.4572)
		(drill 0.254)
		(layers "F.Cu" "B.Cu")
		(net "FM_PWR_R_BTN")
	)
	(segment
		(start 15.7226 -96.4946)
		(end 15.24 -96.9772)
		(width 0.11684)
		(layer "B.Cu")
		(net "FM_PWR_R_BTN")
	)
	(segment
		(start 15.7226 -95.758)
		(end 15.7226 -96.4946)
		(width 0.11684)
		(layer "B.Cu")
		(net "FM_PWR_R_BTN")
	)
	(segment
		(start 16.664178 -95.182182)
		(end 16.298418 -95.182182)
		(width 0.11684)
		(layer "B.Cu")
		(net "FM_PWR_R_BTN")
	)
	(segment
		(start 15.24 -96.9772)
		(end 13.9192 -96.9772)
		(width 0.11684)
		(layer "B.Cu")
		(net "FM_PWR_R_BTN")
	)
	(segment
		(start 13.17625 -96.9772)
		(end 13.9192 -96.9772)
		(width 0.11684)
		(layer "B.Cu")
		(net "FM_PWR_R_BTN")
	)
	(segment
		(start 16.298418 -95.182182)
		(end 15.7226 -95.758)
		(width 0.11684)
		(layer "B.Cu")
		(net "FM_PWR_R_BTN")
	)
	(segment
		(start 12.71905 -96.52)
		(end 13.17625 -96.9772)
		(width 0.11684)
		(layer "B.Cu")
		(net "FM_PWR_R_BTN")
	)
	(segment
		(start 11.491214 -83.312)
		(end 11.298174 -83.50504)
		(width 0.11684)
		(layer "F.Cu")
		(net "FM_PECI_SEL_R_N")
	)
	(segment
		(start 11.91895 -83.312)
		(end 11.491214 -83.312)
		(width 0.11684)
		(layer "F.Cu")
		(net "FM_PECI_SEL_R_N")
	)
	(segment
		(start 54.494938 -42.571162)
		(end 54.099714 -42.175938)
		(width 0.11684)
		(layer "F.Cu")
		(net "FM_PECI_SEL_R_N")
	)
	(via
		(at 11.298174 -83.50504)
		(size 0.508)
		(drill 0.254)
		(layers "F.Cu" "B.Cu")
		(net "FM_PECI_SEL_R_N")
	)
	(via
		(at 27.85618 -34.55924)
		(size 0.508)
		(drill 0.254)
		(layers "F.Cu" "B.Cu")
		(net "FM_PECI_SEL_R_N")
	)
	(via
		(at 54.099714 -42.175938)
		(size 0.4572)
		(drill 0.254)
		(layers "F.Cu" "B.Cu")
		(net "FM_PECI_SEL_R_N")
	)
	(segment
		(start 50.872136 -35.99688)
		(end 50.87112 -35.99688)
		(width 0.08382)
		(layer "In2.Cu")
		(net "FM_PECI_SEL_R_N")
	)
	(segment
		(start 35.34791 -29.693108)
		(end 32.264604 -32.776414)
		(width 0.08382)
		(layer "In2.Cu")
		(net "FM_PECI_SEL_R_N")
	)
	(segment
		(start 54.099714 -42.175938)
		(end 53.712364 -41.788588)
		(width 0.08382)
		(layer "In2.Cu")
		(net "FM_PECI_SEL_R_N")
	)
	(segment
		(start 44.36364 -32.089852)
		(end 42.827956 -30.554168)
		(width 0.08382)
		(layer "In2.Cu")
		(net "FM_PECI_SEL_R_N")
	)
	(segment
		(start 49.77511 -34.90087)
		(end 47.61103 -34.90087)
		(width 0.08382)
		(layer "In2.Cu")
		(net "FM_PECI_SEL_R_N")
	)
	(segment
		(start 36.042854 -29.693108)
		(end 35.34791 -29.693108)
		(width 0.08382)
		(layer "In2.Cu")
		(net "FM_PECI_SEL_R_N")
	)
	(segment
		(start 42.827956 -30.554168)
		(end 36.903914 -30.554168)
		(width 0.08382)
		(layer "In2.Cu")
		(net "FM_PECI_SEL_R_N")
	)
	(segment
		(start 46.96714 -32.83966)
		(end 46.37913 -32.25165)
		(width 0.08382)
		(layer "In2.Cu")
		(net "FM_PECI_SEL_R_N")
	)
	(segment
		(start 53.185568 -38.310312)
		(end 50.872136 -35.99688)
		(width 0.08382)
		(layer "In2.Cu")
		(net "FM_PECI_SEL_R_N")
	)
	(segment
		(start 53.712364 -38.838124)
		(end 53.185568 -38.311328)
		(width 0.08382)
		(layer "In2.Cu")
		(net "FM_PECI_SEL_R_N")
	)
	(segment
		(start 53.185568 -38.311328)
		(end 53.185568 -38.310312)
		(width 0.08382)
		(layer "In2.Cu")
		(net "FM_PECI_SEL_R_N")
	)
	(segment
		(start 29.639006 -32.776414)
		(end 27.85618 -34.55924)
		(width 0.08382)
		(layer "In2.Cu")
		(net "FM_PECI_SEL_R_N")
	)
	(segment
		(start 36.903914 -30.554168)
		(end 36.042854 -29.693108)
		(width 0.08382)
		(layer "In2.Cu")
		(net "FM_PECI_SEL_R_N")
	)
	(segment
		(start 50.87112 -35.99688)
		(end 49.77511 -34.90087)
		(width 0.08382)
		(layer "In2.Cu")
		(net "FM_PECI_SEL_R_N")
	)
	(segment
		(start 47.61103 -34.90087)
		(end 46.96714 -34.25698)
		(width 0.08382)
		(layer "In2.Cu")
		(net "FM_PECI_SEL_R_N")
	)
	(segment
		(start 46.96714 -34.25698)
		(end 46.96714 -32.83966)
		(width 0.08382)
		(layer "In2.Cu")
		(net "FM_PECI_SEL_R_N")
	)
	(segment
		(start 32.264604 -32.776414)
		(end 29.639006 -32.776414)
		(width 0.08382)
		(layer "In2.Cu")
		(net "FM_PECI_SEL_R_N")
	)
	(segment
		(start 44.754038 -32.25165)
		(end 44.36364 -32.089852)
		(width 0.08382)
		(layer "In2.Cu")
		(net "FM_PECI_SEL_R_N")
	)
	(segment
		(start 46.37913 -32.25165)
		(end 44.754038 -32.25165)
		(width 0.08382)
		(layer "In2.Cu")
		(net "FM_PECI_SEL_R_N")
	)
	(segment
		(start 53.712364 -41.788588)
		(end 53.712364 -38.838124)
		(width 0.08382)
		(layer "In2.Cu")
		(net "FM_PECI_SEL_R_N")
	)
	(segment
		(start 23.56231 -39.869872)
		(end 21.555202 -41.87698)
		(width 0.10668)
		(layer "In4.Cu")
		(net "FM_PECI_SEL_R_N")
	)
	(segment
		(start 15.05966 -71.833994)
		(end 13.82268 -73.070974)
		(width 0.10668)
		(layer "In4.Cu")
		(net "FM_PECI_SEL_R_N")
	)
	(segment
		(start 25.735534 -35.65652)
		(end 25.478486 -35.65652)
		(width 0.10668)
		(layer "In4.Cu")
		(net "FM_PECI_SEL_R_N")
	)
	(segment
		(start 14.416278 -80.081882)
		(end 13.91666 -80.5815)
		(width 0.10668)
		(layer "In4.Cu")
		(net "FM_PECI_SEL_R_N")
	)
	(segment
		(start 13.91666 -82.83194)
		(end 13.24356 -83.50504)
		(width 0.10668)
		(layer "In4.Cu")
		(net "FM_PECI_SEL_R_N")
	)
	(segment
		(start 15.985744 -49.219866)
		(end 16.583914 -49.818036)
		(width 0.10668)
		(layer "In4.Cu")
		(net "FM_PECI_SEL_R_N")
	)
	(segment
		(start 15.456154 -47.222918)
		(end 15.456154 -48.459644)
		(width 0.10668)
		(layer "In4.Cu")
		(net "FM_PECI_SEL_R_N")
	)
	(segment
		(start 15.652242 -58.800238)
		(end 14.74216 -59.71032)
		(width 0.10668)
		(layer "In4.Cu")
		(net "FM_PECI_SEL_R_N")
	)
	(segment
		(start 21.555202 -41.87698)
		(end 17.0942 -41.87698)
		(width 0.10668)
		(layer "In4.Cu")
		(net "FM_PECI_SEL_R_N")
	)
	(segment
		(start 16.583914 -50.186844)
		(end 16.8021 -50.40503)
		(width 0.10668)
		(layer "In4.Cu")
		(net "FM_PECI_SEL_R_N")
	)
	(segment
		(start 15.05966 -68.06946)
		(end 15.05966 -71.833994)
		(width 0.10668)
		(layer "In4.Cu")
		(net "FM_PECI_SEL_R_N")
	)
	(segment
		(start 14.74216 -60.09132)
		(end 15.76324 -61.1124)
		(width 0.10668)
		(layer "In4.Cu")
		(net "FM_PECI_SEL_R_N")
	)
	(segment
		(start 23.56231 -37.572696)
		(end 23.56231 -39.869872)
		(width 0.10668)
		(layer "In4.Cu")
		(net "FM_PECI_SEL_R_N")
	)
	(segment
		(start 16.8021 -51.245008)
		(end 15.652242 -52.394866)
		(width 0.10668)
		(layer "In4.Cu")
		(net "FM_PECI_SEL_R_N")
	)
	(segment
		(start 13.91666 -80.5815)
		(end 13.91666 -82.83194)
		(width 0.10668)
		(layer "In4.Cu")
		(net "FM_PECI_SEL_R_N")
	)
	(segment
		(start 25.478486 -35.65652)
		(end 23.56231 -37.572696)
		(width 0.10668)
		(layer "In4.Cu")
		(net "FM_PECI_SEL_R_N")
	)
	(segment
		(start 14.74216 -59.71032)
		(end 14.74216 -60.09132)
		(width 0.10668)
		(layer "In4.Cu")
		(net "FM_PECI_SEL_R_N")
	)
	(segment
		(start 16.8021 -50.40503)
		(end 16.8021 -51.245008)
		(width 0.10668)
		(layer "In4.Cu")
		(net "FM_PECI_SEL_R_N")
	)
	(segment
		(start 27.85618 -34.55924)
		(end 26.832814 -34.55924)
		(width 0.10668)
		(layer "In4.Cu")
		(net "FM_PECI_SEL_R_N")
	)
	(segment
		(start 15.985744 -48.989234)
		(end 15.985744 -49.219866)
		(width 0.10668)
		(layer "In4.Cu")
		(net "FM_PECI_SEL_R_N")
	)
	(segment
		(start 13.82268 -78.042262)
		(end 14.416278 -78.63586)
		(width 0.10668)
		(layer "In4.Cu")
		(net "FM_PECI_SEL_R_N")
	)
	(segment
		(start 15.76324 -63.603378)
		(end 16.002 -63.842138)
		(width 0.10668)
		(layer "In4.Cu")
		(net "FM_PECI_SEL_R_N")
	)
	(segment
		(start 17.0942 -41.87698)
		(end 16.64208 -42.3291)
		(width 0.10668)
		(layer "In4.Cu")
		(net "FM_PECI_SEL_R_N")
	)
	(segment
		(start 13.82268 -73.070974)
		(end 13.82268 -78.042262)
		(width 0.10668)
		(layer "In4.Cu")
		(net "FM_PECI_SEL_R_N")
	)
	(segment
		(start 26.832814 -34.55924)
		(end 25.735534 -35.65652)
		(width 0.10668)
		(layer "In4.Cu")
		(net "FM_PECI_SEL_R_N")
	)
	(segment
		(start 16.64208 -46.036992)
		(end 15.456154 -47.222918)
		(width 0.10668)
		(layer "In4.Cu")
		(net "FM_PECI_SEL_R_N")
	)
	(segment
		(start 16.583914 -49.818036)
		(end 16.583914 -50.186844)
		(width 0.10668)
		(layer "In4.Cu")
		(net "FM_PECI_SEL_R_N")
	)
	(segment
		(start 14.416278 -78.63586)
		(end 14.416278 -80.081882)
		(width 0.10668)
		(layer "In4.Cu")
		(net "FM_PECI_SEL_R_N")
	)
	(segment
		(start 16.002 -63.842138)
		(end 16.002 -67.12712)
		(width 0.10668)
		(layer "In4.Cu")
		(net "FM_PECI_SEL_R_N")
	)
	(segment
		(start 15.76324 -61.1124)
		(end 15.76324 -63.603378)
		(width 0.10668)
		(layer "In4.Cu")
		(net "FM_PECI_SEL_R_N")
	)
	(segment
		(start 15.652242 -52.394866)
		(end 15.652242 -58.800238)
		(width 0.10668)
		(layer "In4.Cu")
		(net "FM_PECI_SEL_R_N")
	)
	(segment
		(start 16.64208 -42.3291)
		(end 16.64208 -46.036992)
		(width 0.10668)
		(layer "In4.Cu")
		(net "FM_PECI_SEL_R_N")
	)
	(segment
		(start 16.002 -67.12712)
		(end 15.05966 -68.06946)
		(width 0.10668)
		(layer "In4.Cu")
		(net "FM_PECI_SEL_R_N")
	)
	(segment
		(start 15.456154 -48.459644)
		(end 15.985744 -48.989234)
		(width 0.10668)
		(layer "In4.Cu")
		(net "FM_PECI_SEL_R_N")
	)
	(segment
		(start 13.24356 -83.50504)
		(end 11.298174 -83.50504)
		(width 0.10668)
		(layer "In4.Cu")
		(net "FM_PECI_SEL_R_N")
	)
	(segment
		(start 13.402564 -85.335618)
		(end 13.402564 -85.996018)
		(width 0.11684)
		(layer "F.Cu")
		(net "FM_PECI_SEL_N")
	)
	(segment
		(start 13.402564 -85.996018)
		(end 14.477746 -87.0712)
		(width 0.11684)
		(layer "F.Cu")
		(net "FM_PECI_SEL_N")
	)
	(segment
		(start 15.070836 -87.511636)
		(end 15.070836 -87.998554)
		(width 0.11684)
		(layer "F.Cu")
		(net "FM_PECI_SEL_N")
	)
	(segment
		(start 12.71905 -84.652104)
		(end 13.402564 -85.335618)
		(width 0.11684)
		(layer "F.Cu")
		(net "FM_PECI_SEL_N")
	)
	(segment
		(start 14.6304 -87.0712)
		(end 15.070836 -87.511636)
		(width 0.11684)
		(layer "F.Cu")
		(net "FM_PECI_SEL_N")
	)
	(segment
		(start 12.71905 -83.312)
		(end 12.71905 -84.328)
		(width 0.11684)
		(layer "F.Cu")
		(net "FM_PECI_SEL_N")
	)
	(segment
		(start 15.070836 -87.998554)
		(end 15.459456 -88.387174)
		(width 0.11684)
		(layer "F.Cu")
		(net "FM_PECI_SEL_N")
	)
	(segment
		(start 14.477746 -87.0712)
		(end 14.6304 -87.0712)
		(width 0.11684)
		(layer "F.Cu")
		(net "FM_PECI_SEL_N")
	)
	(segment
		(start 12.71905 -84.328)
		(end 12.71905 -84.652104)
		(width 0.11684)
		(layer "F.Cu")
		(net "FM_PECI_SEL_N")
	)
	(segment
		(start 45.695108 -44.971208)
		(end 45.299884 -44.575984)
		(width 0.11684)
		(layer "F.Cu")
		(net "FM_ESPI_PLD_R1_EN")
	)
	(via
		(at 45.299884 -44.575984)
		(size 0.4572)
		(drill 0.254)
		(layers "F.Cu" "B.Cu")
		(net "FM_ESPI_PLD_R1_EN")
	)
	(segment
		(start 45.299884 -44.575984)
		(end 42.944034 -44.575984)
		(width 0.11684)
		(layer "B.Cu")
		(net "FM_ESPI_PLD_R1_EN")
	)
	(segment
		(start 42.944034 -44.575984)
		(end 42.36085 -43.9928)
		(width 0.11684)
		(layer "B.Cu")
		(net "FM_ESPI_PLD_R1_EN")
	)
	(segment
		(start 19.864324 -90.391742)
		(end 20.259548 -90.786966)
		(width 0.11684)
		(layer "F.Cu")
		(net "FM_CPU_MSMI_CATERR_LVT3_PLD_N")
	)
	(via
		(at 19.864324 -90.391742)
		(size 0.4572)
		(drill 0.254)
		(layers "F.Cu" "B.Cu")
		(net "FM_CPU_MSMI_CATERR_LVT3_PLD_N")
	)
	(segment
		(start 19.475704 -88.589104)
		(end 19.475704 -88.952832)
		(width 0.11684)
		(layer "B.Cu")
		(net "FM_CPU_MSMI_CATERR_LVT3_PLD_N")
	)
	(segment
		(start 18.6436 -87.87638)
		(end 18.6436 -88.120982)
		(width 0.11684)
		(layer "B.Cu")
		(net "FM_CPU_MSMI_CATERR_LVT3_PLD_N")
	)
	(segment
		(start 20.016216 -89.180416)
		(end 20.2692 -89.4334)
		(width 0.11684)
		(layer "B.Cu")
		(net "FM_CPU_MSMI_CATERR_LVT3_PLD_N")
	)
	(segment
		(start 19.97583 -89.980516)
		(end 19.864324 -90.092022)
		(width 0.11684)
		(layer "B.Cu")
		(net "FM_CPU_MSMI_CATERR_LVT3_PLD_N")
	)
	(segment
		(start 18.903188 -88.38057)
		(end 19.26717 -88.38057)
		(width 0.11684)
		(layer "B.Cu")
		(net "FM_CPU_MSMI_CATERR_LVT3_PLD_N")
	)
	(segment
		(start 17.58061 -86.81339)
		(end 18.6436 -87.87638)
		(width 0.11684)
		(layer "B.Cu")
		(net "FM_CPU_MSMI_CATERR_LVT3_PLD_N")
	)
	(segment
		(start 19.475704 -88.952832)
		(end 19.703288 -89.180416)
		(width 0.11684)
		(layer "B.Cu")
		(net "FM_CPU_MSMI_CATERR_LVT3_PLD_N")
	)
	(segment
		(start 17.58061 -85.14588)
		(end 17.58061 -86.81339)
		(width 0.11684)
		(layer "B.Cu")
		(net "FM_CPU_MSMI_CATERR_LVT3_PLD_N")
	)
	(segment
		(start 18.6436 -88.120982)
		(end 18.903188 -88.38057)
		(width 0.11684)
		(layer "B.Cu")
		(net "FM_CPU_MSMI_CATERR_LVT3_PLD_N")
	)
	(segment
		(start 20.2692 -89.763346)
		(end 20.05203 -89.980516)
		(width 0.11684)
		(layer "B.Cu")
		(net "FM_CPU_MSMI_CATERR_LVT3_PLD_N")
	)
	(segment
		(start 19.703288 -89.180416)
		(end 20.016216 -89.180416)
		(width 0.11684)
		(layer "B.Cu")
		(net "FM_CPU_MSMI_CATERR_LVT3_PLD_N")
	)
	(segment
		(start 20.2692 -89.4334)
		(end 20.2692 -89.763346)
		(width 0.11684)
		(layer "B.Cu")
		(net "FM_CPU_MSMI_CATERR_LVT3_PLD_N")
	)
	(segment
		(start 19.864324 -90.092022)
		(end 19.864324 -90.391742)
		(width 0.11684)
		(layer "B.Cu")
		(net "FM_CPU_MSMI_CATERR_LVT3_PLD_N")
	)
	(segment
		(start 19.26717 -88.38057)
		(end 19.475704 -88.589104)
		(width 0.11684)
		(layer "B.Cu")
		(net "FM_CPU_MSMI_CATERR_LVT3_PLD_N")
	)
	(segment
		(start 20.05203 -89.980516)
		(end 19.97583 -89.980516)
		(width 0.11684)
		(layer "B.Cu")
		(net "FM_CPU_MSMI_CATERR_LVT3_PLD_N")
	)
	(segment
		(start 54.494938 -58.57113)
		(end 54.099714 -58.966354)
		(width 0.11684)
		(layer "F.Cu")
		(net "FM_BMC_READY_R_PLD_N")
	)
	(via
		(at 54.099714 -58.966354)
		(size 0.4572)
		(drill 0.254)
		(layers "F.Cu" "B.Cu")
		(net "FM_BMC_READY_R_PLD_N")
	)
	(via
		(at 49.350676 -76.3016)
		(size 0.6604)
		(drill 0.3302)
		(layers "F.Cu" "B.Cu")
		(net "FM_BMC_READY_R_PLD_N")
	)
	(via
		(at 50.254662 -78.0288)
		(size 0.508)
		(drill 0.254)
		(layers "F.Cu" "B.Cu")
		(net "FM_BMC_READY_R_PLD_N")
	)
	(segment
		(start 50.52695 -76.3016)
		(end 49.350676 -76.3016)
		(width 0.11684)
		(layer "B.Cu")
		(net "FM_BMC_READY_R_PLD_N")
	)
	(segment
		(start 48.37811 -76.83246)
		(end 47.82185 -76.2762)
		(width 0.11684)
		(layer "B.Cu")
		(net "FM_BMC_READY_R_PLD_N")
	)
	(segment
		(start 50.52695 -77.756512)
		(end 50.254662 -78.0288)
		(width 0.11684)
		(layer "B.Cu")
		(net "FM_BMC_READY_R_PLD_N")
	)
	(segment
		(start 50.52695 -76.3016)
		(end 50.52695 -77.756512)
		(width 0.11684)
		(layer "B.Cu")
		(net "FM_BMC_READY_R_PLD_N")
	)
	(segment
		(start 49.350676 -76.3016)
		(end 48.819816 -76.83246)
		(width 0.11684)
		(layer "B.Cu")
		(net "FM_BMC_READY_R_PLD_N")
	)
	(segment
		(start 48.819816 -76.83246)
		(end 48.37811 -76.83246)
		(width 0.11684)
		(layer "B.Cu")
		(net "FM_BMC_READY_R_PLD_N")
	)
	(segment
		(start 53.991002 -63.694056)
		(end 53.6194 -63.322454)
		(width 0.10668)
		(layer "In4.Cu")
		(net "FM_BMC_READY_R_PLD_N")
	)
	(segment
		(start 53.6194 -63.322454)
		(end 53.6194 -60.7441)
		(width 0.10668)
		(layer "In4.Cu")
		(net "FM_BMC_READY_R_PLD_N")
	)
	(segment
		(start 54.171596 -68.07073)
		(end 54.171596 -67.300348)
		(width 0.10668)
		(layer "In4.Cu")
		(net "FM_BMC_READY_R_PLD_N")
	)
	(segment
		(start 50.254662 -78.0288)
		(end 50.254662 -76.37653)
		(width 0.10668)
		(layer "In4.Cu")
		(net "FM_BMC_READY_R_PLD_N")
	)
	(segment
		(start 53.991002 -64.906144)
		(end 53.991002 -63.694056)
		(width 0.10668)
		(layer "In4.Cu")
		(net "FM_BMC_READY_R_PLD_N")
	)
	(segment
		(start 53.478684 -65.418462)
		(end 53.991002 -64.906144)
		(width 0.10668)
		(layer "In4.Cu")
		(net "FM_BMC_READY_R_PLD_N")
	)
	(segment
		(start 54.099714 -60.263786)
		(end 54.099714 -58.966354)
		(width 0.10668)
		(layer "In4.Cu")
		(net "FM_BMC_READY_R_PLD_N")
	)
	(segment
		(start 54.171596 -67.300348)
		(end 53.478684 -66.607436)
		(width 0.10668)
		(layer "In4.Cu")
		(net "FM_BMC_READY_R_PLD_N")
	)
	(segment
		(start 53.0098 -69.232526)
		(end 54.171596 -68.07073)
		(width 0.10668)
		(layer "In4.Cu")
		(net "FM_BMC_READY_R_PLD_N")
	)
	(segment
		(start 53.0098 -73.622662)
		(end 53.0098 -69.232526)
		(width 0.10668)
		(layer "In4.Cu")
		(net "FM_BMC_READY_R_PLD_N")
	)
	(segment
		(start 53.6194 -60.7441)
		(end 54.099714 -60.263786)
		(width 0.10668)
		(layer "In4.Cu")
		(net "FM_BMC_READY_R_PLD_N")
	)
	(segment
		(start 50.254662 -76.37653)
		(end 53.0098 -73.622662)
		(width 0.10668)
		(layer "In4.Cu")
		(net "FM_BMC_READY_R_PLD_N")
	)
	(segment
		(start 53.478684 -66.607436)
		(end 53.478684 -65.418462)
		(width 0.10668)
		(layer "In4.Cu")
		(net "FM_BMC_READY_R_PLD_N")
	)
	(segment
		(start 17.464278 -95.182182)
		(end 17.859502 -94.786958)
		(width 0.11684)
		(layer "F.Cu")
		(net "FM_BMC_READY_PLD_N")
	)
	(via
		(at 17.464278 -95.182182)
		(size 0.4572)
		(drill 0.254)
		(layers "F.Cu" "B.Cu")
		(net "FM_BMC_READY_PLD_N")
	)
	(via
		(at 46.286928 -75.291696)
		(size 0.508)
		(drill 0.254)
		(layers "F.Cu" "B.Cu")
		(net "FM_BMC_READY_PLD_N")
	)
	(via
		(at 9.40308 -97.9424)
		(size 0.508)
		(drill 0.254)
		(layers "F.Cu" "B.Cu")
		(net "FM_BMC_READY_PLD_N")
	)
	(segment
		(start 46.286928 -75.541378)
		(end 46.286928 -75.291696)
		(width 0.11684)
		(layer "B.Cu")
		(net "FM_BMC_READY_PLD_N")
	)
	(segment
		(start 47.02175 -76.2762)
		(end 46.286928 -75.541378)
		(width 0.11684)
		(layer "B.Cu")
		(net "FM_BMC_READY_PLD_N")
	)
	(segment
		(start 21.485098 -69.45757)
		(end 22.511258 -69.45757)
		(width 0.08382)
		(layer "In2.Cu")
		(net "FM_BMC_READY_PLD_N")
	)
	(segment
		(start 27.847544 -73.203816)
		(end 30.77337 -73.203816)
		(width 0.08382)
		(layer "In2.Cu")
		(net "FM_BMC_READY_PLD_N")
	)
	(segment
		(start 26.332942 -69.75602)
		(end 27.518106 -70.941184)
		(width 0.08382)
		(layer "In2.Cu")
		(net "FM_BMC_READY_PLD_N")
	)
	(segment
		(start 11.345926 -76.51496)
		(end 11.863832 -75.997054)
		(width 0.08382)
		(layer "In2.Cu")
		(net "FM_BMC_READY_PLD_N")
	)
	(segment
		(start 13.94587 -68.78193)
		(end 14.98727 -67.74053)
		(width 0.08382)
		(layer "In2.Cu")
		(net "FM_BMC_READY_PLD_N")
	)
	(segment
		(start 31.71571 -75.90663)
		(end 32.78124 -76.97216)
		(width 0.08382)
		(layer "In2.Cu")
		(net "FM_BMC_READY_PLD_N")
	)
	(segment
		(start 13.512292 -75.997054)
		(end 13.94587 -75.563476)
		(width 0.08382)
		(layer "In2.Cu")
		(net "FM_BMC_READY_PLD_N")
	)
	(segment
		(start 32.78124 -76.97216)
		(end 37.305742 -76.97216)
		(width 0.08382)
		(layer "In2.Cu")
		(net "FM_BMC_READY_PLD_N")
	)
	(segment
		(start 27.518106 -71.31304)
		(end 27.4066 -71.424546)
		(width 0.08382)
		(layer "In2.Cu")
		(net "FM_BMC_READY_PLD_N")
	)
	(segment
		(start 7.29742 -86.88578)
		(end 7.29742 -84.91982)
		(width 0.08382)
		(layer "In2.Cu")
		(net "FM_BMC_READY_PLD_N")
	)
	(segment
		(start 8.179054 -80.49387)
		(end 8.193278 -80.492346)
		(width 0.08382)
		(layer "In2.Cu")
		(net "FM_BMC_READY_PLD_N")
	)
	(segment
		(start 44.475146 -75.07224)
		(end 45.158152 -75.755246)
		(width 0.08382)
		(layer "In2.Cu")
		(net "FM_BMC_READY_PLD_N")
	)
	(segment
		(start 40.44569 -75.755246)
		(end 41.864788 -75.755246)
		(width 0.08382)
		(layer "In2.Cu")
		(net "FM_BMC_READY_PLD_N")
	)
	(segment
		(start 31.31693 -74.592688)
		(end 31.71571 -74.991468)
		(width 0.08382)
		(layer "In2.Cu")
		(net "FM_BMC_READY_PLD_N")
	)
	(segment
		(start 27.4066 -71.424546)
		(end 27.4066 -72.762872)
		(width 0.08382)
		(layer "In2.Cu")
		(net "FM_BMC_READY_PLD_N")
	)
	(segment
		(start 30.77337 -73.203816)
		(end 31.31693 -73.747376)
		(width 0.08382)
		(layer "In2.Cu")
		(net "FM_BMC_READY_PLD_N")
	)
	(segment
		(start 22.809708 -69.75602)
		(end 26.332942 -69.75602)
		(width 0.08382)
		(layer "In2.Cu")
		(net "FM_BMC_READY_PLD_N")
	)
	(segment
		(start 7.0866 -87.0966)
		(end 7.29742 -86.88578)
		(width 0.08382)
		(layer "In2.Cu")
		(net "FM_BMC_READY_PLD_N")
	)
	(segment
		(start 45.823378 -75.755246)
		(end 46.286928 -75.291696)
		(width 0.08382)
		(layer "In2.Cu")
		(net "FM_BMC_READY_PLD_N")
	)
	(segment
		(start 8.379714 -97.9424)
		(end 7.3914 -96.954086)
		(width 0.08382)
		(layer "In2.Cu")
		(net "FM_BMC_READY_PLD_N")
	)
	(segment
		(start 37.988494 -76.289408)
		(end 39.911528 -76.289408)
		(width 0.08382)
		(layer "In2.Cu")
		(net "FM_BMC_READY_PLD_N")
	)
	(segment
		(start 7.3914 -95.0214)
		(end 7.0866 -94.7166)
		(width 0.08382)
		(layer "In2.Cu")
		(net "FM_BMC_READY_PLD_N")
	)
	(segment
		(start 39.911528 -76.289408)
		(end 40.44569 -75.755246)
		(width 0.08382)
		(layer "In2.Cu")
		(net "FM_BMC_READY_PLD_N")
	)
	(segment
		(start 31.71571 -74.991468)
		(end 31.71571 -75.90663)
		(width 0.08382)
		(layer "In2.Cu")
		(net "FM_BMC_READY_PLD_N")
	)
	(segment
		(start 8.193278 -80.492346)
		(end 8.977376 -80.492346)
		(width 0.08382)
		(layer "In2.Cu")
		(net "FM_BMC_READY_PLD_N")
	)
	(segment
		(start 8.977376 -80.492346)
		(end 9.223756 -80.245966)
		(width 0.08382)
		(layer "In2.Cu")
		(net "FM_BMC_READY_PLD_N")
	)
	(segment
		(start 22.511258 -69.45757)
		(end 22.809708 -69.75602)
		(width 0.08382)
		(layer "In2.Cu")
		(net "FM_BMC_READY_PLD_N")
	)
	(segment
		(start 9.89838 -80.245966)
		(end 11.345926 -78.79842)
		(width 0.08382)
		(layer "In2.Cu")
		(net "FM_BMC_READY_PLD_N")
	)
	(segment
		(start 41.864788 -75.755246)
		(end 42.547794 -75.07224)
		(width 0.08382)
		(layer "In2.Cu")
		(net "FM_BMC_READY_PLD_N")
	)
	(segment
		(start 42.547794 -75.07224)
		(end 44.475146 -75.07224)
		(width 0.08382)
		(layer "In2.Cu")
		(net "FM_BMC_READY_PLD_N")
	)
	(segment
		(start 13.94587 -75.563476)
		(end 13.94587 -68.78193)
		(width 0.08382)
		(layer "In2.Cu")
		(net "FM_BMC_READY_PLD_N")
	)
	(segment
		(start 27.518106 -70.941184)
		(end 27.518106 -71.31304)
		(width 0.08382)
		(layer "In2.Cu")
		(net "FM_BMC_READY_PLD_N")
	)
	(segment
		(start 27.4066 -72.762872)
		(end 27.847544 -73.203816)
		(width 0.08382)
		(layer "In2.Cu")
		(net "FM_BMC_READY_PLD_N")
	)
	(segment
		(start 7.0866 -94.7166)
		(end 7.0866 -87.0966)
		(width 0.08382)
		(layer "In2.Cu")
		(net "FM_BMC_READY_PLD_N")
	)
	(segment
		(start 11.345926 -78.79842)
		(end 11.345926 -76.51496)
		(width 0.08382)
		(layer "In2.Cu")
		(net "FM_BMC_READY_PLD_N")
	)
	(segment
		(start 9.40308 -97.9424)
		(end 8.379714 -97.9424)
		(width 0.08382)
		(layer "In2.Cu")
		(net "FM_BMC_READY_PLD_N")
	)
	(segment
		(start 7.3914 -96.954086)
		(end 7.3914 -95.0214)
		(width 0.08382)
		(layer "In2.Cu")
		(net "FM_BMC_READY_PLD_N")
	)
	(segment
		(start 6.97738 -81.693512)
		(end 8.168132 -80.50276)
		(width 0.08382)
		(layer "In2.Cu")
		(net "FM_BMC_READY_PLD_N")
	)
	(segment
		(start 45.158152 -75.755246)
		(end 45.823378 -75.755246)
		(width 0.08382)
		(layer "In2.Cu")
		(net "FM_BMC_READY_PLD_N")
	)
	(segment
		(start 9.223756 -80.245966)
		(end 9.89838 -80.245966)
		(width 0.08382)
		(layer "In2.Cu")
		(net "FM_BMC_READY_PLD_N")
	)
	(segment
		(start 19.768058 -67.74053)
		(end 21.485098 -69.45757)
		(width 0.08382)
		(layer "In2.Cu")
		(net "FM_BMC_READY_PLD_N")
	)
	(segment
		(start 6.97738 -84.59978)
		(end 6.97738 -81.693512)
		(width 0.08382)
		(layer "In2.Cu")
		(net "FM_BMC_READY_PLD_N")
	)
	(segment
		(start 11.863832 -75.997054)
		(end 13.512292 -75.997054)
		(width 0.08382)
		(layer "In2.Cu")
		(net "FM_BMC_READY_PLD_N")
	)
	(segment
		(start 7.29742 -84.91982)
		(end 6.97738 -84.59978)
		(width 0.08382)
		(layer "In2.Cu")
		(net "FM_BMC_READY_PLD_N")
	)
	(segment
		(start 8.168132 -80.50276)
		(end 8.179054 -80.49387)
		(width 0.08382)
		(layer "In2.Cu")
		(net "FM_BMC_READY_PLD_N")
	)
	(segment
		(start 37.305742 -76.97216)
		(end 37.988494 -76.289408)
		(width 0.08382)
		(layer "In2.Cu")
		(net "FM_BMC_READY_PLD_N")
	)
	(segment
		(start 31.31693 -73.747376)
		(end 31.31693 -74.592688)
		(width 0.08382)
		(layer "In2.Cu")
		(net "FM_BMC_READY_PLD_N")
	)
	(segment
		(start 14.98727 -67.74053)
		(end 19.768058 -67.74053)
		(width 0.08382)
		(layer "In2.Cu")
		(net "FM_BMC_READY_PLD_N")
	)
	(segment
		(start 15.818358 -94.798642)
		(end 14.4272 -96.1898)
		(width 0.10668)
		(layer "In4.Cu")
		(net "FM_BMC_READY_PLD_N")
	)
	(segment
		(start 14.4272 -96.1898)
		(end 12.7 -96.1898)
		(width 0.10668)
		(layer "In4.Cu")
		(net "FM_BMC_READY_PLD_N")
	)
	(segment
		(start 9.652 -97.69348)
		(end 9.40308 -97.9424)
		(width 0.10668)
		(layer "In4.Cu")
		(net "FM_BMC_READY_PLD_N")
	)
	(segment
		(start 9.652 -96.7486)
		(end 9.652 -97.69348)
		(width 0.10668)
		(layer "In4.Cu")
		(net "FM_BMC_READY_PLD_N")
	)
	(segment
		(start 17.464278 -95.182182)
		(end 17.080738 -94.798642)
		(width 0.10668)
		(layer "In4.Cu")
		(net "FM_BMC_READY_PLD_N")
	)
	(segment
		(start 12.7 -96.1898)
		(end 12.5222 -96.012)
		(width 0.10668)
		(layer "In4.Cu")
		(net "FM_BMC_READY_PLD_N")
	)
	(segment
		(start 12.5222 -96.012)
		(end 10.3886 -96.012)
		(width 0.10668)
		(layer "In4.Cu")
		(net "FM_BMC_READY_PLD_N")
	)
	(segment
		(start 10.3886 -96.012)
		(end 9.652 -96.7486)
		(width 0.10668)
		(layer "In4.Cu")
		(net "FM_BMC_READY_PLD_N")
	)
	(segment
		(start 17.080738 -94.798642)
		(end 15.818358 -94.798642)
		(width 0.10668)
		(layer "In4.Cu")
		(net "FM_BMC_READY_PLD_N")
	)
	(via
		(at 49.4284 -79.5782)
		(size 0.508)
		(drill 0.254)
		(layers "F.Cu" "B.Cu")
		(net "FM_BMC_BIOS_MUX_CS_SPI_R_SEL_0")
	)
	(via
		(at 45.4406 -76.4794)
		(size 0.6604)
		(drill 0.3302)
		(layers "F.Cu" "B.Cu")
		(net "FM_BMC_BIOS_MUX_CS_SPI_R_SEL_0")
	)
	(via
		(at 48.32858 -104.130348)
		(size 0.508)
		(drill 0.254)
		(layers "F.Cu" "B.Cu")
		(net "FM_BMC_BIOS_MUX_CS_SPI_R_SEL_0")
	)
	(segment
		(start 48.32858 -104.130348)
		(end 48.819562 -104.130348)
		(width 0.11684)
		(layer "B.Cu")
		(net "FM_BMC_BIOS_MUX_CS_SPI_R_SEL_0")
	)
	(segment
		(start 48.29556 -104.130348)
		(end 48.32858 -104.130348)
		(width 0.11684)
		(layer "B.Cu")
		(net "FM_BMC_BIOS_MUX_CS_SPI_R_SEL_0")
	)
	(segment
		(start 46.811184 -103.977948)
		(end 48.14316 -103.977948)
		(width 0.11684)
		(layer "B.Cu")
		(net "FM_BMC_BIOS_MUX_CS_SPI_R_SEL_0")
	)
	(segment
		(start 46.019466 -77.685138)
		(end 45.389038 -77.685138)
		(width 0.11684)
		(layer "B.Cu")
		(net "FM_BMC_BIOS_MUX_CS_SPI_R_SEL_0")
	)
	(segment
		(start 45.9994 -77.0382)
		(end 45.4406 -76.4794)
		(width 0.11684)
		(layer "B.Cu")
		(net "FM_BMC_BIOS_MUX_CS_SPI_R_SEL_0")
	)
	(segment
		(start 44.28871 -76.4286)
		(end 45.3898 -76.4286)
		(width 0.11684)
		(layer "B.Cu")
		(net "FM_BMC_BIOS_MUX_CS_SPI_R_SEL_0")
	)
	(segment
		(start 45.389038 -77.685138)
		(end 44.28871 -76.58481)
		(width 0.11684)
		(layer "B.Cu")
		(net "FM_BMC_BIOS_MUX_CS_SPI_R_SEL_0")
	)
	(segment
		(start 45.3898 -76.4286)
		(end 45.4406 -76.4794)
		(width 0.11684)
		(layer "B.Cu")
		(net "FM_BMC_BIOS_MUX_CS_SPI_R_SEL_0")
	)
	(segment
		(start 48.26 -77.91704)
		(end 47.38116 -77.0382)
		(width 0.11684)
		(layer "B.Cu")
		(net "FM_BMC_BIOS_MUX_CS_SPI_R_SEL_0")
	)
	(segment
		(start 49.4284 -79.5782)
		(end 49.121822 -79.271622)
		(width 0.11684)
		(layer "B.Cu")
		(net "FM_BMC_BIOS_MUX_CS_SPI_R_SEL_0")
	)
	(segment
		(start 47.38116 -77.0382)
		(end 45.9994 -77.0382)
		(width 0.11684)
		(layer "B.Cu")
		(net "FM_BMC_BIOS_MUX_CS_SPI_R_SEL_0")
	)
	(segment
		(start 48.14316 -103.977948)
		(end 48.29556 -104.130348)
		(width 0.11684)
		(layer "B.Cu")
		(net "FM_BMC_BIOS_MUX_CS_SPI_R_SEL_0")
	)
	(segment
		(start 48.819562 -104.130348)
		(end 48.892714 -104.2035)
		(width 0.11684)
		(layer "B.Cu")
		(net "FM_BMC_BIOS_MUX_CS_SPI_R_SEL_0")
	)
	(segment
		(start 48.892714 -104.2035)
		(end 49.39665 -104.2035)
		(width 0.11684)
		(layer "B.Cu")
		(net "FM_BMC_BIOS_MUX_CS_SPI_R_SEL_0")
	)
	(segment
		(start 44.28871 -76.58481)
		(end 44.28871 -76.4286)
		(width 0.11684)
		(layer "B.Cu")
		(net "FM_BMC_BIOS_MUX_CS_SPI_R_SEL_0")
	)
	(segment
		(start 49.096422 -79.271622)
		(end 48.26 -78.4352)
		(width 0.11684)
		(layer "B.Cu")
		(net "FM_BMC_BIOS_MUX_CS_SPI_R_SEL_0")
	)
	(segment
		(start 48.26 -78.4352)
		(end 48.26 -77.91704)
		(width 0.11684)
		(layer "B.Cu")
		(net "FM_BMC_BIOS_MUX_CS_SPI_R_SEL_0")
	)
	(segment
		(start 49.121822 -79.271622)
		(end 49.096422 -79.271622)
		(width 0.11684)
		(layer "B.Cu")
		(net "FM_BMC_BIOS_MUX_CS_SPI_R_SEL_0")
	)
	(segment
		(start 49.3014 -88.45804)
		(end 50.61204 -89.76868)
		(width 0.10668)
		(layer "In4.Cu")
		(net "FM_BMC_BIOS_MUX_CS_SPI_R_SEL_0")
	)
	(segment
		(start 49.0093 -93.476318)
		(end 48.36668 -94.118938)
		(width 0.10668)
		(layer "In4.Cu")
		(net "FM_BMC_BIOS_MUX_CS_SPI_R_SEL_0")
	)
	(segment
		(start 49.0093 -92.902024)
		(end 49.0093 -93.476318)
		(width 0.10668)
		(layer "In4.Cu")
		(net "FM_BMC_BIOS_MUX_CS_SPI_R_SEL_0")
	)
	(segment
		(start 49.53508 -84.48548)
		(end 50.30978 -85.26018)
		(width 0.10668)
		(layer "In4.Cu")
		(net "FM_BMC_BIOS_MUX_CS_SPI_R_SEL_0")
	)
	(segment
		(start 48.29556 -104.130348)
		(end 48.32858 -104.130348)
		(width 0.10668)
		(layer "In4.Cu")
		(net "FM_BMC_BIOS_MUX_CS_SPI_R_SEL_0")
	)
	(segment
		(start 48.36668 -98.25228)
		(end 48.84674 -98.73234)
		(width 0.10668)
		(layer "In4.Cu")
		(net "FM_BMC_BIOS_MUX_CS_SPI_R_SEL_0")
	)
	(segment
		(start 50.30978 -85.26018)
		(end 50.30978 -86.697566)
		(width 0.10668)
		(layer "In4.Cu")
		(net "FM_BMC_BIOS_MUX_CS_SPI_R_SEL_0")
	)
	(segment
		(start 49.3014 -87.705946)
		(end 49.3014 -88.45804)
		(width 0.10668)
		(layer "In4.Cu")
		(net "FM_BMC_BIOS_MUX_CS_SPI_R_SEL_0")
	)
	(segment
		(start 48.84674 -98.73234)
		(end 48.84674 -101.44506)
		(width 0.10668)
		(layer "In4.Cu")
		(net "FM_BMC_BIOS_MUX_CS_SPI_R_SEL_0")
	)
	(segment
		(start 48.04156 -102.25024)
		(end 48.04156 -103.876348)
		(width 0.10668)
		(layer "In4.Cu")
		(net "FM_BMC_BIOS_MUX_CS_SPI_R_SEL_0")
	)
	(segment
		(start 48.84674 -101.44506)
		(end 48.04156 -102.25024)
		(width 0.10668)
		(layer "In4.Cu")
		(net "FM_BMC_BIOS_MUX_CS_SPI_R_SEL_0")
	)
	(segment
		(start 50.61204 -89.76868)
		(end 50.61204 -91.873578)
		(width 0.10668)
		(layer "In4.Cu")
		(net "FM_BMC_BIOS_MUX_CS_SPI_R_SEL_0")
	)
	(segment
		(start 50.61204 -91.873578)
		(end 50.245518 -92.2401)
		(width 0.10668)
		(layer "In4.Cu")
		(net "FM_BMC_BIOS_MUX_CS_SPI_R_SEL_0")
	)
	(segment
		(start 48.36668 -94.118938)
		(end 48.36668 -98.25228)
		(width 0.10668)
		(layer "In4.Cu")
		(net "FM_BMC_BIOS_MUX_CS_SPI_R_SEL_0")
	)
	(segment
		(start 49.4284 -79.5782)
		(end 49.53508 -79.68488)
		(width 0.10668)
		(layer "In4.Cu")
		(net "FM_BMC_BIOS_MUX_CS_SPI_R_SEL_0")
	)
	(segment
		(start 49.671224 -92.2401)
		(end 49.0093 -92.902024)
		(width 0.10668)
		(layer "In4.Cu")
		(net "FM_BMC_BIOS_MUX_CS_SPI_R_SEL_0")
	)
	(segment
		(start 50.245518 -92.2401)
		(end 49.671224 -92.2401)
		(width 0.10668)
		(layer "In4.Cu")
		(net "FM_BMC_BIOS_MUX_CS_SPI_R_SEL_0")
	)
	(segment
		(start 48.04156 -103.876348)
		(end 48.29556 -104.130348)
		(width 0.10668)
		(layer "In4.Cu")
		(net "FM_BMC_BIOS_MUX_CS_SPI_R_SEL_0")
	)
	(segment
		(start 50.30978 -86.697566)
		(end 49.3014 -87.705946)
		(width 0.10668)
		(layer "In4.Cu")
		(net "FM_BMC_BIOS_MUX_CS_SPI_R_SEL_0")
	)
	(segment
		(start 49.53508 -79.68488)
		(end 49.53508 -84.48548)
		(width 0.10668)
		(layer "In4.Cu")
		(net "FM_BMC_BIOS_MUX_CS_SPI_R_SEL_0")
	)
	(segment
		(start 43.91406 -38.36162)
		(end 44.21378 -38.0619)
		(width 0.11684)
		(layer "F.Cu")
		(net "FM_BIOS_DEBUG_EN_R_N")
	)
	(segment
		(start 44.21378 -36.55314)
		(end 43.6626 -36.00196)
		(width 0.11684)
		(layer "F.Cu")
		(net "FM_BIOS_DEBUG_EN_R_N")
	)
	(segment
		(start 43.203876 -35.04565)
		(end 43.109642 -35.04565)
		(width 0.11684)
		(layer "F.Cu")
		(net "FM_BIOS_DEBUG_EN_R_N")
	)
	(segment
		(start 43.227244 -35.022282)
		(end 43.203876 -35.04565)
		(width 0.11684)
		(layer "F.Cu")
		(net "FM_BIOS_DEBUG_EN_R_N")
	)
	(segment
		(start 43.639232 -35.022282)
		(end 43.227244 -35.022282)
		(width 0.11684)
		(layer "F.Cu")
		(net "FM_BIOS_DEBUG_EN_R_N")
	)
	(segment
		(start 44.21378 -38.0619)
		(end 44.21378 -36.55314)
		(width 0.11684)
		(layer "F.Cu")
		(net "FM_BIOS_DEBUG_EN_R_N")
	)
	(segment
		(start 43.91406 -38.92804)
		(end 43.91406 -38.36162)
		(width 0.11684)
		(layer "F.Cu")
		(net "FM_BIOS_DEBUG_EN_R_N")
	)
	(segment
		(start 43.6626 -35.04565)
		(end 43.639232 -35.022282)
		(width 0.11684)
		(layer "F.Cu")
		(net "FM_BIOS_DEBUG_EN_R_N")
	)
	(segment
		(start 43.109642 -35.04565)
		(end 43.107356 -35.047936)
		(width 0.11684)
		(layer "F.Cu")
		(net "FM_BIOS_DEBUG_EN_R_N")
	)
	(segment
		(start 46.494954 -41.771316)
		(end 46.09973 -41.376092)
		(width 0.11684)
		(layer "F.Cu")
		(net "FM_BIOS_DEBUG_EN_R_N")
	)
	(segment
		(start 42.695114 -35.047936)
		(end 42.672 -35.07105)
		(width 0.11684)
		(layer "F.Cu")
		(net "FM_BIOS_DEBUG_EN_R_N")
	)
	(segment
		(start 43.6626 -36.00196)
		(end 43.6626 -35.04565)
		(width 0.11684)
		(layer "F.Cu")
		(net "FM_BIOS_DEBUG_EN_R_N")
	)
	(segment
		(start 43.107356 -35.047936)
		(end 42.695114 -35.047936)
		(width 0.11684)
		(layer "F.Cu")
		(net "FM_BIOS_DEBUG_EN_R_N")
	)
	(via
		(at 43.91406 -38.92804)
		(size 0.508)
		(drill 0.254)
		(layers "F.Cu" "B.Cu")
		(net "FM_BIOS_DEBUG_EN_R_N")
	)
	(via
		(at 46.09973 -41.376092)
		(size 0.4572)
		(drill 0.254)
		(layers "F.Cu" "B.Cu")
		(net "FM_BIOS_DEBUG_EN_R_N")
	)
	(segment
		(start 46.09973 -41.376092)
		(end 45.70222 -40.978582)
		(width 0.11684)
		(layer "B.Cu")
		(net "FM_BIOS_DEBUG_EN_R_N")
	)
	(segment
		(start 44.75734 -39.37)
		(end 44.35602 -39.37)
		(width 0.11684)
		(layer "B.Cu")
		(net "FM_BIOS_DEBUG_EN_R_N")
	)
	(segment
		(start 44.35602 -39.37)
		(end 43.91406 -38.92804)
		(width 0.11684)
		(layer "B.Cu")
		(net "FM_BIOS_DEBUG_EN_R_N")
	)
	(segment
		(start 45.51934 -40.1828)
		(end 45.13326 -40.1828)
		(width 0.11684)
		(layer "B.Cu")
		(net "FM_BIOS_DEBUG_EN_R_N")
	)
	(segment
		(start 44.8945 -39.94404)
		(end 44.8945 -39.50716)
		(width 0.11684)
		(layer "B.Cu")
		(net "FM_BIOS_DEBUG_EN_R_N")
	)
	(segment
		(start 44.8945 -39.50716)
		(end 44.75734 -39.37)
		(width 0.11684)
		(layer "B.Cu")
		(net "FM_BIOS_DEBUG_EN_R_N")
	)
	(segment
		(start 45.70222 -40.36568)
		(end 45.51934 -40.1828)
		(width 0.11684)
		(layer "B.Cu")
		(net "FM_BIOS_DEBUG_EN_R_N")
	)
	(segment
		(start 45.70222 -40.978582)
		(end 45.70222 -40.36568)
		(width 0.11684)
		(layer "B.Cu")
		(net "FM_BIOS_DEBUG_EN_R_N")
	)
	(segment
		(start 45.13326 -40.1828)
		(end 44.8945 -39.94404)
		(width 0.11684)
		(layer "B.Cu")
		(net "FM_BIOS_DEBUG_EN_R_N")
	)
	(segment
		(start 43.6626 -34.24555)
		(end 43.6626 -33.83026)
		(width 0.11684)
		(layer "F.Cu")
		(net "FM_BIOS_DEBUG_EN_N")
	)
	(segment
		(start 18.264124 -95.182182)
		(end 18.659348 -94.786958)
		(width 0.11684)
		(layer "F.Cu")
		(net "FM_BIOS_DEBUG_EN_N")
	)
	(segment
		(start 43.6626 -33.83026)
		(end 43.33494 -33.5026)
		(width 0.11684)
		(layer "F.Cu")
		(net "FM_BIOS_DEBUG_EN_N")
	)
	(via
		(at 28.1686 -96.139)
		(size 0.508)
		(drill 0.254)
		(layers "F.Cu" "B.Cu")
		(net "FM_BIOS_DEBUG_EN_N")
	)
	(via
		(at 18.264124 -95.182182)
		(size 0.4572)
		(drill 0.254)
		(layers "F.Cu" "B.Cu")
		(net "FM_BIOS_DEBUG_EN_N")
	)
	(via
		(at 43.33494 -33.5026)
		(size 0.508)
		(drill 0.254)
		(layers "F.Cu" "B.Cu")
		(net "FM_BIOS_DEBUG_EN_N")
	)
	(segment
		(start 18.678906 -94.7674)
		(end 26.415746 -94.7674)
		(width 0.08382)
		(layer "In2.Cu")
		(net "FM_BIOS_DEBUG_EN_N")
	)
	(segment
		(start 18.264124 -95.182182)
		(end 18.678906 -94.7674)
		(width 0.08382)
		(layer "In2.Cu")
		(net "FM_BIOS_DEBUG_EN_N")
	)
	(segment
		(start 27.787346 -96.139)
		(end 28.1686 -96.139)
		(width 0.08382)
		(layer "In2.Cu")
		(net "FM_BIOS_DEBUG_EN_N")
	)
	(segment
		(start 26.415746 -94.7674)
		(end 27.787346 -96.139)
		(width 0.08382)
		(layer "In2.Cu")
		(net "FM_BIOS_DEBUG_EN_N")
	)
	(segment
		(start 28.83154 -90.54084)
		(end 28.5115 -90.2208)
		(width 0.10668)
		(layer "In4.Cu")
		(net "FM_BIOS_DEBUG_EN_N")
	)
	(segment
		(start 28.6385 -92.37726)
		(end 28.83154 -92.18422)
		(width 0.10668)
		(layer "In4.Cu")
		(net "FM_BIOS_DEBUG_EN_N")
	)
	(segment
		(start 43.33494 -33.86582)
		(end 43.33494 -33.5026)
		(width 0.10668)
		(layer "In4.Cu")
		(net "FM_BIOS_DEBUG_EN_N")
	)
	(segment
		(start 23.06828 -55.4101)
		(end 23.06828 -51.36134)
		(width 0.10668)
		(layer "In4.Cu")
		(net "FM_BIOS_DEBUG_EN_N")
	)
	(segment
		(start 26.24074 -73.0504)
		(end 26.24074 -71.10984)
		(width 0.10668)
		(layer "In4.Cu")
		(net "FM_BIOS_DEBUG_EN_N")
	)
	(segment
		(start 27.6352 -76.50734)
		(end 27.08148 -75.95362)
		(width 0.10668)
		(layer "In4.Cu")
		(net "FM_BIOS_DEBUG_EN_N")
	)
	(segment
		(start 36.34359 -39.38143)
		(end 37.04336 -38.68166)
		(width 0.10668)
		(layer "In4.Cu")
		(net "FM_BIOS_DEBUG_EN_N")
	)
	(segment
		(start 27.36215 -95.33255)
		(end 27.36215 -92.90685)
		(width 0.10668)
		(layer "In4.Cu")
		(net "FM_BIOS_DEBUG_EN_N")
	)
	(segment
		(start 25.50668 -70.37578)
		(end 25.50668 -67.67068)
		(width 0.10668)
		(layer "In4.Cu")
		(net "FM_BIOS_DEBUG_EN_N")
	)
	(segment
		(start 25.50668 -67.67068)
		(end 26.3271 -66.85026)
		(width 0.10668)
		(layer "In4.Cu")
		(net "FM_BIOS_DEBUG_EN_N")
	)
	(segment
		(start 37.04336 -36.76396)
		(end 37.44087 -36.36645)
		(width 0.10668)
		(layer "In4.Cu")
		(net "FM_BIOS_DEBUG_EN_N")
	)
	(segment
		(start 27.08148 -75.95362)
		(end 27.08148 -73.89114)
		(width 0.10668)
		(layer "In4.Cu")
		(net "FM_BIOS_DEBUG_EN_N")
	)
	(segment
		(start 27.1018 -62.46114)
		(end 27.1018 -59.44362)
		(width 0.10668)
		(layer "In4.Cu")
		(net "FM_BIOS_DEBUG_EN_N")
	)
	(segment
		(start 27.36215 -92.90685)
		(end 27.89174 -92.37726)
		(width 0.10668)
		(layer "In4.Cu")
		(net "FM_BIOS_DEBUG_EN_N")
	)
	(segment
		(start 27.17038 -41.55948)
		(end 34.76498 -41.55948)
		(width 0.10668)
		(layer "In4.Cu")
		(net "FM_BIOS_DEBUG_EN_N")
	)
	(segment
		(start 24.12492 -44.60494)
		(end 27.17038 -41.55948)
		(width 0.10668)
		(layer "In4.Cu")
		(net "FM_BIOS_DEBUG_EN_N")
	)
	(segment
		(start 26.3271 -66.85026)
		(end 26.3271 -63.23584)
		(width 0.10668)
		(layer "In4.Cu")
		(net "FM_BIOS_DEBUG_EN_N")
	)
	(segment
		(start 23.57628 -50.85334)
		(end 23.57628 -45.92955)
		(width 0.10668)
		(layer "In4.Cu")
		(net "FM_BIOS_DEBUG_EN_N")
	)
	(segment
		(start 27.6352 -83.4517)
		(end 27.6352 -76.50734)
		(width 0.10668)
		(layer "In4.Cu")
		(net "FM_BIOS_DEBUG_EN_N")
	)
	(segment
		(start 37.04336 -38.68166)
		(end 37.04336 -36.76396)
		(width 0.10668)
		(layer "In4.Cu")
		(net "FM_BIOS_DEBUG_EN_N")
	)
	(segment
		(start 28.5115 -87.9475)
		(end 27.3812 -86.8172)
		(width 0.10668)
		(layer "In4.Cu")
		(net "FM_BIOS_DEBUG_EN_N")
	)
	(segment
		(start 23.57628 -45.92955)
		(end 24.12492 -44.60494)
		(width 0.10668)
		(layer "In4.Cu")
		(net "FM_BIOS_DEBUG_EN_N")
	)
	(segment
		(start 24.68372 -84.5947)
		(end 26.4922 -84.5947)
		(width 0.10668)
		(layer "In4.Cu")
		(net "FM_BIOS_DEBUG_EN_N")
	)
	(segment
		(start 24.81834 -86.8172)
		(end 24.29764 -86.2965)
		(width 0.10668)
		(layer "In4.Cu")
		(net "FM_BIOS_DEBUG_EN_N")
	)
	(segment
		(start 28.5115 -90.2208)
		(end 28.5115 -87.9475)
		(width 0.10668)
		(layer "In4.Cu")
		(net "FM_BIOS_DEBUG_EN_N")
	)
	(segment
		(start 28.83154 -92.18422)
		(end 28.83154 -90.54084)
		(width 0.10668)
		(layer "In4.Cu")
		(net "FM_BIOS_DEBUG_EN_N")
	)
	(segment
		(start 40.83431 -36.36645)
		(end 43.33494 -33.86582)
		(width 0.10668)
		(layer "In4.Cu")
		(net "FM_BIOS_DEBUG_EN_N")
	)
	(segment
		(start 34.76498 -41.55948)
		(end 36.34359 -39.98087)
		(width 0.10668)
		(layer "In4.Cu")
		(net "FM_BIOS_DEBUG_EN_N")
	)
	(segment
		(start 23.06828 -51.36134)
		(end 23.57628 -50.85334)
		(width 0.10668)
		(layer "In4.Cu")
		(net "FM_BIOS_DEBUG_EN_N")
	)
	(segment
		(start 26.3271 -63.23584)
		(end 27.1018 -62.46114)
		(width 0.10668)
		(layer "In4.Cu")
		(net "FM_BIOS_DEBUG_EN_N")
	)
	(segment
		(start 26.4922 -84.5947)
		(end 27.6352 -83.4517)
		(width 0.10668)
		(layer "In4.Cu")
		(net "FM_BIOS_DEBUG_EN_N")
	)
	(segment
		(start 27.89174 -92.37726)
		(end 28.6385 -92.37726)
		(width 0.10668)
		(layer "In4.Cu")
		(net "FM_BIOS_DEBUG_EN_N")
	)
	(segment
		(start 27.08148 -73.89114)
		(end 26.24074 -73.0504)
		(width 0.10668)
		(layer "In4.Cu")
		(net "FM_BIOS_DEBUG_EN_N")
	)
	(segment
		(start 27.3812 -86.8172)
		(end 24.81834 -86.8172)
		(width 0.10668)
		(layer "In4.Cu")
		(net "FM_BIOS_DEBUG_EN_N")
	)
	(segment
		(start 24.29764 -86.2965)
		(end 24.29764 -84.98078)
		(width 0.10668)
		(layer "In4.Cu")
		(net "FM_BIOS_DEBUG_EN_N")
	)
	(segment
		(start 26.24074 -71.10984)
		(end 25.50668 -70.37578)
		(width 0.10668)
		(layer "In4.Cu")
		(net "FM_BIOS_DEBUG_EN_N")
	)
	(segment
		(start 24.29764 -84.98078)
		(end 24.68372 -84.5947)
		(width 0.10668)
		(layer "In4.Cu")
		(net "FM_BIOS_DEBUG_EN_N")
	)
	(segment
		(start 36.34359 -39.98087)
		(end 36.34359 -39.38143)
		(width 0.10668)
		(layer "In4.Cu")
		(net "FM_BIOS_DEBUG_EN_N")
	)
	(segment
		(start 27.1018 -59.44362)
		(end 23.06828 -55.4101)
		(width 0.10668)
		(layer "In4.Cu")
		(net "FM_BIOS_DEBUG_EN_N")
	)
	(segment
		(start 28.1686 -96.139)
		(end 27.36215 -95.33255)
		(width 0.10668)
		(layer "In4.Cu")
		(net "FM_BIOS_DEBUG_EN_N")
	)
	(segment
		(start 37.44087 -36.36645)
		(end 40.83431 -36.36645)
		(width 0.10668)
		(layer "In4.Cu")
		(net "FM_BIOS_DEBUG_EN_N")
	)
	(via
		(at 56.97982 -21.13534)
		(size 0.508)
		(drill 0.254)
		(layers "F.Cu" "B.Cu")
		(net "DEBUG_PORT_UART_TX")
	)
	(via
		(at 38.989 -94.8436)
		(size 0.6604)
		(drill 0.3302)
		(layers "F.Cu" "B.Cu")
		(net "DEBUG_PORT_UART_TX")
	)
	(via
		(at 37.846 -97.29978)
		(size 0.508)
		(drill 0.254)
		(layers "F.Cu" "B.Cu")
		(net "DEBUG_PORT_UART_TX")
	)
	(segment
		(start 56.97982 -23.325074)
		(end 57.384696 -23.72995)
		(width 0.11684)
		(layer "B.Cu")
		(net "DEBUG_PORT_UART_TX")
	)
	(segment
		(start 38.1508 -96.99498)
		(end 38.1508 -95.6564)
		(width 0.11684)
		(layer "B.Cu")
		(net "DEBUG_PORT_UART_TX")
	)
	(segment
		(start 40.679878 -93.863922)
		(end 40.679878 -93.599)
		(width 0.11684)
		(layer "B.Cu")
		(net "DEBUG_PORT_UART_TX")
	)
	(segment
		(start 57.384696 -23.72995)
		(end 57.785 -23.72995)
		(width 0.11684)
		(layer "B.Cu")
		(net "DEBUG_PORT_UART_TX")
	)
	(segment
		(start 57.785 -22.48408)
		(end 57.796938 -22.472142)
		(width 0.11684)
		(layer "B.Cu")
		(net "DEBUG_PORT_UART_TX")
	)
	(segment
		(start 38.1508 -95.6564)
		(end 38.9636 -94.8436)
		(width 0.11684)
		(layer "B.Cu")
		(net "DEBUG_PORT_UART_TX")
	)
	(segment
		(start 37.846 -97.29978)
		(end 38.1508 -96.99498)
		(width 0.11684)
		(layer "B.Cu")
		(net "DEBUG_PORT_UART_TX")
	)
	(segment
		(start 38.989 -94.8436)
		(end 39.7002 -94.8436)
		(width 0.11684)
		(layer "B.Cu")
		(net "DEBUG_PORT_UART_TX")
	)
	(segment
		(start 38.9636 -94.8436)
		(end 38.989 -94.8436)
		(width 0.11684)
		(layer "B.Cu")
		(net "DEBUG_PORT_UART_TX")
	)
	(segment
		(start 56.97982 -21.13534)
		(end 56.97982 -23.325074)
		(width 0.11684)
		(layer "B.Cu")
		(net "DEBUG_PORT_UART_TX")
	)
	(segment
		(start 57.785 -23.72995)
		(end 57.785 -22.48408)
		(width 0.11684)
		(layer "B.Cu")
		(net "DEBUG_PORT_UART_TX")
	)
	(segment
		(start 39.7002 -94.8436)
		(end 40.679878 -93.863922)
		(width 0.11684)
		(layer "B.Cu")
		(net "DEBUG_PORT_UART_TX")
	)
	(segment
		(start 57.796938 -22.472142)
		(end 57.796938 -21.981922)
		(width 0.11684)
		(layer "B.Cu")
		(net "DEBUG_PORT_UART_TX")
	)
	(segment
		(start 27.723592 -18.769076)
		(end 28.53563 -18.769076)
		(width 0.08382)
		(layer "In2.Cu")
		(net "DEBUG_PORT_UART_TX")
	)
	(segment
		(start 26.967434 -19.525234)
		(end 27.723592 -18.769076)
		(width 0.08382)
		(layer "In2.Cu")
		(net "DEBUG_PORT_UART_TX")
	)
	(segment
		(start 32.89681 -97.12579)
		(end 32.36849 -97.65411)
		(width 0.08382)
		(layer "In2.Cu")
		(net "DEBUG_PORT_UART_TX")
	)
	(segment
		(start 10.60196 -22.606)
		(end 11.23696 -21.971)
		(width 0.08382)
		(layer "In2.Cu")
		(net "DEBUG_PORT_UART_TX")
	)
	(segment
		(start 30.621986 -19.640804)
		(end 32.22879 -18.034)
		(width 0.08382)
		(layer "In2.Cu")
		(net "DEBUG_PORT_UART_TX")
	)
	(segment
		(start 34.1376 -18.034)
		(end 34.29 -17.8816)
		(width 0.08382)
		(layer "In2.Cu")
		(net "DEBUG_PORT_UART_TX")
	)
	(segment
		(start 7.78256 -27.239214)
		(end 10.60196 -24.419814)
		(width 0.08382)
		(layer "In2.Cu")
		(net "DEBUG_PORT_UART_TX")
	)
	(segment
		(start 14.581886 -102.79126)
		(end 10.580624 -102.79126)
		(width 0.08382)
		(layer "In2.Cu")
		(net "DEBUG_PORT_UART_TX")
	)
	(segment
		(start 30.378654 -97.3328)
		(end 28.356814 -99.35464)
		(width 0.08382)
		(layer "In2.Cu")
		(net "DEBUG_PORT_UART_TX")
	)
	(segment
		(start 32.36849 -97.65411)
		(end 31.41091 -97.65411)
		(width 0.08382)
		(layer "In2.Cu")
		(net "DEBUG_PORT_UART_TX")
	)
	(segment
		(start 37.67201 -97.12579)
		(end 32.89681 -97.12579)
		(width 0.08382)
		(layer "In2.Cu")
		(net "DEBUG_PORT_UART_TX")
	)
	(segment
		(start 5.21716 -85.152738)
		(end 5.21716 -80.788256)
		(width 0.08382)
		(layer "In2.Cu")
		(net "DEBUG_PORT_UART_TX")
	)
	(segment
		(start 4.748022 -86.285578)
		(end 5.21716 -85.152738)
		(width 0.08382)
		(layer "In2.Cu")
		(net "DEBUG_PORT_UART_TX")
	)
	(segment
		(start 40.259 -19.3802)
		(end 41.360598 -20.481798)
		(width 0.08382)
		(layer "In2.Cu")
		(net "DEBUG_PORT_UART_TX")
	)
	(segment
		(start 18.237962 -100.92182)
		(end 16.451326 -100.92182)
		(width 0.08382)
		(layer "In2.Cu")
		(net "DEBUG_PORT_UART_TX")
	)
	(segment
		(start 9.144508 -103.3018)
		(end 6.883908 -105.5624)
		(width 0.08382)
		(layer "In2.Cu")
		(net "DEBUG_PORT_UART_TX")
	)
	(segment
		(start 7.126224 -27.239214)
		(end 7.78256 -27.239214)
		(width 0.08382)
		(layer "In2.Cu")
		(net "DEBUG_PORT_UART_TX")
	)
	(segment
		(start 3.7338 -105.5624)
		(end 3.048 -104.8766)
		(width 0.08382)
		(layer "In2.Cu")
		(net "DEBUG_PORT_UART_TX")
	)
	(segment
		(start 3.048 -104.8766)
		(end 3.048 -87.9856)
		(width 0.08382)
		(layer "In2.Cu")
		(net "DEBUG_PORT_UART_TX")
	)
	(segment
		(start 16.451326 -100.92182)
		(end 14.581886 -102.79126)
		(width 0.08382)
		(layer "In2.Cu")
		(net "DEBUG_PORT_UART_TX")
	)
	(segment
		(start 38.607492 -18.3642)
		(end 39.623492 -19.3802)
		(width 0.08382)
		(layer "In2.Cu")
		(net "DEBUG_PORT_UART_TX")
	)
	(segment
		(start 6.883908 -105.5624)
		(end 3.7338 -105.5624)
		(width 0.08382)
		(layer "In2.Cu")
		(net "DEBUG_PORT_UART_TX")
	)
	(segment
		(start 19.420078 -99.739704)
		(end 18.237962 -100.92182)
		(width 0.08382)
		(layer "In2.Cu")
		(net "DEBUG_PORT_UART_TX")
	)
	(segment
		(start 20.14347 -18.5674)
		(end 24.9682 -18.5674)
		(width 0.08382)
		(layer "In2.Cu")
		(net "DEBUG_PORT_UART_TX")
	)
	(segment
		(start 10.60196 -24.419814)
		(end 10.60196 -22.606)
		(width 0.08382)
		(layer "In2.Cu")
		(net "DEBUG_PORT_UART_TX")
	)
	(segment
		(start 32.22879 -18.034)
		(end 34.1376 -18.034)
		(width 0.08382)
		(layer "In2.Cu")
		(net "DEBUG_PORT_UART_TX")
	)
	(segment
		(start 11.23696 -21.971)
		(end 14.896084 -21.971)
		(width 0.08382)
		(layer "In2.Cu")
		(net "DEBUG_PORT_UART_TX")
	)
	(segment
		(start 31.41091 -97.65411)
		(end 31.0896 -97.3328)
		(width 0.08382)
		(layer "In2.Cu")
		(net "DEBUG_PORT_UART_TX")
	)
	(segment
		(start 41.360598 -20.481798)
		(end 56.326278 -20.481798)
		(width 0.08382)
		(layer "In2.Cu")
		(net "DEBUG_PORT_UART_TX")
	)
	(segment
		(start 2.454402 -31.082996)
		(end 6.298438 -27.23896)
		(width 0.08382)
		(layer "In2.Cu")
		(net "DEBUG_PORT_UART_TX")
	)
	(segment
		(start 6.298438 -27.23896)
		(end 7.12597 -27.23896)
		(width 0.08382)
		(layer "In2.Cu")
		(net "DEBUG_PORT_UART_TX")
	)
	(segment
		(start 7.12597 -27.23896)
		(end 7.126224 -27.239214)
		(width 0.08382)
		(layer "In2.Cu")
		(net "DEBUG_PORT_UART_TX")
	)
	(segment
		(start 3.048 -87.9856)
		(end 4.748022 -86.285578)
		(width 0.08382)
		(layer "In2.Cu")
		(net "DEBUG_PORT_UART_TX")
	)
	(segment
		(start 23.399496 -99.739704)
		(end 19.420078 -99.739704)
		(width 0.08382)
		(layer "In2.Cu")
		(net "DEBUG_PORT_UART_TX")
	)
	(segment
		(start 23.78456 -99.35464)
		(end 23.399496 -99.739704)
		(width 0.08382)
		(layer "In2.Cu")
		(net "DEBUG_PORT_UART_TX")
	)
	(segment
		(start 5.21716 -80.788256)
		(end 2.454402 -78.025498)
		(width 0.08382)
		(layer "In2.Cu")
		(net "DEBUG_PORT_UART_TX")
	)
	(segment
		(start 14.896084 -21.971)
		(end 18.165064 -18.70202)
		(width 0.08382)
		(layer "In2.Cu")
		(net "DEBUG_PORT_UART_TX")
	)
	(segment
		(start 24.9682 -18.5674)
		(end 25.926034 -19.525234)
		(width 0.08382)
		(layer "In2.Cu")
		(net "DEBUG_PORT_UART_TX")
	)
	(segment
		(start 29.407358 -19.640804)
		(end 30.621986 -19.640804)
		(width 0.08382)
		(layer "In2.Cu")
		(net "DEBUG_PORT_UART_TX")
	)
	(segment
		(start 39.623492 -19.3802)
		(end 40.259 -19.3802)
		(width 0.08382)
		(layer "In2.Cu")
		(net "DEBUG_PORT_UART_TX")
	)
	(segment
		(start 37.846 -97.29978)
		(end 37.67201 -97.12579)
		(width 0.08382)
		(layer "In2.Cu")
		(net "DEBUG_PORT_UART_TX")
	)
	(segment
		(start 10.070084 -103.3018)
		(end 9.144508 -103.3018)
		(width 0.08382)
		(layer "In2.Cu")
		(net "DEBUG_PORT_UART_TX")
	)
	(segment
		(start 37.0586 -17.8816)
		(end 37.5412 -18.3642)
		(width 0.08382)
		(layer "In2.Cu")
		(net "DEBUG_PORT_UART_TX")
	)
	(segment
		(start 31.0896 -97.3328)
		(end 30.378654 -97.3328)
		(width 0.08382)
		(layer "In2.Cu")
		(net "DEBUG_PORT_UART_TX")
	)
	(segment
		(start 28.356814 -99.35464)
		(end 23.78456 -99.35464)
		(width 0.08382)
		(layer "In2.Cu")
		(net "DEBUG_PORT_UART_TX")
	)
	(segment
		(start 10.580624 -102.79126)
		(end 10.070084 -103.3018)
		(width 0.08382)
		(layer "In2.Cu")
		(net "DEBUG_PORT_UART_TX")
	)
	(segment
		(start 56.326278 -20.481798)
		(end 56.97982 -21.13534)
		(width 0.08382)
		(layer "In2.Cu")
		(net "DEBUG_PORT_UART_TX")
	)
	(segment
		(start 25.926034 -19.525234)
		(end 26.967434 -19.525234)
		(width 0.08382)
		(layer "In2.Cu")
		(net "DEBUG_PORT_UART_TX")
	)
	(segment
		(start 18.165064 -18.70202)
		(end 20.00885 -18.70202)
		(width 0.08382)
		(layer "In2.Cu")
		(net "DEBUG_PORT_UART_TX")
	)
	(segment
		(start 28.53563 -18.769076)
		(end 29.407358 -19.640804)
		(width 0.08382)
		(layer "In2.Cu")
		(net "DEBUG_PORT_UART_TX")
	)
	(segment
		(start 37.5412 -18.3642)
		(end 38.607492 -18.3642)
		(width 0.08382)
		(layer "In2.Cu")
		(net "DEBUG_PORT_UART_TX")
	)
	(segment
		(start 34.29 -17.8816)
		(end 37.0586 -17.8816)
		(width 0.08382)
		(layer "In2.Cu")
		(net "DEBUG_PORT_UART_TX")
	)
	(segment
		(start 2.454402 -78.025498)
		(end 2.454402 -31.082996)
		(width 0.08382)
		(layer "In2.Cu")
		(net "DEBUG_PORT_UART_TX")
	)
	(segment
		(start 20.00885 -18.70202)
		(end 20.14347 -18.5674)
		(width 0.08382)
		(layer "In2.Cu")
		(net "DEBUG_PORT_UART_TX")
	)
	(via
		(at 39.243 -98.3869)
		(size 0.508)
		(drill 0.254)
		(layers "F.Cu" "B.Cu")
		(net "DEBUG_PORT_UART_RX")
	)
	(via
		(at 60.96 -17.1196)
		(size 0.508)
		(drill 0.254)
		(layers "F.Cu" "B.Cu")
		(net "DEBUG_PORT_UART_RX")
	)
	(segment
		(start 61.47435 -18.70075)
		(end 61.47435 -18.2626)
		(width 0.11684)
		(layer "B.Cu")
		(net "DEBUG_PORT_UART_RX")
	)
	(segment
		(start 62.23 -19.4564)
		(end 61.47435 -18.70075)
		(width 0.11684)
		(layer "B.Cu")
		(net "DEBUG_PORT_UART_RX")
	)
	(segment
		(start 61.47435 -17.63395)
		(end 61.47435 -18.2626)
		(width 0.11684)
		(layer "B.Cu")
		(net "DEBUG_PORT_UART_RX")
	)
	(segment
		(start 39.243 -98.3869)
		(end 39.243 -97.698306)
		(width 0.11684)
		(layer "B.Cu")
		(net "DEBUG_PORT_UART_RX")
	)
	(segment
		(start 39.243 -97.698306)
		(end 39.788846 -96.380554)
		(width 0.11684)
		(layer "B.Cu")
		(net "DEBUG_PORT_UART_RX")
	)
	(segment
		(start 40.679624 -94.776036)
		(end 41.180004 -94.275656)
		(width 0.11684)
		(layer "B.Cu")
		(net "DEBUG_PORT_UART_RX")
	)
	(segment
		(start 39.788846 -96.380554)
		(end 40.174926 -95.994474)
		(width 0.11684)
		(layer "B.Cu")
		(net "DEBUG_PORT_UART_RX")
	)
	(segment
		(start 40.174926 -95.994474)
		(end 40.679624 -94.776036)
		(width 0.11684)
		(layer "B.Cu")
		(net "DEBUG_PORT_UART_RX")
	)
	(segment
		(start 41.180004 -94.275656)
		(end 41.180004 -93.599)
		(width 0.11684)
		(layer "B.Cu")
		(net "DEBUG_PORT_UART_RX")
	)
	(segment
		(start 62.23 -20.182078)
		(end 62.23 -19.4564)
		(width 0.11684)
		(layer "B.Cu")
		(net "DEBUG_PORT_UART_RX")
	)
	(segment
		(start 60.96 -17.1196)
		(end 61.47435 -17.63395)
		(width 0.11684)
		(layer "B.Cu")
		(net "DEBUG_PORT_UART_RX")
	)
	(segment
		(start 59.17057 -20.128992)
		(end 41.449752 -20.128992)
		(width 0.08382)
		(layer "In2.Cu")
		(net "DEBUG_PORT_UART_RX")
	)
	(segment
		(start 7.65302 -26.926794)
		(end 7.255764 -26.926794)
		(width 0.08382)
		(layer "In2.Cu")
		(net "DEBUG_PORT_UART_RX")
	)
	(segment
		(start 37.122608 -97.98685)
		(end 38.030658 -98.8949)
		(width 0.08382)
		(layer "In2.Cu")
		(net "DEBUG_PORT_UART_RX")
	)
	(segment
		(start 2.7178 -104.98836)
		(end 3.60426 -105.87482)
		(width 0.08382)
		(layer "In2.Cu")
		(net "DEBUG_PORT_UART_RX")
	)
	(segment
		(start 23.308564 -101.6762)
		(end 23.892764 -101.092)
		(width 0.08382)
		(layer "In2.Cu")
		(net "DEBUG_PORT_UART_RX")
	)
	(segment
		(start 36.53663 -16.85544)
		(end 31.875984 -16.85544)
		(width 0.08382)
		(layer "In2.Cu")
		(net "DEBUG_PORT_UART_RX")
	)
	(segment
		(start 38.030658 -98.8949)
		(end 38.735 -98.8949)
		(width 0.08382)
		(layer "In2.Cu")
		(net "DEBUG_PORT_UART_RX")
	)
	(segment
		(start 2.141982 -30.953456)
		(end 2.141982 -78.155292)
		(width 0.08382)
		(layer "In2.Cu")
		(net "DEBUG_PORT_UART_RX")
	)
	(segment
		(start 11.17854 -21.463)
		(end 10.28954 -22.352)
		(width 0.08382)
		(layer "In2.Cu")
		(net "DEBUG_PORT_UART_RX")
	)
	(segment
		(start 30.415738 -18.315686)
		(end 29.160978 -18.315686)
		(width 0.08382)
		(layer "In2.Cu")
		(net "DEBUG_PORT_UART_RX")
	)
	(segment
		(start 60.96 -18.339562)
		(end 59.17057 -20.128992)
		(width 0.08382)
		(layer "In2.Cu")
		(net "DEBUG_PORT_UART_RX")
	)
	(segment
		(start 26.055574 -19.212814)
		(end 25.05456 -18.2118)
		(width 0.08382)
		(layer "In2.Cu")
		(net "DEBUG_PORT_UART_RX")
	)
	(segment
		(start 40.631364 -18.804636)
		(end 39.818818 -17.99209)
		(width 0.08382)
		(layer "In2.Cu")
		(net "DEBUG_PORT_UART_RX")
	)
	(segment
		(start 30.974538 -98.844862)
		(end 31.486348 -98.632772)
		(width 0.08382)
		(layer "In2.Cu")
		(net "DEBUG_PORT_UART_RX")
	)
	(segment
		(start 7.255764 -26.926794)
		(end 7.25551 -26.92654)
		(width 0.08382)
		(layer "In2.Cu")
		(net "DEBUG_PORT_UART_RX")
	)
	(segment
		(start 30.734 -99.21748)
		(end 30.734 -99.0854)
		(width 0.08382)
		(layer "In2.Cu")
		(net "DEBUG_PORT_UART_RX")
	)
	(segment
		(start 29.957522 -99.455478)
		(end 30.496002 -99.455478)
		(width 0.08382)
		(layer "In2.Cu")
		(net "DEBUG_PORT_UART_RX")
	)
	(segment
		(start 29.028898 -18.447766)
		(end 27.602942 -18.447766)
		(width 0.08382)
		(layer "In2.Cu")
		(net "DEBUG_PORT_UART_RX")
	)
	(segment
		(start 29.160978 -18.315686)
		(end 29.028898 -18.447766)
		(width 0.08382)
		(layer "In2.Cu")
		(net "DEBUG_PORT_UART_RX")
	)
	(segment
		(start 2.141982 -78.155292)
		(end 4.90474 -80.91805)
		(width 0.08382)
		(layer "In2.Cu")
		(net "DEBUG_PORT_UART_RX")
	)
	(segment
		(start 28.321 -101.092)
		(end 29.957522 -99.455478)
		(width 0.08382)
		(layer "In2.Cu")
		(net "DEBUG_PORT_UART_RX")
	)
	(segment
		(start 30.734 -99.0854)
		(end 30.974538 -98.844862)
		(width 0.08382)
		(layer "In2.Cu")
		(net "DEBUG_PORT_UART_RX")
	)
	(segment
		(start 17.145 -18.3896)
		(end 14.0716 -21.463)
		(width 0.08382)
		(layer "In2.Cu")
		(net "DEBUG_PORT_UART_RX")
	)
	(segment
		(start 32.608266 -98.632772)
		(end 33.254188 -97.98685)
		(width 0.08382)
		(layer "In2.Cu")
		(net "DEBUG_PORT_UART_RX")
	)
	(segment
		(start 25.05456 -18.2118)
		(end 20.05711 -18.2118)
		(width 0.08382)
		(layer "In2.Cu")
		(net "DEBUG_PORT_UART_RX")
	)
	(segment
		(start 10.28954 -22.352)
		(end 10.28954 -24.290274)
		(width 0.08382)
		(layer "In2.Cu")
		(net "DEBUG_PORT_UART_RX")
	)
	(segment
		(start 31.875984 -16.85544)
		(end 30.415738 -18.315686)
		(width 0.08382)
		(layer "In2.Cu")
		(net "DEBUG_PORT_UART_RX")
	)
	(segment
		(start 17.2974 -102.53218)
		(end 18.07718 -101.7524)
		(width 0.08382)
		(layer "In2.Cu")
		(net "DEBUG_PORT_UART_RX")
	)
	(segment
		(start 41.449752 -20.128992)
		(end 40.631364 -19.310604)
		(width 0.08382)
		(layer "In2.Cu")
		(net "DEBUG_PORT_UART_RX")
	)
	(segment
		(start 30.496002 -99.455478)
		(end 30.734 -99.21748)
		(width 0.08382)
		(layer "In2.Cu")
		(net "DEBUG_PORT_UART_RX")
	)
	(segment
		(start 60.96 -17.1196)
		(end 60.96 -18.339562)
		(width 0.08382)
		(layer "In2.Cu")
		(net "DEBUG_PORT_UART_RX")
	)
	(segment
		(start 39.818818 -17.99209)
		(end 37.67328 -17.99209)
		(width 0.08382)
		(layer "In2.Cu")
		(net "DEBUG_PORT_UART_RX")
	)
	(segment
		(start 4.90474 -80.91805)
		(end 4.90474 -85.069426)
		(width 0.08382)
		(layer "In2.Cu")
		(net "DEBUG_PORT_UART_RX")
	)
	(segment
		(start 21.05787 -101.6762)
		(end 23.308564 -101.6762)
		(width 0.08382)
		(layer "In2.Cu")
		(net "DEBUG_PORT_UART_RX")
	)
	(segment
		(start 16.441674 -102.53218)
		(end 17.2974 -102.53218)
		(width 0.08382)
		(layer "In2.Cu")
		(net "DEBUG_PORT_UART_RX")
	)
	(segment
		(start 15.265908 -104.3432)
		(end 15.4686 -104.140508)
		(width 0.08382)
		(layer "In2.Cu")
		(net "DEBUG_PORT_UART_RX")
	)
	(segment
		(start 31.486348 -98.632772)
		(end 32.608266 -98.632772)
		(width 0.08382)
		(layer "In2.Cu")
		(net "DEBUG_PORT_UART_RX")
	)
	(segment
		(start 15.4686 -103.505254)
		(end 16.441674 -102.53218)
		(width 0.08382)
		(layer "In2.Cu")
		(net "DEBUG_PORT_UART_RX")
	)
	(segment
		(start 10.28954 -24.290274)
		(end 7.65302 -26.926794)
		(width 0.08382)
		(layer "In2.Cu")
		(net "DEBUG_PORT_UART_RX")
	)
	(segment
		(start 14.0716 -21.463)
		(end 11.17854 -21.463)
		(width 0.08382)
		(layer "In2.Cu")
		(net "DEBUG_PORT_UART_RX")
	)
	(segment
		(start 20.98167 -101.7524)
		(end 21.05787 -101.6762)
		(width 0.08382)
		(layer "In2.Cu")
		(net "DEBUG_PORT_UART_RX")
	)
	(segment
		(start 6.168898 -26.92654)
		(end 2.141982 -30.953456)
		(width 0.08382)
		(layer "In2.Cu")
		(net "DEBUG_PORT_UART_RX")
	)
	(segment
		(start 15.4686 -104.140508)
		(end 15.4686 -103.505254)
		(width 0.08382)
		(layer "In2.Cu")
		(net "DEBUG_PORT_UART_RX")
	)
	(segment
		(start 7.25551 -26.92654)
		(end 6.168898 -26.92654)
		(width 0.08382)
		(layer "In2.Cu")
		(net "DEBUG_PORT_UART_RX")
	)
	(segment
		(start 33.254188 -97.98685)
		(end 37.122608 -97.98685)
		(width 0.08382)
		(layer "In2.Cu")
		(net "DEBUG_PORT_UART_RX")
	)
	(segment
		(start 4.90474 -85.069426)
		(end 4.486148 -86.080346)
		(width 0.08382)
		(layer "In2.Cu")
		(net "DEBUG_PORT_UART_RX")
	)
	(segment
		(start 23.892764 -101.092)
		(end 28.321 -101.092)
		(width 0.08382)
		(layer "In2.Cu")
		(net "DEBUG_PORT_UART_RX")
	)
	(segment
		(start 26.837894 -19.212814)
		(end 26.055574 -19.212814)
		(width 0.08382)
		(layer "In2.Cu")
		(net "DEBUG_PORT_UART_RX")
	)
	(segment
		(start 3.60426 -105.87482)
		(end 9.264142 -105.87482)
		(width 0.08382)
		(layer "In2.Cu")
		(net "DEBUG_PORT_UART_RX")
	)
	(segment
		(start 20.05711 -18.2118)
		(end 19.87931 -18.3896)
		(width 0.08382)
		(layer "In2.Cu")
		(net "DEBUG_PORT_UART_RX")
	)
	(segment
		(start 38.735 -98.8949)
		(end 39.243 -98.3869)
		(width 0.08382)
		(layer "In2.Cu")
		(net "DEBUG_PORT_UART_RX")
	)
	(segment
		(start 27.602942 -18.447766)
		(end 26.837894 -19.212814)
		(width 0.08382)
		(layer "In2.Cu")
		(net "DEBUG_PORT_UART_RX")
	)
	(segment
		(start 9.264142 -105.87482)
		(end 10.795762 -104.3432)
		(width 0.08382)
		(layer "In2.Cu")
		(net "DEBUG_PORT_UART_RX")
	)
	(segment
		(start 37.67328 -17.99209)
		(end 36.53663 -16.85544)
		(width 0.08382)
		(layer "In2.Cu")
		(net "DEBUG_PORT_UART_RX")
	)
	(segment
		(start 4.486148 -86.080346)
		(end 2.7178 -87.848694)
		(width 0.08382)
		(layer "In2.Cu")
		(net "DEBUG_PORT_UART_RX")
	)
	(segment
		(start 40.631364 -19.310604)
		(end 40.631364 -18.804636)
		(width 0.08382)
		(layer "In2.Cu")
		(net "DEBUG_PORT_UART_RX")
	)
	(segment
		(start 19.87931 -18.3896)
		(end 17.145 -18.3896)
		(width 0.08382)
		(layer "In2.Cu")
		(net "DEBUG_PORT_UART_RX")
	)
	(segment
		(start 10.795762 -104.3432)
		(end 15.265908 -104.3432)
		(width 0.08382)
		(layer "In2.Cu")
		(net "DEBUG_PORT_UART_RX")
	)
	(segment
		(start 18.07718 -101.7524)
		(end 20.98167 -101.7524)
		(width 0.08382)
		(layer "In2.Cu")
		(net "DEBUG_PORT_UART_RX")
	)
	(segment
		(start 2.7178 -87.848694)
		(end 2.7178 -104.98836)
		(width 0.08382)
		(layer "In2.Cu")
		(net "DEBUG_PORT_UART_RX")
	)
	(via
		(at 9.525 -29.591)
		(size 0.6604)
		(drill 0.3302)
		(layers "F.Cu" "B.Cu")
		(net "DEBUG_PORT_PRSNT_BUF_EN")
	)
	(via
		(at 47.6758 -25.146)
		(size 0.508)
		(drill 0.254)
		(layers "F.Cu" "B.Cu")
		(net "DEBUG_PORT_PRSNT_BUF_EN")
	)
	(via
		(at 8.10006 -28.0416)
		(size 0.508)
		(drill 0.254)
		(layers "F.Cu" "B.Cu")
		(net "DEBUG_PORT_PRSNT_BUF_EN")
	)
	(segment
		(start 8.96874 -29.591)
		(end 9.525 -29.591)
		(width 0.11684)
		(layer "B.Cu")
		(net "DEBUG_PORT_PRSNT_BUF_EN")
	)
	(segment
		(start 15.99184 -56.85536)
		(end 14.5542 -58.293)
		(width 0.11684)
		(layer "B.Cu")
		(net "DEBUG_PORT_PRSNT_BUF_EN")
	)
	(segment
		(start 16.891 -51.482498)
		(end 15.99184 -52.381658)
		(width 0.11684)
		(layer "B.Cu")
		(net "DEBUG_PORT_PRSNT_BUF_EN")
	)
	(segment
		(start 16.891 -49.75098)
		(end 16.891 -51.482498)
		(width 0.11684)
		(layer "B.Cu")
		(net "DEBUG_PORT_PRSNT_BUF_EN")
	)
	(segment
		(start 15.83182 -44.438316)
		(end 17.606264 -46.21276)
		(width 0.11684)
		(layer "B.Cu")
		(net "DEBUG_PORT_PRSNT_BUF_EN")
	)
	(segment
		(start 8.10006 -28.0416)
		(end 8.10006 -28.72232)
		(width 0.11684)
		(layer "B.Cu")
		(net "DEBUG_PORT_PRSNT_BUF_EN")
	)
	(segment
		(start 12.954 -29.591)
		(end 13.843 -30.48)
		(width 0.11684)
		(layer "B.Cu")
		(net "DEBUG_PORT_PRSNT_BUF_EN")
	)
	(segment
		(start 13.843 -30.48)
		(end 13.843 -35.5092)
		(width 0.11684)
		(layer "B.Cu")
		(net "DEBUG_PORT_PRSNT_BUF_EN")
	)
	(segment
		(start 17.606264 -46.21276)
		(end 17.606264 -49.035716)
		(width 0.11684)
		(layer "B.Cu")
		(net "DEBUG_PORT_PRSNT_BUF_EN")
	)
	(segment
		(start 13.843 -35.5092)
		(end 15.83182 -37.49802)
		(width 0.11684)
		(layer "B.Cu")
		(net "DEBUG_PORT_PRSNT_BUF_EN")
	)
	(segment
		(start 8.10006 -28.72232)
		(end 8.96874 -29.591)
		(width 0.11684)
		(layer "B.Cu")
		(net "DEBUG_PORT_PRSNT_BUF_EN")
	)
	(segment
		(start 15.661894 -66.246248)
		(end 15.661894 -67.385946)
		(width 0.11684)
		(layer "B.Cu")
		(net "DEBUG_PORT_PRSNT_BUF_EN")
	)
	(segment
		(start 47.10938 -24.51735)
		(end 47.10938 -24.57958)
		(width 0.11684)
		(layer "B.Cu")
		(net "DEBUG_PORT_PRSNT_BUF_EN")
	)
	(segment
		(start 15.99184 -52.381658)
		(end 15.99184 -56.85536)
		(width 0.11684)
		(layer "B.Cu")
		(net "DEBUG_PORT_PRSNT_BUF_EN")
	)
	(segment
		(start 17.606264 -49.035716)
		(end 16.891 -49.75098)
		(width 0.11684)
		(layer "B.Cu")
		(net "DEBUG_PORT_PRSNT_BUF_EN")
	)
	(segment
		(start 15.83182 -37.49802)
		(end 15.83182 -44.438316)
		(width 0.11684)
		(layer "B.Cu")
		(net "DEBUG_PORT_PRSNT_BUF_EN")
	)
	(segment
		(start 14.5542 -65.138554)
		(end 15.661894 -66.246248)
		(width 0.11684)
		(layer "B.Cu")
		(net "DEBUG_PORT_PRSNT_BUF_EN")
	)
	(segment
		(start 47.10938 -24.57958)
		(end 47.6758 -25.146)
		(width 0.11684)
		(layer "B.Cu")
		(net "DEBUG_PORT_PRSNT_BUF_EN")
	)
	(segment
		(start 9.525 -29.591)
		(end 12.954 -29.591)
		(width 0.11684)
		(layer "B.Cu")
		(net "DEBUG_PORT_PRSNT_BUF_EN")
	)
	(segment
		(start 14.5542 -58.293)
		(end 14.5542 -65.138554)
		(width 0.11684)
		(layer "B.Cu")
		(net "DEBUG_PORT_PRSNT_BUF_EN")
	)
	(segment
		(start 12.73429 -25.668732)
		(end 11.738102 -26.66492)
		(width 0.10668)
		(layer "In4.Cu")
		(net "DEBUG_PORT_PRSNT_BUF_EN")
	)
	(segment
		(start 12.467844 -15.497556)
		(end 12.467844 -15.944596)
		(width 0.10668)
		(layer "In4.Cu")
		(net "DEBUG_PORT_PRSNT_BUF_EN")
	)
	(segment
		(start 11.738102 -26.66492)
		(end 9.47674 -26.66492)
		(width 0.10668)
		(layer "In4.Cu")
		(net "DEBUG_PORT_PRSNT_BUF_EN")
	)
	(segment
		(start 47.1805 -24.6507)
		(end 45.663358 -24.6507)
		(width 0.10668)
		(layer "In4.Cu")
		(net "DEBUG_PORT_PRSNT_BUF_EN")
	)
	(segment
		(start 13.34008 -23.16988)
		(end 13.34008 -24.414226)
		(width 0.10668)
		(layer "In4.Cu")
		(net "DEBUG_PORT_PRSNT_BUF_EN")
	)
	(segment
		(start 45.663358 -24.6507)
		(end 44.309538 -23.29688)
		(width 0.10668)
		(layer "In4.Cu")
		(net "DEBUG_PORT_PRSNT_BUF_EN")
	)
	(segment
		(start 39.403528 -24.160226)
		(end 33.118298 -24.160226)
		(width 0.10668)
		(layer "In4.Cu")
		(net "DEBUG_PORT_PRSNT_BUF_EN")
	)
	(segment
		(start 47.6758 -25.146)
		(end 47.1805 -24.6507)
		(width 0.10668)
		(layer "In4.Cu")
		(net "DEBUG_PORT_PRSNT_BUF_EN")
	)
	(segment
		(start 12.467844 -15.944596)
		(end 11.62304 -16.7894)
		(width 0.10668)
		(layer "In4.Cu")
		(net "DEBUG_PORT_PRSNT_BUF_EN")
	)
	(segment
		(start 12.64666 -15.31874)
		(end 12.467844 -15.497556)
		(width 0.10668)
		(layer "In4.Cu")
		(net "DEBUG_PORT_PRSNT_BUF_EN")
	)
	(segment
		(start 13.34008 -24.414226)
		(end 12.73429 -25.020016)
		(width 0.10668)
		(layer "In4.Cu")
		(net "DEBUG_PORT_PRSNT_BUF_EN")
	)
	(segment
		(start 30.83306 -21.874988)
		(end 30.83306 -21.0312)
		(width 0.10668)
		(layer "In4.Cu")
		(net "DEBUG_PORT_PRSNT_BUF_EN")
	)
	(segment
		(start 44.309538 -23.29688)
		(end 40.266874 -23.29688)
		(width 0.10668)
		(layer "In4.Cu")
		(net "DEBUG_PORT_PRSNT_BUF_EN")
	)
	(segment
		(start 11.62304 -16.7894)
		(end 11.62304 -21.45284)
		(width 0.10668)
		(layer "In4.Cu")
		(net "DEBUG_PORT_PRSNT_BUF_EN")
	)
	(segment
		(start 30.61843 -20.81657)
		(end 30.61843 -16.64843)
		(width 0.10668)
		(layer "In4.Cu")
		(net "DEBUG_PORT_PRSNT_BUF_EN")
	)
	(segment
		(start 12.73429 -25.020016)
		(end 12.73429 -25.668732)
		(width 0.10668)
		(layer "In4.Cu")
		(net "DEBUG_PORT_PRSNT_BUF_EN")
	)
	(segment
		(start 9.47674 -26.66492)
		(end 8.10006 -28.0416)
		(width 0.10668)
		(layer "In4.Cu")
		(net "DEBUG_PORT_PRSNT_BUF_EN")
	)
	(segment
		(start 30.61843 -16.64843)
		(end 28.32608 -14.35608)
		(width 0.10668)
		(layer "In4.Cu")
		(net "DEBUG_PORT_PRSNT_BUF_EN")
	)
	(segment
		(start 28.32608 -14.35608)
		(end 14.02588 -14.35608)
		(width 0.10668)
		(layer "In4.Cu")
		(net "DEBUG_PORT_PRSNT_BUF_EN")
	)
	(segment
		(start 33.118298 -24.160226)
		(end 30.83306 -21.874988)
		(width 0.10668)
		(layer "In4.Cu")
		(net "DEBUG_PORT_PRSNT_BUF_EN")
	)
	(segment
		(start 14.02588 -14.35608)
		(end 13.06322 -15.31874)
		(width 0.10668)
		(layer "In4.Cu")
		(net "DEBUG_PORT_PRSNT_BUF_EN")
	)
	(segment
		(start 11.62304 -21.45284)
		(end 13.34008 -23.16988)
		(width 0.10668)
		(layer "In4.Cu")
		(net "DEBUG_PORT_PRSNT_BUF_EN")
	)
	(segment
		(start 30.83306 -21.0312)
		(end 30.61843 -20.81657)
		(width 0.10668)
		(layer "In4.Cu")
		(net "DEBUG_PORT_PRSNT_BUF_EN")
	)
	(segment
		(start 40.266874 -23.29688)
		(end 39.403528 -24.160226)
		(width 0.10668)
		(layer "In4.Cu")
		(net "DEBUG_PORT_PRSNT_BUF_EN")
	)
	(segment
		(start 13.06322 -15.31874)
		(end 12.64666 -15.31874)
		(width 0.10668)
		(layer "In4.Cu")
		(net "DEBUG_PORT_PRSNT_BUF_EN")
	)
	(via
		(at 44.7802 -25.0698)
		(size 0.508)
		(drill 0.254)
		(layers "F.Cu" "B.Cu")
		(net "DEBUG_PORT_PRSNT")
	)
	(via
		(at 38.53053 -90.9066)
		(size 0.508)
		(drill 0.254)
		(layers "F.Cu" "B.Cu")
		(net "DEBUG_PORT_PRSNT")
	)
	(via
		(at 56.8452 -12.8778)
		(size 0.6604)
		(drill 0.3302)
		(layers "F.Cu" "B.Cu")
		(net "DEBUG_PORT_PRSNT")
	)
	(segment
		(start 45.86986 -21.26234)
		(end 45.30217 -21.26234)
		(width 0.11684)
		(layer "B.Cu")
		(net "DEBUG_PORT_PRSNT")
	)
	(segment
		(start 49.58842 -18.25498)
		(end 49.58842 -15.74038)
		(width 0.11684)
		(layer "B.Cu")
		(net "DEBUG_PORT_PRSNT")
	)
	(segment
		(start 59.0296 -12.8778)
		(end 59.68746 -13.53566)
		(width 0.11684)
		(layer "B.Cu")
		(net "DEBUG_PORT_PRSNT")
	)
	(segment
		(start 59.68746 -14.633702)
		(end 59.4614 -14.859762)
		(width 0.11684)
		(layer "B.Cu")
		(net "DEBUG_PORT_PRSNT")
	)
	(segment
		(start 59.4614 -14.859762)
		(end 59.4614 -16.9164)
		(width 0.11684)
		(layer "B.Cu")
		(net "DEBUG_PORT_PRSNT")
	)
	(segment
		(start 44.45 -21.0312)
		(end 44.45 -20.33905)
		(width 0.11684)
		(layer "B.Cu")
		(net "DEBUG_PORT_PRSNT")
	)
	(segment
		(start 39.67988 -91.53652)
		(end 39.67988 -91.398852)
		(width 0.11684)
		(layer "B.Cu")
		(net "DEBUG_PORT_PRSNT")
	)
	(segment
		(start 39.319454 -91.694254)
		(end 39.522146 -91.694254)
		(width 0.11684)
		(layer "B.Cu")
		(net "DEBUG_PORT_PRSNT")
	)
	(segment
		(start 39.522146 -91.694254)
		(end 39.67988 -91.53652)
		(width 0.11684)
		(layer "B.Cu")
		(net "DEBUG_PORT_PRSNT")
	)
	(segment
		(start 59.9186 -20.828)
		(end 59.297062 -20.206462)
		(width 0.11684)
		(layer "B.Cu")
		(net "DEBUG_PORT_PRSNT")
	)
	(segment
		(start 47.0408 -22.4282)
		(end 47.0408 -21.2852)
		(width 0.11684)
		(layer "B.Cu")
		(net "DEBUG_PORT_PRSNT")
	)
	(segment
		(start 62.980062 -20.202398)
		(end 62.35446 -20.828)
		(width 0.11684)
		(layer "B.Cu")
		(net "DEBUG_PORT_PRSNT")
	)
	(segment
		(start 45.32884 -22.67712)
		(end 46.79188 -22.67712)
		(width 0.11684)
		(layer "B.Cu")
		(net "DEBUG_PORT_PRSNT")
	)
	(segment
		(start 44.45 -20.33905)
		(end 43.942 -19.83105)
		(width 0.11684)
		(layer "B.Cu")
		(net "DEBUG_PORT_PRSNT")
	)
	(segment
		(start 49.58842 -15.74038)
		(end 52.451 -12.8778)
		(width 0.11684)
		(layer "B.Cu")
		(net "DEBUG_PORT_PRSNT")
	)
	(segment
		(start 44.7802 -25.019)
		(end 45.212 -24.5872)
		(width 0.11684)
		(layer "B.Cu")
		(net "DEBUG_PORT_PRSNT")
	)
	(segment
		(start 62.35446 -20.828)
		(end 59.9186 -20.828)
		(width 0.11684)
		(layer "B.Cu")
		(net "DEBUG_PORT_PRSNT")
	)
	(segment
		(start 46.6852 -20.9296)
		(end 46.2026 -20.9296)
		(width 0.11684)
		(layer "B.Cu")
		(net "DEBUG_PORT_PRSNT")
	)
	(segment
		(start 56.8452 -12.8778)
		(end 59.0296 -12.8778)
		(width 0.11684)
		(layer "B.Cu")
		(net "DEBUG_PORT_PRSNT")
	)
	(segment
		(start 59.4614 -16.9164)
		(end 60.7314 -18.1864)
		(width 0.11684)
		(layer "B.Cu")
		(net "DEBUG_PORT_PRSNT")
	)
	(segment
		(start 45.212 -22.79396)
		(end 45.32884 -22.67712)
		(width 0.11684)
		(layer "B.Cu")
		(net "DEBUG_PORT_PRSNT")
	)
	(segment
		(start 52.451 -12.8778)
		(end 56.8452 -12.8778)
		(width 0.11684)
		(layer "B.Cu")
		(net "DEBUG_PORT_PRSNT")
	)
	(segment
		(start 38.5318 -90.9066)
		(end 39.319454 -91.694254)
		(width 0.11684)
		(layer "B.Cu")
		(net "DEBUG_PORT_PRSNT")
	)
	(segment
		(start 60.7314 -18.1864)
		(end 60.7314 -18.74774)
		(width 0.11684)
		(layer "B.Cu")
		(net "DEBUG_PORT_PRSNT")
	)
	(segment
		(start 44.7802 -25.0698)
		(end 44.7802 -25.019)
		(width 0.11684)
		(layer "B.Cu")
		(net "DEBUG_PORT_PRSNT")
	)
	(segment
		(start 43.942 -19.83105)
		(end 48.01235 -19.83105)
		(width 0.11684)
		(layer "B.Cu")
		(net "DEBUG_PORT_PRSNT")
	)
	(segment
		(start 59.68746 -13.53566)
		(end 59.68746 -14.633702)
		(width 0.11684)
		(layer "B.Cu")
		(net "DEBUG_PORT_PRSNT")
	)
	(segment
		(start 45.212 -24.5872)
		(end 45.212 -22.79396)
		(width 0.11684)
		(layer "B.Cu")
		(net "DEBUG_PORT_PRSNT")
	)
	(segment
		(start 47.0408 -21.2852)
		(end 46.6852 -20.9296)
		(width 0.11684)
		(layer "B.Cu")
		(net "DEBUG_PORT_PRSNT")
	)
	(segment
		(start 38.53053 -90.9066)
		(end 38.5318 -90.9066)
		(width 0.11684)
		(layer "B.Cu")
		(net "DEBUG_PORT_PRSNT")
	)
	(segment
		(start 45.30217 -21.26234)
		(end 44.68114 -21.26234)
		(width 0.11684)
		(layer "B.Cu")
		(net "DEBUG_PORT_PRSNT")
	)
	(segment
		(start 48.01235 -19.83105)
		(end 49.58842 -18.25498)
		(width 0.11684)
		(layer "B.Cu")
		(net "DEBUG_PORT_PRSNT")
	)
	(segment
		(start 60.7314 -18.74774)
		(end 59.297062 -20.182078)
		(width 0.11684)
		(layer "B.Cu")
		(net "DEBUG_PORT_PRSNT")
	)
	(segment
		(start 46.79188 -22.67712)
		(end 47.0408 -22.4282)
		(width 0.11684)
		(layer "B.Cu")
		(net "DEBUG_PORT_PRSNT")
	)
	(segment
		(start 46.2026 -20.9296)
		(end 45.86986 -21.26234)
		(width 0.11684)
		(layer "B.Cu")
		(net "DEBUG_PORT_PRSNT")
	)
	(segment
		(start 44.68114 -21.26234)
		(end 44.45 -21.0312)
		(width 0.11684)
		(layer "B.Cu")
		(net "DEBUG_PORT_PRSNT")
	)
	(segment
		(start 59.297062 -20.206462)
		(end 59.297062 -20.182078)
		(width 0.11684)
		(layer "B.Cu")
		(net "DEBUG_PORT_PRSNT")
	)
	(segment
		(start 62.980062 -20.182078)
		(end 62.980062 -20.202398)
		(width 0.11684)
		(layer "B.Cu")
		(net "DEBUG_PORT_PRSNT")
	)
	(segment
		(start 33.8709 -88.46312)
		(end 34.6329 -89.22512)
		(width 0.10668)
		(layer "In7.Cu")
		(net "DEBUG_PORT_PRSNT")
	)
	(segment
		(start 29.09062 -77.569568)
		(end 29.09062 -80.20431)
		(width 0.10668)
		(layer "In7.Cu")
		(net "DEBUG_PORT_PRSNT")
	)
	(segment
		(start 23.65502 -61.29782)
		(end 24.7396 -62.3824)
		(width 0.10668)
		(layer "In7.Cu")
		(net "DEBUG_PORT_PRSNT")
	)
	(segment
		(start 33.32226 -86.25586)
		(end 33.32226 -88.23706)
		(width 0.10668)
		(layer "In7.Cu")
		(net "DEBUG_PORT_PRSNT")
	)
	(segment
		(start 32.731964 -29.633418)
		(end 31.719012 -30.64637)
		(width 0.10668)
		(layer "In7.Cu")
		(net "DEBUG_PORT_PRSNT")
	)
	(segment
		(start 34.6329 -89.22512)
		(end 36.962842 -89.22512)
		(width 0.10668)
		(layer "In7.Cu")
		(net "DEBUG_PORT_PRSNT")
	)
	(segment
		(start 22.16658 -46.003972)
		(end 22.16658 -51.92522)
		(width 0.10668)
		(layer "In7.Cu")
		(net "DEBUG_PORT_PRSNT")
	)
	(segment
		(start 24.7396 -63.08344)
		(end 24.2443 -63.57874)
		(width 0.10668)
		(layer "In7.Cu")
		(net "DEBUG_PORT_PRSNT")
	)
	(segment
		(start 36.962842 -89.22512)
		(end 37.780722 -90.043)
		(width 0.10668)
		(layer "In7.Cu")
		(net "DEBUG_PORT_PRSNT")
	)
	(segment
		(start 31.719012 -31.79699)
		(end 30.8356 -32.680402)
		(width 0.10668)
		(layer "In7.Cu")
		(net "DEBUG_PORT_PRSNT")
	)
	(segment
		(start 28.19908 -38.359588)
		(end 28.19908 -38.917118)
		(width 0.10668)
		(layer "In7.Cu")
		(net "DEBUG_PORT_PRSNT")
	)
	(segment
		(start 44.7802 -25.0698)
		(end 44.54652 -25.30348)
		(width 0.10668)
		(layer "In7.Cu")
		(net "DEBUG_PORT_PRSNT")
	)
	(segment
		(start 33.32226 -88.23706)
		(end 33.54832 -88.46312)
		(width 0.10668)
		(layer "In7.Cu")
		(net "DEBUG_PORT_PRSNT")
	)
	(segment
		(start 33.54832 -88.46312)
		(end 33.8709 -88.46312)
		(width 0.10668)
		(layer "In7.Cu")
		(net "DEBUG_PORT_PRSNT")
	)
	(segment
		(start 38.5318 -90.17)
		(end 38.5318 -90.90533)
		(width 0.10668)
		(layer "In7.Cu")
		(net "DEBUG_PORT_PRSNT")
	)
	(segment
		(start 37.12718 -25.48128)
		(end 34.97961 -25.48128)
		(width 0.10668)
		(layer "In7.Cu")
		(net "DEBUG_PORT_PRSNT")
	)
	(segment
		(start 30.353 -81.46669)
		(end 30.353 -82.544412)
		(width 0.10668)
		(layer "In7.Cu")
		(net "DEBUG_PORT_PRSNT")
	)
	(segment
		(start 21.53412 -52.55768)
		(end 21.53412 -56.862726)
		(width 0.10668)
		(layer "In7.Cu")
		(net "DEBUG_PORT_PRSNT")
	)
	(segment
		(start 24.4856 -71.11746)
		(end 25.1587 -71.79056)
		(width 0.10668)
		(layer "In7.Cu")
		(net "DEBUG_PORT_PRSNT")
	)
	(segment
		(start 23.887938 -66.553842)
		(end 23.887938 -67.212972)
		(width 0.10668)
		(layer "In7.Cu")
		(net "DEBUG_PORT_PRSNT")
	)
	(segment
		(start 37.780722 -90.043)
		(end 38.4048 -90.043)
		(width 0.10668)
		(layer "In7.Cu")
		(net "DEBUG_PORT_PRSNT")
	)
	(segment
		(start 38.4048 -90.043)
		(end 38.5318 -90.17)
		(width 0.10668)
		(layer "In7.Cu")
		(net "DEBUG_PORT_PRSNT")
	)
	(segment
		(start 30.8356 -32.680402)
		(end 30.8356 -35.723068)
		(width 0.10668)
		(layer "In7.Cu")
		(net "DEBUG_PORT_PRSNT")
	)
	(segment
		(start 44.54652 -25.30348)
		(end 37.30498 -25.30348)
		(width 0.10668)
		(layer "In7.Cu")
		(net "DEBUG_PORT_PRSNT")
	)
	(segment
		(start 32.731964 -28.96997)
		(end 32.731964 -29.633418)
		(width 0.10668)
		(layer "In7.Cu")
		(net "DEBUG_PORT_PRSNT")
	)
	(segment
		(start 37.30498 -25.30348)
		(end 37.12718 -25.48128)
		(width 0.10668)
		(layer "In7.Cu")
		(net "DEBUG_PORT_PRSNT")
	)
	(segment
		(start 24.7396 -62.3824)
		(end 24.7396 -63.08344)
		(width 0.10668)
		(layer "In7.Cu")
		(net "DEBUG_PORT_PRSNT")
	)
	(segment
		(start 25.442164 -72.473566)
		(end 26.96718 -73.998582)
		(width 0.10668)
		(layer "In7.Cu")
		(net "DEBUG_PORT_PRSNT")
	)
	(segment
		(start 31.719012 -30.64637)
		(end 31.719012 -31.79699)
		(width 0.10668)
		(layer "In7.Cu")
		(net "DEBUG_PORT_PRSNT")
	)
	(segment
		(start 30.353 -82.544412)
		(end 32.70758 -84.898992)
		(width 0.10668)
		(layer "In7.Cu")
		(net "DEBUG_PORT_PRSNT")
	)
	(segment
		(start 34.97961 -25.48128)
		(end 33.979866 -26.481024)
		(width 0.10668)
		(layer "In7.Cu")
		(net "DEBUG_PORT_PRSNT")
	)
	(segment
		(start 28.19908 -38.917118)
		(end 22.91207 -44.204128)
		(width 0.10668)
		(layer "In7.Cu")
		(net "DEBUG_PORT_PRSNT")
	)
	(segment
		(start 23.65502 -58.983626)
		(end 23.65502 -61.29782)
		(width 0.10668)
		(layer "In7.Cu")
		(net "DEBUG_PORT_PRSNT")
	)
	(segment
		(start 22.91207 -44.204128)
		(end 22.16658 -46.003972)
		(width 0.10668)
		(layer "In7.Cu")
		(net "DEBUG_PORT_PRSNT")
	)
	(segment
		(start 23.887938 -67.212972)
		(end 24.4856 -67.810634)
		(width 0.10668)
		(layer "In7.Cu")
		(net "DEBUG_PORT_PRSNT")
	)
	(segment
		(start 24.2443 -66.19748)
		(end 23.887938 -66.553842)
		(width 0.10668)
		(layer "In7.Cu")
		(net "DEBUG_PORT_PRSNT")
	)
	(segment
		(start 26.96718 -73.998582)
		(end 26.96718 -75.446128)
		(width 0.10668)
		(layer "In7.Cu")
		(net "DEBUG_PORT_PRSNT")
	)
	(segment
		(start 25.1587 -71.79056)
		(end 25.442164 -72.473566)
		(width 0.10668)
		(layer "In7.Cu")
		(net "DEBUG_PORT_PRSNT")
	)
	(segment
		(start 33.979866 -27.722068)
		(end 32.731964 -28.96997)
		(width 0.10668)
		(layer "In7.Cu")
		(net "DEBUG_PORT_PRSNT")
	)
	(segment
		(start 26.96718 -75.446128)
		(end 29.09062 -77.569568)
		(width 0.10668)
		(layer "In7.Cu")
		(net "DEBUG_PORT_PRSNT")
	)
	(segment
		(start 33.979866 -26.481024)
		(end 33.979866 -27.722068)
		(width 0.10668)
		(layer "In7.Cu")
		(net "DEBUG_PORT_PRSNT")
	)
	(segment
		(start 32.70758 -85.64118)
		(end 33.32226 -86.25586)
		(width 0.10668)
		(layer "In7.Cu")
		(net "DEBUG_PORT_PRSNT")
	)
	(segment
		(start 29.09062 -80.20431)
		(end 30.353 -81.46669)
		(width 0.10668)
		(layer "In7.Cu")
		(net "DEBUG_PORT_PRSNT")
	)
	(segment
		(start 24.2443 -63.57874)
		(end 24.2443 -66.19748)
		(width 0.10668)
		(layer "In7.Cu")
		(net "DEBUG_PORT_PRSNT")
	)
	(segment
		(start 38.5318 -90.90533)
		(end 38.53053 -90.9066)
		(width 0.10668)
		(layer "In7.Cu")
		(net "DEBUG_PORT_PRSNT")
	)
	(segment
		(start 24.4856 -67.810634)
		(end 24.4856 -71.11746)
		(width 0.10668)
		(layer "In7.Cu")
		(net "DEBUG_PORT_PRSNT")
	)
	(segment
		(start 22.16658 -51.92522)
		(end 21.53412 -52.55768)
		(width 0.10668)
		(layer "In7.Cu")
		(net "DEBUG_PORT_PRSNT")
	)
	(segment
		(start 32.70758 -84.898992)
		(end 32.70758 -85.64118)
		(width 0.10668)
		(layer "In7.Cu")
		(net "DEBUG_PORT_PRSNT")
	)
	(segment
		(start 30.8356 -35.723068)
		(end 28.19908 -38.359588)
		(width 0.10668)
		(layer "In7.Cu")
		(net "DEBUG_PORT_PRSNT")
	)
	(segment
		(start 21.53412 -56.862726)
		(end 23.65502 -58.983626)
		(width 0.10668)
		(layer "In7.Cu")
		(net "DEBUG_PORT_PRSNT")
	)
	(segment
		(start 35.11169 -51.816)
		(end 34.81705 -51.52136)
		(width 0.11684)
		(layer "F.Cu")
		(net "BMC_PWR_LED")
	)
	(segment
		(start 36.510468 -51.66233)
		(end 36.356798 -51.816)
		(width 0.11684)
		(layer "F.Cu")
		(net "BMC_PWR_LED")
	)
	(segment
		(start 47.295054 -53.771038)
		(end 47.295054 -53.771292)
		(width 0.11684)
		(layer "F.Cu")
		(net "BMC_PWR_LED")
	)
	(segment
		(start 47.699676 -53.366416)
		(end 47.295054 -53.771038)
		(width 0.11684)
		(layer "F.Cu")
		(net "BMC_PWR_LED")
	)
	(segment
		(start 34.81705 -51.52136)
		(end 34.81705 -51.181)
		(width 0.11684)
		(layer "F.Cu")
		(net "BMC_PWR_LED")
	)
	(segment
		(start 36.356798 -51.816)
		(end 35.11169 -51.816)
		(width 0.11684)
		(layer "F.Cu")
		(net "BMC_PWR_LED")
	)
	(via
		(at 47.699676 -53.366416)
		(size 0.4572)
		(drill 0.254)
		(layers "F.Cu" "B.Cu")
		(net "BMC_PWR_LED")
	)
	(via
		(at 36.510468 -51.66233)
		(size 0.508)
		(drill 0.254)
		(layers "F.Cu" "B.Cu")
		(net "BMC_PWR_LED")
	)
	(segment
		(start 37.66693 -51.66233)
		(end 38.03142 -51.29784)
		(width 0.08382)
		(layer "In2.Cu")
		(net "BMC_PWR_LED")
	)
	(segment
		(start 38.03142 -51.29784)
		(end 38.03142 -50.66538)
		(width 0.08382)
		(layer "In2.Cu")
		(net "BMC_PWR_LED")
	)
	(segment
		(start 44.5262 -47.879)
		(end 44.851066 -48.203866)
		(width 0.08382)
		(layer "In2.Cu")
		(net "BMC_PWR_LED")
	)
	(segment
		(start 41.53662 -49.149)
		(end 42.80662 -47.879)
		(width 0.08382)
		(layer "In2.Cu")
		(net "BMC_PWR_LED")
	)
	(segment
		(start 48.107092 -52.959)
		(end 47.699676 -53.366416)
		(width 0.08382)
		(layer "In2.Cu")
		(net "BMC_PWR_LED")
	)
	(segment
		(start 36.510468 -51.66233)
		(end 37.66693 -51.66233)
		(width 0.08382)
		(layer "In2.Cu")
		(net "BMC_PWR_LED")
	)
	(segment
		(start 38.03142 -50.66538)
		(end 38.6334 -50.0634)
		(width 0.08382)
		(layer "In2.Cu")
		(net "BMC_PWR_LED")
	)
	(segment
		(start 40.0304 -49.149)
		(end 41.53662 -49.149)
		(width 0.08382)
		(layer "In2.Cu")
		(net "BMC_PWR_LED")
	)
	(segment
		(start 44.851066 -48.203866)
		(end 46.324012 -48.203866)
		(width 0.08382)
		(layer "In2.Cu")
		(net "BMC_PWR_LED")
	)
	(segment
		(start 48.7172 -52.959)
		(end 48.107092 -52.959)
		(width 0.08382)
		(layer "In2.Cu")
		(net "BMC_PWR_LED")
	)
	(segment
		(start 46.768766 -48.9712)
		(end 47.9044 -48.9712)
		(width 0.08382)
		(layer "In2.Cu")
		(net "BMC_PWR_LED")
	)
	(segment
		(start 47.9044 -48.9712)
		(end 49.1744 -50.2412)
		(width 0.08382)
		(layer "In2.Cu")
		(net "BMC_PWR_LED")
	)
	(segment
		(start 42.80662 -47.879)
		(end 44.5262 -47.879)
		(width 0.08382)
		(layer "In2.Cu")
		(net "BMC_PWR_LED")
	)
	(segment
		(start 49.1744 -50.2412)
		(end 49.1744 -52.5018)
		(width 0.08382)
		(layer "In2.Cu")
		(net "BMC_PWR_LED")
	)
	(segment
		(start 46.52772 -48.730154)
		(end 46.768766 -48.9712)
		(width 0.08382)
		(layer "In2.Cu")
		(net "BMC_PWR_LED")
	)
	(segment
		(start 46.324012 -48.203866)
		(end 46.52772 -48.407574)
		(width 0.08382)
		(layer "In2.Cu")
		(net "BMC_PWR_LED")
	)
	(segment
		(start 46.52772 -48.407574)
		(end 46.52772 -48.730154)
		(width 0.08382)
		(layer "In2.Cu")
		(net "BMC_PWR_LED")
	)
	(segment
		(start 38.6334 -50.0634)
		(end 39.116 -50.0634)
		(width 0.08382)
		(layer "In2.Cu")
		(net "BMC_PWR_LED")
	)
	(segment
		(start 49.1744 -52.5018)
		(end 48.7172 -52.959)
		(width 0.08382)
		(layer "In2.Cu")
		(net "BMC_PWR_LED")
	)
	(segment
		(start 39.116 -50.0634)
		(end 40.0304 -49.149)
		(width 0.08382)
		(layer "In2.Cu")
		(net "BMC_PWR_LED")
	)
	(segment
		(start 13.32865 -92.8624)
		(end 13.32865 -92.456)
		(width 0.11684)
		(layer "F.Cu")
		(net "BMC_CPLD_GPIO_8_R2")
	)
	(segment
		(start 16.664178 -91.191842)
		(end 17.059402 -91.587066)
		(width 0.11684)
		(layer "F.Cu")
		(net "BMC_CPLD_GPIO_8_R2")
	)
	(segment
		(start 12.71905 -93.472)
		(end 13.32865 -92.8624)
		(width 0.11684)
		(layer "F.Cu")
		(net "BMC_CPLD_GPIO_8_R2")
	)
	(via
		(at 13.32865 -92.456)
		(size 0.508)
		(drill 0.254)
		(layers "F.Cu" "B.Cu")
		(net "BMC_CPLD_GPIO_8_R2")
	)
	(via
		(at 16.664178 -91.191842)
		(size 0.4572)
		(drill 0.254)
		(layers "F.Cu" "B.Cu")
		(net "BMC_CPLD_GPIO_8_R2")
	)
	(segment
		(start 14.592808 -91.191842)
		(end 13.32865 -92.456)
		(width 0.08382)
		(layer "In2.Cu")
		(net "BMC_CPLD_GPIO_8_R2")
	)
	(segment
		(start 16.664178 -91.191842)
		(end 14.592808 -91.191842)
		(width 0.08382)
		(layer "In2.Cu")
		(net "BMC_CPLD_GPIO_8_R2")
	)
	(segment
		(start 56.894984 -55.371238)
		(end 57.290208 -55.766462)
		(width 0.11684)
		(layer "F.Cu")
		(net "SPI_BMC_TPM_MISO_R1")
	)
	(via
		(at 57.290208 -55.766462)
		(size 0.4572)
		(drill 0.254)
		(layers "F.Cu" "B.Cu")
		(net "SPI_BMC_TPM_MISO_R1")
	)
	(via
		(at 61.64326 -64.8462)
		(size 0.508)
		(drill 0.254)
		(layers "F.Cu" "B.Cu")
		(net "SPI_BMC_TPM_MISO_R1")
	)
	(segment
		(start 61.64326 -65.4558)
		(end 61.64326 -64.8462)
		(width 0.11684)
		(layer "B.Cu")
		(net "SPI_BMC_TPM_MISO_R1")
	)
	(segment
		(start 61.64326 -64.8462)
		(end 60.381134 -63.810134)
		(width 0.08382)
		(layer "In9.Cu")
		(net "SPI_BMC_TPM_MISO_R1")
	)
	(segment
		(start 57.926986 -56.17464)
		(end 57.518808 -55.766462)
		(width 0.08382)
		(layer "In9.Cu")
		(net "SPI_BMC_TPM_MISO_R1")
	)
	(segment
		(start 58.30824 -56.17464)
		(end 57.926986 -56.17464)
		(width 0.08382)
		(layer "In9.Cu")
		(net "SPI_BMC_TPM_MISO_R1")
	)
	(segment
		(start 58.527696 -56.730138)
		(end 58.527696 -56.394096)
		(width 0.08382)
		(layer "In9.Cu")
		(net "SPI_BMC_TPM_MISO_R1")
	)
	(segment
		(start 59.2836 -57.15)
		(end 59.08167 -56.94807)
		(width 0.08382)
		(layer "In9.Cu")
		(net "SPI_BMC_TPM_MISO_R1")
	)
	(segment
		(start 58.745628 -56.94807)
		(end 58.527696 -56.730138)
		(width 0.08382)
		(layer "In9.Cu")
		(net "SPI_BMC_TPM_MISO_R1")
	)
	(segment
		(start 59.7408 -62.909704)
		(end 59.2836 -60.611258)
		(width 0.08382)
		(layer "In9.Cu")
		(net "SPI_BMC_TPM_MISO_R1")
	)
	(segment
		(start 59.924696 -63.353696)
		(end 59.7408 -62.909704)
		(width 0.08382)
		(layer "In9.Cu")
		(net "SPI_BMC_TPM_MISO_R1")
	)
	(segment
		(start 58.527696 -56.394096)
		(end 58.30824 -56.17464)
		(width 0.08382)
		(layer "In9.Cu")
		(net "SPI_BMC_TPM_MISO_R1")
	)
	(segment
		(start 60.381134 -63.810134)
		(end 59.924696 -63.353696)
		(width 0.08382)
		(layer "In9.Cu")
		(net "SPI_BMC_TPM_MISO_R1")
	)
	(segment
		(start 57.518808 -55.766462)
		(end 57.290208 -55.766462)
		(width 0.08382)
		(layer "In9.Cu")
		(net "SPI_BMC_TPM_MISO_R1")
	)
	(segment
		(start 59.08167 -56.94807)
		(end 58.745628 -56.94807)
		(width 0.08382)
		(layer "In9.Cu")
		(net "SPI_BMC_TPM_MISO_R1")
	)
	(segment
		(start 59.2836 -60.611258)
		(end 59.2836 -57.15)
		(width 0.08382)
		(layer "In9.Cu")
		(net "SPI_BMC_TPM_MISO_R1")
	)
	(segment
		(start 11.91895 -93.472)
		(end 11.91895 -92.456)
		(width 0.11684)
		(layer "F.Cu")
		(net "BMC_CPLD_GPIO_8")
	)
	(segment
		(start 12.71905 -89.147904)
		(end 14.762988 -91.191842)
		(width 0.11684)
		(layer "F.Cu")
		(net "BMC_CPLD_GPIO_7_R2")
	)
	(segment
		(start 12.71905 -88.392)
		(end 12.71905 -89.147904)
		(width 0.11684)
		(layer "F.Cu")
		(net "BMC_CPLD_GPIO_7_R2")
	)
	(segment
		(start 15.864332 -91.191842)
		(end 16.259556 -91.587066)
		(width 0.11684)
		(layer "F.Cu")
		(net "BMC_CPLD_GPIO_7_R2")
	)
	(segment
		(start 14.762988 -91.191842)
		(end 15.864332 -91.191842)
		(width 0.11684)
		(layer "F.Cu")
		(net "BMC_CPLD_GPIO_7_R2")
	)
	(segment
		(start 56.894984 -56.171338)
		(end 56.49976 -56.566562)
		(width 0.11684)
		(layer "F.Cu")
		(net "SPI_BMC_TPM_CLK_R1")
	)
	(segment
		(start 64.9732 -66.0146)
		(end 64.9478 -66.04)
		(width 0.11684)
		(layer "F.Cu")
		(net "SPI_BMC_TPM_CLK_R1")
	)
	(segment
		(start 65.61455 -66.0146)
		(end 64.9732 -66.0146)
		(width 0.11684)
		(layer "F.Cu")
		(net "SPI_BMC_TPM_CLK_R1")
	)
	(via
		(at 56.49976 -56.566562)
		(size 0.4572)
		(drill 0.254)
		(layers "F.Cu" "B.Cu")
		(net "SPI_BMC_TPM_CLK_R1")
	)
	(via
		(at 64.9478 -66.04)
		(size 0.508)
		(drill 0.254)
		(layers "F.Cu" "B.Cu")
		(net "SPI_BMC_TPM_CLK_R1")
	)
	(segment
		(start 63.509652 -65.567052)
		(end 63.928752 -65.986152)
		(width 0.08382)
		(layer "In2.Cu")
		(net "SPI_BMC_TPM_CLK_R1")
	)
	(segment
		(start 58.518044 -57.959244)
		(end 58.518044 -58.320686)
		(width 0.08382)
		(layer "In2.Cu")
		(net "SPI_BMC_TPM_CLK_R1")
	)
	(segment
		(start 64.181482 -66.0908)
		(end 64.5668 -66.0908)
		(width 0.08382)
		(layer "In2.Cu")
		(net "SPI_BMC_TPM_CLK_R1")
	)
	(segment
		(start 56.879998 -56.9468)
		(end 57.4548 -56.9468)
		(width 0.08382)
		(layer "In2.Cu")
		(net "SPI_BMC_TPM_CLK_R1")
	)
	(segment
		(start 59.3598 -58.801)
		(end 59.3598 -59.204606)
		(width 0.08382)
		(layer "In2.Cu")
		(net "SPI_BMC_TPM_CLK_R1")
	)
	(segment
		(start 58.353198 -57.794398)
		(end 58.518044 -57.959244)
		(width 0.08382)
		(layer "In2.Cu")
		(net "SPI_BMC_TPM_CLK_R1")
	)
	(segment
		(start 64.5668 -66.0908)
		(end 64.6176 -66.04)
		(width 0.08382)
		(layer "In2.Cu")
		(net "SPI_BMC_TPM_CLK_R1")
	)
	(segment
		(start 57.727596 -57.600596)
		(end 57.921398 -57.794398)
		(width 0.08382)
		(layer "In2.Cu")
		(net "SPI_BMC_TPM_CLK_R1")
	)
	(segment
		(start 61.09716 -62.627764)
		(end 63.509652 -65.567052)
		(width 0.08382)
		(layer "In2.Cu")
		(net "SPI_BMC_TPM_CLK_R1")
	)
	(segment
		(start 57.921398 -57.794398)
		(end 58.353198 -57.794398)
		(width 0.08382)
		(layer "In2.Cu")
		(net "SPI_BMC_TPM_CLK_R1")
	)
	(segment
		(start 56.49976 -56.566562)
		(end 56.879998 -56.9468)
		(width 0.08382)
		(layer "In2.Cu")
		(net "SPI_BMC_TPM_CLK_R1")
	)
	(segment
		(start 59.097418 -58.538618)
		(end 59.3598 -58.801)
		(width 0.08382)
		(layer "In2.Cu")
		(net "SPI_BMC_TPM_CLK_R1")
	)
	(segment
		(start 57.4548 -56.9468)
		(end 57.727596 -57.219596)
		(width 0.08382)
		(layer "In2.Cu")
		(net "SPI_BMC_TPM_CLK_R1")
	)
	(segment
		(start 63.928752 -65.986152)
		(end 64.181482 -66.0908)
		(width 0.08382)
		(layer "In2.Cu")
		(net "SPI_BMC_TPM_CLK_R1")
	)
	(segment
		(start 59.3598 -59.204606)
		(end 60.256928 -61.370718)
		(width 0.08382)
		(layer "In2.Cu")
		(net "SPI_BMC_TPM_CLK_R1")
	)
	(segment
		(start 57.727596 -57.219596)
		(end 57.727596 -57.600596)
		(width 0.08382)
		(layer "In2.Cu")
		(net "SPI_BMC_TPM_CLK_R1")
	)
	(segment
		(start 60.256928 -61.370718)
		(end 61.09716 -62.627764)
		(width 0.08382)
		(layer "In2.Cu")
		(net "SPI_BMC_TPM_CLK_R1")
	)
	(segment
		(start 58.518044 -58.320686)
		(end 58.735976 -58.538618)
		(width 0.08382)
		(layer "In2.Cu")
		(net "SPI_BMC_TPM_CLK_R1")
	)
	(segment
		(start 64.6176 -66.04)
		(end 64.9478 -66.04)
		(width 0.08382)
		(layer "In2.Cu")
		(net "SPI_BMC_TPM_CLK_R1")
	)
	(segment
		(start 58.735976 -58.538618)
		(end 59.097418 -58.538618)
		(width 0.08382)
		(layer "In2.Cu")
		(net "SPI_BMC_TPM_CLK_R1")
	)
	(segment
		(start 12.065 -89.38895)
		(end 12.065 -88.53805)
		(width 0.11684)
		(layer "F.Cu")
		(net "BMC_CPLD_GPIO_7")
	)
	(segment
		(start 12.065 -88.53805)
		(end 11.91895 -88.392)
		(width 0.11684)
		(layer "F.Cu")
		(net "BMC_CPLD_GPIO_7")
	)
	(segment
		(start 47.5996 -64.9478)
		(end 47.4472 -65.1002)
		(width 0.11684)
		(layer "F.Cu")
		(net "BMC_ID_BEEP_SEL_R1")
	)
	(segment
		(start 47.4472 -65.379346)
		(end 47.6377 -65.569846)
		(width 0.11684)
		(layer "F.Cu")
		(net "BMC_ID_BEEP_SEL_R1")
	)
	(segment
		(start 54.494938 -57.771284)
		(end 54.099714 -58.166508)
		(width 0.11684)
		(layer "F.Cu")
		(net "BMC_ID_BEEP_SEL_R1")
	)
	(segment
		(start 47.4472 -65.1002)
		(end 47.4472 -65.379346)
		(width 0.11684)
		(layer "F.Cu")
		(net "BMC_ID_BEEP_SEL_R1")
	)
	(segment
		(start 47.6377 -65.569846)
		(end 47.6377 -65.95491)
		(width 0.11684)
		(layer "F.Cu")
		(net "BMC_ID_BEEP_SEL_R1")
	)
	(via
		(at 54.099714 -58.166508)
		(size 0.4572)
		(drill 0.254)
		(layers "F.Cu" "B.Cu")
		(net "BMC_ID_BEEP_SEL_R1")
	)
	(via
		(at 47.5996 -64.9478)
		(size 0.508)
		(drill 0.254)
		(layers "F.Cu" "B.Cu")
		(net "BMC_ID_BEEP_SEL_R1")
	)
	(segment
		(start 47.5996 -64.9478)
		(end 47.4472 -64.7954)
		(width 0.08382)
		(layer "In9.Cu")
		(net "BMC_ID_BEEP_SEL_R1")
	)
	(segment
		(start 53.71846 -58.547762)
		(end 54.099714 -58.166508)
		(width 0.08382)
		(layer "In9.Cu")
		(net "BMC_ID_BEEP_SEL_R1")
	)
	(segment
		(start 49.303178 -62.718696)
		(end 51.987704 -61.606684)
		(width 0.08382)
		(layer "In9.Cu")
		(net "BMC_ID_BEEP_SEL_R1")
	)
	(segment
		(start 47.4472 -64.574674)
		(end 49.303178 -62.718696)
		(width 0.08382)
		(layer "In9.Cu")
		(net "BMC_ID_BEEP_SEL_R1")
	)
	(segment
		(start 47.4472 -64.7954)
		(end 47.4472 -64.574674)
		(width 0.08382)
		(layer "In9.Cu")
		(net "BMC_ID_BEEP_SEL_R1")
	)
	(segment
		(start 53.71846 -59.875928)
		(end 53.71846 -58.547762)
		(width 0.08382)
		(layer "In9.Cu")
		(net "BMC_ID_BEEP_SEL_R1")
	)
	(segment
		(start 51.987704 -61.606684)
		(end 53.71846 -59.875928)
		(width 0.08382)
		(layer "In9.Cu")
		(net "BMC_ID_BEEP_SEL_R1")
	)
	(segment
		(start 69.4055 -68.7197)
		(end 69.0372 -68.3514)
		(width 0.11684)
		(layer "F.Cu")
		(net "SPI_BMC_TPM_CS2_R1_N")
	)
	(segment
		(start 57.695084 -56.971184)
		(end 57.29986 -57.366408)
		(width 0.11684)
		(layer "F.Cu")
		(net "SPI_BMC_TPM_CS2_R1_N")
	)
	(segment
		(start 68.1228 -68.3514)
		(end 68.0212 -68.2498)
		(width 0.11684)
		(layer "F.Cu")
		(net "SPI_BMC_TPM_CS2_R1_N")
	)
	(segment
		(start 69.0372 -68.3514)
		(end 68.1228 -68.3514)
		(width 0.11684)
		(layer "F.Cu")
		(net "SPI_BMC_TPM_CS2_R1_N")
	)
	(segment
		(start 69.4055 -69.19595)
		(end 69.4055 -68.7197)
		(width 0.11684)
		(layer "F.Cu")
		(net "SPI_BMC_TPM_CS2_R1_N")
	)
	(segment
		(start 68.0212 -68.2498)
		(end 67.7164 -68.2498)
		(width 0.11684)
		(layer "F.Cu")
		(net "SPI_BMC_TPM_CS2_R1_N")
	)
	(via
		(at 57.29986 -57.366408)
		(size 0.4572)
		(drill 0.254)
		(layers "F.Cu" "B.Cu")
		(net "SPI_BMC_TPM_CS2_R1_N")
	)
	(via
		(at 57.716928 -68.716906)
		(size 0.508)
		(drill 0.254)
		(layers "F.Cu" "B.Cu")
		(net "SPI_BMC_TPM_CS2_R1_N")
	)
	(via
		(at 67.7164 -68.2498)
		(size 0.508)
		(drill 0.254)
		(layers "F.Cu" "B.Cu")
		(net "SPI_BMC_TPM_CS2_R1_N")
	)
	(segment
		(start 63.169546 -67.2592)
		(end 64.48171 -67.2592)
		(width 0.08382)
		(layer "In2.Cu")
		(net "SPI_BMC_TPM_CS2_R1_N")
	)
	(segment
		(start 61.739526 -69.7738)
		(end 62.2554 -69.257926)
		(width 0.08382)
		(layer "In2.Cu")
		(net "SPI_BMC_TPM_CS2_R1_N")
	)
	(segment
		(start 65.69075 -68.46824)
		(end 67.49796 -68.46824)
		(width 0.08382)
		(layer "In2.Cu")
		(net "SPI_BMC_TPM_CS2_R1_N")
	)
	(segment
		(start 57.716928 -68.716906)
		(end 58.773822 -69.7738)
		(width 0.08382)
		(layer "In2.Cu")
		(net "SPI_BMC_TPM_CS2_R1_N")
	)
	(segment
		(start 67.49796 -68.46824)
		(end 67.7164 -68.2498)
		(width 0.08382)
		(layer "In2.Cu")
		(net "SPI_BMC_TPM_CS2_R1_N")
	)
	(segment
		(start 58.773822 -69.7738)
		(end 61.739526 -69.7738)
		(width 0.08382)
		(layer "In2.Cu")
		(net "SPI_BMC_TPM_CS2_R1_N")
	)
	(segment
		(start 62.2554 -69.257926)
		(end 62.2554 -68.173346)
		(width 0.08382)
		(layer "In2.Cu")
		(net "SPI_BMC_TPM_CS2_R1_N")
	)
	(segment
		(start 62.2554 -68.173346)
		(end 63.169546 -67.2592)
		(width 0.08382)
		(layer "In2.Cu")
		(net "SPI_BMC_TPM_CS2_R1_N")
	)
	(segment
		(start 64.48171 -67.2592)
		(end 65.69075 -68.46824)
		(width 0.08382)
		(layer "In2.Cu")
		(net "SPI_BMC_TPM_CS2_R1_N")
	)
	(segment
		(start 57.97296 -67.461638)
		(end 57.856882 -67.34556)
		(width 0.10668)
		(layer "In4.Cu")
		(net "SPI_BMC_TPM_CS2_R1_N")
	)
	(segment
		(start 57.97296 -68.460874)
		(end 57.97296 -67.461638)
		(width 0.10668)
		(layer "In4.Cu")
		(net "SPI_BMC_TPM_CS2_R1_N")
	)
	(segment
		(start 57.856882 -66.16192)
		(end 58.809636 -65.209166)
		(width 0.10668)
		(layer "In4.Cu")
		(net "SPI_BMC_TPM_CS2_R1_N")
	)
	(segment
		(start 58.809636 -65.209166)
		(end 58.87974 -65.040002)
		(width 0.10668)
		(layer "In4.Cu")
		(net "SPI_BMC_TPM_CS2_R1_N")
	)
	(segment
		(start 56.896 -60.110624)
		(end 56.896 -57.770268)
		(width 0.10668)
		(layer "In4.Cu")
		(net "SPI_BMC_TPM_CS2_R1_N")
	)
	(segment
		(start 57.716928 -68.716906)
		(end 57.97296 -68.460874)
		(width 0.10668)
		(layer "In4.Cu")
		(net "SPI_BMC_TPM_CS2_R1_N")
	)
	(segment
		(start 57.856882 -67.34556)
		(end 57.856882 -66.16192)
		(width 0.10668)
		(layer "In4.Cu")
		(net "SPI_BMC_TPM_CS2_R1_N")
	)
	(segment
		(start 57.7596 -63.474346)
		(end 57.7596 -60.974224)
		(width 0.10668)
		(layer "In4.Cu")
		(net "SPI_BMC_TPM_CS2_R1_N")
	)
	(segment
		(start 56.896 -57.770268)
		(end 57.29986 -57.366408)
		(width 0.10668)
		(layer "In4.Cu")
		(net "SPI_BMC_TPM_CS2_R1_N")
	)
	(segment
		(start 57.7596 -60.974224)
		(end 56.896 -60.110624)
		(width 0.10668)
		(layer "In4.Cu")
		(net "SPI_BMC_TPM_CS2_R1_N")
	)
	(segment
		(start 58.87974 -65.040002)
		(end 58.87974 -64.594486)
		(width 0.10668)
		(layer "In4.Cu")
		(net "SPI_BMC_TPM_CS2_R1_N")
	)
	(segment
		(start 58.87974 -64.594486)
		(end 57.7596 -63.474346)
		(width 0.10668)
		(layer "In4.Cu")
		(net "SPI_BMC_TPM_CS2_R1_N")
	)
	(segment
		(start 56.894984 -57.771284)
		(end 57.290208 -58.166508)
		(width 0.11684)
		(layer "F.Cu")
		(net "FM_DEBUG_PORT_PRSNT_R1_N")
	)
	(via
		(at 57.86628 -59.4106)
		(size 0.6604)
		(drill 0.3302)
		(layers "F.Cu" "B.Cu")
		(net "FM_DEBUG_PORT_PRSNT_R1_N")
	)
	(via
		(at 57.290208 -58.166508)
		(size 0.4572)
		(drill 0.254)
		(layers "F.Cu" "B.Cu")
		(net "FM_DEBUG_PORT_PRSNT_R1_N")
	)
	(segment
		(start 57.86628 -58.74258)
		(end 57.290208 -58.166508)
		(width 0.11684)
		(layer "B.Cu")
		(net "FM_DEBUG_PORT_PRSNT_R1_N")
	)
	(segment
		(start 58.235596 -62.83325)
		(end 58.0644 -62.662054)
		(width 0.11684)
		(layer "B.Cu")
		(net "FM_DEBUG_PORT_PRSNT_R1_N")
	)
	(segment
		(start 57.86628 -59.4106)
		(end 57.86628 -58.74258)
		(width 0.11684)
		(layer "B.Cu")
		(net "FM_DEBUG_PORT_PRSNT_R1_N")
	)
	(segment
		(start 58.0644 -61.645546)
		(end 57.86628 -61.447426)
		(width 0.11684)
		(layer "B.Cu")
		(net "FM_DEBUG_PORT_PRSNT_R1_N")
	)
	(segment
		(start 58.0644 -62.662054)
		(end 58.0644 -61.645546)
		(width 0.11684)
		(layer "B.Cu")
		(net "FM_DEBUG_PORT_PRSNT_R1_N")
	)
	(segment
		(start 57.86628 -61.447426)
		(end 57.86628 -59.4106)
		(width 0.11684)
		(layer "B.Cu")
		(net "FM_DEBUG_PORT_PRSNT_R1_N")
	)
	(segment
		(start 58.7375 -62.83325)
		(end 58.235596 -62.83325)
		(width 0.11684)
		(layer "B.Cu")
		(net "FM_DEBUG_PORT_PRSNT_R1_N")
	)
	(segment
		(start 24.654256 -99.181666)
		(end 24.25954 -98.78695)
		(width 0.11684)
		(layer "F.Cu")
		(net "FM_DEBUG_PORT_R2_PRSNT_N")
	)
	(segment
		(start 24.654256 -101.183694)
		(end 24.654256 -99.181666)
		(width 0.11684)
		(layer "F.Cu")
		(net "FM_DEBUG_PORT_R2_PRSNT_N")
	)
	(segment
		(start 23.495 -102.34295)
		(end 24.654256 -101.183694)
		(width 0.11684)
		(layer "F.Cu")
		(net "FM_DEBUG_PORT_R2_PRSNT_N")
	)
	(segment
		(start 27.559 -102.040944)
		(end 26.254456 -100.7364)
		(width 0.11684)
		(layer "F.Cu")
		(net "PWRGD_DSW_PWROK_R2")
	)
	(segment
		(start 27.559 -102.34295)
		(end 27.559 -102.040944)
		(width 0.11684)
		(layer "F.Cu")
		(net "PWRGD_DSW_PWROK_R2")
	)
	(segment
		(start 26.254456 -100.7364)
		(end 26.254456 -99.18192)
		(width 0.11684)
		(layer "F.Cu")
		(net "PWRGD_DSW_PWROK_R2")
	)
	(segment
		(start 26.254456 -99.18192)
		(end 25.859486 -98.78695)
		(width 0.11684)
		(layer "F.Cu")
		(net "PWRGD_DSW_PWROK_R2")
	)
	(segment
		(start 64.170306 -63.356998)
		(end 64.170306 -62.96279)
		(width 0.11684)
		(layer "F.Cu")
		(net "PWRGD_DSW_PWROK_R1")
	)
	(segment
		(start 65.056512 -63.526416)
		(end 64.339724 -63.526416)
		(width 0.11684)
		(layer "F.Cu")
		(net "PWRGD_DSW_PWROK_R1")
	)
	(segment
		(start 64.339724 -63.526416)
		(end 64.170306 -63.356998)
		(width 0.11684)
		(layer "F.Cu")
		(net "PWRGD_DSW_PWROK_R1")
	)
	(segment
		(start 58.49493 -55.371238)
		(end 58.099706 -54.976014)
		(width 0.11684)
		(layer "F.Cu")
		(net "PWRGD_DSW_PWROK_R1")
	)
	(via
		(at 64.170306 -62.96279)
		(size 0.508)
		(drill 0.254)
		(layers "F.Cu" "B.Cu")
		(net "PWRGD_DSW_PWROK_R1")
	)
	(via
		(at 58.099706 -54.976014)
		(size 0.4572)
		(drill 0.254)
		(layers "F.Cu" "B.Cu")
		(net "PWRGD_DSW_PWROK_R1")
	)
	(segment
		(start 57.912 -56.9722)
		(end 57.7088 -56.769)
		(width 0.08382)
		(layer "In2.Cu")
		(net "PWRGD_DSW_PWROK_R1")
	)
	(segment
		(start 60.44946 -61.239146)
		(end 59.77636 -59.613546)
		(width 0.08382)
		(layer "In2.Cu")
		(net "PWRGD_DSW_PWROK_R1")
	)
	(segment
		(start 57.7088 -56.769)
		(end 57.7088 -55.36692)
		(width 0.08382)
		(layer "In2.Cu")
		(net "PWRGD_DSW_PWROK_R1")
	)
	(segment
		(start 58.504328 -57.234328)
		(end 58.2422 -56.9722)
		(width 0.08382)
		(layer "In2.Cu")
		(net "PWRGD_DSW_PWROK_R1")
	)
	(segment
		(start 58.2422 -56.9722)
		(end 57.912 -56.9722)
		(width 0.08382)
		(layer "In2.Cu")
		(net "PWRGD_DSW_PWROK_R1")
	)
	(segment
		(start 59.266582 -58.276236)
		(end 59.266582 -58.01487)
		(width 0.08382)
		(layer "In2.Cu")
		(net "PWRGD_DSW_PWROK_R1")
	)
	(segment
		(start 59.031124 -57.779412)
		(end 58.775092 -57.779412)
		(width 0.08382)
		(layer "In2.Cu")
		(net "PWRGD_DSW_PWROK_R1")
	)
	(segment
		(start 57.7088 -55.36692)
		(end 58.099706 -54.976014)
		(width 0.08382)
		(layer "In2.Cu")
		(net "PWRGD_DSW_PWROK_R1")
	)
	(segment
		(start 58.504328 -57.508648)
		(end 58.504328 -57.234328)
		(width 0.08382)
		(layer "In2.Cu")
		(net "PWRGD_DSW_PWROK_R1")
	)
	(segment
		(start 64.170306 -62.96279)
		(end 63.69939 -62.96279)
		(width 0.08382)
		(layer "In2.Cu")
		(net "PWRGD_DSW_PWROK_R1")
	)
	(segment
		(start 59.266582 -58.01487)
		(end 59.031124 -57.779412)
		(width 0.08382)
		(layer "In2.Cu")
		(net "PWRGD_DSW_PWROK_R1")
	)
	(segment
		(start 59.77636 -58.786014)
		(end 59.266582 -58.276236)
		(width 0.08382)
		(layer "In2.Cu")
		(net "PWRGD_DSW_PWROK_R1")
	)
	(segment
		(start 58.775092 -57.779412)
		(end 58.504328 -57.508648)
		(width 0.08382)
		(layer "In2.Cu")
		(net "PWRGD_DSW_PWROK_R1")
	)
	(segment
		(start 63.054738 -62.318138)
		(end 60.44946 -61.239146)
		(width 0.08382)
		(layer "In2.Cu")
		(net "PWRGD_DSW_PWROK_R1")
	)
	(segment
		(start 59.77636 -59.613546)
		(end 59.77636 -58.786014)
		(width 0.08382)
		(layer "In2.Cu")
		(net "PWRGD_DSW_PWROK_R1")
	)
	(segment
		(start 63.69939 -62.96279)
		(end 63.054738 -62.318138)
		(width 0.08382)
		(layer "In2.Cu")
		(net "PWRGD_DSW_PWROK_R1")
	)
	(segment
		(start 21.463 -103.14305)
		(end 21.463 -104.00284)
		(width 0.11684)
		(layer "F.Cu")
		(net "FM_BMC_CRASHLOG_TRIG_N")
	)
	(segment
		(start 21.463 -104.00284)
		(end 21.539454 -104.07904)
		(width 0.11684)
		(layer "F.Cu")
		(net "FM_BMC_CRASHLOG_TRIG_N")
	)
	(via
		(at 21.539454 -104.07904)
		(size 0.508)
		(drill 0.254)
		(layers "F.Cu" "B.Cu")
		(net "FM_BMC_CRASHLOG_TRIG_N")
	)
	(via
		(at 29.1338 -88.519)
		(size 0.508)
		(drill 0.254)
		(layers "F.Cu" "B.Cu")
		(net "FM_BMC_CRASHLOG_TRIG_N")
	)
	(via
		(at 28.4988 -59.56808)
		(size 0.508)
		(drill 0.254)
		(layers "F.Cu" "B.Cu")
		(net "FM_BMC_CRASHLOG_TRIG_N")
	)
	(via
		(at 37.487098 -30.432502)
		(size 0.6604)
		(drill 0.3302)
		(layers "F.Cu" "B.Cu")
		(net "FM_BMC_CRASHLOG_TRIG_N")
	)
	(via
		(at 24.34463 -107.88777)
		(size 0.508)
		(drill 0.254)
		(layers "F.Cu" "B.Cu")
		(net "FM_BMC_CRASHLOG_TRIG_N")
	)
	(via
		(at 34.1122 -105.769156)
		(size 0.508)
		(drill 0.254)
		(layers "F.Cu" "B.Cu")
		(net "FM_BMC_CRASHLOG_TRIG_N")
	)
	(via
		(at 37.4904 -29.718)
		(size 0.508)
		(drill 0.254)
		(layers "F.Cu" "B.Cu")
		(net "FM_BMC_CRASHLOG_TRIG_N")
	)
	(segment
		(start 37.798502 -30.432502)
		(end 38.484048 -31.118048)
		(width 0.11684)
		(layer "B.Cu")
		(net "FM_BMC_CRASHLOG_TRIG_N")
	)
	(segment
		(start 20.955 -102.997)
		(end 20.955 -102.38105)
		(width 0.11684)
		(layer "B.Cu")
		(net "FM_BMC_CRASHLOG_TRIG_N")
	)
	(segment
		(start 37.487098 -30.432502)
		(end 37.798502 -30.432502)
		(width 0.11684)
		(layer "B.Cu")
		(net "FM_BMC_CRASHLOG_TRIG_N")
	)
	(segment
		(start 40.79875 -37.316664)
		(end 40.79875 -37.338)
		(width 0.11684)
		(layer "B.Cu")
		(net "FM_BMC_CRASHLOG_TRIG_N")
	)
	(segment
		(start 37.4904 -29.718)
		(end 37.487098 -29.721302)
		(width 0.11684)
		(layer "B.Cu")
		(net "FM_BMC_CRASHLOG_TRIG_N")
	)
	(segment
		(start 21.539454 -104.07904)
		(end 21.463 -104.002586)
		(width 0.11684)
		(layer "B.Cu")
		(net "FM_BMC_CRASHLOG_TRIG_N")
	)
	(segment
		(start 21.463 -104.002586)
		(end 21.463 -103.505)
		(width 0.11684)
		(layer "B.Cu")
		(net "FM_BMC_CRASHLOG_TRIG_N")
	)
	(segment
		(start 39.941246 -35.082734)
		(end 39.941246 -36.45916)
		(width 0.11684)
		(layer "B.Cu")
		(net "FM_BMC_CRASHLOG_TRIG_N")
	)
	(segment
		(start 21.463 -103.505)
		(end 20.955 -102.997)
		(width 0.11684)
		(layer "B.Cu")
		(net "FM_BMC_CRASHLOG_TRIG_N")
	)
	(segment
		(start 37.487098 -29.721302)
		(end 37.487098 -30.432502)
		(width 0.11684)
		(layer "B.Cu")
		(net "FM_BMC_CRASHLOG_TRIG_N")
	)
	(segment
		(start 38.484048 -33.321752)
		(end 39.453058 -34.290762)
		(width 0.11684)
		(layer "B.Cu")
		(net "FM_BMC_CRASHLOG_TRIG_N")
	)
	(segment
		(start 39.941246 -36.45916)
		(end 40.79875 -37.316664)
		(width 0.11684)
		(layer "B.Cu")
		(net "FM_BMC_CRASHLOG_TRIG_N")
	)
	(segment
		(start 39.453058 -34.290762)
		(end 39.667942 -34.80943)
		(width 0.11684)
		(layer "B.Cu")
		(net "FM_BMC_CRASHLOG_TRIG_N")
	)
	(segment
		(start 39.667942 -34.80943)
		(end 39.941246 -35.082734)
		(width 0.11684)
		(layer "B.Cu")
		(net "FM_BMC_CRASHLOG_TRIG_N")
	)
	(segment
		(start 38.484048 -31.118048)
		(end 38.484048 -33.321752)
		(width 0.11684)
		(layer "B.Cu")
		(net "FM_BMC_CRASHLOG_TRIG_N")
	)
	(segment
		(start 24.34463 -108.31703)
		(end 24.34463 -107.88777)
		(width 0.08382)
		(layer "In2.Cu")
		(net "FM_BMC_CRASHLOG_TRIG_N")
	)
	(segment
		(start 30.46349 -107.511342)
		(end 30.46349 -108.16971)
		(width 0.08382)
		(layer "In2.Cu")
		(net "FM_BMC_CRASHLOG_TRIG_N")
	)
	(segment
		(start 34.1122 -105.769156)
		(end 33.95218 -105.769156)
		(width 0.08382)
		(layer "In2.Cu")
		(net "FM_BMC_CRASHLOG_TRIG_N")
	)
	(segment
		(start 32.482536 -107.2388)
		(end 30.736032 -107.2388)
		(width 0.08382)
		(layer "In2.Cu")
		(net "FM_BMC_CRASHLOG_TRIG_N")
	)
	(segment
		(start 30.46349 -108.16971)
		(end 28.8798 -109.7534)
		(width 0.08382)
		(layer "In2.Cu")
		(net "FM_BMC_CRASHLOG_TRIG_N")
	)
	(segment
		(start 30.736032 -107.2388)
		(end 30.46349 -107.511342)
		(width 0.08382)
		(layer "In2.Cu")
		(net "FM_BMC_CRASHLOG_TRIG_N")
	)
	(segment
		(start 33.95218 -105.769156)
		(end 32.482536 -107.2388)
		(width 0.08382)
		(layer "In2.Cu")
		(net "FM_BMC_CRASHLOG_TRIG_N")
	)
	(segment
		(start 25.781 -109.7534)
		(end 24.34463 -108.31703)
		(width 0.08382)
		(layer "In2.Cu")
		(net "FM_BMC_CRASHLOG_TRIG_N")
	)
	(segment
		(start 28.8798 -109.7534)
		(end 25.781 -109.7534)
		(width 0.08382)
		(layer "In2.Cu")
		(net "FM_BMC_CRASHLOG_TRIG_N")
	)
	(segment
		(start 29.35224 -65.57264)
		(end 29.35224 -66.993008)
		(width 0.10668)
		(layer "In4.Cu")
		(net "FM_BMC_CRASHLOG_TRIG_N")
	)
	(segment
		(start 23.5712 -106.6546)
		(end 22.7076 -106.6546)
		(width 0.10668)
		(layer "In4.Cu")
		(net "FM_BMC_CRASHLOG_TRIG_N")
	)
	(segment
		(start 28.03144 -63.117476)
		(end 28.774136 -63.860172)
		(width 0.10668)
		(layer "In4.Cu")
		(net "FM_BMC_CRASHLOG_TRIG_N")
	)
	(segment
		(start 21.539454 -105.486454)
		(end 21.539454 -104.07904)
		(width 0.10668)
		(layer "In4.Cu")
		(net "FM_BMC_CRASHLOG_TRIG_N")
	)
	(segment
		(start 28.774136 -64.994536)
		(end 29.35224 -65.57264)
		(width 0.10668)
		(layer "In4.Cu")
		(net "FM_BMC_CRASHLOG_TRIG_N")
	)
	(segment
		(start 28.956 -67.697858)
		(end 28.956 -68.930266)
		(width 0.10668)
		(layer "In4.Cu")
		(net "FM_BMC_CRASHLOG_TRIG_N")
	)
	(segment
		(start 29.491686 -76.671932)
		(end 28.64866 -77.514958)
		(width 0.10668)
		(layer "In4.Cu")
		(net "FM_BMC_CRASHLOG_TRIG_N")
	)
	(segment
		(start 29.491686 -73.257918)
		(end 29.491686 -76.671932)
		(width 0.10668)
		(layer "In4.Cu")
		(net "FM_BMC_CRASHLOG_TRIG_N")
	)
	(segment
		(start 22.7076 -106.6546)
		(end 21.539454 -105.486454)
		(width 0.10668)
		(layer "In4.Cu")
		(net "FM_BMC_CRASHLOG_TRIG_N")
	)
	(segment
		(start 29.141166 -72.352154)
		(end 29.141166 -72.907398)
		(width 0.10668)
		(layer "In4.Cu")
		(net "FM_BMC_CRASHLOG_TRIG_N")
	)
	(segment
		(start 29.35224 -66.993008)
		(end 29.174186 -67.171062)
		(width 0.10668)
		(layer "In4.Cu")
		(net "FM_BMC_CRASHLOG_TRIG_N")
	)
	(segment
		(start 29.14142 -71.305166)
		(end 29.14142 -72.3519)
		(width 0.10668)
		(layer "In4.Cu")
		(net "FM_BMC_CRASHLOG_TRIG_N")
	)
	(segment
		(start 29.174186 -67.171062)
		(end 28.956 -67.697858)
		(width 0.10668)
		(layer "In4.Cu")
		(net "FM_BMC_CRASHLOG_TRIG_N")
	)
	(segment
		(start 24.34463 -107.88777)
		(end 24.34463 -107.42803)
		(width 0.10668)
		(layer "In4.Cu")
		(net "FM_BMC_CRASHLOG_TRIG_N")
	)
	(segment
		(start 28.4988 -59.56808)
		(end 28.03144 -60.03544)
		(width 0.10668)
		(layer "In4.Cu")
		(net "FM_BMC_CRASHLOG_TRIG_N")
	)
	(segment
		(start 29.14142 -72.3519)
		(end 29.141166 -72.352154)
		(width 0.10668)
		(layer "In4.Cu")
		(net "FM_BMC_CRASHLOG_TRIG_N")
	)
	(segment
		(start 28.64866 -77.514958)
		(end 28.64866 -87.39886)
		(width 0.10668)
		(layer "In4.Cu")
		(net "FM_BMC_CRASHLOG_TRIG_N")
	)
	(segment
		(start 28.64866 -87.39886)
		(end 29.1338 -87.884)
		(width 0.10668)
		(layer "In4.Cu")
		(net "FM_BMC_CRASHLOG_TRIG_N")
	)
	(segment
		(start 28.75026 -69.427852)
		(end 28.75026 -70.914006)
		(width 0.10668)
		(layer "In4.Cu")
		(net "FM_BMC_CRASHLOG_TRIG_N")
	)
	(segment
		(start 24.34463 -107.42803)
		(end 23.5712 -106.6546)
		(width 0.10668)
		(layer "In4.Cu")
		(net "FM_BMC_CRASHLOG_TRIG_N")
	)
	(segment
		(start 28.956 -68.930266)
		(end 28.75026 -69.427852)
		(width 0.10668)
		(layer "In4.Cu")
		(net "FM_BMC_CRASHLOG_TRIG_N")
	)
	(segment
		(start 29.141166 -72.907398)
		(end 29.491686 -73.257918)
		(width 0.10668)
		(layer "In4.Cu")
		(net "FM_BMC_CRASHLOG_TRIG_N")
	)
	(segment
		(start 28.774136 -63.860172)
		(end 28.774136 -64.994536)
		(width 0.10668)
		(layer "In4.Cu")
		(net "FM_BMC_CRASHLOG_TRIG_N")
	)
	(segment
		(start 28.75026 -70.914006)
		(end 29.14142 -71.305166)
		(width 0.10668)
		(layer "In4.Cu")
		(net "FM_BMC_CRASHLOG_TRIG_N")
	)
	(segment
		(start 28.03144 -60.03544)
		(end 28.03144 -63.117476)
		(width 0.10668)
		(layer "In4.Cu")
		(net "FM_BMC_CRASHLOG_TRIG_N")
	)
	(segment
		(start 29.1338 -87.884)
		(end 29.1338 -88.519)
		(width 0.10668)
		(layer "In4.Cu")
		(net "FM_BMC_CRASHLOG_TRIG_N")
	)
	(segment
		(start 29.84754 -89.23274)
		(end 29.84754 -91.81338)
		(width 0.10668)
		(layer "In7.Cu")
		(net "FM_BMC_CRASHLOG_TRIG_N")
	)
	(segment
		(start 32.702754 -96.605852)
		(end 32.88538 -97.046796)
		(width 0.10668)
		(layer "In7.Cu")
		(net "FM_BMC_CRASHLOG_TRIG_N")
	)
	(segment
		(start 35.7124 -35.526218)
		(end 35.7124 -34.5694)
		(width 0.10668)
		(layer "In7.Cu")
		(net "FM_BMC_CRASHLOG_TRIG_N")
	)
	(segment
		(start 37.760402 -30.168088)
		(end 37.760402 -29.988002)
		(width 0.10668)
		(layer "In7.Cu")
		(net "FM_BMC_CRASHLOG_TRIG_N")
	)
	(segment
		(start 31.99638 -95.899478)
		(end 32.702754 -96.605852)
		(width 0.10668)
		(layer "In7.Cu")
		(net "FM_BMC_CRASHLOG_TRIG_N")
	)
	(segment
		(start 34.4043 -99.002342)
		(end 34.4043 -100.135182)
		(width 0.10668)
		(layer "In7.Cu")
		(net "FM_BMC_CRASHLOG_TRIG_N")
	)
	(segment
		(start 34.4043 -100.135182)
		(end 33.805114 -100.734368)
		(width 0.10668)
		(layer "In7.Cu")
		(net "FM_BMC_CRASHLOG_TRIG_N")
	)
	(segment
		(start 28.438094 -58.252106)
		(end 30.191202 -56.498998)
		(width 0.10668)
		(layer "In7.Cu")
		(net "FM_BMC_CRASHLOG_TRIG_N")
	)
	(segment
		(start 29.84754 -91.81338)
		(end 30.02788 -91.99372)
		(width 0.10668)
		(layer "In7.Cu")
		(net "FM_BMC_CRASHLOG_TRIG_N")
	)
	(segment
		(start 33.6042 -104.30764)
		(end 33.6042 -105.261156)
		(width 0.10668)
		(layer "In7.Cu")
		(net "FM_BMC_CRASHLOG_TRIG_N")
	)
	(segment
		(start 32.88538 -97.483422)
		(end 34.4043 -99.002342)
		(width 0.10668)
		(layer "In7.Cu")
		(net "FM_BMC_CRASHLOG_TRIG_N")
	)
	(segment
		(start 30.02788 -93.025722)
		(end 30.286706 -93.284548)
		(width 0.10668)
		(layer "In7.Cu")
		(net "FM_BMC_CRASHLOG_TRIG_N")
	)
	(segment
		(start 30.286706 -93.284548)
		(end 30.855158 -93.284548)
		(width 0.10668)
		(layer "In7.Cu")
		(net "FM_BMC_CRASHLOG_TRIG_N")
	)
	(segment
		(start 37.338 -31.6992)
		(end 37.338 -30.59049)
		(width 0.10668)
		(layer "In7.Cu")
		(net "FM_BMC_CRASHLOG_TRIG_N")
	)
	(segment
		(start 33.42132 -103.186738)
		(end 33.42132 -104.12476)
		(width 0.10668)
		(layer "In7.Cu")
		(net "FM_BMC_CRASHLOG_TRIG_N")
	)
	(segment
		(start 36.6522 -33.6296)
		(end 36.6522 -32.385)
		(width 0.10668)
		(layer "In7.Cu")
		(net "FM_BMC_CRASHLOG_TRIG_N")
	)
	(segment
		(start 32.08274 -42.44086)
		(end 33.40608 -41.11752)
		(width 0.10668)
		(layer "In7.Cu")
		(net "FM_BMC_CRASHLOG_TRIG_N")
	)
	(segment
		(start 32.85998 -101.270308)
		(end 32.85998 -102.625398)
		(width 0.10668)
		(layer "In7.Cu")
		(net "FM_BMC_CRASHLOG_TRIG_N")
	)
	(segment
		(start 34.36874 -38.98646)
		(end 34.36874 -36.869878)
		(width 0.10668)
		(layer "In7.Cu")
		(net "FM_BMC_CRASHLOG_TRIG_N")
	)
	(segment
		(start 32.85998 -102.625398)
		(end 33.42132 -103.186738)
		(width 0.10668)
		(layer "In7.Cu")
		(net "FM_BMC_CRASHLOG_TRIG_N")
	)
	(segment
		(start 31.99638 -94.425516)
		(end 31.99638 -95.899478)
		(width 0.10668)
		(layer "In7.Cu")
		(net "FM_BMC_CRASHLOG_TRIG_N")
	)
	(segment
		(start 31.818072 -53.898038)
		(end 31.04388 -53.123846)
		(width 0.10668)
		(layer "In7.Cu")
		(net "FM_BMC_CRASHLOG_TRIG_N")
	)
	(segment
		(start 31.818072 -54.229)
		(end 31.818072 -53.898038)
		(width 0.10668)
		(layer "In7.Cu")
		(net "FM_BMC_CRASHLOG_TRIG_N")
	)
	(segment
		(start 33.42132 -104.12476)
		(end 33.6042 -104.30764)
		(width 0.10668)
		(layer "In7.Cu")
		(net "FM_BMC_CRASHLOG_TRIG_N")
	)
	(segment
		(start 31.304992 -93.734128)
		(end 31.99638 -94.425516)
		(width 0.10668)
		(layer "In7.Cu")
		(net "FM_BMC_CRASHLOG_TRIG_N")
	)
	(segment
		(start 33.40608 -39.94912)
		(end 34.36874 -38.98646)
		(width 0.10668)
		(layer "In7.Cu")
		(net "FM_BMC_CRASHLOG_TRIG_N")
	)
	(segment
		(start 31.304738 -93.734128)
		(end 31.304992 -93.734128)
		(width 0.10668)
		(layer "In7.Cu")
		(net "FM_BMC_CRASHLOG_TRIG_N")
	)
	(segment
		(start 34.36874 -36.869878)
		(end 35.7124 -35.526218)
		(width 0.10668)
		(layer "In7.Cu")
		(net "FM_BMC_CRASHLOG_TRIG_N")
	)
	(segment
		(start 30.645862 -55.40121)
		(end 31.818072 -54.229)
		(width 0.10668)
		(layer "In7.Cu")
		(net "FM_BMC_CRASHLOG_TRIG_N")
	)
	(segment
		(start 28.438094 -59.507374)
		(end 28.438094 -58.252106)
		(width 0.10668)
		(layer "In7.Cu")
		(net "FM_BMC_CRASHLOG_TRIG_N")
	)
	(segment
		(start 36.6522 -32.385)
		(end 37.338 -31.6992)
		(width 0.10668)
		(layer "In7.Cu")
		(net "FM_BMC_CRASHLOG_TRIG_N")
	)
	(segment
		(start 33.39592 -100.734368)
		(end 32.85998 -101.270308)
		(width 0.10668)
		(layer "In7.Cu")
		(net "FM_BMC_CRASHLOG_TRIG_N")
	)
	(segment
		(start 31.04388 -53.123846)
		(end 31.04388 -44.158408)
		(width 0.10668)
		(layer "In7.Cu")
		(net "FM_BMC_CRASHLOG_TRIG_N")
	)
	(segment
		(start 33.40608 -41.11752)
		(end 33.40608 -39.94912)
		(width 0.10668)
		(layer "In7.Cu")
		(net "FM_BMC_CRASHLOG_TRIG_N")
	)
	(segment
		(start 35.7124 -34.5694)
		(end 36.6522 -33.6296)
		(width 0.10668)
		(layer "In7.Cu")
		(net "FM_BMC_CRASHLOG_TRIG_N")
	)
	(segment
		(start 28.4988 -59.56808)
		(end 28.438094 -59.507374)
		(width 0.10668)
		(layer "In7.Cu")
		(net "FM_BMC_CRASHLOG_TRIG_N")
	)
	(segment
		(start 31.04388 -44.158408)
		(end 32.08274 -43.119548)
		(width 0.10668)
		(layer "In7.Cu")
		(net "FM_BMC_CRASHLOG_TRIG_N")
	)
	(segment
		(start 37.338 -30.59049)
		(end 37.760402 -30.168088)
		(width 0.10668)
		(layer "In7.Cu")
		(net "FM_BMC_CRASHLOG_TRIG_N")
	)
	(segment
		(start 32.08274 -43.119548)
		(end 32.08274 -42.44086)
		(width 0.10668)
		(layer "In7.Cu")
		(net "FM_BMC_CRASHLOG_TRIG_N")
	)
	(segment
		(start 30.02788 -91.99372)
		(end 30.02788 -93.025722)
		(width 0.10668)
		(layer "In7.Cu")
		(net "FM_BMC_CRASHLOG_TRIG_N")
	)
	(segment
		(start 33.805114 -100.734368)
		(end 33.39592 -100.734368)
		(width 0.10668)
		(layer "In7.Cu")
		(net "FM_BMC_CRASHLOG_TRIG_N")
	)
	(segment
		(start 30.191202 -56.498998)
		(end 30.645862 -55.40121)
		(width 0.10668)
		(layer "In7.Cu")
		(net "FM_BMC_CRASHLOG_TRIG_N")
	)
	(segment
		(start 30.855158 -93.284548)
		(end 31.304738 -93.734128)
		(width 0.10668)
		(layer "In7.Cu")
		(net "FM_BMC_CRASHLOG_TRIG_N")
	)
	(segment
		(start 33.6042 -105.261156)
		(end 34.1122 -105.769156)
		(width 0.10668)
		(layer "In7.Cu")
		(net "FM_BMC_CRASHLOG_TRIG_N")
	)
	(segment
		(start 37.760402 -29.988002)
		(end 37.4904 -29.718)
		(width 0.10668)
		(layer "In7.Cu")
		(net "FM_BMC_CRASHLOG_TRIG_N")
	)
	(segment
		(start 29.1338 -88.519)
		(end 29.84754 -89.23274)
		(width 0.10668)
		(layer "In7.Cu")
		(net "FM_BMC_CRASHLOG_TRIG_N")
	)
	(segment
		(start 32.88538 -97.046796)
		(end 32.88538 -97.483422)
		(width 0.10668)
		(layer "In7.Cu")
		(net "FM_BMC_CRASHLOG_TRIG_N")
	)
	(segment
		(start 27.50185 -101.2698)
		(end 27.294332 -101.2698)
		(width 0.11684)
		(layer "F.Cu")
		(net "FM_SOL_UART_CH_SEL_R2")
	)
	(segment
		(start 26.659332 -100.6348)
		(end 26.659332 -99.58705)
		(width 0.11684)
		(layer "F.Cu")
		(net "FM_SOL_UART_CH_SEL_R2")
	)
	(segment
		(start 27.294332 -101.2698)
		(end 26.659332 -100.6348)
		(width 0.11684)
		(layer "F.Cu")
		(net "FM_SOL_UART_CH_SEL_R2")
	)
	(segment
		(start 28.575 -102.34295)
		(end 27.50185 -101.2698)
		(width 0.11684)
		(layer "F.Cu")
		(net "FM_SOL_UART_CH_SEL_R2")
	)
	(segment
		(start 44.3484 -55.3212)
		(end 44.398438 -55.371238)
		(width 0.11684)
		(layer "F.Cu")
		(net "FM_SOL_UART_CH_SEL_R1")
	)
	(segment
		(start 44.398438 -55.371238)
		(end 44.895008 -55.371238)
		(width 0.11684)
		(layer "F.Cu")
		(net "FM_SOL_UART_CH_SEL_R1")
	)
	(via
		(at 44.3484 -55.3212)
		(size 0.4572)
		(drill 0.254)
		(layers "F.Cu" "B.Cu")
		(net "FM_SOL_UART_CH_SEL_R1")
	)
	(segment
		(start 45.0342 -55.04815)
		(end 44.661328 -55.04815)
		(width 0.11684)
		(layer "B.Cu")
		(net "FM_SOL_UART_CH_SEL_R1")
	)
	(segment
		(start 44.661328 -55.04815)
		(end 44.388278 -55.3212)
		(width 0.11684)
		(layer "B.Cu")
		(net "FM_SOL_UART_CH_SEL_R1")
	)
	(segment
		(start 44.388278 -55.3212)
		(end 44.3484 -55.3212)
		(width 0.11684)
		(layer "B.Cu")
		(net "FM_SOL_UART_CH_SEL_R1")
	)
	(segment
		(start 25.45461 -98.382328)
		(end 25.059386 -97.987104)
		(width 0.381)
		(layer "F.Cu")
		(net "FM_P12V_HSC_ENABLE_R2")
	)
	(via
		(at 25.45461 -98.382328)
		(size 0.4572)
		(drill 0.254)
		(layers "F.Cu" "B.Cu")
		(net "FM_P12V_HSC_ENABLE_R2")
	)
	(via
		(at 25.019 -100.2792)
		(size 0.6604)
		(drill 0.3302)
		(layers "F.Cu" "B.Cu")
		(net "FM_P12V_HSC_ENABLE_R2")
	)
	(segment
		(start 25.45461 -99.183444)
		(end 25.019 -99.619054)
		(width 0.11684)
		(layer "B.Cu")
		(net "FM_P12V_HSC_ENABLE_R2")
	)
	(segment
		(start 25.019 -99.619054)
		(end 25.019 -100.2792)
		(width 0.11684)
		(layer "B.Cu")
		(net "FM_P12V_HSC_ENABLE_R2")
	)
	(segment
		(start 25.45461 -98.382328)
		(end 25.45461 -99.183444)
		(width 0.11684)
		(layer "B.Cu")
		(net "FM_P12V_HSC_ENABLE_R2")
	)
	(segment
		(start 25.019 -100.2792)
		(end 25.019 -101.58095)
		(width 0.11684)
		(layer "B.Cu")
		(net "FM_P12V_HSC_ENABLE_R2")
	)
	(segment
		(start 39.941754 -61.6585)
		(end 41.57218 -60.028074)
		(width 0.11684)
		(layer "F.Cu")
		(net "FM_P12V_HSC_ENABLE_R1")
	)
	(segment
		(start 41.57218 -60.028074)
		(end 41.57218 -59.776614)
		(width 0.11684)
		(layer "F.Cu")
		(net "FM_P12V_HSC_ENABLE_R1")
	)
	(segment
		(start 43.385994 -57.9628)
		(end 44.1198 -57.9628)
		(width 0.11684)
		(layer "F.Cu")
		(net "FM_P12V_HSC_ENABLE_R1")
	)
	(segment
		(start 39.62781 -61.6585)
		(end 39.941754 -61.6585)
		(width 0.11684)
		(layer "F.Cu")
		(net "FM_P12V_HSC_ENABLE_R1")
	)
	(segment
		(start 44.1198 -57.9628)
		(end 44.895008 -57.187592)
		(width 0.11684)
		(layer "F.Cu")
		(net "FM_P12V_HSC_ENABLE_R1")
	)
	(segment
		(start 41.57218 -59.776614)
		(end 43.385994 -57.9628)
		(width 0.11684)
		(layer "F.Cu")
		(net "FM_P12V_HSC_ENABLE_R1")
	)
	(segment
		(start 44.895008 -57.187592)
		(end 44.895008 -56.971184)
		(width 0.11684)
		(layer "F.Cu")
		(net "FM_P12V_HSC_ENABLE_R1")
	)
	(segment
		(start 38.82771 -62.672468)
		(end 38.608 -62.892178)
		(width 0.11684)
		(layer "F.Cu")
		(net "FM_P12V_HSC_ENABLE")
	)
	(segment
		(start 45.3898 -70.8406)
		(end 45.484288 -70.746112)
		(width 0.11684)
		(layer "F.Cu")
		(net "FM_P12V_HSC_ENABLE")
	)
	(segment
		(start 39.2176 -70.5612)
		(end 41.2496 -70.5612)
		(width 0.11684)
		(layer "F.Cu")
		(net "FM_P12V_HSC_ENABLE")
	)
	(segment
		(start 37.26434 -70.66534)
		(end 37.8206 -71.2216)
		(width 0.11684)
		(layer "F.Cu")
		(net "FM_P12V_HSC_ENABLE")
	)
	(segment
		(start 45.484288 -70.746112)
		(end 45.521118 -70.746112)
		(width 0.11684)
		(layer "F.Cu")
		(net "FM_P12V_HSC_ENABLE")
	)
	(segment
		(start 37.8206 -71.2216)
		(end 38.5572 -71.2216)
		(width 0.11684)
		(layer "F.Cu")
		(net "FM_P12V_HSC_ENABLE")
	)
	(segment
		(start 37.26434 -66.44386)
		(end 37.26434 -70.66534)
		(width 0.11684)
		(layer "F.Cu")
		(net "FM_P12V_HSC_ENABLE")
	)
	(segment
		(start 38.608 -65.1002)
		(end 37.26434 -66.44386)
		(width 0.11684)
		(layer "F.Cu")
		(net "FM_P12V_HSC_ENABLE")
	)
	(segment
		(start 41.2496 -70.5612)
		(end 41.529 -70.8406)
		(width 0.11684)
		(layer "F.Cu")
		(net "FM_P12V_HSC_ENABLE")
	)
	(segment
		(start 41.529 -70.8406)
		(end 45.3898 -70.8406)
		(width 0.11684)
		(layer "F.Cu")
		(net "FM_P12V_HSC_ENABLE")
	)
	(segment
		(start 38.82771 -61.6585)
		(end 38.82771 -62.672468)
		(width 0.11684)
		(layer "F.Cu")
		(net "FM_P12V_HSC_ENABLE")
	)
	(segment
		(start 38.608 -62.892178)
		(end 38.608 -65.1002)
		(width 0.11684)
		(layer "F.Cu")
		(net "FM_P12V_HSC_ENABLE")
	)
	(segment
		(start 38.5572 -71.2216)
		(end 39.2176 -70.5612)
		(width 0.11684)
		(layer "F.Cu")
		(net "FM_P12V_HSC_ENABLE")
	)
	(via
		(at 45.521118 -70.746112)
		(size 0.508)
		(drill 0.254)
		(layers "F.Cu" "B.Cu")
		(net "FM_P12V_HSC_ENABLE")
	)
	(via
		(at 24.9682 -103.5304)
		(size 0.508)
		(drill 0.254)
		(layers "F.Cu" "B.Cu")
		(net "FM_P12V_HSC_ENABLE")
	)
	(segment
		(start 25.019 -103.4796)
		(end 24.9682 -103.5304)
		(width 0.11684)
		(layer "B.Cu")
		(net "FM_P12V_HSC_ENABLE")
	)
	(segment
		(start 25.019 -102.38105)
		(end 25.019 -103.4796)
		(width 0.11684)
		(layer "B.Cu")
		(net "FM_P12V_HSC_ENABLE")
	)
	(segment
		(start 24.003 -102.38105)
		(end 25.019 -102.38105)
		(width 0.11684)
		(layer "B.Cu")
		(net "FM_P12V_HSC_ENABLE")
	)
	(segment
		(start 28.332176 -103.638858)
		(end 27.965654 -104.00538)
		(width 0.08382)
		(layer "In9.Cu")
		(net "FM_P12V_HSC_ENABLE")
	)
	(segment
		(start 45.521118 -70.746112)
		(end 45.484288 -70.746112)
		(width 0.08382)
		(layer "In9.Cu")
		(net "FM_P12V_HSC_ENABLE")
	)
	(segment
		(start 34.43097 -92.659708)
		(end 34.43097 -95.003112)
		(width 0.08382)
		(layer "In9.Cu")
		(net "FM_P12V_HSC_ENABLE")
	)
	(segment
		(start 32.68345 -100.203)
		(end 32.68345 -102.710234)
		(width 0.08382)
		(layer "In9.Cu")
		(net "FM_P12V_HSC_ENABLE")
	)
	(segment
		(start 45.484288 -70.746112)
		(end 45.3771 -70.8533)
		(width 0.08382)
		(layer "In9.Cu")
		(net "FM_P12V_HSC_ENABLE")
	)
	(segment
		(start 27.965654 -104.730804)
		(end 27.616658 -105.0798)
		(width 0.08382)
		(layer "In9.Cu")
		(net "FM_P12V_HSC_ENABLE")
	)
	(segment
		(start 45.3771 -70.8533)
		(end 45.3517 -70.8533)
		(width 0.08382)
		(layer "In9.Cu")
		(net "FM_P12V_HSC_ENABLE")
	)
	(segment
		(start 35.65017 -87.33663)
		(end 35.65017 -88.954102)
		(width 0.08382)
		(layer "In9.Cu")
		(net "FM_P12V_HSC_ENABLE")
	)
	(segment
		(start 24.9682 -104.0384)
		(end 24.9682 -103.5304)
		(width 0.08382)
		(layer "In9.Cu")
		(net "FM_P12V_HSC_ENABLE")
	)
	(segment
		(start 35.65017 -88.954102)
		(end 34.80308 -89.801192)
		(width 0.08382)
		(layer "In9.Cu")
		(net "FM_P12V_HSC_ENABLE")
	)
	(segment
		(start 33.00603 -99.88042)
		(end 32.68345 -100.203)
		(width 0.08382)
		(layer "In9.Cu")
		(net "FM_P12V_HSC_ENABLE")
	)
	(segment
		(start 34.18459 -98.223324)
		(end 33.00603 -99.401884)
		(width 0.08382)
		(layer "In9.Cu")
		(net "FM_P12V_HSC_ENABLE")
	)
	(segment
		(start 34.43097 -95.003112)
		(end 34.18459 -95.59798)
		(width 0.08382)
		(layer "In9.Cu")
		(net "FM_P12V_HSC_ENABLE")
	)
	(segment
		(start 34.80308 -89.801192)
		(end 34.80308 -90.554556)
		(width 0.08382)
		(layer "In9.Cu")
		(net "FM_P12V_HSC_ENABLE")
	)
	(segment
		(start 31.754826 -103.638858)
		(end 28.332176 -103.638858)
		(width 0.08382)
		(layer "In9.Cu")
		(net "FM_P12V_HSC_ENABLE")
	)
	(segment
		(start 44.562776 -71.642224)
		(end 44.562776 -72.048624)
		(width 0.08382)
		(layer "In9.Cu")
		(net "FM_P12V_HSC_ENABLE")
	)
	(segment
		(start 27.616658 -105.0798)
		(end 26.0096 -105.0798)
		(width 0.08382)
		(layer "In9.Cu")
		(net "FM_P12V_HSC_ENABLE")
	)
	(segment
		(start 27.965654 -104.00538)
		(end 27.965654 -104.730804)
		(width 0.08382)
		(layer "In9.Cu")
		(net "FM_P12V_HSC_ENABLE")
	)
	(segment
		(start 26.0096 -105.0798)
		(end 24.9682 -104.0384)
		(width 0.08382)
		(layer "In9.Cu")
		(net "FM_P12V_HSC_ENABLE")
	)
	(segment
		(start 40.1828 -76.4286)
		(end 40.1828 -77.2414)
		(width 0.08382)
		(layer "In9.Cu")
		(net "FM_P12V_HSC_ENABLE")
	)
	(segment
		(start 45.3517 -70.8533)
		(end 44.562776 -71.642224)
		(width 0.08382)
		(layer "In9.Cu")
		(net "FM_P12V_HSC_ENABLE")
	)
	(segment
		(start 37.2364 -80.1878)
		(end 37.2364 -85.7504)
		(width 0.08382)
		(layer "In9.Cu")
		(net "FM_P12V_HSC_ENABLE")
	)
	(segment
		(start 37.2364 -85.7504)
		(end 35.65017 -87.33663)
		(width 0.08382)
		(layer "In9.Cu")
		(net "FM_P12V_HSC_ENABLE")
	)
	(segment
		(start 34.80435 -92.286328)
		(end 34.43097 -92.659708)
		(width 0.08382)
		(layer "In9.Cu")
		(net "FM_P12V_HSC_ENABLE")
	)
	(segment
		(start 44.562776 -72.048624)
		(end 40.1828 -76.4286)
		(width 0.08382)
		(layer "In9.Cu")
		(net "FM_P12V_HSC_ENABLE")
	)
	(segment
		(start 34.80435 -90.555826)
		(end 34.80435 -92.286328)
		(width 0.08382)
		(layer "In9.Cu")
		(net "FM_P12V_HSC_ENABLE")
	)
	(segment
		(start 34.18459 -95.59798)
		(end 34.18459 -98.223324)
		(width 0.08382)
		(layer "In9.Cu")
		(net "FM_P12V_HSC_ENABLE")
	)
	(segment
		(start 40.1828 -77.2414)
		(end 37.2364 -80.1878)
		(width 0.08382)
		(layer "In9.Cu")
		(net "FM_P12V_HSC_ENABLE")
	)
	(segment
		(start 32.68345 -102.710234)
		(end 31.754826 -103.638858)
		(width 0.08382)
		(layer "In9.Cu")
		(net "FM_P12V_HSC_ENABLE")
	)
	(segment
		(start 34.80308 -90.554556)
		(end 34.80435 -90.555826)
		(width 0.08382)
		(layer "In9.Cu")
		(net "FM_P12V_HSC_ENABLE")
	)
	(segment
		(start 33.00603 -99.401884)
		(end 33.00603 -99.88042)
		(width 0.08382)
		(layer "In9.Cu")
		(net "FM_P12V_HSC_ENABLE")
	)
	(segment
		(start 35.941 -61.36005)
		(end 35.70605 -61.595)
		(width 0.11684)
		(layer "F.Cu")
		(net "BMC_CPLD_GPIO_2")
	)
	(segment
		(start 32.22244 -59.66206)
		(end 30.7848 -59.66206)
		(width 0.11684)
		(layer "F.Cu")
		(net "BMC_CPLD_GPIO_2")
	)
	(segment
		(start 35.70605 -61.595)
		(end 33.39846 -61.595)
		(width 0.11684)
		(layer "F.Cu")
		(net "BMC_CPLD_GPIO_2")
	)
	(segment
		(start 33.39846 -61.595)
		(end 33.16224 -61.35878)
		(width 0.11684)
		(layer "F.Cu")
		(net "BMC_CPLD_GPIO_2")
	)
	(segment
		(start 33.16224 -60.60186)
		(end 32.22244 -59.66206)
		(width 0.11684)
		(layer "F.Cu")
		(net "BMC_CPLD_GPIO_2")
	)
	(segment
		(start 33.16224 -61.35878)
		(end 33.16224 -60.60186)
		(width 0.11684)
		(layer "F.Cu")
		(net "BMC_CPLD_GPIO_2")
	)
	(via
		(at 64.262 -19.685)
		(size 0.508)
		(drill 0.254)
		(layers "F.Cu" "B.Cu")
		(net "BMC_CPLD_GPIO_2")
	)
	(via
		(at 30.5308 -91.8464)
		(size 0.508)
		(drill 0.254)
		(layers "F.Cu" "B.Cu")
		(net "BMC_CPLD_GPIO_2")
	)
	(via
		(at 30.7848 -59.66206)
		(size 0.762)
		(drill 0.254)
		(layers "F.Cu" "B.Cu")
		(net "BMC_CPLD_GPIO_2")
	)
	(via
		(at 39.80434 -18.64868)
		(size 0.508)
		(drill 0.254)
		(layers "F.Cu" "B.Cu")
		(net "BMC_CPLD_GPIO_2")
	)
	(via
		(at 20.3962 -61.8998)
		(size 0.508)
		(drill 0.254)
		(layers "F.Cu" "B.Cu")
		(net "BMC_CPLD_GPIO_2")
	)
	(segment
		(start 29.868876 -91.063826)
		(end 29.86405 -91.059)
		(width 0.11684)
		(layer "B.Cu")
		(net "BMC_CPLD_GPIO_2")
	)
	(segment
		(start 29.8958 -91.059)
		(end 30.2514 -91.4146)
		(width 0.11684)
		(layer "B.Cu")
		(net "BMC_CPLD_GPIO_2")
	)
	(segment
		(start 29.868876 -92.106242)
		(end 29.868876 -91.063826)
		(width 0.11684)
		(layer "B.Cu")
		(net "BMC_CPLD_GPIO_2")
	)
	(segment
		(start 29.86405 -91.059)
		(end 29.8958 -91.059)
		(width 0.11684)
		(layer "B.Cu")
		(net "BMC_CPLD_GPIO_2")
	)
	(segment
		(start 64.262 -19.06905)
		(end 64.262 -19.685)
		(width 0.11684)
		(layer "B.Cu")
		(net "BMC_CPLD_GPIO_2")
	)
	(segment
		(start 30.2514 -91.4146)
		(end 30.2514 -91.567)
		(width 0.11684)
		(layer "B.Cu")
		(net "BMC_CPLD_GPIO_2")
	)
	(segment
		(start 30.2514 -91.567)
		(end 30.5308 -91.8464)
		(width 0.11684)
		(layer "B.Cu")
		(net "BMC_CPLD_GPIO_2")
	)
	(segment
		(start 30.117542 -61.96711)
		(end 29.45511 -61.96711)
		(width 0.08382)
		(layer "In2.Cu")
		(net "BMC_CPLD_GPIO_2")
	)
	(segment
		(start 28.300172 -62.190376)
		(end 20.635976 -62.190376)
		(width 0.08382)
		(layer "In2.Cu")
		(net "BMC_CPLD_GPIO_2")
	)
	(segment
		(start 29.31287 -61.82487)
		(end 28.665678 -61.82487)
		(width 0.08382)
		(layer "In2.Cu")
		(net "BMC_CPLD_GPIO_2")
	)
	(segment
		(start 28.665678 -61.82487)
		(end 28.300172 -62.190376)
		(width 0.08382)
		(layer "In2.Cu")
		(net "BMC_CPLD_GPIO_2")
	)
	(segment
		(start 30.7848 -61.299852)
		(end 30.117542 -61.96711)
		(width 0.08382)
		(layer "In2.Cu")
		(net "BMC_CPLD_GPIO_2")
	)
	(segment
		(start 30.7848 -59.66206)
		(end 30.7848 -61.299852)
		(width 0.08382)
		(layer "In2.Cu")
		(net "BMC_CPLD_GPIO_2")
	)
	(segment
		(start 29.45511 -61.96711)
		(end 29.31287 -61.82487)
		(width 0.08382)
		(layer "In2.Cu")
		(net "BMC_CPLD_GPIO_2")
	)
	(segment
		(start 20.3962 -61.9506)
		(end 20.3962 -61.8998)
		(width 0.08382)
		(layer "In2.Cu")
		(net "BMC_CPLD_GPIO_2")
	)
	(segment
		(start 20.635976 -62.190376)
		(end 20.3962 -61.9506)
		(width 0.08382)
		(layer "In2.Cu")
		(net "BMC_CPLD_GPIO_2")
	)
	(segment
		(start 61.043312 -19.417792)
		(end 61.58484 -19.95932)
		(width 0.10668)
		(layer "In4.Cu")
		(net "BMC_CPLD_GPIO_2")
	)
	(segment
		(start 54.722014 -19.417792)
		(end 61.043312 -19.417792)
		(width 0.10668)
		(layer "In4.Cu")
		(net "BMC_CPLD_GPIO_2")
	)
	(segment
		(start 53.820822 -18.5166)
		(end 54.722014 -19.417792)
		(width 0.10668)
		(layer "In4.Cu")
		(net "BMC_CPLD_GPIO_2")
	)
	(segment
		(start 49.744376 -16.152876)
		(end 52.1081 -18.5166)
		(width 0.10668)
		(layer "In4.Cu")
		(net "BMC_CPLD_GPIO_2")
	)
	(segment
		(start 63.98768 -19.95932)
		(end 64.262 -19.685)
		(width 0.10668)
		(layer "In4.Cu")
		(net "BMC_CPLD_GPIO_2")
	)
	(segment
		(start 39.80434 -18.64868)
		(end 39.80434 -17.92986)
		(width 0.10668)
		(layer "In4.Cu")
		(net "BMC_CPLD_GPIO_2")
	)
	(segment
		(start 39.80434 -17.92986)
		(end 41.581324 -16.152876)
		(width 0.10668)
		(layer "In4.Cu")
		(net "BMC_CPLD_GPIO_2")
	)
	(segment
		(start 52.1081 -18.5166)
		(end 53.820822 -18.5166)
		(width 0.10668)
		(layer "In4.Cu")
		(net "BMC_CPLD_GPIO_2")
	)
	(segment
		(start 61.58484 -19.95932)
		(end 63.98768 -19.95932)
		(width 0.10668)
		(layer "In4.Cu")
		(net "BMC_CPLD_GPIO_2")
	)
	(segment
		(start 41.581324 -16.152876)
		(end 49.744376 -16.152876)
		(width 0.10668)
		(layer "In4.Cu")
		(net "BMC_CPLD_GPIO_2")
	)
	(segment
		(start 24.79548 -80.21828)
		(end 24.79548 -77.077062)
		(width 0.10668)
		(layer "In7.Cu")
		(net "BMC_CPLD_GPIO_2")
	)
	(segment
		(start 18.0848 -50.1904)
		(end 17.5768 -50.1904)
		(width 0.10668)
		(layer "In7.Cu")
		(net "BMC_CPLD_GPIO_2")
	)
	(segment
		(start 17.601184 -45.103288)
		(end 19.189192 -43.51528)
		(width 0.10668)
		(layer "In7.Cu")
		(net "BMC_CPLD_GPIO_2")
	)
	(segment
		(start 39.79926 -18.6436)
		(end 39.80434 -18.64868)
		(width 0.10668)
		(layer "In7.Cu")
		(net "BMC_CPLD_GPIO_2")
	)
	(segment
		(start 28.702 -18.542)
		(end 29.89326 -17.35074)
		(width 0.10668)
		(layer "In7.Cu")
		(net "BMC_CPLD_GPIO_2")
	)
	(segment
		(start 17.1704 -49.784)
		(end 17.1704 -49.428654)
		(width 0.10668)
		(layer "In7.Cu")
		(net "BMC_CPLD_GPIO_2")
	)
	(segment
		(start 30.10662 -88.197944)
		(end 28.764484 -86.855808)
		(width 0.10668)
		(layer "In7.Cu")
		(net "BMC_CPLD_GPIO_2")
	)
	(segment
		(start 20.3962 -61.66104)
		(end 19.9644 -61.22924)
		(width 0.10668)
		(layer "In7.Cu")
		(net "BMC_CPLD_GPIO_2")
	)
	(segment
		(start 28.690062 -86.855808)
		(end 28.689808 -86.855554)
		(width 0.10668)
		(layer "In7.Cu")
		(net "BMC_CPLD_GPIO_2")
	)
	(segment
		(start 21.19122 -62.74562)
		(end 20.3962 -61.9506)
		(width 0.10668)
		(layer "In7.Cu")
		(net "BMC_CPLD_GPIO_2")
	)
	(segment
		(start 24.01824 -74.796142)
		(end 23.288498 -74.0664)
		(width 0.10668)
		(layer "In7.Cu")
		(net "BMC_CPLD_GPIO_2")
	)
	(segment
		(start 22.521672 -74.0664)
		(end 20.88642 -72.431148)
		(width 0.10668)
		(layer "In7.Cu")
		(net "BMC_CPLD_GPIO_2")
	)
	(segment
		(start 25.98928 -23.83028)
		(end 25.98928 -23.368)
		(width 0.10668)
		(layer "In7.Cu")
		(net "BMC_CPLD_GPIO_2")
	)
	(segment
		(start 20.24888 -69.111622)
		(end 20.24888 -67.285616)
		(width 0.10668)
		(layer "In7.Cu")
		(net "BMC_CPLD_GPIO_2")
	)
	(segment
		(start 28.702 -19.304)
		(end 28.702 -18.542)
		(width 0.10668)
		(layer "In7.Cu")
		(net "BMC_CPLD_GPIO_2")
	)
	(segment
		(start 20.58162 -70.559422)
		(end 20.58162 -69.444362)
		(width 0.10668)
		(layer "In7.Cu")
		(net "BMC_CPLD_GPIO_2")
	)
	(segment
		(start 28.764484 -86.855808)
		(end 28.690062 -86.855808)
		(width 0.10668)
		(layer "In7.Cu")
		(net "BMC_CPLD_GPIO_2")
	)
	(segment
		(start 28.678632 -86.855554)
		(end 27.9273 -86.104222)
		(width 0.10668)
		(layer "In7.Cu")
		(net "BMC_CPLD_GPIO_2")
	)
	(segment
		(start 35.53714 -17.35074)
		(end 36.83 -18.6436)
		(width 0.10668)
		(layer "In7.Cu")
		(net "BMC_CPLD_GPIO_2")
	)
	(segment
		(start 20.464018 -66.55816)
		(end 20.450556 -66.525648)
		(width 0.10668)
		(layer "In7.Cu")
		(net "BMC_CPLD_GPIO_2")
	)
	(segment
		(start 19.9644 -58.8518)
		(end 19.09572 -57.98312)
		(width 0.10668)
		(layer "In7.Cu")
		(net "BMC_CPLD_GPIO_2")
	)
	(segment
		(start 23.288498 -74.0664)
		(end 22.521672 -74.0664)
		(width 0.10668)
		(layer "In7.Cu")
		(net "BMC_CPLD_GPIO_2")
	)
	(segment
		(start 29.89326 -17.35074)
		(end 35.53714 -17.35074)
		(width 0.10668)
		(layer "In7.Cu")
		(net "BMC_CPLD_GPIO_2")
	)
	(segment
		(start 20.24888 -67.285616)
		(end 20.464018 -67.070478)
		(width 0.10668)
		(layer "In7.Cu")
		(net "BMC_CPLD_GPIO_2")
	)
	(segment
		(start 26.679906 -82.361278)
		(end 26.679906 -82.102706)
		(width 0.10668)
		(layer "In7.Cu")
		(net "BMC_CPLD_GPIO_2")
	)
	(segment
		(start 28.956 -20.828)
		(end 28.956 -19.558)
		(width 0.10668)
		(layer "In7.Cu")
		(net "BMC_CPLD_GPIO_2")
	)
	(segment
		(start 20.58162 -69.444362)
		(end 20.24888 -69.111622)
		(width 0.10668)
		(layer "In7.Cu")
		(net "BMC_CPLD_GPIO_2")
	)
	(segment
		(start 17.1704 -49.428654)
		(end 17.601184 -48.99787)
		(width 0.10668)
		(layer "In7.Cu")
		(net "BMC_CPLD_GPIO_2")
	)
	(segment
		(start 25.98928 -23.368)
		(end 26.75128 -22.606)
		(width 0.10668)
		(layer "In7.Cu")
		(net "BMC_CPLD_GPIO_2")
	)
	(segment
		(start 27.178 -22.606)
		(end 28.956 -20.828)
		(width 0.10668)
		(layer "In7.Cu")
		(net "BMC_CPLD_GPIO_2")
	)
	(segment
		(start 21.19122 -64.237108)
		(end 21.19122 -62.74562)
		(width 0.10668)
		(layer "In7.Cu")
		(net "BMC_CPLD_GPIO_2")
	)
	(segment
		(start 17.5768 -50.1904)
		(end 17.1704 -49.784)
		(width 0.10668)
		(layer "In7.Cu")
		(net "BMC_CPLD_GPIO_2")
	)
	(segment
		(start 18.796 -52.202334)
		(end 18.796 -50.9016)
		(width 0.10668)
		(layer "In7.Cu")
		(net "BMC_CPLD_GPIO_2")
	)
	(segment
		(start 19.9644 -61.22924)
		(end 19.9644 -58.8518)
		(width 0.10668)
		(layer "In7.Cu")
		(net "BMC_CPLD_GPIO_2")
	)
	(segment
		(start 30.5308 -91.8464)
		(end 30.10662 -91.42222)
		(width 0.10668)
		(layer "In7.Cu")
		(net "BMC_CPLD_GPIO_2")
	)
	(segment
		(start 23.6601 -39.619936)
		(end 23.6601 -37.882322)
		(width 0.10668)
		(layer "In7.Cu")
		(net "BMC_CPLD_GPIO_2")
	)
	(segment
		(start 27.9273 -83.849718)
		(end 27.485848 -83.408266)
		(width 0.10668)
		(layer "In7.Cu")
		(net "BMC_CPLD_GPIO_2")
	)
	(segment
		(start 17.747742 -55.0418)
		(end 17.747742 -53.250592)
		(width 0.10668)
		(layer "In7.Cu")
		(net "BMC_CPLD_GPIO_2")
	)
	(segment
		(start 27.9273 -86.104222)
		(end 27.9273 -83.849718)
		(width 0.10668)
		(layer "In7.Cu")
		(net "BMC_CPLD_GPIO_2")
	)
	(segment
		(start 30.10662 -91.42222)
		(end 30.10662 -88.197944)
		(width 0.10668)
		(layer "In7.Cu")
		(net "BMC_CPLD_GPIO_2")
	)
	(segment
		(start 26.442924 -24.283924)
		(end 25.98928 -23.83028)
		(width 0.10668)
		(layer "In7.Cu")
		(net "BMC_CPLD_GPIO_2")
	)
	(segment
		(start 25.2476 -36.294822)
		(end 25.2476 -31.5976)
		(width 0.10668)
		(layer "In7.Cu")
		(net "BMC_CPLD_GPIO_2")
	)
	(segment
		(start 19.189192 -43.51528)
		(end 19.764756 -43.51528)
		(width 0.10668)
		(layer "In7.Cu")
		(net "BMC_CPLD_GPIO_2")
	)
	(segment
		(start 19.764756 -43.51528)
		(end 23.6601 -39.619936)
		(width 0.10668)
		(layer "In7.Cu")
		(net "BMC_CPLD_GPIO_2")
	)
	(segment
		(start 26.442924 -30.402276)
		(end 26.442924 -24.283924)
		(width 0.10668)
		(layer "In7.Cu")
		(net "BMC_CPLD_GPIO_2")
	)
	(segment
		(start 19.09572 -57.98312)
		(end 19.09572 -56.389778)
		(width 0.10668)
		(layer "In7.Cu")
		(net "BMC_CPLD_GPIO_2")
	)
	(segment
		(start 20.88642 -72.431148)
		(end 20.88642 -71.295768)
		(width 0.10668)
		(layer "In7.Cu")
		(net "BMC_CPLD_GPIO_2")
	)
	(segment
		(start 24.79548 -77.077062)
		(end 24.01824 -76.299822)
		(width 0.10668)
		(layer "In7.Cu")
		(net "BMC_CPLD_GPIO_2")
	)
	(segment
		(start 17.601184 -48.99787)
		(end 17.601184 -45.103288)
		(width 0.10668)
		(layer "In7.Cu")
		(net "BMC_CPLD_GPIO_2")
	)
	(segment
		(start 20.3962 -61.8998)
		(end 20.3962 -61.66104)
		(width 0.10668)
		(layer "In7.Cu")
		(net "BMC_CPLD_GPIO_2")
	)
	(segment
		(start 26.75128 -22.606)
		(end 27.178 -22.606)
		(width 0.10668)
		(layer "In7.Cu")
		(net "BMC_CPLD_GPIO_2")
	)
	(segment
		(start 26.679906 -82.102706)
		(end 24.79548 -80.21828)
		(width 0.10668)
		(layer "In7.Cu")
		(net "BMC_CPLD_GPIO_2")
	)
	(segment
		(start 20.464018 -67.070478)
		(end 20.464018 -66.55816)
		(width 0.10668)
		(layer "In7.Cu")
		(net "BMC_CPLD_GPIO_2")
	)
	(segment
		(start 20.450556 -66.525648)
		(end 20.450556 -64.977772)
		(width 0.10668)
		(layer "In7.Cu")
		(net "BMC_CPLD_GPIO_2")
	)
	(segment
		(start 28.689808 -86.855554)
		(end 28.678632 -86.855554)
		(width 0.10668)
		(layer "In7.Cu")
		(net "BMC_CPLD_GPIO_2")
	)
	(segment
		(start 27.485848 -83.408266)
		(end 27.485848 -83.16722)
		(width 0.10668)
		(layer "In7.Cu")
		(net "BMC_CPLD_GPIO_2")
	)
	(segment
		(start 23.6601 -37.882322)
		(end 25.2476 -36.294822)
		(width 0.10668)
		(layer "In7.Cu")
		(net "BMC_CPLD_GPIO_2")
	)
	(segment
		(start 24.01824 -76.299822)
		(end 24.01824 -74.796142)
		(width 0.10668)
		(layer "In7.Cu")
		(net "BMC_CPLD_GPIO_2")
	)
	(segment
		(start 19.09572 -56.389778)
		(end 17.747742 -55.0418)
		(width 0.10668)
		(layer "In7.Cu")
		(net "BMC_CPLD_GPIO_2")
	)
	(segment
		(start 25.2476 -31.5976)
		(end 26.442924 -30.402276)
		(width 0.10668)
		(layer "In7.Cu")
		(net "BMC_CPLD_GPIO_2")
	)
	(segment
		(start 28.956 -19.558)
		(end 28.702 -19.304)
		(width 0.10668)
		(layer "In7.Cu")
		(net "BMC_CPLD_GPIO_2")
	)
	(segment
		(start 17.747742 -53.250592)
		(end 18.796 -52.202334)
		(width 0.10668)
		(layer "In7.Cu")
		(net "BMC_CPLD_GPIO_2")
	)
	(segment
		(start 36.83 -18.6436)
		(end 39.79926 -18.6436)
		(width 0.10668)
		(layer "In7.Cu")
		(net "BMC_CPLD_GPIO_2")
	)
	(segment
		(start 18.796 -50.9016)
		(end 18.0848 -50.1904)
		(width 0.10668)
		(layer "In7.Cu")
		(net "BMC_CPLD_GPIO_2")
	)
	(segment
		(start 20.450556 -64.977772)
		(end 21.19122 -64.237108)
		(width 0.10668)
		(layer "In7.Cu")
		(net "BMC_CPLD_GPIO_2")
	)
	(segment
		(start 20.3962 -61.9506)
		(end 20.3962 -61.8998)
		(width 0.10668)
		(layer "In7.Cu")
		(net "BMC_CPLD_GPIO_2")
	)
	(segment
		(start 27.485848 -83.16722)
		(end 26.679906 -82.361278)
		(width 0.10668)
		(layer "In7.Cu")
		(net "BMC_CPLD_GPIO_2")
	)
	(segment
		(start 20.88642 -71.295768)
		(end 20.58162 -70.559422)
		(width 0.10668)
		(layer "In7.Cu")
		(net "BMC_CPLD_GPIO_2")
	)
	(segment
		(start 46.6852 -31.26105)
		(end 47.294546 -31.870396)
		(width 0.11684)
		(layer "F.Cu")
		(net "RST_ROT_CPU_R1_N")
	)
	(segment
		(start 47.294546 -31.902146)
		(end 47.2948 -31.9024)
		(width 0.11684)
		(layer "F.Cu")
		(net "RST_ROT_CPU_R1_N")
	)
	(segment
		(start 48.0949 -44.171362)
		(end 47.699676 -43.776138)
		(width 0.11684)
		(layer "F.Cu")
		(net "RST_ROT_CPU_R1_N")
	)
	(segment
		(start 47.294546 -31.870396)
		(end 47.294546 -31.902146)
		(width 0.11684)
		(layer "F.Cu")
		(net "RST_ROT_CPU_R1_N")
	)
	(via
		(at 47.699676 -43.776138)
		(size 0.4572)
		(drill 0.254)
		(layers "F.Cu" "B.Cu")
		(net "RST_ROT_CPU_R1_N")
	)
	(via
		(at 47.2948 -31.9024)
		(size 0.508)
		(drill 0.254)
		(layers "F.Cu" "B.Cu")
		(net "RST_ROT_CPU_R1_N")
	)
	(segment
		(start 48.116236 -42.016934)
		(end 48.116236 -42.333164)
		(width 0.10668)
		(layer "In7.Cu")
		(net "RST_ROT_CPU_R1_N")
	)
	(segment
		(start 47.2948 -31.9024)
		(end 48.176688 -32.784288)
		(width 0.10668)
		(layer "In7.Cu")
		(net "RST_ROT_CPU_R1_N")
	)
	(segment
		(start 47.316136 -42.817034)
		(end 47.316136 -43.392598)
		(width 0.10668)
		(layer "In7.Cu")
		(net "RST_ROT_CPU_R1_N")
	)
	(segment
		(start 47.316136 -43.392598)
		(end 47.699676 -43.776138)
		(width 0.10668)
		(layer "In7.Cu")
		(net "RST_ROT_CPU_R1_N")
	)
	(segment
		(start 49.276 -35.8394)
		(end 49.276 -38.94836)
		(width 0.10668)
		(layer "In7.Cu")
		(net "RST_ROT_CPU_R1_N")
	)
	(segment
		(start 48.116236 -42.333164)
		(end 47.856902 -42.592498)
		(width 0.10668)
		(layer "In7.Cu")
		(net "RST_ROT_CPU_R1_N")
	)
	(segment
		(start 47.856902 -42.592498)
		(end 47.540672 -42.592498)
		(width 0.10668)
		(layer "In7.Cu")
		(net "RST_ROT_CPU_R1_N")
	)
	(segment
		(start 47.540672 -42.592498)
		(end 47.316136 -42.817034)
		(width 0.10668)
		(layer "In7.Cu")
		(net "RST_ROT_CPU_R1_N")
	)
	(segment
		(start 48.373284 -41.759632)
		(end 48.116236 -42.016934)
		(width 0.10668)
		(layer "In7.Cu")
		(net "RST_ROT_CPU_R1_N")
	)
	(segment
		(start 48.176688 -32.784288)
		(end 48.176688 -34.740088)
		(width 0.10668)
		(layer "In7.Cu")
		(net "RST_ROT_CPU_R1_N")
	)
	(segment
		(start 48.895 -39.32936)
		(end 48.895 -41.5798)
		(width 0.10668)
		(layer "In7.Cu")
		(net "RST_ROT_CPU_R1_N")
	)
	(segment
		(start 48.176688 -34.740088)
		(end 49.276 -35.8394)
		(width 0.10668)
		(layer "In7.Cu")
		(net "RST_ROT_CPU_R1_N")
	)
	(segment
		(start 48.715168 -41.759632)
		(end 48.373284 -41.759632)
		(width 0.10668)
		(layer "In7.Cu")
		(net "RST_ROT_CPU_R1_N")
	)
	(segment
		(start 49.276 -38.94836)
		(end 48.895 -39.32936)
		(width 0.10668)
		(layer "In7.Cu")
		(net "RST_ROT_CPU_R1_N")
	)
	(segment
		(start 48.895 -41.5798)
		(end 48.715168 -41.759632)
		(width 0.10668)
		(layer "In7.Cu")
		(net "RST_ROT_CPU_R1_N")
	)
	(segment
		(start 16.002 -102.34295)
		(end 16.002 -101.928676)
		(width 0.11684)
		(layer "F.Cu")
		(net "SMB_BMC_ALERT16_R2_N")
	)
	(segment
		(start 14.586204 -100.51288)
		(end 14.586204 -99.660202)
		(width 0.11684)
		(layer "F.Cu")
		(net "SMB_BMC_ALERT16_R2_N")
	)
	(segment
		(start 16.002 -101.928676)
		(end 14.586204 -100.51288)
		(width 0.11684)
		(layer "F.Cu")
		(net "SMB_BMC_ALERT16_R2_N")
	)
	(segment
		(start 14.586204 -99.660202)
		(end 15.459456 -98.78695)
		(width 0.11684)
		(layer "F.Cu")
		(net "SMB_BMC_ALERT16_R2_N")
	)
	(segment
		(start 12.71905 -95.182944)
		(end 12.71905 -95.504)
		(width 0.11684)
		(layer "F.Cu")
		(net "BMC_CPLD_GPIO_13_R2")
	)
	(segment
		(start 15.242032 -93.575632)
		(end 15.0114 -93.345)
		(width 0.11684)
		(layer "F.Cu")
		(net "BMC_CPLD_GPIO_13_R2")
	)
	(segment
		(start 15.0114 -93.345)
		(end 13.919454 -93.345)
		(width 0.11684)
		(layer "F.Cu")
		(net "BMC_CPLD_GPIO_13_R2")
	)
	(segment
		(start 15.620492 -93.575632)
		(end 15.242032 -93.575632)
		(width 0.11684)
		(layer "F.Cu")
		(net "BMC_CPLD_GPIO_13_R2")
	)
	(segment
		(start 13.5382 -93.726254)
		(end 13.5382 -94.363794)
		(width 0.11684)
		(layer "F.Cu")
		(net "BMC_CPLD_GPIO_13_R2")
	)
	(segment
		(start 16.259556 -93.187012)
		(end 16.009112 -93.187012)
		(width 0.11684)
		(layer "F.Cu")
		(net "BMC_CPLD_GPIO_13_R2")
	)
	(segment
		(start 13.919454 -93.345)
		(end 13.5382 -93.726254)
		(width 0.11684)
		(layer "F.Cu")
		(net "BMC_CPLD_GPIO_13_R2")
	)
	(segment
		(start 13.5382 -94.363794)
		(end 12.71905 -95.182944)
		(width 0.11684)
		(layer "F.Cu")
		(net "BMC_CPLD_GPIO_13_R2")
	)
	(segment
		(start 16.009112 -93.187012)
		(end 15.620492 -93.575632)
		(width 0.11684)
		(layer "F.Cu")
		(net "BMC_CPLD_GPIO_13_R2")
	)
	(segment
		(start 56.4642 -70.4088)
		(end 57.531 -69.342)
		(width 0.11684)
		(layer "F.Cu")
		(net "FLASH_WP_STATUS_R1")
	)
	(segment
		(start 52.894992 -42.571162)
		(end 52.499768 -42.175938)
		(width 0.11684)
		(layer "F.Cu")
		(net "FLASH_WP_STATUS_R1")
	)
	(segment
		(start 56.4642 -70.87235)
		(end 56.4642 -70.4088)
		(width 0.11684)
		(layer "F.Cu")
		(net "FLASH_WP_STATUS_R1")
	)
	(via
		(at 52.499768 -42.175938)
		(size 0.4572)
		(drill 0.254)
		(layers "F.Cu" "B.Cu")
		(net "FLASH_WP_STATUS_R1")
	)
	(via
		(at 57.531 -69.342)
		(size 0.508)
		(drill 0.254)
		(layers "F.Cu" "B.Cu")
		(net "FLASH_WP_STATUS_R1")
	)
	(segment
		(start 52.1208 -43.1292)
		(end 52.1208 -42.554906)
		(width 0.08382)
		(layer "In2.Cu")
		(net "FLASH_WP_STATUS_R1")
	)
	(segment
		(start 55.4736 -58.5724)
		(end 54.8386 -57.9374)
		(width 0.08382)
		(layer "In2.Cu")
		(net "FLASH_WP_STATUS_R1")
	)
	(segment
		(start 52.5272 -43.5356)
		(end 52.1208 -43.1292)
		(width 0.08382)
		(layer "In2.Cu")
		(net "FLASH_WP_STATUS_R1")
	)
	(segment
		(start 53.6956 -56.7436)
		(end 53.6956 -43.8404)
		(width 0.08382)
		(layer "In2.Cu")
		(net "FLASH_WP_STATUS_R1")
	)
	(segment
		(start 52.1208 -42.554906)
		(end 52.499768 -42.175938)
		(width 0.08382)
		(layer "In2.Cu")
		(net "FLASH_WP_STATUS_R1")
	)
	(segment
		(start 57.0484 -68.8594)
		(end 57.0484 -67.2338)
		(width 0.08382)
		(layer "In2.Cu")
		(net "FLASH_WP_STATUS_R1")
	)
	(segment
		(start 57.1754 -65.151)
		(end 57.3278 -64.9986)
		(width 0.08382)
		(layer "In2.Cu")
		(net "FLASH_WP_STATUS_R1")
	)
	(segment
		(start 54.8386 -57.9374)
		(end 54.8386 -57.531)
		(width 0.08382)
		(layer "In2.Cu")
		(net "FLASH_WP_STATUS_R1")
	)
	(segment
		(start 56.9468 -61.7982)
		(end 56.9468 -59.5884)
		(width 0.08382)
		(layer "In2.Cu")
		(net "FLASH_WP_STATUS_R1")
	)
	(segment
		(start 56.769 -62.8396)
		(end 56.769 -61.976)
		(width 0.08382)
		(layer "In2.Cu")
		(net "FLASH_WP_STATUS_R1")
	)
	(segment
		(start 57.3278 -64.9986)
		(end 57.3278 -63.3984)
		(width 0.08382)
		(layer "In2.Cu")
		(net "FLASH_WP_STATUS_R1")
	)
	(segment
		(start 55.9308 -58.5724)
		(end 55.4736 -58.5724)
		(width 0.08382)
		(layer "In2.Cu")
		(net "FLASH_WP_STATUS_R1")
	)
	(segment
		(start 54.3052 -56.9976)
		(end 53.9496 -56.9976)
		(width 0.08382)
		(layer "In2.Cu")
		(net "FLASH_WP_STATUS_R1")
	)
	(segment
		(start 56.769 -61.976)
		(end 56.9468 -61.7982)
		(width 0.08382)
		(layer "In2.Cu")
		(net "FLASH_WP_STATUS_R1")
	)
	(segment
		(start 57.1754 -67.1068)
		(end 57.1754 -65.151)
		(width 0.08382)
		(layer "In2.Cu")
		(net "FLASH_WP_STATUS_R1")
	)
	(segment
		(start 57.0484 -67.2338)
		(end 57.1754 -67.1068)
		(width 0.08382)
		(layer "In2.Cu")
		(net "FLASH_WP_STATUS_R1")
	)
	(segment
		(start 56.9468 -59.5884)
		(end 55.9308 -58.5724)
		(width 0.08382)
		(layer "In2.Cu")
		(net "FLASH_WP_STATUS_R1")
	)
	(segment
		(start 53.6956 -43.8404)
		(end 53.3908 -43.5356)
		(width 0.08382)
		(layer "In2.Cu")
		(net "FLASH_WP_STATUS_R1")
	)
	(segment
		(start 54.8386 -57.531)
		(end 54.3052 -56.9976)
		(width 0.08382)
		(layer "In2.Cu")
		(net "FLASH_WP_STATUS_R1")
	)
	(segment
		(start 53.3908 -43.5356)
		(end 52.5272 -43.5356)
		(width 0.08382)
		(layer "In2.Cu")
		(net "FLASH_WP_STATUS_R1")
	)
	(segment
		(start 53.9496 -56.9976)
		(end 53.6956 -56.7436)
		(width 0.08382)
		(layer "In2.Cu")
		(net "FLASH_WP_STATUS_R1")
	)
	(segment
		(start 57.531 -69.342)
		(end 57.0484 -68.8594)
		(width 0.08382)
		(layer "In2.Cu")
		(net "FLASH_WP_STATUS_R1")
	)
	(segment
		(start 57.3278 -63.3984)
		(end 56.769 -62.8396)
		(width 0.08382)
		(layer "In2.Cu")
		(net "FLASH_WP_STATUS_R1")
	)
	(segment
		(start 11.91895 -95.504)
		(end 11.30935 -95.504)
		(width 0.11684)
		(layer "F.Cu")
		(net "BMC_CPLD_GPIO_13")
	)
	(via
		(at 11.30935 -95.504)
		(size 0.508)
		(drill 0.254)
		(layers "F.Cu" "B.Cu")
		(net "BMC_CPLD_GPIO_13")
	)
	(segment
		(start 11.91895 -95.504)
		(end 11.30935 -95.504)
		(width 0.11684)
		(layer "B.Cu")
		(net "BMC_CPLD_GPIO_13")
	)
	(segment
		(start 13.208 -93.99905)
		(end 12.71905 -94.488)
		(width 0.11684)
		(layer "F.Cu")
		(net "BMC_CPLD_GPIO_12_R2")
	)
	(segment
		(start 15.459456 -92.387166)
		(end 14.343888 -92.387166)
		(width 0.11684)
		(layer "F.Cu")
		(net "BMC_CPLD_GPIO_12_R2")
	)
	(segment
		(start 13.208 -93.523054)
		(end 13.208 -93.99905)
		(width 0.11684)
		(layer "F.Cu")
		(net "BMC_CPLD_GPIO_12_R2")
	)
	(segment
		(start 14.343888 -92.387166)
		(end 13.208 -93.523054)
		(width 0.11684)
		(layer "F.Cu")
		(net "BMC_CPLD_GPIO_12_R2")
	)
	(segment
		(start 57.670446 -63.40475)
		(end 57.3278 -63.40475)
		(width 0.11684)
		(layer "F.Cu")
		(net "FM_FLASH_LATCH_N_R1")
	)
	(segment
		(start 57.785 -64.490854)
		(end 57.785 -63.519304)
		(width 0.11684)
		(layer "F.Cu")
		(net "FM_FLASH_LATCH_N_R1")
	)
	(segment
		(start 57.785 -63.519304)
		(end 57.670446 -63.40475)
		(width 0.11684)
		(layer "F.Cu")
		(net "FM_FLASH_LATCH_N_R1")
	)
	(segment
		(start 56.68772 -61.51118)
		(end 57.288684 -60.910216)
		(width 0.11684)
		(layer "F.Cu")
		(net "FM_FLASH_LATCH_N_R1")
	)
	(segment
		(start 57.19953 -65.076324)
		(end 57.785 -64.490854)
		(width 0.11684)
		(layer "F.Cu")
		(net "FM_FLASH_LATCH_N_R1")
	)
	(segment
		(start 57.19953 -65.76822)
		(end 57.19953 -65.076324)
		(width 0.11684)
		(layer "F.Cu")
		(net "FM_FLASH_LATCH_N_R1")
	)
	(segment
		(start 56.68772 -62.76467)
		(end 56.68772 -61.51118)
		(width 0.11684)
		(layer "F.Cu")
		(net "FM_FLASH_LATCH_N_R1")
	)
	(segment
		(start 57.288684 -60.910216)
		(end 57.288684 -58.96483)
		(width 0.11684)
		(layer "F.Cu")
		(net "FM_FLASH_LATCH_N_R1")
	)
	(segment
		(start 57.3278 -63.40475)
		(end 56.68772 -62.76467)
		(width 0.11684)
		(layer "F.Cu")
		(net "FM_FLASH_LATCH_N_R1")
	)
	(segment
		(start 57.288684 -58.96483)
		(end 56.894984 -58.57113)
		(width 0.11684)
		(layer "F.Cu")
		(net "FM_FLASH_LATCH_N_R1")
	)
	(segment
		(start 10.5156 -93.726)
		(end 9.3472 -93.726)
		(width 0.11684)
		(layer "F.Cu")
		(net "BMC_CPLD_GPIO_12")
	)
	(segment
		(start 11.91895 -94.488)
		(end 11.2776 -94.488)
		(width 0.11684)
		(layer "F.Cu")
		(net "BMC_CPLD_GPIO_12")
	)
	(segment
		(start 9.3472 -93.726)
		(end 9.1948 -93.5736)
		(width 0.11684)
		(layer "F.Cu")
		(net "BMC_CPLD_GPIO_12")
	)
	(segment
		(start 11.2776 -94.488)
		(end 10.5156 -93.726)
		(width 0.11684)
		(layer "F.Cu")
		(net "BMC_CPLD_GPIO_12")
	)
	(via
		(at 9.1948 -93.5736)
		(size 0.508)
		(drill 0.254)
		(layers "F.Cu" "B.Cu")
		(net "BMC_CPLD_GPIO_12")
	)
	(segment
		(start 9.1948 -93.5736)
		(end 9.74217 -93.5736)
		(width 0.11684)
		(layer "B.Cu")
		(net "BMC_CPLD_GPIO_12")
	)
	(segment
		(start 9.74217 -93.5736)
		(end 10.40892 -94.24035)
		(width 0.11684)
		(layer "B.Cu")
		(net "BMC_CPLD_GPIO_12")
	)
	(segment
		(start 50.69713 -96.051116)
		(end 50.336196 -96.41205)
		(width 0.11684)
		(layer "F.Cu")
		(net "BJT_Q3_C")
	)
	(segment
		(start 51.7525 -94.995746)
		(end 51.7525 -93.9546)
		(width 0.11684)
		(layer "F.Cu")
		(net "BJT_Q3_C")
	)
	(segment
		(start 50.69713 -96.051116)
		(end 51.7525 -94.995746)
		(width 0.11684)
		(layer "F.Cu")
		(net "BJT_Q3_C")
	)
	(segment
		(start 50.336196 -96.41205)
		(end 49.2125 -96.41205)
		(width 0.11684)
		(layer "F.Cu")
		(net "BJT_Q3_C")
	)
	(segment
		(start 49.647856 -91.634818)
		(end 49.235868 -91.634818)
		(width 0.11684)
		(layer "F.Cu")
		(net "BJT_Q3_B")
	)
	(segment
		(start 49.671224 -91.61145)
		(end 49.647856 -91.634818)
		(width 0.11684)
		(layer "F.Cu")
		(net "BJT_Q3_B")
	)
	(segment
		(start 49.93513 -91.61145)
		(end 49.671224 -91.61145)
		(width 0.11684)
		(layer "F.Cu")
		(net "BJT_Q3_B")
	)
	(segment
		(start 50.7365 -91.7194)
		(end 50.04308 -91.7194)
		(width 0.11684)
		(layer "F.Cu")
		(net "BJT_Q3_B")
	)
	(segment
		(start 50.04308 -91.7194)
		(end 49.93513 -91.61145)
		(width 0.11684)
		(layer "F.Cu")
		(net "BJT_Q3_B")
	)
	(segment
		(start 49.235868 -91.634818)
		(end 49.2125 -91.61145)
		(width 0.11684)
		(layer "F.Cu")
		(net "BJT_Q3_B")
	)
	(via
		(at 31.9278 -46.6598)
		(size 0.508)
		(drill 0.254)
		(layers "F.Cu" "B.Cu")
		(net "FM_ESPI_PLD_EN")
	)
	(via
		(at 16.2687 -51.05654)
		(size 0.508)
		(drill 0.254)
		(layers "F.Cu" "B.Cu")
		(net "FM_ESPI_PLD_EN")
	)
	(via
		(at 11.303 -88.392)
		(size 0.508)
		(drill 0.254)
		(layers "F.Cu" "B.Cu")
		(net "FM_ESPI_PLD_EN")
	)
	(via
		(at 32.7406 -46.6598)
		(size 0.6604)
		(drill 0.3302)
		(layers "F.Cu" "B.Cu")
		(net "FM_ESPI_PLD_EN")
	)
	(segment
		(start 37.572696 -42.96664)
		(end 35.49142 -45.047916)
		(width 0.11684)
		(layer "B.Cu")
		(net "FM_ESPI_PLD_EN")
	)
	(segment
		(start 35.49142 -45.761402)
		(end 34.593022 -46.6598)
		(width 0.11684)
		(layer "B.Cu")
		(net "FM_ESPI_PLD_EN")
	)
	(segment
		(start 34.593022 -46.6598)
		(end 32.7406 -46.6598)
		(width 0.11684)
		(layer "B.Cu")
		(net "FM_ESPI_PLD_EN")
	)
	(segment
		(start 39.71036 -43.52036)
		(end 39.15664 -42.96664)
		(width 0.11684)
		(layer "B.Cu")
		(net "FM_ESPI_PLD_EN")
	)
	(segment
		(start 41.56075 -43.9928)
		(end 41.190672 -43.9928)
		(width 0.11684)
		(layer "B.Cu")
		(net "FM_ESPI_PLD_EN")
	)
	(segment
		(start 39.15664 -42.96664)
		(end 37.572696 -42.96664)
		(width 0.11684)
		(layer "B.Cu")
		(net "FM_ESPI_PLD_EN")
	)
	(segment
		(start 35.49142 -45.047916)
		(end 35.49142 -45.761402)
		(width 0.11684)
		(layer "B.Cu")
		(net "FM_ESPI_PLD_EN")
	)
	(segment
		(start 31.9278 -46.6598)
		(end 32.7406 -46.6598)
		(width 0.11684)
		(layer "B.Cu")
		(net "FM_ESPI_PLD_EN")
	)
	(segment
		(start 41.190672 -43.9928)
		(end 40.718232 -43.52036)
		(width 0.11684)
		(layer "B.Cu")
		(net "FM_ESPI_PLD_EN")
	)
	(segment
		(start 11.91895 -88.392)
		(end 11.303 -88.392)
		(width 0.11684)
		(layer "B.Cu")
		(net "FM_ESPI_PLD_EN")
	)
	(segment
		(start 40.718232 -43.52036)
		(end 39.71036 -43.52036)
		(width 0.11684)
		(layer "B.Cu")
		(net "FM_ESPI_PLD_EN")
	)
	(segment
		(start 17.678146 -50.2666)
		(end 16.888206 -51.05654)
		(width 0.08382)
		(layer "In2.Cu")
		(net "FM_ESPI_PLD_EN")
	)
	(segment
		(start 22.290532 -47.792132)
		(end 19.816064 -50.2666)
		(width 0.08382)
		(layer "In2.Cu")
		(net "FM_ESPI_PLD_EN")
	)
	(segment
		(start 25.206452 -41.82364)
		(end 22.290532 -44.73956)
		(width 0.08382)
		(layer "In2.Cu")
		(net "FM_ESPI_PLD_EN")
	)
	(segment
		(start 31.9278 -46.6598)
		(end 31.60014 -46.33214)
		(width 0.08382)
		(layer "In2.Cu")
		(net "FM_ESPI_PLD_EN")
	)
	(segment
		(start 22.290532 -44.73956)
		(end 22.290532 -47.792132)
		(width 0.08382)
		(layer "In2.Cu")
		(net "FM_ESPI_PLD_EN")
	)
	(segment
		(start 31.60014 -46.33214)
		(end 31.60014 -44.61002)
		(width 0.08382)
		(layer "In2.Cu")
		(net "FM_ESPI_PLD_EN")
	)
	(segment
		(start 28.81376 -41.82364)
		(end 25.206452 -41.82364)
		(width 0.08382)
		(layer "In2.Cu")
		(net "FM_ESPI_PLD_EN")
	)
	(segment
		(start 31.60014 -44.61002)
		(end 28.81376 -41.82364)
		(width 0.08382)
		(layer "In2.Cu")
		(net "FM_ESPI_PLD_EN")
	)
	(segment
		(start 16.888206 -51.05654)
		(end 16.2687 -51.05654)
		(width 0.08382)
		(layer "In2.Cu")
		(net "FM_ESPI_PLD_EN")
	)
	(segment
		(start 19.816064 -50.2666)
		(end 17.678146 -50.2666)
		(width 0.08382)
		(layer "In2.Cu")
		(net "FM_ESPI_PLD_EN")
	)
	(segment
		(start 11.303 -88.392)
		(end 11.582146 -88.392)
		(width 0.08382)
		(layer "In9.Cu")
		(net "FM_ESPI_PLD_EN")
	)
	(segment
		(start 15.82166 -59.051444)
		(end 15.82166 -57.447688)
		(width 0.08382)
		(layer "In9.Cu")
		(net "FM_ESPI_PLD_EN")
	)
	(segment
		(start 15.82166 -57.447688)
		(end 16.03883 -57.230518)
		(width 0.08382)
		(layer "In9.Cu")
		(net "FM_ESPI_PLD_EN")
	)
	(segment
		(start 16.6751 -59.904884)
		(end 15.82166 -59.051444)
		(width 0.08382)
		(layer "In9.Cu")
		(net "FM_ESPI_PLD_EN")
	)
	(segment
		(start 16.03883 -51.49342)
		(end 16.2687 -51.26355)
		(width 0.08382)
		(layer "In9.Cu")
		(net "FM_ESPI_PLD_EN")
	)
	(segment
		(start 16.03883 -57.230518)
		(end 16.03883 -51.49342)
		(width 0.08382)
		(layer "In9.Cu")
		(net "FM_ESPI_PLD_EN")
	)
	(segment
		(start 16.6751 -61.87567)
		(end 16.6751 -59.904884)
		(width 0.08382)
		(layer "In9.Cu")
		(net "FM_ESPI_PLD_EN")
	)
	(segment
		(start 12.1412 -85.4202)
		(end 13.89634 -83.66506)
		(width 0.08382)
		(layer "In9.Cu")
		(net "FM_ESPI_PLD_EN")
	)
	(segment
		(start 13.89634 -83.66506)
		(end 13.89634 -80.617822)
		(width 0.08382)
		(layer "In9.Cu")
		(net "FM_ESPI_PLD_EN")
	)
	(segment
		(start 11.582146 -88.392)
		(end 12.1412 -87.832946)
		(width 0.08382)
		(layer "In9.Cu")
		(net "FM_ESPI_PLD_EN")
	)
	(segment
		(start 13.89634 -80.617822)
		(end 14.64818 -79.865982)
		(width 0.08382)
		(layer "In9.Cu")
		(net "FM_ESPI_PLD_EN")
	)
	(segment
		(start 14.64818 -79.865982)
		(end 14.64818 -78.652878)
		(width 0.08382)
		(layer "In9.Cu")
		(net "FM_ESPI_PLD_EN")
	)
	(segment
		(start 13.94841 -64.60236)
		(end 16.6751 -61.87567)
		(width 0.08382)
		(layer "In9.Cu")
		(net "FM_ESPI_PLD_EN")
	)
	(segment
		(start 13.94841 -77.953108)
		(end 13.94841 -64.60236)
		(width 0.08382)
		(layer "In9.Cu")
		(net "FM_ESPI_PLD_EN")
	)
	(segment
		(start 12.1412 -87.832946)
		(end 12.1412 -85.4202)
		(width 0.08382)
		(layer "In9.Cu")
		(net "FM_ESPI_PLD_EN")
	)
	(segment
		(start 14.64818 -78.652878)
		(end 13.94841 -77.953108)
		(width 0.08382)
		(layer "In9.Cu")
		(net "FM_ESPI_PLD_EN")
	)
	(segment
		(start 16.2687 -51.26355)
		(end 16.2687 -51.05654)
		(width 0.08382)
		(layer "In9.Cu")
		(net "FM_ESPI_PLD_EN")
	)
	(segment
		(start 40.887142 -63.126112)
		(end 43.943524 -60.06973)
		(width 0.11684)
		(layer "F.Cu")
		(net "I3C1_SDA_R")
	)
	(segment
		(start 44.78147 -60.06973)
		(end 45.2882 -59.563)
		(width 0.11684)
		(layer "F.Cu")
		(net "I3C1_SDA_R")
	)
	(segment
		(start 40.887142 -63.356744)
		(end 40.887142 -63.126112)
		(width 0.11684)
		(layer "F.Cu")
		(net "I3C1_SDA_R")
	)
	(segment
		(start 43.943524 -60.06973)
		(end 44.78147 -60.06973)
		(width 0.11684)
		(layer "F.Cu")
		(net "I3C1_SDA_R")
	)
	(segment
		(start 45.508926 -58.961274)
		(end 46.10481 -58.961274)
		(width 0.11684)
		(layer "F.Cu")
		(net "I3C1_SDA_R")
	)
	(segment
		(start 45.2882 -59.563)
		(end 45.2882 -59.182)
		(width 0.11684)
		(layer "F.Cu")
		(net "I3C1_SDA_R")
	)
	(segment
		(start 45.2882 -59.182)
		(end 45.508926 -58.961274)
		(width 0.11684)
		(layer "F.Cu")
		(net "I3C1_SDA_R")
	)
	(segment
		(start 46.10481 -58.961274)
		(end 46.494954 -58.57113)
		(width 0.11684)
		(layer "F.Cu")
		(net "I3C1_SDA_R")
	)
	(segment
		(start 42.4942 -64.089788)
		(end 42.992294 -62.887352)
		(width 0.11684)
		(layer "F.Cu")
		(net "I3C1_SCL_R")
	)
	(segment
		(start 42.189654 -65.376044)
		(end 42.4942 -65.071498)
		(width 0.11684)
		(layer "F.Cu")
		(net "I3C1_SCL_R")
	)
	(segment
		(start 42.992294 -62.887352)
		(end 44.040552 -61.839094)
		(width 0.11684)
		(layer "F.Cu")
		(net "I3C1_SCL_R")
	)
	(segment
		(start 44.040552 -61.839094)
		(end 45.044106 -61.839094)
		(width 0.11684)
		(layer "F.Cu")
		(net "I3C1_SCL_R")
	)
	(segment
		(start 41.859454 -65.376044)
		(end 42.189654 -65.376044)
		(width 0.11684)
		(layer "F.Cu")
		(net "I3C1_SCL_R")
	)
	(segment
		(start 47.295054 -59.588146)
		(end 47.295054 -59.37123)
		(width 0.11684)
		(layer "F.Cu")
		(net "I3C1_SCL_R")
	)
	(segment
		(start 42.4942 -65.071498)
		(end 42.4942 -64.089788)
		(width 0.11684)
		(layer "F.Cu")
		(net "I3C1_SCL_R")
	)
	(segment
		(start 45.044106 -61.839094)
		(end 47.295054 -59.588146)
		(width 0.11684)
		(layer "F.Cu")
		(net "I3C1_SCL_R")
	)
	(segment
		(start 9.52119 -65.736978)
		(end 8.799068 -65.736978)
		(width 0.254)
		(layer "F.Cu")
		(net "P3V3_AUX_REF")
	)
	(segment
		(start 10.497566 -65.948052)
		(end 10.072624 -65.948052)
		(width 0.254)
		(layer "F.Cu")
		(net "P3V3_AUX_REF")
	)
	(segment
		(start 10.072624 -65.948052)
		(end 9.86155 -65.736978)
		(width 0.254)
		(layer "F.Cu")
		(net "P3V3_AUX_REF")
	)
	(segment
		(start 9.86155 -65.736978)
		(end 9.52119 -65.736978)
		(width 0.254)
		(layer "F.Cu")
		(net "P3V3_AUX_REF")
	)
	(via
		(at 9.52119 -65.736978)
		(size 0.508)
		(drill 0.254)
		(layers "F.Cu" "B.Cu")
		(net "P3V3_AUX_REF")
	)
	(segment
		(start 6.27507 -65.726818)
		(end 6.28523 -65.736978)
		(width 0.254)
		(layer "F.Cu")
		(net "P3V3_AUX_MODE")
	)
	(segment
		(start 5.4102 -65.983358)
		(end 6.01853 -65.983358)
		(width 0.254)
		(layer "F.Cu")
		(net "P3V3_AUX_MODE")
	)
	(segment
		(start 6.28523 -65.736978)
		(end 6.799072 -65.736978)
		(width 0.254)
		(layer "F.Cu")
		(net "P3V3_AUX_MODE")
	)
	(segment
		(start 6.01853 -65.983358)
		(end 6.27507 -65.726818)
		(width 0.254)
		(layer "F.Cu")
		(net "P3V3_AUX_MODE")
	)
	(via
		(at 6.27507 -65.726818)
		(size 0.508)
		(drill 0.254)
		(layers "F.Cu" "B.Cu")
		(net "P3V3_AUX_MODE")
	)
	(segment
		(start 9.08939 -62.513464)
		(end 9.249918 -62.513464)
		(width 0.254)
		(layer "F.Cu")
		(net "P3V3_AUX_CS")
	)
	(segment
		(start 8.298942 -63.937134)
		(end 8.298942 -63.303912)
		(width 0.254)
		(layer "F.Cu")
		(net "P3V3_AUX_CS")
	)
	(segment
		(start 8.298942 -63.303912)
		(end 9.08939 -62.513464)
		(width 0.254)
		(layer "F.Cu")
		(net "P3V3_AUX_CS")
	)
	(segment
		(start 24.3332 -31.03245)
		(end 24.356314 -31.009336)
		(width 0.381)
		(layer "F.Cu")
		(net "PVCC2_AUX")
	)
	(segment
		(start 24.511762 -31.625286)
		(end 24.3332 -31.446724)
		(width 0.381)
		(layer "F.Cu")
		(net "PVCC2_AUX")
	)
	(segment
		(start 24.511762 -32.130492)
		(end 24.511762 -31.625286)
		(width 0.381)
		(layer "F.Cu")
		(net "PVCC2_AUX")
	)
	(segment
		(start 24.768556 -31.009336)
		(end 24.769572 -31.00832)
		(width 0.381)
		(layer "F.Cu")
		(net "PVCC2_AUX")
	)
	(segment
		(start 24.769572 -31.00832)
		(end 24.887428 -31.00832)
		(width 0.381)
		(layer "F.Cu")
		(net "PVCC2_AUX")
	)
	(segment
		(start 23.34895 -31.98495)
		(end 23.622 -32.258)
		(width 0.381)
		(layer "F.Cu")
		(net "PVCC2_AUX")
	)
	(segment
		(start 24.888444 -31.009336)
		(end 25.300686 -31.009336)
		(width 0.381)
		(layer "F.Cu")
		(net "PVCC2_AUX")
	)
	(segment
		(start 24.887428 -31.00832)
		(end 24.888444 -31.009336)
		(width 0.381)
		(layer "F.Cu")
		(net "PVCC2_AUX")
	)
	(segment
		(start 23.622 -32.258)
		(end 24.003 -32.258)
		(width 0.381)
		(layer "F.Cu")
		(net "PVCC2_AUX")
	)
	(segment
		(start 24.003 -32.258)
		(end 24.384254 -32.258)
		(width 0.381)
		(layer "F.Cu")
		(net "PVCC2_AUX")
	)
	(segment
		(start 24.356314 -31.009336)
		(end 24.768556 -31.009336)
		(width 0.381)
		(layer "F.Cu")
		(net "PVCC2_AUX")
	)
	(segment
		(start 24.384254 -32.258)
		(end 24.511762 -32.130492)
		(width 0.381)
		(layer "F.Cu")
		(net "PVCC2_AUX")
	)
	(segment
		(start 23.34895 -31.031434)
		(end 23.34895 -31.98495)
		(width 0.381)
		(layer "F.Cu")
		(net "PVCC2_AUX")
	)
	(segment
		(start 25.300686 -31.009336)
		(end 25.3238 -31.03245)
		(width 0.381)
		(layer "F.Cu")
		(net "PVCC2_AUX")
	)
	(segment
		(start 24.3332 -31.446724)
		(end 24.3332 -31.03245)
		(width 0.381)
		(layer "F.Cu")
		(net "PVCC2_AUX")
	)
	(via
		(at 24.003 -32.258)
		(size 0.762)
		(drill 0.381)
		(layers "F.Cu" "B.Cu")
		(net "PVCC2_AUX")
	)
	(segment
		(start 85.749638 -70.058788)
		(end 85.7504 -70.05955)
		(width 0.381)
		(layer "F.Cu")
		(net "PVCC1_AUX")
	)
	(segment
		(start 83.77555 -70.058788)
		(end 84.795106 -70.058788)
		(width 0.381)
		(layer "F.Cu")
		(net "PVCC1_AUX")
	)
	(segment
		(start 84.795106 -70.058788)
		(end 85.749638 -70.058788)
		(width 0.381)
		(layer "F.Cu")
		(net "PVCC1_AUX")
	)
	(segment
		(start 17.059402 -89.98712)
		(end 16.664178 -89.591896)
		(width 0.11684)
		(layer "F.Cu")
		(net "H_CPU0_MEMTRIP_LVC1_N")
	)
	(segment
		(start 47.295054 -56.171338)
		(end 46.89983 -56.566562)
		(width 0.11684)
		(layer "F.Cu")
		(net "H_CPU0_MEMTRIP_LVC1_N")
	)
	(via
		(at 16.664178 -89.591896)
		(size 0.4572)
		(drill 0.254)
		(layers "F.Cu" "B.Cu")
		(net "H_CPU0_MEMTRIP_LVC1_N")
	)
	(via
		(at 46.89983 -56.566562)
		(size 0.4572)
		(drill 0.254)
		(layers "F.Cu" "B.Cu")
		(net "H_CPU0_MEMTRIP_LVC1_N")
	)
	(segment
		(start 44.345606 -57.794398)
		(end 44.069 -58.071004)
		(width 0.08382)
		(layer "In9.Cu")
		(net "H_CPU0_MEMTRIP_LVC1_N")
	)
	(segment
		(start 45.945552 -56.994298)
		(end 45.671994 -57.267856)
		(width 0.08382)
		(layer "In9.Cu")
		(net "H_CPU0_MEMTRIP_LVC1_N")
	)
	(segment
		(start 45.671994 -57.520586)
		(end 45.398182 -57.794398)
		(width 0.08382)
		(layer "In9.Cu")
		(net "H_CPU0_MEMTRIP_LVC1_N")
	)
	(segment
		(start 31.9786 -80.327754)
		(end 30.44698 -81.859374)
		(width 0.08382)
		(layer "In9.Cu")
		(net "H_CPU0_MEMTRIP_LVC1_N")
	)
	(segment
		(start 43.320716 -59.203844)
		(end 43.320716 -59.876182)
		(width 0.08382)
		(layer "In9.Cu")
		(net "H_CPU0_MEMTRIP_LVC1_N")
	)
	(segment
		(start 35.203638 -73.082912)
		(end 34.917888 -73.082912)
		(width 0.08382)
		(layer "In9.Cu")
		(net "H_CPU0_MEMTRIP_LVC1_N")
	)
	(segment
		(start 29.6164 -90.85072)
		(end 29.6164 -92.8116)
		(width 0.08382)
		(layer "In9.Cu")
		(net "H_CPU0_MEMTRIP_LVC1_N")
	)
	(segment
		(start 17.1958 -93.1672)
		(end 17.0434 -93.0148)
		(width 0.08382)
		(layer "In9.Cu")
		(net "H_CPU0_MEMTRIP_LVC1_N")
	)
	(segment
		(start 17.0434 -93.0148)
		(end 17.0434 -90.0938)
		(width 0.08382)
		(layer "In9.Cu")
		(net "H_CPU0_MEMTRIP_LVC1_N")
	)
	(segment
		(start 33.335976 -77.012546)
		(end 31.9786 -78.369922)
		(width 0.08382)
		(layer "In9.Cu")
		(net "H_CPU0_MEMTRIP_LVC1_N")
	)
	(segment
		(start 27.8384 -93.4466)
		(end 27.559 -93.1672)
		(width 0.08382)
		(layer "In9.Cu")
		(net "H_CPU0_MEMTRIP_LVC1_N")
	)
	(segment
		(start 29.92882 -90.5383)
		(end 29.6164 -90.85072)
		(width 0.08382)
		(layer "In9.Cu")
		(net "H_CPU0_MEMTRIP_LVC1_N")
	)
	(segment
		(start 44.069 -58.45556)
		(end 43.320716 -59.203844)
		(width 0.08382)
		(layer "In9.Cu")
		(net "H_CPU0_MEMTRIP_LVC1_N")
	)
	(segment
		(start 38.70198 -68.735956)
		(end 36.9443 -70.493636)
		(width 0.08382)
		(layer "In9.Cu")
		(net "H_CPU0_MEMTRIP_LVC1_N")
	)
	(segment
		(start 46.488604 -56.736996)
		(end 46.231302 -56.994298)
		(width 0.08382)
		(layer "In9.Cu")
		(net "H_CPU0_MEMTRIP_LVC1_N")
	)
	(segment
		(start 27.559 -93.1672)
		(end 17.1958 -93.1672)
		(width 0.08382)
		(layer "In9.Cu")
		(net "H_CPU0_MEMTRIP_LVC1_N")
	)
	(segment
		(start 30.44698 -86.885526)
		(end 29.92882 -87.403686)
		(width 0.08382)
		(layer "In9.Cu")
		(net "H_CPU0_MEMTRIP_LVC1_N")
	)
	(segment
		(start 38.90391 -64.082168)
		(end 38.90391 -66.083688)
		(width 0.08382)
		(layer "In9.Cu")
		(net "H_CPU0_MEMTRIP_LVC1_N")
	)
	(segment
		(start 45.671994 -57.267856)
		(end 45.671994 -57.520586)
		(width 0.08382)
		(layer "In9.Cu")
		(net "H_CPU0_MEMTRIP_LVC1_N")
	)
	(segment
		(start 43.320716 -59.876182)
		(end 39.721028 -63.47587)
		(width 0.08382)
		(layer "In9.Cu")
		(net "H_CPU0_MEMTRIP_LVC1_N")
	)
	(segment
		(start 38.70198 -66.285618)
		(end 38.70198 -68.735956)
		(width 0.08382)
		(layer "In9.Cu")
		(net "H_CPU0_MEMTRIP_LVC1_N")
	)
	(segment
		(start 36.9443 -71.34225)
		(end 35.203638 -73.082912)
		(width 0.08382)
		(layer "In9.Cu")
		(net "H_CPU0_MEMTRIP_LVC1_N")
	)
	(segment
		(start 46.231302 -56.994298)
		(end 45.945552 -56.994298)
		(width 0.08382)
		(layer "In9.Cu")
		(net "H_CPU0_MEMTRIP_LVC1_N")
	)
	(segment
		(start 45.398182 -57.794398)
		(end 44.345606 -57.794398)
		(width 0.08382)
		(layer "In9.Cu")
		(net "H_CPU0_MEMTRIP_LVC1_N")
	)
	(segment
		(start 33.335976 -74.664824)
		(end 33.335976 -77.012546)
		(width 0.08382)
		(layer "In9.Cu")
		(net "H_CPU0_MEMTRIP_LVC1_N")
	)
	(segment
		(start 38.90391 -66.083688)
		(end 38.70198 -66.285618)
		(width 0.08382)
		(layer "In9.Cu")
		(net "H_CPU0_MEMTRIP_LVC1_N")
	)
	(segment
		(start 16.664178 -89.714578)
		(end 16.664178 -89.591896)
		(width 0.08382)
		(layer "In9.Cu")
		(net "H_CPU0_MEMTRIP_LVC1_N")
	)
	(segment
		(start 34.917888 -73.082912)
		(end 33.335976 -74.664824)
		(width 0.08382)
		(layer "In9.Cu")
		(net "H_CPU0_MEMTRIP_LVC1_N")
	)
	(segment
		(start 28.9814 -93.4466)
		(end 27.8384 -93.4466)
		(width 0.08382)
		(layer "In9.Cu")
		(net "H_CPU0_MEMTRIP_LVC1_N")
	)
	(segment
		(start 39.721028 -63.47587)
		(end 39.510208 -63.47587)
		(width 0.08382)
		(layer "In9.Cu")
		(net "H_CPU0_MEMTRIP_LVC1_N")
	)
	(segment
		(start 31.9786 -78.369922)
		(end 31.9786 -80.327754)
		(width 0.08382)
		(layer "In9.Cu")
		(net "H_CPU0_MEMTRIP_LVC1_N")
	)
	(segment
		(start 29.92882 -87.403686)
		(end 29.92882 -90.5383)
		(width 0.08382)
		(layer "In9.Cu")
		(net "H_CPU0_MEMTRIP_LVC1_N")
	)
	(segment
		(start 36.9443 -70.493636)
		(end 36.9443 -71.34225)
		(width 0.08382)
		(layer "In9.Cu")
		(net "H_CPU0_MEMTRIP_LVC1_N")
	)
	(segment
		(start 17.0434 -90.0938)
		(end 16.664178 -89.714578)
		(width 0.08382)
		(layer "In9.Cu")
		(net "H_CPU0_MEMTRIP_LVC1_N")
	)
	(segment
		(start 44.069 -58.071004)
		(end 44.069 -58.45556)
		(width 0.08382)
		(layer "In9.Cu")
		(net "H_CPU0_MEMTRIP_LVC1_N")
	)
	(segment
		(start 30.44698 -81.859374)
		(end 30.44698 -86.885526)
		(width 0.08382)
		(layer "In9.Cu")
		(net "H_CPU0_MEMTRIP_LVC1_N")
	)
	(segment
		(start 46.89983 -56.566562)
		(end 46.488604 -56.736996)
		(width 0.08382)
		(layer "In9.Cu")
		(net "H_CPU0_MEMTRIP_LVC1_N")
	)
	(segment
		(start 39.510208 -63.47587)
		(end 38.90391 -64.082168)
		(width 0.08382)
		(layer "In9.Cu")
		(net "H_CPU0_MEMTRIP_LVC1_N")
	)
	(segment
		(start 29.6164 -92.8116)
		(end 28.9814 -93.4466)
		(width 0.08382)
		(layer "In9.Cu")
		(net "H_CPU0_MEMTRIP_LVC1_N")
	)
	(segment
		(start 44.085764 -51.35245)
		(end 44.085764 -50.186082)
		(width 0.11684)
		(layer "F.Cu")
		(net "FM_THERMTRIP_DLY_LVC1_R_N")
	)
	(segment
		(start 40.55745 -50.292)
		(end 39.97325 -49.7078)
		(width 0.11684)
		(layer "F.Cu")
		(net "FM_THERMTRIP_DLY_LVC1_R_N")
	)
	(segment
		(start 44.895008 -51.371246)
		(end 44.499784 -51.76647)
		(width 0.11684)
		(layer "F.Cu")
		(net "FM_THERMTRIP_DLY_LVC1_R_N")
	)
	(segment
		(start 42.570654 -50.292)
		(end 41.8592 -50.292)
		(width 0.11684)
		(layer "F.Cu")
		(net "FM_THERMTRIP_DLY_LVC1_R_N")
	)
	(segment
		(start 16.259556 -87.587074)
		(end 15.864332 -87.19185)
		(width 0.11684)
		(layer "F.Cu")
		(net "FM_THERMTRIP_DLY_LVC1_R_N")
	)
	(segment
		(start 44.085764 -50.186082)
		(end 43.828462 -49.92878)
		(width 0.11684)
		(layer "F.Cu")
		(net "FM_THERMTRIP_DLY_LVC1_R_N")
	)
	(segment
		(start 41.8592 -50.292)
		(end 40.55745 -50.292)
		(width 0.11684)
		(layer "F.Cu")
		(net "FM_THERMTRIP_DLY_LVC1_R_N")
	)
	(segment
		(start 42.933874 -49.92878)
		(end 42.570654 -50.292)
		(width 0.11684)
		(layer "F.Cu")
		(net "FM_THERMTRIP_DLY_LVC1_R_N")
	)
	(segment
		(start 43.828462 -49.92878)
		(end 42.933874 -49.92878)
		(width 0.11684)
		(layer "F.Cu")
		(net "FM_THERMTRIP_DLY_LVC1_R_N")
	)
	(segment
		(start 44.499784 -51.76647)
		(end 44.085764 -51.35245)
		(width 0.11684)
		(layer "F.Cu")
		(net "FM_THERMTRIP_DLY_LVC1_R_N")
	)
	(via
		(at 41.8592 -50.292)
		(size 0.762)
		(drill 0.381)
		(layers "F.Cu" "B.Cu")
		(net "FM_THERMTRIP_DLY_LVC1_R_N")
	)
	(via
		(at 44.499784 -51.76647)
		(size 0.4572)
		(drill 0.254)
		(layers "F.Cu" "B.Cu")
		(net "FM_THERMTRIP_DLY_LVC1_R_N")
	)
	(via
		(at 15.864332 -87.19185)
		(size 0.4572)
		(drill 0.254)
		(layers "F.Cu" "B.Cu")
		(net "FM_THERMTRIP_DLY_LVC1_R_N")
	)
	(segment
		(start 17.000982 -86.0552)
		(end 18.643346 -86.0552)
		(width 0.08382)
		(layer "In9.Cu")
		(net "FM_THERMTRIP_DLY_LVC1_R_N")
	)
	(segment
		(start 33.541208 -63.386462)
		(end 33.541208 -61.51118)
		(width 0.08382)
		(layer "In9.Cu")
		(net "FM_THERMTRIP_DLY_LVC1_R_N")
	)
	(segment
		(start 35.079686 -59.870086)
		(end 35.07994 -59.869578)
		(width 0.08382)
		(layer "In9.Cu")
		(net "FM_THERMTRIP_DLY_LVC1_R_N")
	)
	(segment
		(start 20.091146 -87.503)
		(end 24.9174 -87.503)
		(width 0.08382)
		(layer "In9.Cu")
		(net "FM_THERMTRIP_DLY_LVC1_R_N")
	)
	(segment
		(start 34.765234 -64.86906)
		(end 34.765234 -64.610488)
		(width 0.08382)
		(layer "In9.Cu")
		(net "FM_THERMTRIP_DLY_LVC1_R_N")
	)
	(segment
		(start 26.6954 -84.49056)
		(end 27.901138 -83.284822)
		(width 0.08382)
		(layer "In9.Cu")
		(net "FM_THERMTRIP_DLY_LVC1_R_N")
	)
	(segment
		(start 24.9174 -87.503)
		(end 26.6954 -85.725)
		(width 0.08382)
		(layer "In9.Cu")
		(net "FM_THERMTRIP_DLY_LVC1_R_N")
	)
	(segment
		(start 34.765234 -64.610488)
		(end 33.541208 -63.386462)
		(width 0.08382)
		(layer "In9.Cu")
		(net "FM_THERMTRIP_DLY_LVC1_R_N")
	)
	(segment
		(start 34.76498 -65.77838)
		(end 34.76498 -64.869314)
		(width 0.08382)
		(layer "In9.Cu")
		(net "FM_THERMTRIP_DLY_LVC1_R_N")
	)
	(segment
		(start 41.820592 -50.675286)
		(end 42.242232 -50.675286)
		(width 0.08382)
		(layer "In9.Cu")
		(net "FM_THERMTRIP_DLY_LVC1_R_N")
	)
	(segment
		(start 34.76498 -64.869314)
		(end 34.765234 -64.86906)
		(width 0.08382)
		(layer "In9.Cu")
		(net "FM_THERMTRIP_DLY_LVC1_R_N")
	)
	(segment
		(start 26.6954 -85.725)
		(end 26.6954 -84.49056)
		(width 0.08382)
		(layer "In9.Cu")
		(net "FM_THERMTRIP_DLY_LVC1_R_N")
	)
	(segment
		(start 39.612316 -55.861712)
		(end 39.90594 -55.152798)
		(width 0.08382)
		(layer "In9.Cu")
		(net "FM_THERMTRIP_DLY_LVC1_R_N")
	)
	(segment
		(start 32.03702 -71.289418)
		(end 32.03702 -70.866508)
		(width 0.08382)
		(layer "In9.Cu")
		(net "FM_THERMTRIP_DLY_LVC1_R_N")
	)
	(segment
		(start 39.90594 -54.19598)
		(end 40.192706 -53.909214)
		(width 0.08382)
		(layer "In9.Cu")
		(net "FM_THERMTRIP_DLY_LVC1_R_N")
	)
	(segment
		(start 34.88309 -59.95162)
		(end 34.883598 -59.951366)
		(width 0.08382)
		(layer "In9.Cu")
		(net "FM_THERMTRIP_DLY_LVC1_R_N")
	)
	(segment
		(start 27.901138 -83.284822)
		(end 27.901138 -77.571092)
		(width 0.08382)
		(layer "In9.Cu")
		(net "FM_THERMTRIP_DLY_LVC1_R_N")
	)
	(segment
		(start 34.46907 -60.12307)
		(end 34.49447 -60.112656)
		(width 0.08382)
		(layer "In9.Cu")
		(net "FM_THERMTRIP_DLY_LVC1_R_N")
	)
	(segment
		(start 39.90594 -55.152798)
		(end 39.90594 -54.19598)
		(width 0.08382)
		(layer "In9.Cu")
		(net "FM_THERMTRIP_DLY_LVC1_R_N")
	)
	(segment
		(start 29.536136 -73.790302)
		(end 32.03702 -71.289418)
		(width 0.08382)
		(layer "In9.Cu")
		(net "FM_THERMTRIP_DLY_LVC1_R_N")
	)
	(segment
		(start 34.49447 -60.112656)
		(end 34.88309 -59.95162)
		(width 0.08382)
		(layer "In9.Cu")
		(net "FM_THERMTRIP_DLY_LVC1_R_N")
	)
	(segment
		(start 43.333416 -51.76647)
		(end 44.499784 -51.76647)
		(width 0.08382)
		(layer "In9.Cu")
		(net "FM_THERMTRIP_DLY_LVC1_R_N")
	)
	(segment
		(start 15.864332 -87.19185)
		(end 17.000982 -86.0552)
		(width 0.08382)
		(layer "In9.Cu")
		(net "FM_THERMTRIP_DLY_LVC1_R_N")
	)
	(segment
		(start 33.1724 -68.545202)
		(end 33.95853 -67.759072)
		(width 0.08382)
		(layer "In9.Cu")
		(net "FM_THERMTRIP_DLY_LVC1_R_N")
	)
	(segment
		(start 27.901138 -77.571092)
		(end 29.15285 -76.31938)
		(width 0.08382)
		(layer "In9.Cu")
		(net "FM_THERMTRIP_DLY_LVC1_R_N")
	)
	(segment
		(start 33.95853 -66.58483)
		(end 34.76498 -65.77838)
		(width 0.08382)
		(layer "In9.Cu")
		(net "FM_THERMTRIP_DLY_LVC1_R_N")
	)
	(segment
		(start 36.46424 -59.296046)
		(end 37.900864 -58.336434)
		(width 0.08382)
		(layer "In9.Cu")
		(net "FM_THERMTRIP_DLY_LVC1_R_N")
	)
	(segment
		(start 35.047936 -59.883294)
		(end 35.079686 -59.870086)
		(width 0.08382)
		(layer "In9.Cu")
		(net "FM_THERMTRIP_DLY_LVC1_R_N")
	)
	(segment
		(start 40.192706 -53.909214)
		(end 40.192706 -52.76469)
		(width 0.08382)
		(layer "In9.Cu")
		(net "FM_THERMTRIP_DLY_LVC1_R_N")
	)
	(segment
		(start 41.0718 -51.424078)
		(end 41.820592 -50.675286)
		(width 0.08382)
		(layer "In9.Cu")
		(net "FM_THERMTRIP_DLY_LVC1_R_N")
	)
	(segment
		(start 32.03702 -70.866508)
		(end 33.1724 -69.731128)
		(width 0.08382)
		(layer "In9.Cu")
		(net "FM_THERMTRIP_DLY_LVC1_R_N")
	)
	(segment
		(start 35.07994 -59.869578)
		(end 36.46424 -59.296046)
		(width 0.08382)
		(layer "In9.Cu")
		(net "FM_THERMTRIP_DLY_LVC1_R_N")
	)
	(segment
		(start 33.95853 -67.759072)
		(end 33.95853 -66.58483)
		(width 0.08382)
		(layer "In9.Cu")
		(net "FM_THERMTRIP_DLY_LVC1_R_N")
	)
	(segment
		(start 29.15285 -76.31938)
		(end 29.536136 -75.392788)
		(width 0.08382)
		(layer "In9.Cu")
		(net "FM_THERMTRIP_DLY_LVC1_R_N")
	)
	(segment
		(start 37.900864 -58.336434)
		(end 38.55974 -57.677558)
		(width 0.08382)
		(layer "In9.Cu")
		(net "FM_THERMTRIP_DLY_LVC1_R_N")
	)
	(segment
		(start 29.536136 -75.392788)
		(end 29.536136 -73.790302)
		(width 0.08382)
		(layer "In9.Cu")
		(net "FM_THERMTRIP_DLY_LVC1_R_N")
	)
	(segment
		(start 41.0718 -51.885596)
		(end 41.0718 -51.424078)
		(width 0.08382)
		(layer "In9.Cu")
		(net "FM_THERMTRIP_DLY_LVC1_R_N")
	)
	(segment
		(start 42.242232 -50.675286)
		(end 43.333416 -51.76647)
		(width 0.08382)
		(layer "In9.Cu")
		(net "FM_THERMTRIP_DLY_LVC1_R_N")
	)
	(segment
		(start 34.883598 -59.951366)
		(end 35.047936 -59.883294)
		(width 0.08382)
		(layer "In9.Cu")
		(net "FM_THERMTRIP_DLY_LVC1_R_N")
	)
	(segment
		(start 38.55974 -57.677558)
		(end 38.55974 -56.913526)
		(width 0.08382)
		(layer "In9.Cu")
		(net "FM_THERMTRIP_DLY_LVC1_R_N")
	)
	(segment
		(start 40.192706 -52.76469)
		(end 41.0718 -51.885596)
		(width 0.08382)
		(layer "In9.Cu")
		(net "FM_THERMTRIP_DLY_LVC1_R_N")
	)
	(segment
		(start 18.643346 -86.0552)
		(end 20.091146 -87.503)
		(width 0.08382)
		(layer "In9.Cu")
		(net "FM_THERMTRIP_DLY_LVC1_R_N")
	)
	(segment
		(start 33.1724 -69.731128)
		(end 33.1724 -68.545202)
		(width 0.08382)
		(layer "In9.Cu")
		(net "FM_THERMTRIP_DLY_LVC1_R_N")
	)
	(segment
		(start 38.55974 -56.913526)
		(end 39.612316 -55.861712)
		(width 0.08382)
		(layer "In9.Cu")
		(net "FM_THERMTRIP_DLY_LVC1_R_N")
	)
	(segment
		(start 33.541208 -61.51118)
		(end 34.46907 -60.12307)
		(width 0.08382)
		(layer "In9.Cu")
		(net "FM_THERMTRIP_DLY_LVC1_R_N")
	)
	(segment
		(start 48.0949 -56.171338)
		(end 47.699676 -56.566562)
		(width 0.11684)
		(layer "F.Cu")
		(net "FM_PWR_BTN")
	)
	(via
		(at 44.740576 -59.147202)
		(size 0.6604)
		(drill 0.3302)
		(layers "F.Cu" "B.Cu")
		(net "FM_PWR_BTN")
	)
	(via
		(at 18.544794 -62.57671)
		(size 0.508)
		(drill 0.254)
		(layers "F.Cu" "B.Cu")
		(net "FM_PWR_BTN")
	)
	(via
		(at 47.699676 -56.566562)
		(size 0.4572)
		(drill 0.254)
		(layers "F.Cu" "B.Cu")
		(net "FM_PWR_BTN")
	)
	(via
		(at 9.4742 -95.25)
		(size 0.508)
		(drill 0.254)
		(layers "F.Cu" "B.Cu")
		(net "FM_PWR_BTN")
	)
	(segment
		(start 43.815 -59.3598)
		(end 44.027598 -59.147202)
		(width 0.11684)
		(layer "B.Cu")
		(net "FM_PWR_BTN")
	)
	(segment
		(start 9.1186 -96.148906)
		(end 9.427464 -96.45777)
		(width 0.11684)
		(layer "B.Cu")
		(net "FM_PWR_BTN")
	)
	(segment
		(start 47.038006 -57.777888)
		(end 45.938694 -57.777888)
		(width 0.11684)
		(layer "B.Cu")
		(net "FM_PWR_BTN")
	)
	(segment
		(start 11.91895 -96.170496)
		(end 11.91895 -96.52)
		(width 0.11684)
		(layer "B.Cu")
		(net "FM_PWR_BTN")
	)
	(segment
		(start 45.71111 -58.58129)
		(end 45.145198 -59.147202)
		(width 0.11684)
		(layer "B.Cu")
		(net "FM_PWR_BTN")
	)
	(segment
		(start 47.28845 -56.977788)
		(end 47.28845 -57.527444)
		(width 0.11684)
		(layer "B.Cu")
		(net "FM_PWR_BTN")
	)
	(segment
		(start 45.938694 -57.777888)
		(end 45.71111 -58.005472)
		(width 0.11684)
		(layer "B.Cu")
		(net "FM_PWR_BTN")
	)
	(segment
		(start 44.027598 -59.147202)
		(end 44.740576 -59.147202)
		(width 0.11684)
		(layer "B.Cu")
		(net "FM_PWR_BTN")
	)
	(segment
		(start 10.693146 -96.0374)
		(end 11.785854 -96.0374)
		(width 0.11684)
		(layer "B.Cu")
		(net "FM_PWR_BTN")
	)
	(segment
		(start 43.561 -59.944)
		(end 43.815 -59.69)
		(width 0.11684)
		(layer "B.Cu")
		(net "FM_PWR_BTN")
	)
	(segment
		(start 47.28845 -57.527444)
		(end 47.038006 -57.777888)
		(width 0.11684)
		(layer "B.Cu")
		(net "FM_PWR_BTN")
	)
	(segment
		(start 42.318178 -60.55233)
		(end 42.678096 -60.192412)
		(width 0.11684)
		(layer "B.Cu")
		(net "FM_PWR_BTN")
	)
	(segment
		(start 9.427464 -96.45777)
		(end 10.272776 -96.45777)
		(width 0.11684)
		(layer "B.Cu")
		(net "FM_PWR_BTN")
	)
	(segment
		(start 42.318178 -60.573666)
		(end 42.318178 -60.55233)
		(width 0.11684)
		(layer "B.Cu")
		(net "FM_PWR_BTN")
	)
	(segment
		(start 42.678096 -60.119768)
		(end 42.853864 -59.944)
		(width 0.11684)
		(layer "B.Cu")
		(net "FM_PWR_BTN")
	)
	(segment
		(start 42.678096 -60.192412)
		(end 42.678096 -60.119768)
		(width 0.11684)
		(layer "B.Cu")
		(net "FM_PWR_BTN")
	)
	(segment
		(start 45.71111 -58.005472)
		(end 45.71111 -58.58129)
		(width 0.11684)
		(layer "B.Cu")
		(net "FM_PWR_BTN")
	)
	(segment
		(start 45.145198 -59.147202)
		(end 44.740576 -59.147202)
		(width 0.11684)
		(layer "B.Cu")
		(net "FM_PWR_BTN")
	)
	(segment
		(start 9.1186 -95.6056)
		(end 9.1186 -96.148906)
		(width 0.11684)
		(layer "B.Cu")
		(net "FM_PWR_BTN")
	)
	(segment
		(start 10.272776 -96.45777)
		(end 10.693146 -96.0374)
		(width 0.11684)
		(layer "B.Cu")
		(net "FM_PWR_BTN")
	)
	(segment
		(start 43.815 -59.69)
		(end 43.815 -59.3598)
		(width 0.11684)
		(layer "B.Cu")
		(net "FM_PWR_BTN")
	)
	(segment
		(start 11.785854 -96.0374)
		(end 11.91895 -96.170496)
		(width 0.11684)
		(layer "B.Cu")
		(net "FM_PWR_BTN")
	)
	(segment
		(start 47.699676 -56.566562)
		(end 47.28845 -56.977788)
		(width 0.11684)
		(layer "B.Cu")
		(net "FM_PWR_BTN")
	)
	(segment
		(start 42.853864 -59.944)
		(end 43.561 -59.944)
		(width 0.11684)
		(layer "B.Cu")
		(net "FM_PWR_BTN")
	)
	(segment
		(start 9.4742 -95.25)
		(end 9.1186 -95.6056)
		(width 0.11684)
		(layer "B.Cu")
		(net "FM_PWR_BTN")
	)
	(segment
		(start 28.317698 -62.815216)
		(end 28.569412 -63.06693)
		(width 0.08382)
		(layer "In2.Cu")
		(net "FM_PWR_BTN")
	)
	(segment
		(start 37.411914 -60.726066)
		(end 38.19398 -59.944)
		(width 0.08382)
		(layer "In2.Cu")
		(net "FM_PWR_BTN")
	)
	(segment
		(start 28.569412 -63.06693)
		(end 29.134308 -63.06693)
		(width 0.08382)
		(layer "In2.Cu")
		(net "FM_PWR_BTN")
	)
	(segment
		(start 48.39462 -61.43498)
		(end 49.6824 -60.1472)
		(width 0.08382)
		(layer "In2.Cu")
		(net "FM_PWR_BTN")
	)
	(segment
		(start 49.6824 -60.1472)
		(end 49.6824 -57.1246)
		(width 0.08382)
		(layer "In2.Cu")
		(net "FM_PWR_BTN")
	)
	(segment
		(start 20.612354 -63.39713)
		(end 21.900134 -64.68491)
		(width 0.08382)
		(layer "In2.Cu")
		(net "FM_PWR_BTN")
	)
	(segment
		(start 48.079914 -56.9468)
		(end 47.699676 -56.566562)
		(width 0.08382)
		(layer "In2.Cu")
		(net "FM_PWR_BTN")
	)
	(segment
		(start 49.5046 -56.9468)
		(end 48.079914 -56.9468)
		(width 0.08382)
		(layer "In2.Cu")
		(net "FM_PWR_BTN")
	)
	(segment
		(start 18.544794 -62.57671)
		(end 18.544794 -62.900814)
		(width 0.08382)
		(layer "In2.Cu")
		(net "FM_PWR_BTN")
	)
	(segment
		(start 38.19398 -59.944)
		(end 38.52926 -59.944)
		(width 0.08382)
		(layer "In2.Cu")
		(net "FM_PWR_BTN")
	)
	(segment
		(start 38.9128 -60.32754)
		(end 38.9128 -61.268102)
		(width 0.08382)
		(layer "In2.Cu")
		(net "FM_PWR_BTN")
	)
	(segment
		(start 49.6824 -57.1246)
		(end 49.5046 -56.9468)
		(width 0.08382)
		(layer "In2.Cu")
		(net "FM_PWR_BTN")
	)
	(segment
		(start 30.497272 -62.66942)
		(end 30.894782 -63.06693)
		(width 0.08382)
		(layer "In2.Cu")
		(net "FM_PWR_BTN")
	)
	(segment
		(start 18.544794 -62.900814)
		(end 19.04111 -63.39713)
		(width 0.08382)
		(layer "In2.Cu")
		(net "FM_PWR_BTN")
	)
	(segment
		(start 38.52926 -59.944)
		(end 38.9128 -60.32754)
		(width 0.08382)
		(layer "In2.Cu")
		(net "FM_PWR_BTN")
	)
	(segment
		(start 34.920174 -60.726066)
		(end 37.411914 -60.726066)
		(width 0.08382)
		(layer "In2.Cu")
		(net "FM_PWR_BTN")
	)
	(segment
		(start 43.002962 -62.060582)
		(end 43.628564 -61.43498)
		(width 0.08382)
		(layer "In2.Cu")
		(net "FM_PWR_BTN")
	)
	(segment
		(start 25.246076 -62.815216)
		(end 28.317698 -62.815216)
		(width 0.08382)
		(layer "In2.Cu")
		(net "FM_PWR_BTN")
	)
	(segment
		(start 43.628564 -61.43498)
		(end 48.39462 -61.43498)
		(width 0.08382)
		(layer "In2.Cu")
		(net "FM_PWR_BTN")
	)
	(segment
		(start 23.376382 -64.68491)
		(end 25.246076 -62.815216)
		(width 0.08382)
		(layer "In2.Cu")
		(net "FM_PWR_BTN")
	)
	(segment
		(start 21.900134 -64.68491)
		(end 23.376382 -64.68491)
		(width 0.08382)
		(layer "In2.Cu")
		(net "FM_PWR_BTN")
	)
	(segment
		(start 29.134308 -63.06693)
		(end 29.531818 -62.66942)
		(width 0.08382)
		(layer "In2.Cu")
		(net "FM_PWR_BTN")
	)
	(segment
		(start 29.531818 -62.66942)
		(end 30.497272 -62.66942)
		(width 0.08382)
		(layer "In2.Cu")
		(net "FM_PWR_BTN")
	)
	(segment
		(start 38.9128 -61.268102)
		(end 39.70528 -62.060582)
		(width 0.08382)
		(layer "In2.Cu")
		(net "FM_PWR_BTN")
	)
	(segment
		(start 19.04111 -63.39713)
		(end 20.612354 -63.39713)
		(width 0.08382)
		(layer "In2.Cu")
		(net "FM_PWR_BTN")
	)
	(segment
		(start 32.57931 -63.06693)
		(end 34.920174 -60.726066)
		(width 0.08382)
		(layer "In2.Cu")
		(net "FM_PWR_BTN")
	)
	(segment
		(start 30.894782 -63.06693)
		(end 32.57931 -63.06693)
		(width 0.08382)
		(layer "In2.Cu")
		(net "FM_PWR_BTN")
	)
	(segment
		(start 39.70528 -62.060582)
		(end 43.002962 -62.060582)
		(width 0.08382)
		(layer "In2.Cu")
		(net "FM_PWR_BTN")
	)
	(segment
		(start 9.4742 -95.25)
		(end 10.76706 -93.95714)
		(width 0.10668)
		(layer "In4.Cu")
		(net "FM_PWR_BTN")
	)
	(segment
		(start 12.8778 -88.392)
		(end 14.605 -88.392)
		(width 0.10668)
		(layer "In4.Cu")
		(net "FM_PWR_BTN")
	)
	(segment
		(start 12.6492 -88.6206)
		(end 12.8778 -88.392)
		(width 0.10668)
		(layer "In4.Cu")
		(net "FM_PWR_BTN")
	)
	(segment
		(start 18.544794 -63.393828)
		(end 18.544794 -62.57671)
		(width 0.10668)
		(layer "In4.Cu")
		(net "FM_PWR_BTN")
	)
	(segment
		(start 18.83918 -66.718942)
		(end 18.83918 -63.688214)
		(width 0.10668)
		(layer "In4.Cu")
		(net "FM_PWR_BTN")
	)
	(segment
		(start 14.75232 -75.456542)
		(end 18.23974 -71.969122)
		(width 0.10668)
		(layer "In4.Cu")
		(net "FM_PWR_BTN")
	)
	(segment
		(start 18.23974 -71.969122)
		(end 18.23974 -70.893686)
		(width 0.10668)
		(layer "In4.Cu")
		(net "FM_PWR_BTN")
	)
	(segment
		(start 12.6492 -93.11259)
		(end 12.6492 -88.6206)
		(width 0.10668)
		(layer "In4.Cu")
		(net "FM_PWR_BTN")
	)
	(segment
		(start 17.21104 -69.864986)
		(end 17.21104 -68.347082)
		(width 0.10668)
		(layer "In4.Cu")
		(net "FM_PWR_BTN")
	)
	(segment
		(start 16.46174 -79.27975)
		(end 15.604998 -78.423008)
		(width 0.10668)
		(layer "In4.Cu")
		(net "FM_PWR_BTN")
	)
	(segment
		(start 14.75232 -77.202792)
		(end 14.75232 -75.456542)
		(width 0.10668)
		(layer "In4.Cu")
		(net "FM_PWR_BTN")
	)
	(segment
		(start 18.83918 -63.688214)
		(end 18.544794 -63.393828)
		(width 0.10668)
		(layer "In4.Cu")
		(net "FM_PWR_BTN")
	)
	(segment
		(start 16.46174 -85.08746)
		(end 16.46174 -79.27975)
		(width 0.10668)
		(layer "In4.Cu")
		(net "FM_PWR_BTN")
	)
	(segment
		(start 18.23974 -70.893686)
		(end 17.21104 -69.864986)
		(width 0.10668)
		(layer "In4.Cu")
		(net "FM_PWR_BTN")
	)
	(segment
		(start 15.604998 -78.05547)
		(end 14.75232 -77.202792)
		(width 0.10668)
		(layer "In4.Cu")
		(net "FM_PWR_BTN")
	)
	(segment
		(start 15.604998 -78.423008)
		(end 15.604998 -78.05547)
		(width 0.10668)
		(layer "In4.Cu")
		(net "FM_PWR_BTN")
	)
	(segment
		(start 11.80465 -93.95714)
		(end 12.6492 -93.11259)
		(width 0.10668)
		(layer "In4.Cu")
		(net "FM_PWR_BTN")
	)
	(segment
		(start 15.0622 -86.487)
		(end 16.46174 -85.08746)
		(width 0.10668)
		(layer "In4.Cu")
		(net "FM_PWR_BTN")
	)
	(segment
		(start 14.605 -88.392)
		(end 15.0622 -87.9348)
		(width 0.10668)
		(layer "In4.Cu")
		(net "FM_PWR_BTN")
	)
	(segment
		(start 15.0622 -87.9348)
		(end 15.0622 -86.487)
		(width 0.10668)
		(layer "In4.Cu")
		(net "FM_PWR_BTN")
	)
	(segment
		(start 10.76706 -93.95714)
		(end 11.80465 -93.95714)
		(width 0.10668)
		(layer "In4.Cu")
		(net "FM_PWR_BTN")
	)
	(segment
		(start 17.21104 -68.347082)
		(end 18.83918 -66.718942)
		(width 0.10668)
		(layer "In4.Cu")
		(net "FM_PWR_BTN")
	)
	(segment
		(start 52.894992 -57.771284)
		(end 52.499768 -58.166508)
		(width 0.11684)
		(layer "F.Cu")
		(net "FM_PCHHOT_R_N")
	)
	(segment
		(start 19.064224 -95.182182)
		(end 19.459448 -94.786958)
		(width 0.11684)
		(layer "F.Cu")
		(net "FM_PCHHOT_R_N")
	)
	(via
		(at 52.499768 -58.166508)
		(size 0.4572)
		(drill 0.254)
		(layers "F.Cu" "B.Cu")
		(net "FM_PCHHOT_R_N")
	)
	(via
		(at 19.064224 -95.182182)
		(size 0.4572)
		(drill 0.254)
		(layers "F.Cu" "B.Cu")
		(net "FM_PCHHOT_R_N")
	)
	(segment
		(start 40.9448 -72.8218)
		(end 40.0304 -73.7362)
		(width 0.08382)
		(layer "In9.Cu")
		(net "FM_PCHHOT_R_N")
	)
	(segment
		(start 31.953708 -96.342708)
		(end 32.53867 -96.92767)
		(width 0.08382)
		(layer "In9.Cu")
		(net "FM_PCHHOT_R_N")
	)
	(segment
		(start 26.0858 -95.5802)
		(end 19.735546 -95.5802)
		(width 0.08382)
		(layer "In9.Cu")
		(net "FM_PCHHOT_R_N")
	)
	(segment
		(start 48.218344 -60.122816)
		(end 45.745146 -62.596014)
		(width 0.08382)
		(layer "In9.Cu")
		(net "FM_PCHHOT_R_N")
	)
	(segment
		(start 52.499768 -58.166508)
		(end 52.126388 -57.793128)
		(width 0.08382)
		(layer "In9.Cu")
		(net "FM_PCHHOT_R_N")
	)
	(segment
		(start 44.013374 -62.596014)
		(end 43.61307 -62.996318)
		(width 0.08382)
		(layer "In9.Cu")
		(net "FM_PCHHOT_R_N")
	)
	(segment
		(start 39.99738 -73.790556)
		(end 39.99738 -74.81062)
		(width 0.08382)
		(layer "In9.Cu")
		(net "FM_PCHHOT_R_N")
	)
	(segment
		(start 52.126388 -57.793128)
		(end 49.826672 -57.793128)
		(width 0.08382)
		(layer "In9.Cu")
		(net "FM_PCHHOT_R_N")
	)
	(segment
		(start 32.78505 -93.008704)
		(end 32.78505 -93.998288)
		(width 0.08382)
		(layer "In9.Cu")
		(net "FM_PCHHOT_R_N")
	)
	(segment
		(start 35.5092 -77.3938)
		(end 33.68802 -79.21498)
		(width 0.08382)
		(layer "In9.Cu")
		(net "FM_PCHHOT_R_N")
	)
	(segment
		(start 43.61307 -62.996318)
		(end 43.61307 -65.80759)
		(width 0.08382)
		(layer "In9.Cu")
		(net "FM_PCHHOT_R_N")
	)
	(segment
		(start 32.69615 -90.374216)
		(end 32.54883 -90.521536)
		(width 0.08382)
		(layer "In9.Cu")
		(net "FM_PCHHOT_R_N")
	)
	(segment
		(start 32.69615 -88.428322)
		(end 32.69615 -90.374216)
		(width 0.08382)
		(layer "In9.Cu")
		(net "FM_PCHHOT_R_N")
	)
	(segment
		(start 32.53867 -96.92767)
		(end 32.53867 -97.540572)
		(width 0.08382)
		(layer "In9.Cu")
		(net "FM_PCHHOT_R_N")
	)
	(segment
		(start 38.9636 -75.8444)
		(end 38.9636 -76.7588)
		(width 0.08382)
		(layer "In9.Cu")
		(net "FM_PCHHOT_R_N")
	)
	(segment
		(start 31.859728 -97.66681)
		(end 31.208726 -97.015808)
		(width 0.08382)
		(layer "In9.Cu")
		(net "FM_PCHHOT_R_N")
	)
	(segment
		(start 29.596588 -97.67316)
		(end 28.17876 -97.67316)
		(width 0.08382)
		(layer "In9.Cu")
		(net "FM_PCHHOT_R_N")
	)
	(segment
		(start 33.13811 -83.858354)
		(end 33.13811 -87.986362)
		(width 0.08382)
		(layer "In9.Cu")
		(net "FM_PCHHOT_R_N")
	)
	(segment
		(start 32.54883 -90.521536)
		(end 32.54883 -92.772484)
		(width 0.08382)
		(layer "In9.Cu")
		(net "FM_PCHHOT_R_N")
	)
	(segment
		(start 19.337528 -95.182182)
		(end 19.064224 -95.182182)
		(width 0.08382)
		(layer "In9.Cu")
		(net "FM_PCHHOT_R_N")
	)
	(segment
		(start 32.412432 -97.66681)
		(end 31.859728 -97.66681)
		(width 0.08382)
		(layer "In9.Cu")
		(net "FM_PCHHOT_R_N")
	)
	(segment
		(start 39.99738 -74.81062)
		(end 38.9636 -75.8444)
		(width 0.08382)
		(layer "In9.Cu")
		(net "FM_PCHHOT_R_N")
	)
	(segment
		(start 49.20107 -58.538618)
		(end 48.218344 -59.521344)
		(width 0.08382)
		(layer "In9.Cu")
		(net "FM_PCHHOT_R_N")
	)
	(segment
		(start 38.9636 -76.7588)
		(end 38.3286 -77.3938)
		(width 0.08382)
		(layer "In9.Cu")
		(net "FM_PCHHOT_R_N")
	)
	(segment
		(start 43.61307 -65.80759)
		(end 43.059858 -66.360802)
		(width 0.08382)
		(layer "In9.Cu")
		(net "FM_PCHHOT_R_N")
	)
	(segment
		(start 31.953708 -94.82963)
		(end 31.953708 -96.342708)
		(width 0.08382)
		(layer "In9.Cu")
		(net "FM_PCHHOT_R_N")
	)
	(segment
		(start 32.54883 -92.772484)
		(end 32.78505 -93.008704)
		(width 0.08382)
		(layer "In9.Cu")
		(net "FM_PCHHOT_R_N")
	)
	(segment
		(start 48.218344 -59.521344)
		(end 48.218344 -60.122816)
		(width 0.08382)
		(layer "In9.Cu")
		(net "FM_PCHHOT_R_N")
	)
	(segment
		(start 40.0304 -73.7362)
		(end 40.0304 -73.757536)
		(width 0.08382)
		(layer "In9.Cu")
		(net "FM_PCHHOT_R_N")
	)
	(segment
		(start 32.78505 -93.998288)
		(end 31.953708 -94.82963)
		(width 0.08382)
		(layer "In9.Cu")
		(net "FM_PCHHOT_R_N")
	)
	(segment
		(start 49.671986 -57.947814)
		(end 49.671986 -58.320686)
		(width 0.08382)
		(layer "In9.Cu")
		(net "FM_PCHHOT_R_N")
	)
	(segment
		(start 28.17876 -97.67316)
		(end 26.0858 -95.5802)
		(width 0.08382)
		(layer "In9.Cu")
		(net "FM_PCHHOT_R_N")
	)
	(segment
		(start 31.208726 -97.015808)
		(end 30.25394 -97.015808)
		(width 0.08382)
		(layer "In9.Cu")
		(net "FM_PCHHOT_R_N")
	)
	(segment
		(start 43.059858 -68.290694)
		(end 40.9448 -70.405752)
		(width 0.08382)
		(layer "In9.Cu")
		(net "FM_PCHHOT_R_N")
	)
	(segment
		(start 19.735546 -95.5802)
		(end 19.337528 -95.182182)
		(width 0.08382)
		(layer "In9.Cu")
		(net "FM_PCHHOT_R_N")
	)
	(segment
		(start 45.745146 -62.596014)
		(end 44.013374 -62.596014)
		(width 0.08382)
		(layer "In9.Cu")
		(net "FM_PCHHOT_R_N")
	)
	(segment
		(start 49.454054 -58.538618)
		(end 49.20107 -58.538618)
		(width 0.08382)
		(layer "In9.Cu")
		(net "FM_PCHHOT_R_N")
	)
	(segment
		(start 33.13811 -87.986362)
		(end 32.69615 -88.428322)
		(width 0.08382)
		(layer "In9.Cu")
		(net "FM_PCHHOT_R_N")
	)
	(segment
		(start 40.0304 -73.757536)
		(end 39.99738 -73.790556)
		(width 0.08382)
		(layer "In9.Cu")
		(net "FM_PCHHOT_R_N")
	)
	(segment
		(start 43.059858 -66.360802)
		(end 43.059858 -68.290694)
		(width 0.08382)
		(layer "In9.Cu")
		(net "FM_PCHHOT_R_N")
	)
	(segment
		(start 33.68802 -79.21498)
		(end 33.68802 -83.308444)
		(width 0.08382)
		(layer "In9.Cu")
		(net "FM_PCHHOT_R_N")
	)
	(segment
		(start 38.3286 -77.3938)
		(end 35.5092 -77.3938)
		(width 0.08382)
		(layer "In9.Cu")
		(net "FM_PCHHOT_R_N")
	)
	(segment
		(start 49.826672 -57.793128)
		(end 49.671986 -57.947814)
		(width 0.08382)
		(layer "In9.Cu")
		(net "FM_PCHHOT_R_N")
	)
	(segment
		(start 49.671986 -58.320686)
		(end 49.454054 -58.538618)
		(width 0.08382)
		(layer "In9.Cu")
		(net "FM_PCHHOT_R_N")
	)
	(segment
		(start 33.68802 -83.308444)
		(end 33.13811 -83.858354)
		(width 0.08382)
		(layer "In9.Cu")
		(net "FM_PCHHOT_R_N")
	)
	(segment
		(start 40.9448 -70.405752)
		(end 40.9448 -72.8218)
		(width 0.08382)
		(layer "In9.Cu")
		(net "FM_PCHHOT_R_N")
	)
	(segment
		(start 32.53867 -97.540572)
		(end 32.412432 -97.66681)
		(width 0.08382)
		(layer "In9.Cu")
		(net "FM_PCHHOT_R_N")
	)
	(segment
		(start 30.25394 -97.015808)
		(end 29.596588 -97.67316)
		(width 0.08382)
		(layer "In9.Cu")
		(net "FM_PCHHOT_R_N")
	)
	(segment
		(start 47.295054 -57.771284)
		(end 46.89983 -58.166508)
		(width 0.11684)
		(layer "F.Cu")
		(net "FM_PCIE_M2_SSD0_PRSNT_N")
	)
	(segment
		(start 23.054564 -91.191842)
		(end 22.65934 -91.587066)
		(width 0.11684)
		(layer "F.Cu")
		(net "FM_PCIE_M2_SSD0_PRSNT_N")
	)
	(via
		(at 40.1574 -112.4458)
		(size 0.508)
		(drill 0.254)
		(layers "F.Cu" "B.Cu")
		(net "FM_PCIE_M2_SSD0_PRSNT_N")
	)
	(via
		(at 23.054564 -91.191842)
		(size 0.4572)
		(drill 0.254)
		(layers "F.Cu" "B.Cu")
		(net "FM_PCIE_M2_SSD0_PRSNT_N")
	)
	(via
		(at 46.89983 -58.166508)
		(size 0.4572)
		(drill 0.254)
		(layers "F.Cu" "B.Cu")
		(net "FM_PCIE_M2_SSD0_PRSNT_N")
	)
	(via
		(at 28.414726 -92.825316)
		(size 0.508)
		(drill 0.254)
		(layers "F.Cu" "B.Cu")
		(net "FM_PCIE_M2_SSD0_PRSNT_N")
	)
	(segment
		(start 23.440898 -91.578176)
		(end 23.054564 -91.191842)
		(width 0.10414)
		(layer "In2.Cu")
		(net "FM_PCIE_M2_SSD0_PRSNT_N")
	)
	(segment
		(start 26.579576 -91.578176)
		(end 23.440898 -91.578176)
		(width 0.10414)
		(layer "In2.Cu")
		(net "FM_PCIE_M2_SSD0_PRSNT_N")
	)
	(segment
		(start 27.826716 -92.825316)
		(end 26.579576 -91.578176)
		(width 0.10414)
		(layer "In2.Cu")
		(net "FM_PCIE_M2_SSD0_PRSNT_N")
	)
	(segment
		(start 28.414726 -92.825316)
		(end 27.826716 -92.825316)
		(width 0.10414)
		(layer "In2.Cu")
		(net "FM_PCIE_M2_SSD0_PRSNT_N")
	)
	(segment
		(start 40.1574 -112.4458)
		(end 41.394126 -111.209074)
		(width 0.10668)
		(layer "In4.Cu")
		(net "FM_PCIE_M2_SSD0_PRSNT_N")
	)
	(segment
		(start 45.84192 -63.96482)
		(end 45.84192 -60.263278)
		(width 0.10668)
		(layer "In4.Cu")
		(net "FM_PCIE_M2_SSD0_PRSNT_N")
	)
	(segment
		(start 45.66158 -69.783198)
		(end 45.66158 -68.841874)
		(width 0.10668)
		(layer "In4.Cu")
		(net "FM_PCIE_M2_SSD0_PRSNT_N")
	)
	(segment
		(start 43.95216 -99.354386)
		(end 43.95216 -97.092262)
		(width 0.10668)
		(layer "In4.Cu")
		(net "FM_PCIE_M2_SSD0_PRSNT_N")
	)
	(segment
		(start 41.394126 -111.209074)
		(end 41.394126 -110.0582)
		(width 0.10668)
		(layer "In4.Cu")
		(net "FM_PCIE_M2_SSD0_PRSNT_N")
	)
	(segment
		(start 46.0756 -66.675762)
		(end 46.3042 -66.12382)
		(width 0.10668)
		(layer "In4.Cu")
		(net "FM_PCIE_M2_SSD0_PRSNT_N")
	)
	(segment
		(start 46.3042 -65.584832)
		(end 46.111414 -64.615314)
		(width 0.10668)
		(layer "In4.Cu")
		(net "FM_PCIE_M2_SSD0_PRSNT_N")
	)
	(segment
		(start 43.95216 -97.092262)
		(end 46.82744 -94.216982)
		(width 0.10668)
		(layer "In4.Cu")
		(net "FM_PCIE_M2_SSD0_PRSNT_N")
	)
	(segment
		(start 40.9448 -109.608874)
		(end 40.9448 -106.68)
		(width 0.10668)
		(layer "In4.Cu")
		(net "FM_PCIE_M2_SSD0_PRSNT_N")
	)
	(segment
		(start 45.96892 -68.534534)
		(end 45.96892 -66.970402)
		(width 0.10668)
		(layer "In4.Cu")
		(net "FM_PCIE_M2_SSD0_PRSNT_N")
	)
	(segment
		(start 42.0624 -105.5624)
		(end 42.0624 -101.244146)
		(width 0.10668)
		(layer "In4.Cu")
		(net "FM_PCIE_M2_SSD0_PRSNT_N")
	)
	(segment
		(start 46.82744 -94.216982)
		(end 46.82744 -90.568018)
		(width 0.10668)
		(layer "In4.Cu")
		(net "FM_PCIE_M2_SSD0_PRSNT_N")
	)
	(segment
		(start 42.0624 -101.244146)
		(end 43.95216 -99.354386)
		(width 0.10668)
		(layer "In4.Cu")
		(net "FM_PCIE_M2_SSD0_PRSNT_N")
	)
	(segment
		(start 45.96892 -66.970402)
		(end 46.0756 -66.712592)
		(width 0.10668)
		(layer "In4.Cu")
		(net "FM_PCIE_M2_SSD0_PRSNT_N")
	)
	(segment
		(start 41.394126 -110.0582)
		(end 40.9448 -109.608874)
		(width 0.10668)
		(layer "In4.Cu")
		(net "FM_PCIE_M2_SSD0_PRSNT_N")
	)
	(segment
		(start 46.861222 -75.897232)
		(end 46.861222 -70.98284)
		(width 0.10668)
		(layer "In4.Cu")
		(net "FM_PCIE_M2_SSD0_PRSNT_N")
	)
	(segment
		(start 46.489874 -58.829702)
		(end 46.89983 -58.419746)
		(width 0.10668)
		(layer "In4.Cu")
		(net "FM_PCIE_M2_SSD0_PRSNT_N")
	)
	(segment
		(start 46.82744 -90.568018)
		(end 45.20184 -88.942418)
		(width 0.10668)
		(layer "In4.Cu")
		(net "FM_PCIE_M2_SSD0_PRSNT_N")
	)
	(segment
		(start 46.0502 -76.708254)
		(end 46.861222 -75.897232)
		(width 0.10668)
		(layer "In4.Cu")
		(net "FM_PCIE_M2_SSD0_PRSNT_N")
	)
	(segment
		(start 45.20184 -88.942418)
		(end 45.20184 -83.264502)
		(width 0.10668)
		(layer "In4.Cu")
		(net "FM_PCIE_M2_SSD0_PRSNT_N")
	)
	(segment
		(start 46.489874 -59.615324)
		(end 46.489874 -58.829702)
		(width 0.10668)
		(layer "In4.Cu")
		(net "FM_PCIE_M2_SSD0_PRSNT_N")
	)
	(segment
		(start 46.111414 -64.615314)
		(end 45.84192 -63.96482)
		(width 0.10668)
		(layer "In4.Cu")
		(net "FM_PCIE_M2_SSD0_PRSNT_N")
	)
	(segment
		(start 46.3042 -66.12382)
		(end 46.3042 -65.584832)
		(width 0.10668)
		(layer "In4.Cu")
		(net "FM_PCIE_M2_SSD0_PRSNT_N")
	)
	(segment
		(start 46.0756 -66.712592)
		(end 46.0756 -66.675762)
		(width 0.10668)
		(layer "In4.Cu")
		(net "FM_PCIE_M2_SSD0_PRSNT_N")
	)
	(segment
		(start 45.66158 -68.841874)
		(end 45.96892 -68.534534)
		(width 0.10668)
		(layer "In4.Cu")
		(net "FM_PCIE_M2_SSD0_PRSNT_N")
	)
	(segment
		(start 45.84192 -60.263278)
		(end 46.489874 -59.615324)
		(width 0.10668)
		(layer "In4.Cu")
		(net "FM_PCIE_M2_SSD0_PRSNT_N")
	)
	(segment
		(start 45.20184 -83.264502)
		(end 46.0502 -82.416142)
		(width 0.10668)
		(layer "In4.Cu")
		(net "FM_PCIE_M2_SSD0_PRSNT_N")
	)
	(segment
		(start 46.0502 -82.416142)
		(end 46.0502 -76.708254)
		(width 0.10668)
		(layer "In4.Cu")
		(net "FM_PCIE_M2_SSD0_PRSNT_N")
	)
	(segment
		(start 46.861222 -70.98284)
		(end 45.66158 -69.783198)
		(width 0.10668)
		(layer "In4.Cu")
		(net "FM_PCIE_M2_SSD0_PRSNT_N")
	)
	(segment
		(start 46.89983 -58.419746)
		(end 46.89983 -58.166508)
		(width 0.10668)
		(layer "In4.Cu")
		(net "FM_PCIE_M2_SSD0_PRSNT_N")
	)
	(segment
		(start 40.9448 -106.68)
		(end 42.0624 -105.5624)
		(width 0.10668)
		(layer "In4.Cu")
		(net "FM_PCIE_M2_SSD0_PRSNT_N")
	)
	(segment
		(start 28.414726 -92.825316)
		(end 28.414726 -93.163898)
		(width 0.10668)
		(layer "In7.Cu")
		(net "FM_PCIE_M2_SSD0_PRSNT_N")
	)
	(segment
		(start 39.42588 -111.248698)
		(end 39.622222 -111.44504)
		(width 0.10668)
		(layer "In7.Cu")
		(net "FM_PCIE_M2_SSD0_PRSNT_N")
	)
	(segment
		(start 40.12057 -109.354112)
		(end 39.15664 -110.318042)
		(width 0.10668)
		(layer "In7.Cu")
		(net "FM_PCIE_M2_SSD0_PRSNT_N")
	)
	(segment
		(start 32.29864 -105.738422)
		(end 32.986218 -106.426)
		(width 0.10668)
		(layer "In7.Cu")
		(net "FM_PCIE_M2_SSD0_PRSNT_N")
	)
	(segment
		(start 39.15664 -110.318042)
		(end 39.15664 -110.976918)
		(width 0.10668)
		(layer "In7.Cu")
		(net "FM_PCIE_M2_SSD0_PRSNT_N")
	)
	(segment
		(start 39.622222 -111.44504)
		(end 40.376602 -111.44504)
		(width 0.10668)
		(layer "In7.Cu")
		(net "FM_PCIE_M2_SSD0_PRSNT_N")
	)
	(segment
		(start 39.39032 -106.437938)
		(end 40.12057 -107.168188)
		(width 0.10668)
		(layer "In7.Cu")
		(net "FM_PCIE_M2_SSD0_PRSNT_N")
	)
	(segment
		(start 32.512 -103.632)
		(end 32.29864 -103.84536)
		(width 0.10668)
		(layer "In7.Cu")
		(net "FM_PCIE_M2_SSD0_PRSNT_N")
	)
	(segment
		(start 39.42588 -111.246158)
		(end 39.42588 -111.248698)
		(width 0.10668)
		(layer "In7.Cu")
		(net "FM_PCIE_M2_SSD0_PRSNT_N")
	)
	(segment
		(start 40.376602 -111.44504)
		(end 40.4622 -111.530638)
		(width 0.10668)
		(layer "In7.Cu")
		(net "FM_PCIE_M2_SSD0_PRSNT_N")
	)
	(segment
		(start 40.4622 -111.530638)
		(end 40.4622 -112.141)
		(width 0.10668)
		(layer "In7.Cu")
		(net "FM_PCIE_M2_SSD0_PRSNT_N")
	)
	(segment
		(start 28.414726 -93.163898)
		(end 28.9814 -94.532196)
		(width 0.10668)
		(layer "In7.Cu")
		(net "FM_PCIE_M2_SSD0_PRSNT_N")
	)
	(segment
		(start 32.986218 -106.426)
		(end 39.39032 -106.426)
		(width 0.10668)
		(layer "In7.Cu")
		(net "FM_PCIE_M2_SSD0_PRSNT_N")
	)
	(segment
		(start 39.15664 -110.976918)
		(end 39.42588 -111.246158)
		(width 0.10668)
		(layer "In7.Cu")
		(net "FM_PCIE_M2_SSD0_PRSNT_N")
	)
	(segment
		(start 32.512 -102.835964)
		(end 32.512 -103.632)
		(width 0.10668)
		(layer "In7.Cu")
		(net "FM_PCIE_M2_SSD0_PRSNT_N")
	)
	(segment
		(start 39.39032 -106.426)
		(end 39.39032 -106.437938)
		(width 0.10668)
		(layer "In7.Cu")
		(net "FM_PCIE_M2_SSD0_PRSNT_N")
	)
	(segment
		(start 40.4622 -112.141)
		(end 40.1574 -112.4458)
		(width 0.10668)
		(layer "In7.Cu")
		(net "FM_PCIE_M2_SSD0_PRSNT_N")
	)
	(segment
		(start 28.9814 -94.532196)
		(end 28.9814 -99.305364)
		(width 0.10668)
		(layer "In7.Cu")
		(net "FM_PCIE_M2_SSD0_PRSNT_N")
	)
	(segment
		(start 40.12057 -107.168188)
		(end 40.12057 -109.354112)
		(width 0.10668)
		(layer "In7.Cu")
		(net "FM_PCIE_M2_SSD0_PRSNT_N")
	)
	(segment
		(start 28.9814 -99.305364)
		(end 32.512 -102.835964)
		(width 0.10668)
		(layer "In7.Cu")
		(net "FM_PCIE_M2_SSD0_PRSNT_N")
	)
	(segment
		(start 32.29864 -103.84536)
		(end 32.29864 -105.738422)
		(width 0.10668)
		(layer "In7.Cu")
		(net "FM_PCIE_M2_SSD0_PRSNT_N")
	)
	(segment
		(start 27.762708 -93.598492)
		(end 27.94254 -93.41866)
		(width 0.11684)
		(layer "F.Cu")
		(net "FM_PMBUS_ALERT_EN")
	)
	(segment
		(start 29.49194 -93.41866)
		(end 30.28442 -92.62618)
		(width 0.11684)
		(layer "F.Cu")
		(net "FM_PMBUS_ALERT_EN")
	)
	(segment
		(start 44.895008 -57.771284)
		(end 44.499784 -58.166508)
		(width 0.11684)
		(layer "F.Cu")
		(net "FM_PMBUS_ALERT_EN")
	)
	(segment
		(start 15.459456 -93.987112)
		(end 15.7099 -93.987112)
		(width 0.11684)
		(layer "F.Cu")
		(net "FM_PMBUS_ALERT_EN")
	)
	(segment
		(start 15.7099 -93.987112)
		(end 16.09852 -93.598492)
		(width 0.11684)
		(layer "F.Cu")
		(net "FM_PMBUS_ALERT_EN")
	)
	(segment
		(start 30.28442 -92.62618)
		(end 31.07182 -92.62618)
		(width 0.11684)
		(layer "F.Cu")
		(net "FM_PMBUS_ALERT_EN")
	)
	(segment
		(start 27.94254 -93.41866)
		(end 29.49194 -93.41866)
		(width 0.11684)
		(layer "F.Cu")
		(net "FM_PMBUS_ALERT_EN")
	)
	(segment
		(start 16.09852 -93.598492)
		(end 27.762708 -93.598492)
		(width 0.11684)
		(layer "F.Cu")
		(net "FM_PMBUS_ALERT_EN")
	)
	(via
		(at 44.499784 -58.166508)
		(size 0.4572)
		(drill 0.254)
		(layers "F.Cu" "B.Cu")
		(net "FM_PMBUS_ALERT_EN")
	)
	(via
		(at 31.07182 -92.62618)
		(size 0.508)
		(drill 0.254)
		(layers "F.Cu" "B.Cu")
		(net "FM_PMBUS_ALERT_EN")
	)
	(segment
		(start 39.608252 -63.71209)
		(end 39.877492 -63.71209)
		(width 0.08382)
		(layer "In9.Cu")
		(net "FM_PMBUS_ALERT_EN")
	)
	(segment
		(start 29.9212 -91.948)
		(end 29.9212 -91.15552)
		(width 0.08382)
		(layer "In9.Cu")
		(net "FM_PMBUS_ALERT_EN")
	)
	(segment
		(start 30.59938 -92.62618)
		(end 29.9212 -91.948)
		(width 0.08382)
		(layer "In9.Cu")
		(net "FM_PMBUS_ALERT_EN")
	)
	(segment
		(start 39.14013 -64.180212)
		(end 39.608252 -63.71209)
		(width 0.08382)
		(layer "In9.Cu")
		(net "FM_PMBUS_ALERT_EN")
	)
	(segment
		(start 30.6832 -86.98357)
		(end 30.6832 -81.957418)
		(width 0.08382)
		(layer "In9.Cu")
		(net "FM_PMBUS_ALERT_EN")
	)
	(segment
		(start 32.23387 -80.406748)
		(end 32.23387 -78.492096)
		(width 0.08382)
		(layer "In9.Cu")
		(net "FM_PMBUS_ALERT_EN")
	)
	(segment
		(start 30.16504 -87.50173)
		(end 30.6832 -86.98357)
		(width 0.08382)
		(layer "In9.Cu")
		(net "FM_PMBUS_ALERT_EN")
	)
	(segment
		(start 43.556936 -60.032646)
		(end 43.556936 -59.316112)
		(width 0.08382)
		(layer "In9.Cu")
		(net "FM_PMBUS_ALERT_EN")
	)
	(segment
		(start 38.94963 -68.91401)
		(end 38.94963 -66.372232)
		(width 0.08382)
		(layer "In9.Cu")
		(net "FM_PMBUS_ALERT_EN")
	)
	(segment
		(start 35.015932 -73.319132)
		(end 35.301682 -73.319132)
		(width 0.08382)
		(layer "In9.Cu")
		(net "FM_PMBUS_ALERT_EN")
	)
	(segment
		(start 30.6832 -81.957418)
		(end 32.23387 -80.406748)
		(width 0.08382)
		(layer "In9.Cu")
		(net "FM_PMBUS_ALERT_EN")
	)
	(segment
		(start 37.18052 -71.440294)
		(end 37.18052 -70.68312)
		(width 0.08382)
		(layer "In9.Cu")
		(net "FM_PMBUS_ALERT_EN")
	)
	(segment
		(start 31.07182 -92.62618)
		(end 30.59938 -92.62618)
		(width 0.08382)
		(layer "In9.Cu")
		(net "FM_PMBUS_ALERT_EN")
	)
	(segment
		(start 43.556936 -59.316112)
		(end 44.499784 -58.373264)
		(width 0.08382)
		(layer "In9.Cu")
		(net "FM_PMBUS_ALERT_EN")
	)
	(segment
		(start 35.301682 -73.319132)
		(end 37.18052 -71.440294)
		(width 0.08382)
		(layer "In9.Cu")
		(net "FM_PMBUS_ALERT_EN")
	)
	(segment
		(start 29.9212 -91.15552)
		(end 30.16504 -90.91168)
		(width 0.08382)
		(layer "In9.Cu")
		(net "FM_PMBUS_ALERT_EN")
	)
	(segment
		(start 44.499784 -58.373264)
		(end 44.499784 -58.166508)
		(width 0.08382)
		(layer "In9.Cu")
		(net "FM_PMBUS_ALERT_EN")
	)
	(segment
		(start 33.572196 -74.762868)
		(end 35.015932 -73.319132)
		(width 0.08382)
		(layer "In9.Cu")
		(net "FM_PMBUS_ALERT_EN")
	)
	(segment
		(start 38.94963 -66.372232)
		(end 39.14013 -66.181732)
		(width 0.08382)
		(layer "In9.Cu")
		(net "FM_PMBUS_ALERT_EN")
	)
	(segment
		(start 30.16504 -90.91168)
		(end 30.16504 -87.50173)
		(width 0.08382)
		(layer "In9.Cu")
		(net "FM_PMBUS_ALERT_EN")
	)
	(segment
		(start 32.23387 -78.492096)
		(end 33.572196 -77.15377)
		(width 0.08382)
		(layer "In9.Cu")
		(net "FM_PMBUS_ALERT_EN")
	)
	(segment
		(start 37.18052 -70.68312)
		(end 38.94963 -68.91401)
		(width 0.08382)
		(layer "In9.Cu")
		(net "FM_PMBUS_ALERT_EN")
	)
	(segment
		(start 33.572196 -77.15377)
		(end 33.572196 -74.762868)
		(width 0.08382)
		(layer "In9.Cu")
		(net "FM_PMBUS_ALERT_EN")
	)
	(segment
		(start 39.877492 -63.71209)
		(end 43.556936 -60.032646)
		(width 0.08382)
		(layer "In9.Cu")
		(net "FM_PMBUS_ALERT_EN")
	)
	(segment
		(start 39.14013 -66.181732)
		(end 39.14013 -64.180212)
		(width 0.08382)
		(layer "In9.Cu")
		(net "FM_PMBUS_ALERT_EN")
	)
	(segment
		(start 46.494954 -56.171338)
		(end 46.09973 -56.566562)
		(width 0.11684)
		(layer "F.Cu")
		(net "H_CPU1_MEMTRIP_LVC1_N")
	)
	(segment
		(start 15.459456 -89.98712)
		(end 14.875256 -89.98712)
		(width 0.11684)
		(layer "F.Cu")
		(net "H_CPU1_MEMTRIP_LVC1_N")
	)
	(via
		(at 46.09973 -56.566562)
		(size 0.4572)
		(drill 0.254)
		(layers "F.Cu" "B.Cu")
		(net "H_CPU1_MEMTRIP_LVC1_N")
	)
	(via
		(at 14.875256 -89.98712)
		(size 0.4572)
		(drill 0.254)
		(layers "F.Cu" "B.Cu")
		(net "H_CPU1_MEMTRIP_LVC1_N")
	)
	(segment
		(start 15.2146 -90.326464)
		(end 14.875256 -89.98712)
		(width 0.08382)
		(layer "In9.Cu")
		(net "H_CPU1_MEMTRIP_LVC1_N")
	)
	(segment
		(start 30.3276 -96.6216)
		(end 29.14904 -95.44304)
		(width 0.08382)
		(layer "In9.Cu")
		(net "H_CPU1_MEMTRIP_LVC1_N")
	)
	(segment
		(start 41.335452 -64.963548)
		(end 40.3352 -65.9638)
		(width 0.08382)
		(layer "In9.Cu")
		(net "H_CPU1_MEMTRIP_LVC1_N")
	)
	(segment
		(start 32.07639 -90.301064)
		(end 32.07639 -93.087444)
		(width 0.08382)
		(layer "In9.Cu")
		(net "H_CPU1_MEMTRIP_LVC1_N")
	)
	(segment
		(start 25.58034 -93.8022)
		(end 16.0782 -93.8022)
		(width 0.08382)
		(layer "In9.Cu")
		(net "H_CPU1_MEMTRIP_LVC1_N")
	)
	(segment
		(start 31.455868 -96.6216)
		(end 30.3276 -96.6216)
		(width 0.08382)
		(layer "In9.Cu")
		(net "H_CPU1_MEMTRIP_LVC1_N")
	)
	(segment
		(start 40.3352 -65.9638)
		(end 40.3352 -67.035172)
		(width 0.08382)
		(layer "In9.Cu")
		(net "H_CPU1_MEMTRIP_LVC1_N")
	)
	(segment
		(start 37.811202 -72.50176)
		(end 37.45611 -72.50176)
		(width 0.08382)
		(layer "In9.Cu")
		(net "H_CPU1_MEMTRIP_LVC1_N")
	)
	(segment
		(start 32.44342 -86.254082)
		(end 32.44342 -87.016844)
		(width 0.08382)
		(layer "In9.Cu")
		(net "H_CPU1_MEMTRIP_LVC1_N")
	)
	(segment
		(start 47.1932 -58.547)
		(end 46.736 -58.547)
		(width 0.08382)
		(layer "In9.Cu")
		(net "H_CPU1_MEMTRIP_LVC1_N")
	)
	(segment
		(start 33.188148 -81.643982)
		(end 32.44342 -82.38871)
		(width 0.08382)
		(layer "In9.Cu")
		(net "H_CPU1_MEMTRIP_LVC1_N")
	)
	(segment
		(start 15.2146 -92.9386)
		(end 15.2146 -90.326464)
		(width 0.08382)
		(layer "In9.Cu")
		(net "H_CPU1_MEMTRIP_LVC1_N")
	)
	(segment
		(start 40.06596 -70.247002)
		(end 37.811202 -72.50176)
		(width 0.08382)
		(layer "In9.Cu")
		(net "H_CPU1_MEMTRIP_LVC1_N")
	)
	(segment
		(start 32.66567 -84.807552)
		(end 32.66567 -85.375496)
		(width 0.08382)
		(layer "In9.Cu")
		(net "H_CPU1_MEMTRIP_LVC1_N")
	)
	(segment
		(start 29.14904 -95.44304)
		(end 27.22118 -95.44304)
		(width 0.08382)
		(layer "In9.Cu")
		(net "H_CPU1_MEMTRIP_LVC1_N")
	)
	(segment
		(start 35.408108 -74.264012)
		(end 34.61893 -75.05319)
		(width 0.08382)
		(layer "In9.Cu")
		(net "H_CPU1_MEMTRIP_LVC1_N")
	)
	(segment
		(start 32.44342 -84.585302)
		(end 32.66567 -84.807552)
		(width 0.08382)
		(layer "In9.Cu")
		(net "H_CPU1_MEMTRIP_LVC1_N")
	)
	(segment
		(start 35.693858 -74.264012)
		(end 35.408108 -74.264012)
		(width 0.08382)
		(layer "In9.Cu")
		(net "H_CPU1_MEMTRIP_LVC1_N")
	)
	(segment
		(start 32.07639 -93.087444)
		(end 32.385 -93.396054)
		(width 0.08382)
		(layer "In9.Cu")
		(net "H_CPU1_MEMTRIP_LVC1_N")
	)
	(segment
		(start 32.3596 -88.096344)
		(end 32.22371 -88.232234)
		(width 0.08382)
		(layer "In9.Cu")
		(net "H_CPU1_MEMTRIP_LVC1_N")
	)
	(segment
		(start 32.44342 -87.016844)
		(end 32.3596 -87.100664)
		(width 0.08382)
		(layer "In9.Cu")
		(net "H_CPU1_MEMTRIP_LVC1_N")
	)
	(segment
		(start 34.61893 -75.05319)
		(end 34.61893 -77.444346)
		(width 0.08382)
		(layer "In9.Cu")
		(net "H_CPU1_MEMTRIP_LVC1_N")
	)
	(segment
		(start 32.66313 -86.034372)
		(end 32.44342 -86.254082)
		(width 0.08382)
		(layer "In9.Cu")
		(net "H_CPU1_MEMTRIP_LVC1_N")
	)
	(segment
		(start 32.385 -93.396054)
		(end 32.385 -93.928946)
		(width 0.08382)
		(layer "In9.Cu")
		(net "H_CPU1_MEMTRIP_LVC1_N")
	)
	(segment
		(start 47.1932 -56.1594)
		(end 47.3202 -56.2864)
		(width 0.08382)
		(layer "In9.Cu")
		(net "H_CPU1_MEMTRIP_LVC1_N")
	)
	(segment
		(start 27.22118 -95.44304)
		(end 25.58034 -93.8022)
		(width 0.08382)
		(layer "In9.Cu")
		(net "H_CPU1_MEMTRIP_LVC1_N")
	)
	(segment
		(start 33.188148 -78.875128)
		(end 33.188148 -81.643982)
		(width 0.08382)
		(layer "In9.Cu")
		(net "H_CPU1_MEMTRIP_LVC1_N")
	)
	(segment
		(start 45.085 -60.198)
		(end 44.394628 -60.198)
		(width 0.08382)
		(layer "In9.Cu")
		(net "H_CPU1_MEMTRIP_LVC1_N")
	)
	(segment
		(start 37.45611 -72.50176)
		(end 35.693858 -74.264012)
		(width 0.08382)
		(layer "In9.Cu")
		(net "H_CPU1_MEMTRIP_LVC1_N")
	)
	(segment
		(start 31.582868 -96.4946)
		(end 31.455868 -96.6216)
		(width 0.08382)
		(layer "In9.Cu")
		(net "H_CPU1_MEMTRIP_LVC1_N")
	)
	(segment
		(start 41.335452 -63.257176)
		(end 41.335452 -64.963548)
		(width 0.08382)
		(layer "In9.Cu")
		(net "H_CPU1_MEMTRIP_LVC1_N")
	)
	(segment
		(start 46.09973 -56.566562)
		(end 46.506892 -56.1594)
		(width 0.08382)
		(layer "In9.Cu")
		(net "H_CPU1_MEMTRIP_LVC1_N")
	)
	(segment
		(start 40.3352 -67.035172)
		(end 40.06596 -67.304412)
		(width 0.08382)
		(layer "In9.Cu")
		(net "H_CPU1_MEMTRIP_LVC1_N")
	)
	(segment
		(start 44.394628 -60.198)
		(end 41.335452 -63.257176)
		(width 0.08382)
		(layer "In9.Cu")
		(net "H_CPU1_MEMTRIP_LVC1_N")
	)
	(segment
		(start 32.66313 -85.378036)
		(end 32.66313 -86.034372)
		(width 0.08382)
		(layer "In9.Cu")
		(net "H_CPU1_MEMTRIP_LVC1_N")
	)
	(segment
		(start 32.22371 -90.153744)
		(end 32.07639 -90.301064)
		(width 0.08382)
		(layer "In9.Cu")
		(net "H_CPU1_MEMTRIP_LVC1_N")
	)
	(segment
		(start 32.44342 -82.38871)
		(end 32.44342 -84.585302)
		(width 0.08382)
		(layer "In9.Cu")
		(net "H_CPU1_MEMTRIP_LVC1_N")
	)
	(segment
		(start 46.506892 -56.1594)
		(end 47.1932 -56.1594)
		(width 0.08382)
		(layer "In9.Cu")
		(net "H_CPU1_MEMTRIP_LVC1_N")
	)
	(segment
		(start 32.3596 -87.100664)
		(end 32.3596 -88.096344)
		(width 0.08382)
		(layer "In9.Cu")
		(net "H_CPU1_MEMTRIP_LVC1_N")
	)
	(segment
		(start 32.66567 -85.375496)
		(end 32.66313 -85.378036)
		(width 0.08382)
		(layer "In9.Cu")
		(net "H_CPU1_MEMTRIP_LVC1_N")
	)
	(segment
		(start 16.0782 -93.8022)
		(end 15.2146 -92.9386)
		(width 0.08382)
		(layer "In9.Cu")
		(net "H_CPU1_MEMTRIP_LVC1_N")
	)
	(segment
		(start 40.06596 -67.304412)
		(end 40.06596 -70.247002)
		(width 0.08382)
		(layer "In9.Cu")
		(net "H_CPU1_MEMTRIP_LVC1_N")
	)
	(segment
		(start 32.22371 -88.232234)
		(end 32.22371 -90.153744)
		(width 0.08382)
		(layer "In9.Cu")
		(net "H_CPU1_MEMTRIP_LVC1_N")
	)
	(segment
		(start 47.3202 -58.42)
		(end 47.1932 -58.547)
		(width 0.08382)
		(layer "In9.Cu")
		(net "H_CPU1_MEMTRIP_LVC1_N")
	)
	(segment
		(start 32.385 -93.928946)
		(end 31.582868 -94.731078)
		(width 0.08382)
		(layer "In9.Cu")
		(net "H_CPU1_MEMTRIP_LVC1_N")
	)
	(segment
		(start 31.582868 -94.731078)
		(end 31.582868 -96.4946)
		(width 0.08382)
		(layer "In9.Cu")
		(net "H_CPU1_MEMTRIP_LVC1_N")
	)
	(segment
		(start 47.3202 -56.2864)
		(end 47.3202 -58.42)
		(width 0.08382)
		(layer "In9.Cu")
		(net "H_CPU1_MEMTRIP_LVC1_N")
	)
	(segment
		(start 46.736 -58.547)
		(end 45.085 -60.198)
		(width 0.08382)
		(layer "In9.Cu")
		(net "H_CPU1_MEMTRIP_LVC1_N")
	)
	(segment
		(start 34.61893 -77.444346)
		(end 33.188148 -78.875128)
		(width 0.08382)
		(layer "In9.Cu")
		(net "H_CPU1_MEMTRIP_LVC1_N")
	)
	(segment
		(start 16.259556 -90.786966)
		(end 15.864332 -90.391742)
		(width 0.11684)
		(layer "F.Cu")
		(net "FM_SPD_REMOTE_EN_R")
	)
	(segment
		(start 47.295054 -56.971184)
		(end 46.89983 -57.366408)
		(width 0.11684)
		(layer "F.Cu")
		(net "FM_SPD_REMOTE_EN_R")
	)
	(via
		(at 15.864332 -90.391742)
		(size 0.4572)
		(drill 0.254)
		(layers "F.Cu" "B.Cu")
		(net "FM_SPD_REMOTE_EN_R")
	)
	(via
		(at 46.89983 -57.366408)
		(size 0.4572)
		(drill 0.254)
		(layers "F.Cu" "B.Cu")
		(net "FM_SPD_REMOTE_EN_R")
	)
	(segment
		(start 44.26331 -59.9948)
		(end 44.882054 -59.9948)
		(width 0.08382)
		(layer "In9.Cu")
		(net "FM_SPD_REMOTE_EN_R")
	)
	(segment
		(start 35.49777 -73.791572)
		(end 37.107622 -72.18172)
		(width 0.08382)
		(layer "In9.Cu")
		(net "FM_SPD_REMOTE_EN_R")
	)
	(segment
		(start 40.31869 -65.034922)
		(end 40.31869 -63.93942)
		(width 0.08382)
		(layer "In9.Cu")
		(net "FM_SPD_REMOTE_EN_R")
	)
	(segment
		(start 29.486098 -95.13824)
		(end 31.75635 -92.867988)
		(width 0.08382)
		(layer "In9.Cu")
		(net "FM_SPD_REMOTE_EN_R")
	)
	(segment
		(start 40.31869 -63.93942)
		(end 44.26331 -59.9948)
		(width 0.08382)
		(layer "In9.Cu")
		(net "FM_SPD_REMOTE_EN_R")
	)
	(segment
		(start 27.24658 -95.13824)
		(end 29.486098 -95.13824)
		(width 0.08382)
		(layer "In9.Cu")
		(net "FM_SPD_REMOTE_EN_R")
	)
	(segment
		(start 39.42207 -70.52691)
		(end 39.42207 -66.56832)
		(width 0.08382)
		(layer "In9.Cu")
		(net "FM_SPD_REMOTE_EN_R")
	)
	(segment
		(start 39.42207 -66.56832)
		(end 39.61257 -66.37782)
		(width 0.08382)
		(layer "In9.Cu")
		(net "FM_SPD_REMOTE_EN_R")
	)
	(segment
		(start 15.492222 -92.835222)
		(end 16.256 -93.599)
		(width 0.08382)
		(layer "In9.Cu")
		(net "FM_SPD_REMOTE_EN_R")
	)
	(segment
		(start 16.256 -93.599)
		(end 25.70734 -93.599)
		(width 0.08382)
		(layer "In9.Cu")
		(net "FM_SPD_REMOTE_EN_R")
	)
	(segment
		(start 32.715708 -80.593438)
		(end 32.715708 -78.678786)
		(width 0.08382)
		(layer "In9.Cu")
		(net "FM_SPD_REMOTE_EN_R")
	)
	(segment
		(start 39.61257 -66.37782)
		(end 39.61257 -65.741042)
		(width 0.08382)
		(layer "In9.Cu")
		(net "FM_SPD_REMOTE_EN_R")
	)
	(segment
		(start 37.76726 -72.18172)
		(end 39.42207 -70.52691)
		(width 0.08382)
		(layer "In9.Cu")
		(net "FM_SPD_REMOTE_EN_R")
	)
	(segment
		(start 32.715708 -78.678786)
		(end 34.044636 -77.349858)
		(width 0.08382)
		(layer "In9.Cu")
		(net "FM_SPD_REMOTE_EN_R")
	)
	(segment
		(start 15.492222 -90.763852)
		(end 15.492222 -92.835222)
		(width 0.08382)
		(layer "In9.Cu")
		(net "FM_SPD_REMOTE_EN_R")
	)
	(segment
		(start 34.044636 -74.958956)
		(end 35.21202 -73.791572)
		(width 0.08382)
		(layer "In9.Cu")
		(net "FM_SPD_REMOTE_EN_R")
	)
	(segment
		(start 46.89983 -57.596024)
		(end 46.89983 -57.366408)
		(width 0.08382)
		(layer "In9.Cu")
		(net "FM_SPD_REMOTE_EN_R")
	)
	(segment
		(start 46.505876 -57.989978)
		(end 46.89983 -57.596024)
		(width 0.08382)
		(layer "In9.Cu")
		(net "FM_SPD_REMOTE_EN_R")
	)
	(segment
		(start 44.882054 -59.9948)
		(end 46.505876 -58.370978)
		(width 0.08382)
		(layer "In9.Cu")
		(net "FM_SPD_REMOTE_EN_R")
	)
	(segment
		(start 39.61257 -65.741042)
		(end 40.31869 -65.034922)
		(width 0.08382)
		(layer "In9.Cu")
		(net "FM_SPD_REMOTE_EN_R")
	)
	(segment
		(start 30.63748 -87.697818)
		(end 31.15564 -87.179658)
		(width 0.08382)
		(layer "In9.Cu")
		(net "FM_SPD_REMOTE_EN_R")
	)
	(segment
		(start 46.505876 -58.370978)
		(end 46.505876 -57.989978)
		(width 0.08382)
		(layer "In9.Cu")
		(net "FM_SPD_REMOTE_EN_R")
	)
	(segment
		(start 37.107622 -72.18172)
		(end 37.76726 -72.18172)
		(width 0.08382)
		(layer "In9.Cu")
		(net "FM_SPD_REMOTE_EN_R")
	)
	(segment
		(start 15.864332 -90.391742)
		(end 15.492222 -90.763852)
		(width 0.08382)
		(layer "In9.Cu")
		(net "FM_SPD_REMOTE_EN_R")
	)
	(segment
		(start 34.044636 -77.349858)
		(end 34.044636 -74.958956)
		(width 0.08382)
		(layer "In9.Cu")
		(net "FM_SPD_REMOTE_EN_R")
	)
	(segment
		(start 30.63748 -90.098626)
		(end 30.63748 -87.697818)
		(width 0.08382)
		(layer "In9.Cu")
		(net "FM_SPD_REMOTE_EN_R")
	)
	(segment
		(start 25.70734 -93.599)
		(end 27.24658 -95.13824)
		(width 0.08382)
		(layer "In9.Cu")
		(net "FM_SPD_REMOTE_EN_R")
	)
	(segment
		(start 31.75635 -92.867988)
		(end 31.75635 -91.217496)
		(width 0.08382)
		(layer "In9.Cu")
		(net "FM_SPD_REMOTE_EN_R")
	)
	(segment
		(start 31.75635 -91.217496)
		(end 30.63748 -90.098626)
		(width 0.08382)
		(layer "In9.Cu")
		(net "FM_SPD_REMOTE_EN_R")
	)
	(segment
		(start 31.15564 -87.179658)
		(end 31.15564 -82.153506)
		(width 0.08382)
		(layer "In9.Cu")
		(net "FM_SPD_REMOTE_EN_R")
	)
	(segment
		(start 31.15564 -82.153506)
		(end 32.715708 -80.593438)
		(width 0.08382)
		(layer "In9.Cu")
		(net "FM_SPD_REMOTE_EN_R")
	)
	(segment
		(start 35.21202 -73.791572)
		(end 35.49777 -73.791572)
		(width 0.08382)
		(layer "In9.Cu")
		(net "FM_SPD_REMOTE_EN_R")
	)
	(segment
		(start 18.659348 -87.290148)
		(end 18.659348 -87.587074)
		(width 0.11684)
		(layer "F.Cu")
		(net "FM_ADR_COMPLETE")
	)
	(segment
		(start 46.494954 -56.971184)
		(end 46.09973 -57.366408)
		(width 0.11684)
		(layer "F.Cu")
		(net "FM_ADR_COMPLETE")
	)
	(segment
		(start 18.2118 -86.8426)
		(end 18.659348 -87.290148)
		(width 0.11684)
		(layer "F.Cu")
		(net "FM_ADR_COMPLETE")
	)
	(segment
		(start 18.2118 -86.5124)
		(end 18.2118 -86.8426)
		(width 0.11684)
		(layer "F.Cu")
		(net "FM_ADR_COMPLETE")
	)
	(via
		(at 46.09973 -57.366408)
		(size 0.4572)
		(drill 0.254)
		(layers "F.Cu" "B.Cu")
		(net "FM_ADR_COMPLETE")
	)
	(via
		(at 18.2118 -86.5124)
		(size 0.508)
		(drill 0.254)
		(layers "F.Cu" "B.Cu")
		(net "FM_ADR_COMPLETE")
	)
	(segment
		(start 37.986462 -71.538338)
		(end 39.18585 -70.33895)
		(width 0.08382)
		(layer "In9.Cu")
		(net "FM_ADR_COMPLETE")
	)
	(segment
		(start 17.1958 -87.5284)
		(end 17.1958 -87.6046)
		(width 0.08382)
		(layer "In9.Cu")
		(net "FM_ADR_COMPLETE")
	)
	(segment
		(start 43.793156 -59.414156)
		(end 44.050712 -59.1566)
		(width 0.08382)
		(layer "In9.Cu")
		(net "FM_ADR_COMPLETE")
	)
	(segment
		(start 39.18585 -66.470276)
		(end 39.37635 -66.279776)
		(width 0.08382)
		(layer "In9.Cu")
		(net "FM_ADR_COMPLETE")
	)
	(segment
		(start 44.050712 -59.1566)
		(end 44.83608 -59.1566)
		(width 0.08382)
		(layer "In9.Cu")
		(net "FM_ADR_COMPLETE")
	)
	(segment
		(start 29.503116 -94.85884)
		(end 31.57093 -92.791026)
		(width 0.08382)
		(layer "In9.Cu")
		(net "FM_ADR_COMPLETE")
	)
	(segment
		(start 46.09973 -57.532016)
		(end 46.09973 -57.366408)
		(width 0.08382)
		(layer "In9.Cu")
		(net "FM_ADR_COMPLETE")
	)
	(segment
		(start 17.1958 -87.6046)
		(end 16.2814 -88.519)
		(width 0.08382)
		(layer "In9.Cu")
		(net "FM_ADR_COMPLETE")
	)
	(segment
		(start 15.864332 -92.877132)
		(end 16.3576 -93.3704)
		(width 0.08382)
		(layer "In9.Cu")
		(net "FM_ADR_COMPLETE")
	)
	(segment
		(start 30.40126 -87.599774)
		(end 30.91942 -87.081614)
		(width 0.08382)
		(layer "In9.Cu")
		(net "FM_ADR_COMPLETE")
	)
	(segment
		(start 16.3576 -93.3704)
		(end 25.83434 -93.3704)
		(width 0.08382)
		(layer "In9.Cu")
		(net "FM_ADR_COMPLETE")
	)
	(segment
		(start 43.793156 -60.13069)
		(end 43.793156 -59.414156)
		(width 0.08382)
		(layer "In9.Cu")
		(net "FM_ADR_COMPLETE")
	)
	(segment
		(start 33.808416 -74.860912)
		(end 35.113976 -73.555352)
		(width 0.08382)
		(layer "In9.Cu")
		(net "FM_ADR_COMPLETE")
	)
	(segment
		(start 45.671994 -58.320686)
		(end 45.671994 -57.959752)
		(width 0.08382)
		(layer "In9.Cu")
		(net "FM_ADR_COMPLETE")
	)
	(segment
		(start 37.41674 -71.538338)
		(end 37.986462 -71.538338)
		(width 0.08382)
		(layer "In9.Cu")
		(net "FM_ADR_COMPLETE")
	)
	(segment
		(start 15.864332 -91.145868)
		(end 15.864332 -92.877132)
		(width 0.08382)
		(layer "In9.Cu")
		(net "FM_ADR_COMPLETE")
	)
	(segment
		(start 30.91942 -87.081614)
		(end 30.91942 -82.055462)
		(width 0.08382)
		(layer "In9.Cu")
		(net "FM_ADR_COMPLETE")
	)
	(segment
		(start 30.40126 -90.24366)
		(end 30.40126 -87.599774)
		(width 0.08382)
		(layer "In9.Cu")
		(net "FM_ADR_COMPLETE")
	)
	(segment
		(start 39.18585 -70.33895)
		(end 39.18585 -66.470276)
		(width 0.08382)
		(layer "In9.Cu")
		(net "FM_ADR_COMPLETE")
	)
	(segment
		(start 27.32278 -94.85884)
		(end 29.503116 -94.85884)
		(width 0.08382)
		(layer "In9.Cu")
		(net "FM_ADR_COMPLETE")
	)
	(segment
		(start 39.706296 -63.94831)
		(end 39.975536 -63.94831)
		(width 0.08382)
		(layer "In9.Cu")
		(net "FM_ADR_COMPLETE")
	)
	(segment
		(start 18.2118 -86.5124)
		(end 17.1958 -87.5284)
		(width 0.08382)
		(layer "In9.Cu")
		(net "FM_ADR_COMPLETE")
	)
	(segment
		(start 16.2814 -90.7288)
		(end 15.864332 -91.145868)
		(width 0.08382)
		(layer "In9.Cu")
		(net "FM_ADR_COMPLETE")
	)
	(segment
		(start 39.975536 -63.94831)
		(end 43.793156 -60.13069)
		(width 0.08382)
		(layer "In9.Cu")
		(net "FM_ADR_COMPLETE")
	)
	(segment
		(start 44.83608 -59.1566)
		(end 45.671994 -58.320686)
		(width 0.08382)
		(layer "In9.Cu")
		(net "FM_ADR_COMPLETE")
	)
	(segment
		(start 32.479488 -78.580742)
		(end 33.808416 -77.251814)
		(width 0.08382)
		(layer "In9.Cu")
		(net "FM_ADR_COMPLETE")
	)
	(segment
		(start 25.83434 -93.3704)
		(end 27.32278 -94.85884)
		(width 0.08382)
		(layer "In9.Cu")
		(net "FM_ADR_COMPLETE")
	)
	(segment
		(start 31.57093 -92.791026)
		(end 31.57093 -91.41333)
		(width 0.08382)
		(layer "In9.Cu")
		(net "FM_ADR_COMPLETE")
	)
	(segment
		(start 45.671994 -57.959752)
		(end 46.09973 -57.532016)
		(width 0.08382)
		(layer "In9.Cu")
		(net "FM_ADR_COMPLETE")
	)
	(segment
		(start 30.91942 -82.055462)
		(end 32.479488 -80.495394)
		(width 0.08382)
		(layer "In9.Cu")
		(net "FM_ADR_COMPLETE")
	)
	(segment
		(start 31.57093 -91.41333)
		(end 30.40126 -90.24366)
		(width 0.08382)
		(layer "In9.Cu")
		(net "FM_ADR_COMPLETE")
	)
	(segment
		(start 39.37635 -66.279776)
		(end 39.37635 -64.278256)
		(width 0.08382)
		(layer "In9.Cu")
		(net "FM_ADR_COMPLETE")
	)
	(segment
		(start 39.37635 -64.278256)
		(end 39.706296 -63.94831)
		(width 0.08382)
		(layer "In9.Cu")
		(net "FM_ADR_COMPLETE")
	)
	(segment
		(start 32.479488 -80.495394)
		(end 32.479488 -78.580742)
		(width 0.08382)
		(layer "In9.Cu")
		(net "FM_ADR_COMPLETE")
	)
	(segment
		(start 33.808416 -77.251814)
		(end 33.808416 -74.860912)
		(width 0.08382)
		(layer "In9.Cu")
		(net "FM_ADR_COMPLETE")
	)
	(segment
		(start 35.113976 -73.555352)
		(end 35.399726 -73.555352)
		(width 0.08382)
		(layer "In9.Cu")
		(net "FM_ADR_COMPLETE")
	)
	(segment
		(start 16.2814 -88.519)
		(end 16.2814 -90.7288)
		(width 0.08382)
		(layer "In9.Cu")
		(net "FM_ADR_COMPLETE")
	)
	(segment
		(start 35.399726 -73.555352)
		(end 37.41674 -71.538338)
		(width 0.08382)
		(layer "In9.Cu")
		(net "FM_ADR_COMPLETE")
	)
	(segment
		(start 45.695108 -57.771284)
		(end 45.299884 -58.166508)
		(width 0.11684)
		(layer "F.Cu")
		(net "FM_ADR_TRIGGER_N")
	)
	(segment
		(start 17.464278 -94.382336)
		(end 17.859502 -93.987112)
		(width 0.11684)
		(layer "F.Cu")
		(net "FM_ADR_TRIGGER_N")
	)
	(via
		(at 45.085 -93.7514)
		(size 0.508)
		(drill 0.254)
		(layers "F.Cu" "B.Cu")
		(net "FM_ADR_TRIGGER_N")
	)
	(via
		(at 17.464278 -94.382336)
		(size 0.4572)
		(drill 0.254)
		(layers "F.Cu" "B.Cu")
		(net "FM_ADR_TRIGGER_N")
	)
	(via
		(at 45.299884 -58.166508)
		(size 0.4572)
		(drill 0.254)
		(layers "F.Cu" "B.Cu")
		(net "FM_ADR_TRIGGER_N")
	)
	(segment
		(start 17.225518 -94.382336)
		(end 17.464278 -94.382336)
		(width 0.11684)
		(layer "B.Cu")
		(net "FM_ADR_TRIGGER_N")
	)
	(segment
		(start 15.18285 -95.5802)
		(end 15.97025 -94.7928)
		(width 0.11684)
		(layer "B.Cu")
		(net "FM_ADR_TRIGGER_N")
	)
	(segment
		(start 15.97025 -94.7928)
		(end 16.815054 -94.7928)
		(width 0.11684)
		(layer "B.Cu")
		(net "FM_ADR_TRIGGER_N")
	)
	(segment
		(start 16.815054 -94.7928)
		(end 17.225518 -94.382336)
		(width 0.11684)
		(layer "B.Cu")
		(net "FM_ADR_TRIGGER_N")
	)
	(segment
		(start 34.4932 -93.2434)
		(end 33.65119 -94.08541)
		(width 0.08382)
		(layer "In2.Cu")
		(net "FM_ADR_TRIGGER_N")
	)
	(segment
		(start 33.65119 -94.08541)
		(end 30.06979 -94.08541)
		(width 0.08382)
		(layer "In2.Cu")
		(net "FM_ADR_TRIGGER_N")
	)
	(segment
		(start 18.146014 -93.7006)
		(end 17.464278 -94.382336)
		(width 0.08382)
		(layer "In2.Cu")
		(net "FM_ADR_TRIGGER_N")
	)
	(segment
		(start 44.577 -93.2434)
		(end 34.4932 -93.2434)
		(width 0.08382)
		(layer "In2.Cu")
		(net "FM_ADR_TRIGGER_N")
	)
	(segment
		(start 29.02712 -95.12808)
		(end 27.63012 -95.12808)
		(width 0.08382)
		(layer "In2.Cu")
		(net "FM_ADR_TRIGGER_N")
	)
	(segment
		(start 30.06979 -94.08541)
		(end 29.02712 -95.12808)
		(width 0.08382)
		(layer "In2.Cu")
		(net "FM_ADR_TRIGGER_N")
	)
	(segment
		(start 27.63012 -95.12808)
		(end 26.20264 -93.7006)
		(width 0.08382)
		(layer "In2.Cu")
		(net "FM_ADR_TRIGGER_N")
	)
	(segment
		(start 26.20264 -93.7006)
		(end 18.146014 -93.7006)
		(width 0.08382)
		(layer "In2.Cu")
		(net "FM_ADR_TRIGGER_N")
	)
	(segment
		(start 45.085 -93.7514)
		(end 44.577 -93.2434)
		(width 0.08382)
		(layer "In2.Cu")
		(net "FM_ADR_TRIGGER_N")
	)
	(segment
		(start 45.53204 -73.560686)
		(end 45.53204 -77.21092)
		(width 0.10668)
		(layer "In4.Cu")
		(net "FM_ADR_TRIGGER_N")
	)
	(segment
		(start 45.197776 -61.634878)
		(end 45.197776 -65.753234)
		(width 0.10668)
		(layer "In4.Cu")
		(net "FM_ADR_TRIGGER_N")
	)
	(segment
		(start 45.085 -92.0496)
		(end 45.085 -93.7514)
		(width 0.10668)
		(layer "In4.Cu")
		(net "FM_ADR_TRIGGER_N")
	)
	(segment
		(start 45.6946 -66.250058)
		(end 45.6946 -68.427854)
		(width 0.10668)
		(layer "In4.Cu")
		(net "FM_ADR_TRIGGER_N")
	)
	(segment
		(start 44.48048 -81.45272)
		(end 44.48048 -89.591642)
		(width 0.10668)
		(layer "In4.Cu")
		(net "FM_ADR_TRIGGER_N")
	)
	(segment
		(start 44.24426 -80.33766)
		(end 44.24426 -81.2165)
		(width 0.10668)
		(layer "In4.Cu")
		(net "FM_ADR_TRIGGER_N")
	)
	(segment
		(start 45.58284 -58.449464)
		(end 45.58284 -61.249814)
		(width 0.10668)
		(layer "In4.Cu")
		(net "FM_ADR_TRIGGER_N")
	)
	(segment
		(start 45.4025 -68.719954)
		(end 45.4025 -69.94906)
		(width 0.10668)
		(layer "In4.Cu")
		(net "FM_ADR_TRIGGER_N")
	)
	(segment
		(start 45.99432 -71.25208)
		(end 45.4914 -71.755)
		(width 0.10668)
		(layer "In4.Cu")
		(net "FM_ADR_TRIGGER_N")
	)
	(segment
		(start 45.4914 -71.755)
		(end 45.4914 -73.520046)
		(width 0.10668)
		(layer "In4.Cu")
		(net "FM_ADR_TRIGGER_N")
	)
	(segment
		(start 45.53204 -77.21092)
		(end 43.48226 -79.2607)
		(width 0.10668)
		(layer "In4.Cu")
		(net "FM_ADR_TRIGGER_N")
	)
	(segment
		(start 45.99432 -70.54088)
		(end 45.99432 -71.25208)
		(width 0.10668)
		(layer "In4.Cu")
		(net "FM_ADR_TRIGGER_N")
	)
	(segment
		(start 45.6946 -68.427854)
		(end 45.4025 -68.719954)
		(width 0.10668)
		(layer "In4.Cu")
		(net "FM_ADR_TRIGGER_N")
	)
	(segment
		(start 45.299884 -58.166508)
		(end 45.58284 -58.449464)
		(width 0.10668)
		(layer "In4.Cu")
		(net "FM_ADR_TRIGGER_N")
	)
	(segment
		(start 45.58284 -61.249814)
		(end 45.197776 -61.634878)
		(width 0.10668)
		(layer "In4.Cu")
		(net "FM_ADR_TRIGGER_N")
	)
	(segment
		(start 44.4754 -89.596722)
		(end 44.4754 -91.44)
		(width 0.10668)
		(layer "In4.Cu")
		(net "FM_ADR_TRIGGER_N")
	)
	(segment
		(start 45.4914 -73.520046)
		(end 45.53204 -73.560686)
		(width 0.10668)
		(layer "In4.Cu")
		(net "FM_ADR_TRIGGER_N")
	)
	(segment
		(start 43.48226 -79.2607)
		(end 43.48226 -79.57566)
		(width 0.10668)
		(layer "In4.Cu")
		(net "FM_ADR_TRIGGER_N")
	)
	(segment
		(start 44.4754 -91.44)
		(end 45.085 -92.0496)
		(width 0.10668)
		(layer "In4.Cu")
		(net "FM_ADR_TRIGGER_N")
	)
	(segment
		(start 44.48048 -89.591642)
		(end 44.4754 -89.596722)
		(width 0.10668)
		(layer "In4.Cu")
		(net "FM_ADR_TRIGGER_N")
	)
	(segment
		(start 45.4025 -69.94906)
		(end 45.99432 -70.54088)
		(width 0.10668)
		(layer "In4.Cu")
		(net "FM_ADR_TRIGGER_N")
	)
	(segment
		(start 43.48226 -79.57566)
		(end 44.24426 -80.33766)
		(width 0.10668)
		(layer "In4.Cu")
		(net "FM_ADR_TRIGGER_N")
	)
	(segment
		(start 45.197776 -65.753234)
		(end 45.6946 -66.250058)
		(width 0.10668)
		(layer "In4.Cu")
		(net "FM_ADR_TRIGGER_N")
	)
	(segment
		(start 44.24426 -81.2165)
		(end 44.48048 -81.45272)
		(width 0.10668)
		(layer "In4.Cu")
		(net "FM_ADR_TRIGGER_N")
	)
	(segment
		(start 40.47998 -59.48807)
		(end 40.47998 -59.19851)
		(width 0.11684)
		(layer "F.Cu")
		(net "ID_RST_BTN_BMC_R_N")
	)
	(segment
		(start 36.9824 -60.57265)
		(end 37.30879 -60.89904)
		(width 0.11684)
		(layer "F.Cu")
		(net "ID_RST_BTN_BMC_R_N")
	)
	(segment
		(start 39.918132 -60.198)
		(end 40.241728 -60.063888)
		(width 0.11684)
		(layer "F.Cu")
		(net "ID_RST_BTN_BMC_R_N")
	)
	(segment
		(start 40.47998 -59.19851)
		(end 41.306242 -57.204102)
		(width 0.11684)
		(layer "F.Cu")
		(net "ID_RST_BTN_BMC_R_N")
	)
	(segment
		(start 41.306242 -57.204102)
		(end 41.969944 -56.5404)
		(width 0.11684)
		(layer "F.Cu")
		(net "ID_RST_BTN_BMC_R_N")
	)
	(segment
		(start 47.295054 -55.371238)
		(end 46.89983 -55.766462)
		(width 0.11684)
		(layer "F.Cu")
		(net "ID_RST_BTN_BMC_R_N")
	)
	(segment
		(start 41.969944 -56.5404)
		(end 42.4688 -56.5404)
		(width 0.11684)
		(layer "F.Cu")
		(net "ID_RST_BTN_BMC_R_N")
	)
	(segment
		(start 37.30879 -60.89904)
		(end 38.924992 -60.89904)
		(width 0.11684)
		(layer "F.Cu")
		(net "ID_RST_BTN_BMC_R_N")
	)
	(segment
		(start 40.241728 -60.063888)
		(end 40.47998 -59.48807)
		(width 0.11684)
		(layer "F.Cu")
		(net "ID_RST_BTN_BMC_R_N")
	)
	(segment
		(start 38.924992 -60.89904)
		(end 39.626032 -60.198)
		(width 0.11684)
		(layer "F.Cu")
		(net "ID_RST_BTN_BMC_R_N")
	)
	(segment
		(start 39.626032 -60.198)
		(end 39.918132 -60.198)
		(width 0.11684)
		(layer "F.Cu")
		(net "ID_RST_BTN_BMC_R_N")
	)
	(via
		(at 42.4688 -56.5404)
		(size 0.508)
		(drill 0.254)
		(layers "F.Cu" "B.Cu")
		(net "ID_RST_BTN_BMC_R_N")
	)
	(via
		(at 46.89983 -55.766462)
		(size 0.4572)
		(drill 0.254)
		(layers "F.Cu" "B.Cu")
		(net "ID_RST_BTN_BMC_R_N")
	)
	(segment
		(start 46.47692 -56.189372)
		(end 46.89983 -55.766462)
		(width 0.08382)
		(layer "In2.Cu")
		(net "ID_RST_BTN_BMC_R_N")
	)
	(segment
		(start 42.4688 -56.5404)
		(end 42.75582 -56.82742)
		(width 0.08382)
		(layer "In2.Cu")
		(net "ID_RST_BTN_BMC_R_N")
	)
	(segment
		(start 45.639228 -56.189372)
		(end 46.47692 -56.189372)
		(width 0.08382)
		(layer "In2.Cu")
		(net "ID_RST_BTN_BMC_R_N")
	)
	(segment
		(start 42.75582 -56.82742)
		(end 45.00118 -56.82742)
		(width 0.08382)
		(layer "In2.Cu")
		(net "ID_RST_BTN_BMC_R_N")
	)
	(segment
		(start 45.00118 -56.82742)
		(end 45.639228 -56.189372)
		(width 0.08382)
		(layer "In2.Cu")
		(net "ID_RST_BTN_BMC_R_N")
	)
	(segment
		(start 53.695092 -39.37127)
		(end 53.299868 -38.976046)
		(width 0.11684)
		(layer "F.Cu")
		(net "IRQ_PCH_SCI_WHEA_R_N")
	)
	(via
		(at 53.299868 -38.976046)
		(size 0.4572)
		(drill 0.254)
		(layers "F.Cu" "B.Cu")
		(net "IRQ_PCH_SCI_WHEA_R_N")
	)
	(segment
		(start 53.387498 -37.862002)
		(end 53.387498 -37.596064)
		(width 0.11684)
		(layer "B.Cu")
		(net "IRQ_PCH_SCI_WHEA_R_N")
	)
	(segment
		(start 53.299868 -38.976046)
		(end 53.299868 -38.720014)
		(width 0.11684)
		(layer "B.Cu")
		(net "IRQ_PCH_SCI_WHEA_R_N")
	)
	(segment
		(start 53.1368 -38.556946)
		(end 53.1368 -38.1127)
		(width 0.11684)
		(layer "B.Cu")
		(net "IRQ_PCH_SCI_WHEA_R_N")
	)
	(segment
		(start 54.023006 -35.227006)
		(end 53.833776 -35.037776)
		(width 0.11684)
		(layer "B.Cu")
		(net "IRQ_PCH_SCI_WHEA_R_N")
	)
	(segment
		(start 53.387498 -37.596064)
		(end 54.177184 -36.806378)
		(width 0.11684)
		(layer "B.Cu")
		(net "IRQ_PCH_SCI_WHEA_R_N")
	)
	(segment
		(start 53.1368 -38.1127)
		(end 53.387498 -37.862002)
		(width 0.11684)
		(layer "B.Cu")
		(net "IRQ_PCH_SCI_WHEA_R_N")
	)
	(segment
		(start 54.18836 -35.808666)
		(end 54.18836 -35.802824)
		(width 0.11684)
		(layer "B.Cu")
		(net "IRQ_PCH_SCI_WHEA_R_N")
	)
	(segment
		(start 54.177184 -36.806378)
		(end 54.25948 -36.60775)
		(width 0.11684)
		(layer "B.Cu")
		(net "IRQ_PCH_SCI_WHEA_R_N")
	)
	(segment
		(start 54.25948 -35.981386)
		(end 54.18836 -35.808666)
		(width 0.11684)
		(layer "B.Cu")
		(net "IRQ_PCH_SCI_WHEA_R_N")
	)
	(segment
		(start 53.299868 -38.720014)
		(end 53.1368 -38.556946)
		(width 0.11684)
		(layer "B.Cu")
		(net "IRQ_PCH_SCI_WHEA_R_N")
	)
	(segment
		(start 54.18836 -35.802824)
		(end 54.1782 -35.778186)
		(width 0.11684)
		(layer "B.Cu")
		(net "IRQ_PCH_SCI_WHEA_R_N")
	)
	(segment
		(start 54.25948 -36.60775)
		(end 54.25948 -35.981386)
		(width 0.11684)
		(layer "B.Cu")
		(net "IRQ_PCH_SCI_WHEA_R_N")
	)
	(segment
		(start 53.833776 -35.037776)
		(end 53.5432 -35.037776)
		(width 0.11684)
		(layer "B.Cu")
		(net "IRQ_PCH_SCI_WHEA_R_N")
	)
	(segment
		(start 54.1782 -35.778186)
		(end 54.1782 -35.602672)
		(width 0.11684)
		(layer "B.Cu")
		(net "IRQ_PCH_SCI_WHEA_R_N")
	)
	(segment
		(start 54.1782 -35.602672)
		(end 54.023006 -35.227006)
		(width 0.11684)
		(layer "B.Cu")
		(net "IRQ_PCH_SCI_WHEA_R_N")
	)
	(segment
		(start 51.855624 -103.936038)
		(end 52.106576 -103.685086)
		(width 0.11684)
		(layer "F.Cu")
		(net "SPI_SYS_MUX_WP_IO2")
	)
	(segment
		(start 51.479196 -103.739442)
		(end 51.675792 -103.936038)
		(width 0.11684)
		(layer "F.Cu")
		(net "SPI_SYS_MUX_WP_IO2")
	)
	(segment
		(start 52.223416 -101.8286)
		(end 53.135784 -101.8286)
		(width 0.11684)
		(layer "F.Cu")
		(net "SPI_SYS_MUX_WP_IO2")
	)
	(segment
		(start 49.628044 -101.684328)
		(end 49.96942 -102.025704)
		(width 0.11684)
		(layer "F.Cu")
		(net "SPI_SYS_MUX_WP_IO2")
	)
	(segment
		(start 50.242216 -101.344984)
		(end 49.798224 -101.344984)
		(width 0.11684)
		(layer "F.Cu")
		(net "SPI_SYS_MUX_WP_IO2")
	)
	(segment
		(start 48.9458 -103.90505)
		(end 49.425606 -104.384856)
		(width 0.11684)
		(layer "F.Cu")
		(net "SPI_SYS_MUX_WP_IO2")
	)
	(segment
		(start 49.955958 -104.384856)
		(end 50.23358 -104.107234)
		(width 0.11684)
		(layer "F.Cu")
		(net "SPI_SYS_MUX_WP_IO2")
	)
	(segment
		(start 53.545486 -102.238302)
		(end 53.545486 -103.197914)
		(width 0.11684)
		(layer "F.Cu")
		(net "SPI_SYS_MUX_WP_IO2")
	)
	(segment
		(start 48.9458 -103.518716)
		(end 48.9458 -103.90505)
		(width 0.11684)
		(layer "F.Cu")
		(net "SPI_SYS_MUX_WP_IO2")
	)
	(segment
		(start 51.479196 -102.7684)
		(end 51.479196 -101.797358)
		(width 0.11684)
		(layer "F.Cu")
		(net "SPI_SYS_MUX_WP_IO2")
	)
	(segment
		(start 52.106576 -103.685086)
		(end 52.106576 -101.94544)
		(width 0.11684)
		(layer "F.Cu")
		(net "SPI_SYS_MUX_WP_IO2")
	)
	(segment
		(start 52.5526 -106.5784)
		(end 52.50815 -106.5784)
		(width 0.11684)
		(layer "F.Cu")
		(net "SPI_SYS_MUX_WP_IO2")
	)
	(segment
		(start 49.425606 -104.384856)
		(end 49.955958 -104.384856)
		(width 0.11684)
		(layer "F.Cu")
		(net "SPI_SYS_MUX_WP_IO2")
	)
	(segment
		(start 53.281326 -105.849674)
		(end 52.5526 -106.5784)
		(width 0.11684)
		(layer "F.Cu")
		(net "SPI_SYS_MUX_WP_IO2")
	)
	(segment
		(start 50.474372 -102.618032)
		(end 50.76952 -102.322884)
		(width 0.11684)
		(layer "F.Cu")
		(net "SPI_SYS_MUX_WP_IO2")
	)
	(segment
		(start 53.281326 -103.462074)
		(end 53.281326 -105.849674)
		(width 0.11684)
		(layer "F.Cu")
		(net "SPI_SYS_MUX_WP_IO2")
	)
	(segment
		(start 50.23358 -103.199438)
		(end 50.474372 -102.618032)
		(width 0.11684)
		(layer "F.Cu")
		(net "SPI_SYS_MUX_WP_IO2")
	)
	(segment
		(start 53.545486 -103.197914)
		(end 53.281326 -103.462074)
		(width 0.11684)
		(layer "F.Cu")
		(net "SPI_SYS_MUX_WP_IO2")
	)
	(segment
		(start 52.106576 -101.94544)
		(end 52.223416 -101.8286)
		(width 0.11684)
		(layer "F.Cu")
		(net "SPI_SYS_MUX_WP_IO2")
	)
	(segment
		(start 51.675792 -103.936038)
		(end 51.855624 -103.936038)
		(width 0.11684)
		(layer "F.Cu")
		(net "SPI_SYS_MUX_WP_IO2")
	)
	(segment
		(start 49.96942 -102.025704)
		(end 49.96942 -102.495096)
		(width 0.11684)
		(layer "F.Cu")
		(net "SPI_SYS_MUX_WP_IO2")
	)
	(segment
		(start 50.23358 -104.107234)
		(end 50.23358 -103.199438)
		(width 0.11684)
		(layer "F.Cu")
		(net "SPI_SYS_MUX_WP_IO2")
	)
	(segment
		(start 50.593752 -101.69652)
		(end 50.242216 -101.344984)
		(width 0.11684)
		(layer "F.Cu")
		(net "SPI_SYS_MUX_WP_IO2")
	)
	(segment
		(start 49.96942 -102.495096)
		(end 48.9458 -103.518716)
		(width 0.11684)
		(layer "F.Cu")
		(net "SPI_SYS_MUX_WP_IO2")
	)
	(segment
		(start 49.628044 -101.515164)
		(end 49.628044 -101.684328)
		(width 0.11684)
		(layer "F.Cu")
		(net "SPI_SYS_MUX_WP_IO2")
	)
	(segment
		(start 53.135784 -101.8286)
		(end 53.545486 -102.238302)
		(width 0.11684)
		(layer "F.Cu")
		(net "SPI_SYS_MUX_WP_IO2")
	)
	(segment
		(start 51.378358 -101.69652)
		(end 50.593752 -101.69652)
		(width 0.11684)
		(layer "F.Cu")
		(net "SPI_SYS_MUX_WP_IO2")
	)
	(segment
		(start 51.479196 -102.7684)
		(end 51.479196 -103.739442)
		(width 0.11684)
		(layer "F.Cu")
		(net "SPI_SYS_MUX_WP_IO2")
	)
	(segment
		(start 49.798224 -101.344984)
		(end 49.628044 -101.515164)
		(width 0.11684)
		(layer "F.Cu")
		(net "SPI_SYS_MUX_WP_IO2")
	)
	(segment
		(start 51.479196 -101.797358)
		(end 51.378358 -101.69652)
		(width 0.11684)
		(layer "F.Cu")
		(net "SPI_SYS_MUX_WP_IO2")
	)
	(via
		(at 51.479196 -102.7684)
		(size 0.762)
		(drill 0.381)
		(layers "F.Cu" "B.Cu")
		(net "SPI_SYS_MUX_WP_IO2")
	)
	(via
		(at 50.76952 -102.322884)
		(size 0.508)
		(drill 0.254)
		(layers "F.Cu" "B.Cu")
		(net "SPI_SYS_MUX_WP_IO2")
	)
	(segment
		(start 47.770288 -103.327962)
		(end 46.811184 -103.327962)
		(width 0.11684)
		(layer "B.Cu")
		(net "SPI_SYS_MUX_WP_IO2")
	)
	(segment
		(start 49.533556 -103.558848)
		(end 48.001174 -103.558848)
		(width 0.11684)
		(layer "B.Cu")
		(net "SPI_SYS_MUX_WP_IO2")
	)
	(segment
		(start 50.76952 -102.322884)
		(end 49.533556 -103.558848)
		(width 0.11684)
		(layer "B.Cu")
		(net "SPI_SYS_MUX_WP_IO2")
	)
	(segment
		(start 48.001174 -103.558848)
		(end 47.770288 -103.327962)
		(width 0.11684)
		(layer "B.Cu")
		(net "SPI_SYS_MUX_WP_IO2")
	)
	(segment
		(start 54.10708 -107.579668)
		(end 54.675024 -108.951014)
		(width 0.11684)
		(layer "F.Cu")
		(net "SPI_SYS_MUX_MOSI")
	)
	(segment
		(start 54.10708 -103.800656)
		(end 54.10708 -107.579668)
		(width 0.11684)
		(layer "F.Cu")
		(net "SPI_SYS_MUX_MOSI")
	)
	(segment
		(start 54.675024 -108.951014)
		(end 54.7878 -108.99775)
		(width 0.11684)
		(layer "F.Cu")
		(net "SPI_SYS_MUX_MOSI")
	)
	(segment
		(start 54.2925 -101.527864)
		(end 54.2925 -103.615236)
		(width 0.11684)
		(layer "F.Cu")
		(net "SPI_SYS_MUX_MOSI")
	)
	(segment
		(start 54.1528 -101.388164)
		(end 54.2925 -101.527864)
		(width 0.11684)
		(layer "F.Cu")
		(net "SPI_SYS_MUX_MOSI")
	)
	(segment
		(start 54.2925 -103.615236)
		(end 54.10708 -103.800656)
		(width 0.11684)
		(layer "F.Cu")
		(net "SPI_SYS_MUX_MOSI")
	)
	(via
		(at 54.1528 -101.388164)
		(size 0.508)
		(drill 0.254)
		(layers "F.Cu" "B.Cu")
		(net "SPI_SYS_MUX_MOSI")
	)
	(via
		(at 54.40045 -84.76996)
		(size 0.508)
		(drill 0.254)
		(layers "F.Cu" "B.Cu")
		(net "SPI_SYS_MUX_MOSI")
	)
	(via
		(at 51.41976 -84.68868)
		(size 0.6604)
		(drill 0.3302)
		(layers "F.Cu" "B.Cu")
		(net "SPI_SYS_MUX_MOSI")
	)
	(segment
		(start 47.449486 -84.68868)
		(end 46.578266 -83.81746)
		(width 0.11684)
		(layer "B.Cu")
		(net "SPI_SYS_MUX_MOSI")
	)
	(segment
		(start 54.40045 -84.76996)
		(end 54.31917 -84.68868)
		(width 0.11684)
		(layer "B.Cu")
		(net "SPI_SYS_MUX_MOSI")
	)
	(segment
		(start 45.20819 -83.81746)
		(end 43.12793 -81.7372)
		(width 0.11684)
		(layer "B.Cu")
		(net "SPI_SYS_MUX_MOSI")
	)
	(segment
		(start 42.2148 -80.51546)
		(end 42.482516 -79.869284)
		(width 0.11684)
		(layer "B.Cu")
		(net "SPI_SYS_MUX_MOSI")
	)
	(segment
		(start 51.41976 -84.68868)
		(end 47.449486 -84.68868)
		(width 0.11684)
		(layer "B.Cu")
		(net "SPI_SYS_MUX_MOSI")
	)
	(segment
		(start 46.578266 -83.81746)
		(end 45.20819 -83.81746)
		(width 0.11684)
		(layer "B.Cu")
		(net "SPI_SYS_MUX_MOSI")
	)
	(segment
		(start 43.12793 -81.7372)
		(end 42.697654 -81.7372)
		(width 0.11684)
		(layer "B.Cu")
		(net "SPI_SYS_MUX_MOSI")
	)
	(segment
		(start 42.2148 -81.254346)
		(end 42.2148 -80.51546)
		(width 0.11684)
		(layer "B.Cu")
		(net "SPI_SYS_MUX_MOSI")
	)
	(segment
		(start 42.482516 -79.869284)
		(end 44.016676 -78.335124)
		(width 0.11684)
		(layer "B.Cu")
		(net "SPI_SYS_MUX_MOSI")
	)
	(segment
		(start 54.31917 -84.68868)
		(end 51.41976 -84.68868)
		(width 0.11684)
		(layer "B.Cu")
		(net "SPI_SYS_MUX_MOSI")
	)
	(segment
		(start 42.697654 -81.7372)
		(end 42.2148 -81.254346)
		(width 0.11684)
		(layer "B.Cu")
		(net "SPI_SYS_MUX_MOSI")
	)
	(segment
		(start 44.016676 -78.335124)
		(end 46.019466 -78.335124)
		(width 0.11684)
		(layer "B.Cu")
		(net "SPI_SYS_MUX_MOSI")
	)
	(segment
		(start 53.31841 -92.853002)
		(end 53.63845 -96.102932)
		(width 0.08382)
		(layer "In9.Cu")
		(net "SPI_SYS_MUX_MOSI")
	)
	(segment
		(start 53.2638 -89.99474)
		(end 53.31841 -91.107514)
		(width 0.08382)
		(layer "In9.Cu")
		(net "SPI_SYS_MUX_MOSI")
	)
	(segment
		(start 53.31841 -91.107514)
		(end 53.31841 -92.853002)
		(width 0.08382)
		(layer "In9.Cu")
		(net "SPI_SYS_MUX_MOSI")
	)
	(segment
		(start 53.63845 -96.102932)
		(end 53.63845 -100.873814)
		(width 0.08382)
		(layer "In9.Cu")
		(net "SPI_SYS_MUX_MOSI")
	)
	(segment
		(start 53.63845 -100.873814)
		(end 54.1528 -101.388164)
		(width 0.08382)
		(layer "In9.Cu")
		(net "SPI_SYS_MUX_MOSI")
	)
	(segment
		(start 54.41696 -84.78647)
		(end 54.41696 -86.247986)
		(width 0.08382)
		(layer "In9.Cu")
		(net "SPI_SYS_MUX_MOSI")
	)
	(segment
		(start 54.40045 -84.76996)
		(end 54.41696 -84.78647)
		(width 0.08382)
		(layer "In9.Cu")
		(net "SPI_SYS_MUX_MOSI")
	)
	(segment
		(start 53.2638 -87.401146)
		(end 53.2638 -89.99474)
		(width 0.08382)
		(layer "In9.Cu")
		(net "SPI_SYS_MUX_MOSI")
	)
	(segment
		(start 54.41696 -86.247986)
		(end 53.2638 -87.401146)
		(width 0.08382)
		(layer "In9.Cu")
		(net "SPI_SYS_MUX_MOSI")
	)
	(segment
		(start 51.674014 -100.298758)
		(end 51.779932 -100.19284)
		(width 0.11684)
		(layer "F.Cu")
		(net "SPI_SYS_MUX_MISO")
	)
	(segment
		(start 52.174394 -100.298758)
		(end 52.174394 -100.958142)
		(width 0.11684)
		(layer "F.Cu")
		(net "SPI_SYS_MUX_MISO")
	)
	(segment
		(start 52.346352 -101.1301)
		(end 52.9082 -101.1301)
		(width 0.11684)
		(layer "F.Cu")
		(net "SPI_SYS_MUX_MISO")
	)
	(segment
		(start 50.856388 -101.1301)
		(end 51.552856 -101.1301)
		(width 0.11684)
		(layer "F.Cu")
		(net "SPI_SYS_MUX_MISO")
	)
	(segment
		(start 51.674014 -101.008942)
		(end 51.674014 -100.298758)
		(width 0.11684)
		(layer "F.Cu")
		(net "SPI_SYS_MUX_MISO")
	)
	(segment
		(start 53.92166 -103.461566)
		(end 53.73624 -103.646986)
		(width 0.11684)
		(layer "F.Cu")
		(net "SPI_SYS_MUX_MISO")
	)
	(segment
		(start 51.779932 -100.19284)
		(end 52.068476 -100.19284)
		(width 0.11684)
		(layer "F.Cu")
		(net "SPI_SYS_MUX_MISO")
	)
	(segment
		(start 52.068476 -100.19284)
		(end 52.174394 -100.298758)
		(width 0.11684)
		(layer "F.Cu")
		(net "SPI_SYS_MUX_MISO")
	)
	(segment
		(start 51.552856 -101.1301)
		(end 51.674014 -101.008942)
		(width 0.11684)
		(layer "F.Cu")
		(net "SPI_SYS_MUX_MISO")
	)
	(segment
		(start 53.73624 -108.96219)
		(end 53.7718 -108.99775)
		(width 0.11684)
		(layer "F.Cu")
		(net "SPI_SYS_MUX_MISO")
	)
	(segment
		(start 52.9082 -101.1301)
		(end 52.971954 -101.1301)
		(width 0.11684)
		(layer "F.Cu")
		(net "SPI_SYS_MUX_MISO")
	)
	(segment
		(start 52.971954 -101.1301)
		(end 53.92166 -102.079806)
		(width 0.11684)
		(layer "F.Cu")
		(net "SPI_SYS_MUX_MISO")
	)
	(segment
		(start 53.92166 -102.079806)
		(end 53.92166 -103.461566)
		(width 0.11684)
		(layer "F.Cu")
		(net "SPI_SYS_MUX_MISO")
	)
	(segment
		(start 53.73624 -103.646986)
		(end 53.73624 -108.96219)
		(width 0.11684)
		(layer "F.Cu")
		(net "SPI_SYS_MUX_MISO")
	)
	(segment
		(start 52.174394 -100.958142)
		(end 52.346352 -101.1301)
		(width 0.11684)
		(layer "F.Cu")
		(net "SPI_SYS_MUX_MISO")
	)
	(via
		(at 52.9082 -101.1301)
		(size 0.762)
		(drill 0.381)
		(layers "F.Cu" "B.Cu")
		(net "SPI_SYS_MUX_MISO")
	)
	(via
		(at 50.856388 -101.1301)
		(size 0.508)
		(drill 0.254)
		(layers "F.Cu" "B.Cu")
		(net "SPI_SYS_MUX_MISO")
	)
	(segment
		(start 51.161442 -99.954842)
		(end 51.014884 -100.1014)
		(width 0.11684)
		(layer "B.Cu")
		(net "SPI_SYS_MUX_MISO")
	)
	(segment
		(start 52.3748 -100.9142)
		(end 52.3748 -100.329746)
		(width 0.11684)
		(layer "B.Cu")
		(net "SPI_SYS_MUX_MISO")
	)
	(segment
		(start 48.97374 -101.53142)
		(end 47.78502 -101.53142)
		(width 0.11684)
		(layer "B.Cu")
		(net "SPI_SYS_MUX_MISO")
	)
	(segment
		(start 51.661822 -98.566986)
		(end 51.661822 -97.555558)
		(width 0.11684)
		(layer "B.Cu")
		(net "SPI_SYS_MUX_MISO")
	)
	(segment
		(start 52.3748 -100.329746)
		(end 52.146454 -100.1014)
		(width 0.11684)
		(layer "B.Cu")
		(net "SPI_SYS_MUX_MISO")
	)
	(segment
		(start 49.5046 -100.1014)
		(end 49.09058 -100.51542)
		(width 0.11684)
		(layer "B.Cu")
		(net "SPI_SYS_MUX_MISO")
	)
	(segment
		(start 52.1589 -101.1301)
		(end 52.3748 -100.9142)
		(width 0.11684)
		(layer "B.Cu")
		(net "SPI_SYS_MUX_MISO")
	)
	(segment
		(start 51.308 -97.409)
		(end 51.161442 -97.555558)
		(width 0.11684)
		(layer "B.Cu")
		(net "SPI_SYS_MUX_MISO")
	)
	(segment
		(start 53.676042 -98.738944)
		(end 51.83378 -98.738944)
		(width 0.11684)
		(layer "B.Cu")
		(net "SPI_SYS_MUX_MISO")
	)
	(segment
		(start 47.78502 -101.53142)
		(end 47.63135 -101.37775)
		(width 0.11684)
		(layer "B.Cu")
		(net "SPI_SYS_MUX_MISO")
	)
	(segment
		(start 51.661822 -99.360482)
		(end 51.78298 -99.239324)
		(width 0.11684)
		(layer "B.Cu")
		(net "SPI_SYS_MUX_MISO")
	)
	(segment
		(start 51.515264 -97.409)
		(end 51.308 -97.409)
		(width 0.11684)
		(layer "B.Cu")
		(net "SPI_SYS_MUX_MISO")
	)
	(segment
		(start 53.8226 -98.885502)
		(end 53.676042 -98.738944)
		(width 0.11684)
		(layer "B.Cu")
		(net "SPI_SYS_MUX_MISO")
	)
	(segment
		(start 51.661822 -99.954842)
		(end 51.661822 -99.360482)
		(width 0.11684)
		(layer "B.Cu")
		(net "SPI_SYS_MUX_MISO")
	)
	(segment
		(start 51.80838 -100.1014)
		(end 51.661822 -99.954842)
		(width 0.11684)
		(layer "B.Cu")
		(net "SPI_SYS_MUX_MISO")
	)
	(segment
		(start 51.014884 -100.1014)
		(end 49.5046 -100.1014)
		(width 0.11684)
		(layer "B.Cu")
		(net "SPI_SYS_MUX_MISO")
	)
	(segment
		(start 53.676042 -99.239324)
		(end 53.8226 -99.092766)
		(width 0.11684)
		(layer "B.Cu")
		(net "SPI_SYS_MUX_MISO")
	)
	(segment
		(start 51.78298 -99.239324)
		(end 53.676042 -99.239324)
		(width 0.11684)
		(layer "B.Cu")
		(net "SPI_SYS_MUX_MISO")
	)
	(segment
		(start 50.856388 -101.1301)
		(end 52.1589 -101.1301)
		(width 0.11684)
		(layer "B.Cu")
		(net "SPI_SYS_MUX_MISO")
	)
	(segment
		(start 52.146454 -100.1014)
		(end 51.80838 -100.1014)
		(width 0.11684)
		(layer "B.Cu")
		(net "SPI_SYS_MUX_MISO")
	)
	(segment
		(start 53.8226 -99.092766)
		(end 53.8226 -98.885502)
		(width 0.11684)
		(layer "B.Cu")
		(net "SPI_SYS_MUX_MISO")
	)
	(segment
		(start 49.09058 -100.51542)
		(end 49.09058 -101.41458)
		(width 0.11684)
		(layer "B.Cu")
		(net "SPI_SYS_MUX_MISO")
	)
	(segment
		(start 51.661822 -97.555558)
		(end 51.515264 -97.409)
		(width 0.11684)
		(layer "B.Cu")
		(net "SPI_SYS_MUX_MISO")
	)
	(segment
		(start 51.83378 -98.738944)
		(end 51.661822 -98.566986)
		(width 0.11684)
		(layer "B.Cu")
		(net "SPI_SYS_MUX_MISO")
	)
	(segment
		(start 51.161442 -97.555558)
		(end 51.161442 -99.954842)
		(width 0.11684)
		(layer "B.Cu")
		(net "SPI_SYS_MUX_MISO")
	)
	(segment
		(start 49.09058 -101.41458)
		(end 48.97374 -101.53142)
		(width 0.11684)
		(layer "B.Cu")
		(net "SPI_SYS_MUX_MISO")
	)
	(segment
		(start 47.63135 -101.37775)
		(end 46.811184 -101.37775)
		(width 0.11684)
		(layer "B.Cu")
		(net "SPI_SYS_MUX_MISO")
	)
	(segment
		(start 52.183538 -108.527088)
		(end 51.82489 -108.527088)
		(width 0.11684)
		(layer "F.Cu")
		(net "SPI_SYS_MUX_HOLD_IO3")
	)
	(segment
		(start 52.6542 -108.99775)
		(end 52.183538 -108.527088)
		(width 0.11684)
		(layer "F.Cu")
		(net "SPI_SYS_MUX_HOLD_IO3")
	)
	(segment
		(start 51.4858 -108.187998)
		(end 51.4858 -106.8324)
		(width 0.11684)
		(layer "F.Cu")
		(net "SPI_SYS_MUX_HOLD_IO3")
	)
	(segment
		(start 51.4858 -106.8324)
		(end 52.648612 -105.669588)
		(width 0.11684)
		(layer "F.Cu")
		(net "SPI_SYS_MUX_HOLD_IO3")
	)
	(segment
		(start 51.82489 -108.527088)
		(end 51.4858 -108.187998)
		(width 0.11684)
		(layer "F.Cu")
		(net "SPI_SYS_MUX_HOLD_IO3")
	)
	(via
		(at 54.96687 -85.33638)
		(size 0.508)
		(drill 0.254)
		(layers "F.Cu" "B.Cu")
		(net "SPI_SYS_MUX_HOLD_IO3")
	)
	(via
		(at 52.648612 -105.669588)
		(size 0.508)
		(drill 0.254)
		(layers "F.Cu" "B.Cu")
		(net "SPI_SYS_MUX_HOLD_IO3")
	)
	(via
		(at 47.54372 -83.71586)
		(size 0.6604)
		(drill 0.3302)
		(layers "F.Cu" "B.Cu")
		(net "SPI_SYS_MUX_HOLD_IO3")
	)
	(segment
		(start 42.98442 -81.31302)
		(end 42.715434 -81.044034)
		(width 0.11684)
		(layer "B.Cu")
		(net "SPI_SYS_MUX_HOLD_IO3")
	)
	(segment
		(start 47.27448 -83.44662)
		(end 45.36186 -83.44662)
		(width 0.11684)
		(layer "B.Cu")
		(net "SPI_SYS_MUX_HOLD_IO3")
	)
	(segment
		(start 43.2816 -79.8576)
		(end 43.864784 -79.8576)
		(width 0.11684)
		(layer "B.Cu")
		(net "SPI_SYS_MUX_HOLD_IO3")
	)
	(segment
		(start 42.715434 -81.044034)
		(end 42.715434 -80.423766)
		(width 0.11684)
		(layer "B.Cu")
		(net "SPI_SYS_MUX_HOLD_IO3")
	)
	(segment
		(start 43.22826 -81.31302)
		(end 42.98442 -81.31302)
		(width 0.11684)
		(layer "B.Cu")
		(net "SPI_SYS_MUX_HOLD_IO3")
	)
	(segment
		(start 45.033946 -80.3656)
		(end 45.11421 -80.285336)
		(width 0.11684)
		(layer "B.Cu")
		(net "SPI_SYS_MUX_HOLD_IO3")
	)
	(segment
		(start 42.715434 -80.423766)
		(end 43.2816 -79.8576)
		(width 0.11684)
		(layer "B.Cu")
		(net "SPI_SYS_MUX_HOLD_IO3")
	)
	(segment
		(start 45.11421 -80.285336)
		(end 46.019466 -80.285336)
		(width 0.11684)
		(layer "B.Cu")
		(net "SPI_SYS_MUX_HOLD_IO3")
	)
	(segment
		(start 48.36668 -84.0232)
		(end 50.583084 -84.0232)
		(width 0.11684)
		(layer "B.Cu")
		(net "SPI_SYS_MUX_HOLD_IO3")
	)
	(segment
		(start 47.54372 -83.71586)
		(end 47.27448 -83.44662)
		(width 0.11684)
		(layer "B.Cu")
		(net "SPI_SYS_MUX_HOLD_IO3")
	)
	(segment
		(start 51.110896 -84.08162)
		(end 51.169316 -84.0232)
		(width 0.11684)
		(layer "B.Cu")
		(net "SPI_SYS_MUX_HOLD_IO3")
	)
	(segment
		(start 50.583084 -84.0232)
		(end 50.641504 -84.08162)
		(width 0.11684)
		(layer "B.Cu")
		(net "SPI_SYS_MUX_HOLD_IO3")
	)
	(segment
		(start 54.5846 -84.0232)
		(end 54.96687 -84.40547)
		(width 0.11684)
		(layer "B.Cu")
		(net "SPI_SYS_MUX_HOLD_IO3")
	)
	(segment
		(start 44.372784 -80.3656)
		(end 45.033946 -80.3656)
		(width 0.11684)
		(layer "B.Cu")
		(net "SPI_SYS_MUX_HOLD_IO3")
	)
	(segment
		(start 50.641504 -84.08162)
		(end 51.110896 -84.08162)
		(width 0.11684)
		(layer "B.Cu")
		(net "SPI_SYS_MUX_HOLD_IO3")
	)
	(segment
		(start 47.54372 -83.71586)
		(end 48.05934 -83.71586)
		(width 0.11684)
		(layer "B.Cu")
		(net "SPI_SYS_MUX_HOLD_IO3")
	)
	(segment
		(start 51.169316 -84.0232)
		(end 54.5846 -84.0232)
		(width 0.11684)
		(layer "B.Cu")
		(net "SPI_SYS_MUX_HOLD_IO3")
	)
	(segment
		(start 48.05934 -83.71586)
		(end 48.36668 -84.0232)
		(width 0.11684)
		(layer "B.Cu")
		(net "SPI_SYS_MUX_HOLD_IO3")
	)
	(segment
		(start 45.36186 -83.44662)
		(end 43.22826 -81.31302)
		(width 0.11684)
		(layer "B.Cu")
		(net "SPI_SYS_MUX_HOLD_IO3")
	)
	(segment
		(start 54.96687 -84.40547)
		(end 54.96687 -85.33638)
		(width 0.11684)
		(layer "B.Cu")
		(net "SPI_SYS_MUX_HOLD_IO3")
	)
	(segment
		(start 43.864784 -79.8576)
		(end 44.372784 -80.3656)
		(width 0.11684)
		(layer "B.Cu")
		(net "SPI_SYS_MUX_HOLD_IO3")
	)
	(segment
		(start 55.25008 -94.599252)
		(end 54.21122 -92.090748)
		(width 0.10668)
		(layer "In4.Cu")
		(net "SPI_SYS_MUX_HOLD_IO3")
	)
	(segment
		(start 54.96687 -86.18093)
		(end 54.96687 -85.33638)
		(width 0.10668)
		(layer "In4.Cu")
		(net "SPI_SYS_MUX_HOLD_IO3")
	)
	(segment
		(start 53.6194 -102.59314)
		(end 52.91582 -101.88956)
		(width 0.10668)
		(layer "In4.Cu")
		(net "SPI_SYS_MUX_HOLD_IO3")
	)
	(segment
		(start 53.6194 -104.6988)
		(end 53.6194 -102.59314)
		(width 0.10668)
		(layer "In4.Cu")
		(net "SPI_SYS_MUX_HOLD_IO3")
	)
	(segment
		(start 54.21122 -92.090748)
		(end 54.21122 -86.93658)
		(width 0.10668)
		(layer "In4.Cu")
		(net "SPI_SYS_MUX_HOLD_IO3")
	)
	(segment
		(start 55.22341 -96.319086)
		(end 55.25008 -96.292416)
		(width 0.10668)
		(layer "In4.Cu")
		(net "SPI_SYS_MUX_HOLD_IO3")
	)
	(segment
		(start 52.91582 -101.88956)
		(end 55.22341 -96.319086)
		(width 0.10668)
		(layer "In4.Cu")
		(net "SPI_SYS_MUX_HOLD_IO3")
	)
	(segment
		(start 55.25008 -96.292416)
		(end 55.25008 -94.599252)
		(width 0.10668)
		(layer "In4.Cu")
		(net "SPI_SYS_MUX_HOLD_IO3")
	)
	(segment
		(start 52.648612 -105.669588)
		(end 53.6194 -104.6988)
		(width 0.10668)
		(layer "In4.Cu")
		(net "SPI_SYS_MUX_HOLD_IO3")
	)
	(segment
		(start 54.21122 -86.93658)
		(end 54.96687 -86.18093)
		(width 0.10668)
		(layer "In4.Cu")
		(net "SPI_SYS_MUX_HOLD_IO3")
	)
	(segment
		(start 56.638444 -101.682042)
		(end 57.502552 -102.54615)
		(width 0.11684)
		(layer "F.Cu")
		(net "SPI_SYS_MUX_CLK")
	)
	(segment
		(start 57.502552 -102.54615)
		(end 57.531 -102.54615)
		(width 0.11684)
		(layer "F.Cu")
		(net "SPI_SYS_MUX_CLK")
	)
	(via
		(at 55.1942 -81.9912)
		(size 0.508)
		(drill 0.254)
		(layers "F.Cu" "B.Cu")
		(net "SPI_SYS_MUX_CLK")
	)
	(via
		(at 56.638444 -101.682042)
		(size 0.508)
		(drill 0.254)
		(layers "F.Cu" "B.Cu")
		(net "SPI_SYS_MUX_CLK")
	)
	(via
		(at 53.57622 -80.935322)
		(size 0.6604)
		(drill 0.3302)
		(layers "F.Cu" "B.Cu")
		(net "SPI_SYS_MUX_CLK")
	)
	(segment
		(start 51.861466 -80.935322)
		(end 53.57622 -80.935322)
		(width 0.11684)
		(layer "B.Cu")
		(net "SPI_SYS_MUX_CLK")
	)
	(segment
		(start 54.152546 -81.5848)
		(end 53.57622 -81.008474)
		(width 0.11684)
		(layer "B.Cu")
		(net "SPI_SYS_MUX_CLK")
	)
	(segment
		(start 54.9148 -81.9912)
		(end 54.5084 -81.5848)
		(width 0.11684)
		(layer "B.Cu")
		(net "SPI_SYS_MUX_CLK")
	)
	(segment
		(start 54.5084 -81.5848)
		(end 54.152546 -81.5848)
		(width 0.11684)
		(layer "B.Cu")
		(net "SPI_SYS_MUX_CLK")
	)
	(segment
		(start 55.1942 -81.9912)
		(end 54.9148 -81.9912)
		(width 0.11684)
		(layer "B.Cu")
		(net "SPI_SYS_MUX_CLK")
	)
	(segment
		(start 53.57622 -81.008474)
		(end 53.57622 -80.935322)
		(width 0.11684)
		(layer "B.Cu")
		(net "SPI_SYS_MUX_CLK")
	)
	(segment
		(start 56.0578 -94.488762)
		(end 56.0578 -96.9264)
		(width 0.10668)
		(layer "In4.Cu")
		(net "SPI_SYS_MUX_CLK")
	)
	(segment
		(start 56.007 -86.53272)
		(end 55.442866 -87.096854)
		(width 0.10668)
		(layer "In4.Cu")
		(net "SPI_SYS_MUX_CLK")
	)
	(segment
		(start 57.14619 -98.01479)
		(end 57.14619 -98.710496)
		(width 0.10668)
		(layer "In4.Cu")
		(net "SPI_SYS_MUX_CLK")
	)
	(segment
		(start 55.1942 -82.2706)
		(end 55.4482 -82.5246)
		(width 0.10668)
		(layer "In4.Cu")
		(net "SPI_SYS_MUX_CLK")
	)
	(segment
		(start 55.1942 -81.9912)
		(end 55.1942 -82.2706)
		(width 0.10668)
		(layer "In4.Cu")
		(net "SPI_SYS_MUX_CLK")
	)
	(segment
		(start 55.442866 -93.004386)
		(end 56.0578 -94.488762)
		(width 0.10668)
		(layer "In4.Cu")
		(net "SPI_SYS_MUX_CLK")
	)
	(segment
		(start 55.4482 -84.294472)
		(end 56.007 -84.853272)
		(width 0.10668)
		(layer "In4.Cu")
		(net "SPI_SYS_MUX_CLK")
	)
	(segment
		(start 56.638444 -99.218242)
		(end 56.638444 -101.682042)
		(width 0.10668)
		(layer "In4.Cu")
		(net "SPI_SYS_MUX_CLK")
	)
	(segment
		(start 55.442866 -87.096854)
		(end 55.442866 -93.004386)
		(width 0.10668)
		(layer "In4.Cu")
		(net "SPI_SYS_MUX_CLK")
	)
	(segment
		(start 56.007 -84.853272)
		(end 56.007 -86.53272)
		(width 0.10668)
		(layer "In4.Cu")
		(net "SPI_SYS_MUX_CLK")
	)
	(segment
		(start 57.14619 -98.710496)
		(end 56.638444 -99.218242)
		(width 0.10668)
		(layer "In4.Cu")
		(net "SPI_SYS_MUX_CLK")
	)
	(segment
		(start 55.4482 -82.5246)
		(end 55.4482 -84.294472)
		(width 0.10668)
		(layer "In4.Cu")
		(net "SPI_SYS_MUX_CLK")
	)
	(segment
		(start 56.0578 -96.9264)
		(end 57.14619 -98.01479)
		(width 0.10668)
		(layer "In4.Cu")
		(net "SPI_SYS_MUX_CLK")
	)
	(segment
		(start 22.254718 -90.391742)
		(end 21.859494 -90.786966)
		(width 0.11684)
		(layer "F.Cu")
		(net "FM_BIOS_POST_CMPLT_BMC_N")
	)
	(segment
		(start 44.895008 -52.171346)
		(end 44.499784 -52.56657)
		(width 0.11684)
		(layer "F.Cu")
		(net "FM_BIOS_POST_CMPLT_BMC_N")
	)
	(via
		(at 22.254718 -90.391742)
		(size 0.4572)
		(drill 0.254)
		(layers "F.Cu" "B.Cu")
		(net "FM_BIOS_POST_CMPLT_BMC_N")
	)
	(via
		(at 27.054556 -88.791796)
		(size 0.4572)
		(drill 0.254)
		(layers "F.Cu" "B.Cu")
		(net "FM_BIOS_POST_CMPLT_BMC_N")
	)
	(via
		(at 44.499784 -52.56657)
		(size 0.4572)
		(drill 0.254)
		(layers "F.Cu" "B.Cu")
		(net "FM_BIOS_POST_CMPLT_BMC_N")
	)
	(segment
		(start 23.472394 -89.76106)
		(end 23.223982 -90.009472)
		(width 0.10414)
		(layer "In2.Cu")
		(net "FM_BIOS_POST_CMPLT_BMC_N")
	)
	(segment
		(start 27.054556 -88.791796)
		(end 26.651458 -89.194894)
		(width 0.10414)
		(layer "In2.Cu")
		(net "FM_BIOS_POST_CMPLT_BMC_N")
	)
	(segment
		(start 26.651458 -89.194894)
		(end 23.7109 -89.194894)
		(width 0.10414)
		(layer "In2.Cu")
		(net "FM_BIOS_POST_CMPLT_BMC_N")
	)
	(segment
		(start 22.511258 -90.391742)
		(end 22.254718 -90.391742)
		(width 0.10414)
		(layer "In2.Cu")
		(net "FM_BIOS_POST_CMPLT_BMC_N")
	)
	(segment
		(start 23.223982 -90.009472)
		(end 22.893528 -90.009472)
		(width 0.10414)
		(layer "In2.Cu")
		(net "FM_BIOS_POST_CMPLT_BMC_N")
	)
	(segment
		(start 23.7109 -89.194894)
		(end 23.472394 -89.4334)
		(width 0.10414)
		(layer "In2.Cu")
		(net "FM_BIOS_POST_CMPLT_BMC_N")
	)
	(segment
		(start 23.472394 -89.4334)
		(end 23.472394 -89.76106)
		(width 0.10414)
		(layer "In2.Cu")
		(net "FM_BIOS_POST_CMPLT_BMC_N")
	)
	(segment
		(start 22.893528 -90.009472)
		(end 22.511258 -90.391742)
		(width 0.10414)
		(layer "In2.Cu")
		(net "FM_BIOS_POST_CMPLT_BMC_N")
	)
	(segment
		(start 35.390074 -64.351408)
		(end 35.390074 -65.12814)
		(width 0.08382)
		(layer "In9.Cu")
		(net "FM_BIOS_POST_CMPLT_BMC_N")
	)
	(segment
		(start 30.160976 -74.049382)
		(end 30.160976 -75.569572)
		(width 0.08382)
		(layer "In9.Cu")
		(net "FM_BIOS_POST_CMPLT_BMC_N")
	)
	(segment
		(start 39.766748 -56.622188)
		(end 39.185088 -57.20334)
		(width 0.08382)
		(layer "In9.Cu")
		(net "FM_BIOS_POST_CMPLT_BMC_N")
	)
	(segment
		(start 28.525978 -77.83068)
		(end 28.525978 -83.543902)
		(width 0.08382)
		(layer "In9.Cu")
		(net "FM_BIOS_POST_CMPLT_BMC_N")
	)
	(segment
		(start 35.38982 -66.03746)
		(end 34.58337 -66.84391)
		(width 0.08382)
		(layer "In9.Cu")
		(net "FM_BIOS_POST_CMPLT_BMC_N")
	)
	(segment
		(start 34.58337 -66.84391)
		(end 34.58337 -68.018152)
		(width 0.08382)
		(layer "In9.Cu")
		(net "FM_BIOS_POST_CMPLT_BMC_N")
	)
	(segment
		(start 32.66186 -71.548498)
		(end 30.160976 -74.049382)
		(width 0.08382)
		(layer "In9.Cu")
		(net "FM_BIOS_POST_CMPLT_BMC_N")
	)
	(segment
		(start 39.185088 -57.20334)
		(end 39.18458 -57.270396)
		(width 0.08382)
		(layer "In9.Cu")
		(net "FM_BIOS_POST_CMPLT_BMC_N")
	)
	(segment
		(start 41.8846 -52.8066)
		(end 41.783 -52.705)
		(width 0.08382)
		(layer "In9.Cu")
		(net "FM_BIOS_POST_CMPLT_BMC_N")
	)
	(segment
		(start 39.18458 -57.936638)
		(end 38.297866 -58.823352)
		(width 0.08382)
		(layer "In9.Cu")
		(net "FM_BIOS_POST_CMPLT_BMC_N")
	)
	(segment
		(start 34.999168 -60.58027)
		(end 34.998406 -60.580524)
		(width 0.08382)
		(layer "In9.Cu")
		(net "FM_BIOS_POST_CMPLT_BMC_N")
	)
	(segment
		(start 28.525978 -83.543902)
		(end 27.35834 -84.71154)
		(width 0.08382)
		(layer "In9.Cu")
		(net "FM_BIOS_POST_CMPLT_BMC_N")
	)
	(segment
		(start 34.39795 -69.860922)
		(end 33.701482 -70.55739)
		(width 0.08382)
		(layer "In9.Cu")
		(net "FM_BIOS_POST_CMPLT_BMC_N")
	)
	(segment
		(start 34.166048 -61.70168)
		(end 34.166048 -63.127382)
		(width 0.08382)
		(layer "In9.Cu")
		(net "FM_BIOS_POST_CMPLT_BMC_N")
	)
	(segment
		(start 38.297866 -58.823352)
		(end 36.758372 -59.851798)
		(width 0.08382)
		(layer "In9.Cu")
		(net "FM_BIOS_POST_CMPLT_BMC_N")
	)
	(segment
		(start 44.49826 -52.56657)
		(end 44.39031 -52.45862)
		(width 0.08382)
		(layer "In9.Cu")
		(net "FM_BIOS_POST_CMPLT_BMC_N")
	)
	(segment
		(start 27.35834 -84.71154)
		(end 27.35834 -86.077806)
		(width 0.08382)
		(layer "In9.Cu")
		(net "FM_BIOS_POST_CMPLT_BMC_N")
	)
	(segment
		(start 34.998406 -60.580524)
		(end 34.883344 -60.628276)
		(width 0.08382)
		(layer "In9.Cu")
		(net "FM_BIOS_POST_CMPLT_BMC_N")
	)
	(segment
		(start 44.499784 -52.56657)
		(end 44.49826 -52.56657)
		(width 0.08382)
		(layer "In9.Cu")
		(net "FM_BIOS_POST_CMPLT_BMC_N")
	)
	(segment
		(start 30.160976 -75.569572)
		(end 29.71927 -76.637388)
		(width 0.08382)
		(layer "In9.Cu")
		(net "FM_BIOS_POST_CMPLT_BMC_N")
	)
	(segment
		(start 32.66186 -71.125588)
		(end 32.66186 -71.548498)
		(width 0.08382)
		(layer "In9.Cu")
		(net "FM_BIOS_POST_CMPLT_BMC_N")
	)
	(segment
		(start 34.883344 -60.628276)
		(end 34.166048 -61.70168)
		(width 0.08382)
		(layer "In9.Cu")
		(net "FM_BIOS_POST_CMPLT_BMC_N")
	)
	(segment
		(start 34.39795 -68.203572)
		(end 34.39795 -69.860922)
		(width 0.08382)
		(layer "In9.Cu")
		(net "FM_BIOS_POST_CMPLT_BMC_N")
	)
	(segment
		(start 33.230058 -70.55739)
		(end 32.66186 -71.125588)
		(width 0.08382)
		(layer "In9.Cu")
		(net "FM_BIOS_POST_CMPLT_BMC_N")
	)
	(segment
		(start 40.8178 -53.023516)
		(end 40.8178 -54.16804)
		(width 0.08382)
		(layer "In9.Cu")
		(net "FM_BIOS_POST_CMPLT_BMC_N")
	)
	(segment
		(start 40.12057 -56.26862)
		(end 39.766748 -56.622188)
		(width 0.08382)
		(layer "In9.Cu")
		(net "FM_BIOS_POST_CMPLT_BMC_N")
	)
	(segment
		(start 41.136316 -52.705)
		(end 40.8178 -53.023516)
		(width 0.08382)
		(layer "In9.Cu")
		(net "FM_BIOS_POST_CMPLT_BMC_N")
	)
	(segment
		(start 40.53078 -54.45506)
		(end 40.53078 -55.27802)
		(width 0.08382)
		(layer "In9.Cu")
		(net "FM_BIOS_POST_CMPLT_BMC_N")
	)
	(segment
		(start 26.695146 -88.432386)
		(end 27.054556 -88.791796)
		(width 0.08382)
		(layer "In9.Cu")
		(net "FM_BIOS_POST_CMPLT_BMC_N")
	)
	(segment
		(start 41.783 -52.705)
		(end 41.136316 -52.705)
		(width 0.08382)
		(layer "In9.Cu")
		(net "FM_BIOS_POST_CMPLT_BMC_N")
	)
	(segment
		(start 36.758372 -59.851798)
		(end 34.999168 -60.58027)
		(width 0.08382)
		(layer "In9.Cu")
		(net "FM_BIOS_POST_CMPLT_BMC_N")
	)
	(segment
		(start 27.35834 -86.077806)
		(end 26.695146 -86.741)
		(width 0.08382)
		(layer "In9.Cu")
		(net "FM_BIOS_POST_CMPLT_BMC_N")
	)
	(segment
		(start 34.166048 -63.127382)
		(end 35.390074 -64.351408)
		(width 0.08382)
		(layer "In9.Cu")
		(net "FM_BIOS_POST_CMPLT_BMC_N")
	)
	(segment
		(start 39.18458 -57.270396)
		(end 39.18458 -57.936638)
		(width 0.08382)
		(layer "In9.Cu")
		(net "FM_BIOS_POST_CMPLT_BMC_N")
	)
	(segment
		(start 34.58337 -68.018152)
		(end 34.39795 -68.203572)
		(width 0.08382)
		(layer "In9.Cu")
		(net "FM_BIOS_POST_CMPLT_BMC_N")
	)
	(segment
		(start 33.701482 -70.55739)
		(end 33.230058 -70.55739)
		(width 0.08382)
		(layer "In9.Cu")
		(net "FM_BIOS_POST_CMPLT_BMC_N")
	)
	(segment
		(start 44.39031 -52.45862)
		(end 42.81678 -52.45862)
		(width 0.08382)
		(layer "In9.Cu")
		(net "FM_BIOS_POST_CMPLT_BMC_N")
	)
	(segment
		(start 42.4688 -52.8066)
		(end 41.8846 -52.8066)
		(width 0.08382)
		(layer "In9.Cu")
		(net "FM_BIOS_POST_CMPLT_BMC_N")
	)
	(segment
		(start 26.695146 -86.741)
		(end 26.695146 -88.432386)
		(width 0.08382)
		(layer "In9.Cu")
		(net "FM_BIOS_POST_CMPLT_BMC_N")
	)
	(segment
		(start 42.81678 -52.45862)
		(end 42.4688 -52.8066)
		(width 0.08382)
		(layer "In9.Cu")
		(net "FM_BIOS_POST_CMPLT_BMC_N")
	)
	(segment
		(start 29.71927 -76.637388)
		(end 28.525978 -77.83068)
		(width 0.08382)
		(layer "In9.Cu")
		(net "FM_BIOS_POST_CMPLT_BMC_N")
	)
	(segment
		(start 40.53078 -55.27802)
		(end 40.12057 -56.26862)
		(width 0.08382)
		(layer "In9.Cu")
		(net "FM_BIOS_POST_CMPLT_BMC_N")
	)
	(segment
		(start 35.390074 -65.12814)
		(end 35.38982 -65.128394)
		(width 0.08382)
		(layer "In9.Cu")
		(net "FM_BIOS_POST_CMPLT_BMC_N")
	)
	(segment
		(start 35.38982 -65.128394)
		(end 35.38982 -66.03746)
		(width 0.08382)
		(layer "In9.Cu")
		(net "FM_BIOS_POST_CMPLT_BMC_N")
	)
	(segment
		(start 40.8178 -54.16804)
		(end 40.53078 -54.45506)
		(width 0.08382)
		(layer "In9.Cu")
		(net "FM_BIOS_POST_CMPLT_BMC_N")
	)
	(segment
		(start 44.895008 -53.771292)
		(end 44.499784 -54.166516)
		(width 0.11684)
		(layer "F.Cu")
		(net "PWRGD_CPUPWRGD_LVC1")
	)
	(segment
		(start 19.064224 -88.791796)
		(end 19.459448 -89.18702)
		(width 0.11684)
		(layer "F.Cu")
		(net "PWRGD_CPUPWRGD_LVC1")
	)
	(via
		(at 31.2674 -75.177396)
		(size 0.508)
		(drill 0.254)
		(layers "F.Cu" "B.Cu")
		(net "PWRGD_CPUPWRGD_LVC1")
	)
	(via
		(at 44.499784 -54.166516)
		(size 0.4572)
		(drill 0.254)
		(layers "F.Cu" "B.Cu")
		(net "PWRGD_CPUPWRGD_LVC1")
	)
	(via
		(at 19.064224 -88.791796)
		(size 0.4572)
		(drill 0.254)
		(layers "F.Cu" "B.Cu")
		(net "PWRGD_CPUPWRGD_LVC1")
	)
	(segment
		(start 37.34181 -64.895984)
		(end 37.34181 -65.435988)
		(width 0.08382)
		(layer "In9.Cu")
		(net "PWRGD_CPUPWRGD_LVC1")
	)
	(segment
		(start 35.51428 -63.486538)
		(end 36.645342 -64.6176)
		(width 0.08382)
		(layer "In9.Cu")
		(net "PWRGD_CPUPWRGD_LVC1")
	)
	(segment
		(start 37.487606 -60.5028)
		(end 36.820348 -60.5028)
		(width 0.08382)
		(layer "In9.Cu")
		(net "PWRGD_CPUPWRGD_LVC1")
	)
	(segment
		(start 18.636234 -88.958166)
		(end 18.636234 -89.690194)
		(width 0.08382)
		(layer "In9.Cu")
		(net "PWRGD_CPUPWRGD_LVC1")
	)
	(segment
		(start 40.101012 -58.828432)
		(end 40.13708 -58.8645)
		(width 0.08382)
		(layer "In9.Cu")
		(net "PWRGD_CPUPWRGD_LVC1")
	)
	(segment
		(start 27.7368 -86.6648)
		(end 28.03398 -86.36762)
		(width 0.08382)
		(layer "In9.Cu")
		(net "PWRGD_CPUPWRGD_LVC1")
	)
	(segment
		(start 40.363394 -57.069228)
		(end 40.101012 -57.33161)
		(width 0.08382)
		(layer "In9.Cu")
		(net "PWRGD_CPUPWRGD_LVC1")
	)
	(segment
		(start 18.965672 -90.019632)
		(end 25.859232 -90.019632)
		(width 0.08382)
		(layer "In9.Cu")
		(net "PWRGD_CPUPWRGD_LVC1")
	)
	(segment
		(start 31.773876 -74.67092)
		(end 31.2674 -75.177396)
		(width 0.08382)
		(layer "In9.Cu")
		(net "PWRGD_CPUPWRGD_LVC1")
	)
	(segment
		(start 31.773876 -74.017124)
		(end 31.773876 -74.67092)
		(width 0.08382)
		(layer "In9.Cu")
		(net "PWRGD_CPUPWRGD_LVC1")
	)
	(segment
		(start 18.802604 -88.791796)
		(end 18.636234 -88.958166)
		(width 0.08382)
		(layer "In9.Cu")
		(net "PWRGD_CPUPWRGD_LVC1")
	)
	(segment
		(start 34.555938 -71.520812)
		(end 34.270188 -71.520812)
		(width 0.08382)
		(layer "In9.Cu")
		(net "PWRGD_CPUPWRGD_LVC1")
	)
	(segment
		(start 41.684194 -56.511952)
		(end 41.126918 -57.069228)
		(width 0.08382)
		(layer "In9.Cu")
		(net "PWRGD_CPUPWRGD_LVC1")
	)
	(segment
		(start 35.969956 -60.855606)
		(end 35.51428 -61.537342)
		(width 0.08382)
		(layer "In9.Cu")
		(net "PWRGD_CPUPWRGD_LVC1")
	)
	(segment
		(start 41.126918 -57.069228)
		(end 40.363394 -57.069228)
		(width 0.08382)
		(layer "In9.Cu")
		(net "PWRGD_CPUPWRGD_LVC1")
	)
	(segment
		(start 40.13708 -58.8645)
		(end 40.13708 -59.78144)
		(width 0.08382)
		(layer "In9.Cu")
		(net "PWRGD_CPUPWRGD_LVC1")
	)
	(segment
		(start 19.064224 -88.791796)
		(end 18.802604 -88.791796)
		(width 0.08382)
		(layer "In9.Cu")
		(net "PWRGD_CPUPWRGD_LVC1")
	)
	(segment
		(start 35.687 -67.090798)
		(end 35.687 -69.957696)
		(width 0.08382)
		(layer "In9.Cu")
		(net "PWRGD_CPUPWRGD_LVC1")
	)
	(segment
		(start 38.76675 -60.17387)
		(end 38.5572 -59.96432)
		(width 0.08382)
		(layer "In9.Cu")
		(net "PWRGD_CPUPWRGD_LVC1")
	)
	(segment
		(start 27.175968 -90.3732)
		(end 27.7368 -89.812368)
		(width 0.08382)
		(layer "In9.Cu")
		(net "PWRGD_CPUPWRGD_LVC1")
	)
	(segment
		(start 18.636234 -89.690194)
		(end 18.965672 -90.019632)
		(width 0.08382)
		(layer "In9.Cu")
		(net "PWRGD_CPUPWRGD_LVC1")
	)
	(segment
		(start 35.3822 -70.262496)
		(end 35.3822 -70.69455)
		(width 0.08382)
		(layer "In9.Cu")
		(net "PWRGD_CPUPWRGD_LVC1")
	)
	(segment
		(start 35.51428 -61.537342)
		(end 35.51428 -63.486538)
		(width 0.08382)
		(layer "In9.Cu")
		(net "PWRGD_CPUPWRGD_LVC1")
	)
	(segment
		(start 35.3822 -70.69455)
		(end 34.555938 -71.520812)
		(width 0.08382)
		(layer "In9.Cu")
		(net "PWRGD_CPUPWRGD_LVC1")
	)
	(segment
		(start 29.150818 -78.090014)
		(end 30.524704 -76.716128)
		(width 0.08382)
		(layer "In9.Cu")
		(net "PWRGD_CPUPWRGD_LVC1")
	)
	(segment
		(start 38.026086 -59.96432)
		(end 37.487606 -60.5028)
		(width 0.08382)
		(layer "In9.Cu")
		(net "PWRGD_CPUPWRGD_LVC1")
	)
	(segment
		(start 28.03398 -84.91982)
		(end 29.150818 -83.802982)
		(width 0.08382)
		(layer "In9.Cu")
		(net "PWRGD_CPUPWRGD_LVC1")
	)
	(segment
		(start 39.74465 -60.17387)
		(end 38.76675 -60.17387)
		(width 0.08382)
		(layer "In9.Cu")
		(net "PWRGD_CPUPWRGD_LVC1")
	)
	(segment
		(start 41.684194 -56.213756)
		(end 41.684194 -56.511952)
		(width 0.08382)
		(layer "In9.Cu")
		(net "PWRGD_CPUPWRGD_LVC1")
	)
	(segment
		(start 38.5572 -59.96432)
		(end 38.026086 -59.96432)
		(width 0.08382)
		(layer "In9.Cu")
		(net "PWRGD_CPUPWRGD_LVC1")
	)
	(segment
		(start 42.588434 -55.309516)
		(end 41.684194 -56.213756)
		(width 0.08382)
		(layer "In9.Cu")
		(net "PWRGD_CPUPWRGD_LVC1")
	)
	(segment
		(start 36.645342 -64.6176)
		(end 37.063426 -64.6176)
		(width 0.08382)
		(layer "In9.Cu")
		(net "PWRGD_CPUPWRGD_LVC1")
	)
	(segment
		(start 44.499784 -54.166516)
		(end 43.901614 -54.764686)
		(width 0.08382)
		(layer "In9.Cu")
		(net "PWRGD_CPUPWRGD_LVC1")
	)
	(segment
		(start 30.524704 -76.716128)
		(end 30.524704 -76.325476)
		(width 0.08382)
		(layer "In9.Cu")
		(net "PWRGD_CPUPWRGD_LVC1")
	)
	(segment
		(start 29.150818 -83.802982)
		(end 29.150818 -78.090014)
		(width 0.08382)
		(layer "In9.Cu")
		(net "PWRGD_CPUPWRGD_LVC1")
	)
	(segment
		(start 27.7368 -89.812368)
		(end 27.7368 -86.6648)
		(width 0.08382)
		(layer "In9.Cu")
		(net "PWRGD_CPUPWRGD_LVC1")
	)
	(segment
		(start 43.901614 -54.764686)
		(end 42.588434 -55.309516)
		(width 0.08382)
		(layer "In9.Cu")
		(net "PWRGD_CPUPWRGD_LVC1")
	)
	(segment
		(start 30.945074 -75.311)
		(end 31.2674 -75.177396)
		(width 0.08382)
		(layer "In9.Cu")
		(net "PWRGD_CPUPWRGD_LVC1")
	)
	(segment
		(start 37.063426 -64.6176)
		(end 37.34181 -64.895984)
		(width 0.08382)
		(layer "In9.Cu")
		(net "PWRGD_CPUPWRGD_LVC1")
	)
	(segment
		(start 36.820348 -60.5028)
		(end 35.969956 -60.855606)
		(width 0.08382)
		(layer "In9.Cu")
		(net "PWRGD_CPUPWRGD_LVC1")
	)
	(segment
		(start 35.687 -69.957696)
		(end 35.3822 -70.262496)
		(width 0.08382)
		(layer "In9.Cu")
		(net "PWRGD_CPUPWRGD_LVC1")
	)
	(segment
		(start 40.13708 -59.78144)
		(end 39.74465 -60.17387)
		(width 0.08382)
		(layer "In9.Cu")
		(net "PWRGD_CPUPWRGD_LVC1")
	)
	(segment
		(start 26.2128 -90.3732)
		(end 27.175968 -90.3732)
		(width 0.08382)
		(layer "In9.Cu")
		(net "PWRGD_CPUPWRGD_LVC1")
	)
	(segment
		(start 40.101012 -57.33161)
		(end 40.101012 -58.828432)
		(width 0.08382)
		(layer "In9.Cu")
		(net "PWRGD_CPUPWRGD_LVC1")
	)
	(segment
		(start 37.34181 -65.435988)
		(end 35.687 -67.090798)
		(width 0.08382)
		(layer "In9.Cu")
		(net "PWRGD_CPUPWRGD_LVC1")
	)
	(segment
		(start 34.270188 -71.520812)
		(end 31.773876 -74.017124)
		(width 0.08382)
		(layer "In9.Cu")
		(net "PWRGD_CPUPWRGD_LVC1")
	)
	(segment
		(start 25.859232 -90.019632)
		(end 26.2128 -90.3732)
		(width 0.08382)
		(layer "In9.Cu")
		(net "PWRGD_CPUPWRGD_LVC1")
	)
	(segment
		(start 28.03398 -86.36762)
		(end 28.03398 -84.91982)
		(width 0.08382)
		(layer "In9.Cu")
		(net "PWRGD_CPUPWRGD_LVC1")
	)
	(segment
		(start 30.524704 -76.325476)
		(end 30.945074 -75.311)
		(width 0.08382)
		(layer "In9.Cu")
		(net "PWRGD_CPUPWRGD_LVC1")
	)
	(segment
		(start 47.295054 -51.371246)
		(end 46.89983 -51.76647)
		(width 0.11684)
		(layer "F.Cu")
		(net "PWRGD_PCH_PWROK")
	)
	(segment
		(start 23.054564 -90.391742)
		(end 22.65934 -90.786966)
		(width 0.11684)
		(layer "F.Cu")
		(net "PWRGD_PCH_PWROK")
	)
	(via
		(at 27.05481 -89.591896)
		(size 0.4572)
		(drill 0.254)
		(layers "F.Cu" "B.Cu")
		(net "PWRGD_PCH_PWROK")
	)
	(via
		(at 23.054564 -90.391742)
		(size 0.4572)
		(drill 0.254)
		(layers "F.Cu" "B.Cu")
		(net "PWRGD_PCH_PWROK")
	)
	(via
		(at 46.89983 -51.76647)
		(size 0.4572)
		(drill 0.254)
		(layers "F.Cu" "B.Cu")
		(net "PWRGD_PCH_PWROK")
	)
	(segment
		(start 26.64841 -89.998296)
		(end 23.70709 -89.998296)
		(width 0.10414)
		(layer "In2.Cu")
		(net "PWRGD_PCH_PWROK")
	)
	(segment
		(start 27.05481 -89.591896)
		(end 26.64841 -89.998296)
		(width 0.10414)
		(layer "In2.Cu")
		(net "PWRGD_PCH_PWROK")
	)
	(segment
		(start 23.313644 -90.391742)
		(end 23.054564 -90.391742)
		(width 0.10414)
		(layer "In2.Cu")
		(net "PWRGD_PCH_PWROK")
	)
	(segment
		(start 23.70709 -89.998296)
		(end 23.313644 -90.391742)
		(width 0.10414)
		(layer "In2.Cu")
		(net "PWRGD_PCH_PWROK")
	)
	(segment
		(start 41.485312 -52.39258)
		(end 41.006776 -52.39258)
		(width 0.08382)
		(layer "In9.Cu")
		(net "PWRGD_PCH_PWROK")
	)
	(segment
		(start 40.505126 -54.038754)
		(end 40.21836 -54.32552)
		(width 0.08382)
		(layer "In9.Cu")
		(net "PWRGD_PCH_PWROK")
	)
	(segment
		(start 38.872922 -57.073292)
		(end 38.87216 -57.269634)
		(width 0.08382)
		(layer "In9.Cu")
		(net "PWRGD_PCH_PWROK")
	)
	(segment
		(start 25.8572 -89.027)
		(end 26.1874 -89.3572)
		(width 0.08382)
		(layer "In9.Cu")
		(net "PWRGD_PCH_PWROK")
	)
	(segment
		(start 34.08553 -68.074032)
		(end 34.08553 -69.731382)
		(width 0.08382)
		(layer "In9.Cu")
		(net "PWRGD_PCH_PWROK")
	)
	(segment
		(start 38.87216 -57.269634)
		(end 38.87216 -57.807098)
		(width 0.08382)
		(layer "In9.Cu")
		(net "PWRGD_PCH_PWROK")
	)
	(segment
		(start 26.1874 -89.3572)
		(end 26.820114 -89.3572)
		(width 0.08382)
		(layer "In9.Cu")
		(net "PWRGD_PCH_PWROK")
	)
	(segment
		(start 42.027602 -51.85029)
		(end 41.485312 -52.39258)
		(width 0.08382)
		(layer "In9.Cu")
		(net "PWRGD_PCH_PWROK")
	)
	(segment
		(start 40.21836 -54.32552)
		(end 40.21836 -55.215536)
		(width 0.08382)
		(layer "In9.Cu")
		(net "PWRGD_PCH_PWROK")
	)
	(segment
		(start 35.012884 -60.2361)
		(end 34.67608 -60.3758)
		(width 0.08382)
		(layer "In9.Cu")
		(net "PWRGD_PCH_PWROK")
	)
	(segment
		(start 35.0774 -64.998854)
		(end 35.0774 -65.90792)
		(width 0.08382)
		(layer "In9.Cu")
		(net "PWRGD_PCH_PWROK")
	)
	(segment
		(start 46.88713 -51.76647)
		(end 46.5074 -52.1462)
		(width 0.08382)
		(layer "In9.Cu")
		(net "PWRGD_PCH_PWROK")
	)
	(segment
		(start 29.848556 -75.507342)
		(end 29.454348 -76.460096)
		(width 0.08382)
		(layer "In9.Cu")
		(net "PWRGD_PCH_PWROK")
	)
	(segment
		(start 32.34944 -71.418958)
		(end 29.848556 -73.919842)
		(width 0.08382)
		(layer "In9.Cu")
		(net "PWRGD_PCH_PWROK")
	)
	(segment
		(start 35.287204 -60.122562)
		(end 35.02787 -60.230004)
		(width 0.08382)
		(layer "In9.Cu")
		(net "PWRGD_PCH_PWROK")
	)
	(segment
		(start 28.213558 -83.414362)
		(end 27.04592 -84.582)
		(width 0.08382)
		(layer "In9.Cu")
		(net "PWRGD_PCH_PWROK")
	)
	(segment
		(start 41.006776 -52.39258)
		(end 40.505126 -52.89423)
		(width 0.08382)
		(layer "In9.Cu")
		(net "PWRGD_PCH_PWROK")
	)
	(segment
		(start 38.1 -58.579258)
		(end 36.61029 -59.574684)
		(width 0.08382)
		(layer "In9.Cu")
		(net "PWRGD_PCH_PWROK")
	)
	(segment
		(start 27.04592 -85.856826)
		(end 25.8572 -87.045546)
		(width 0.08382)
		(layer "In9.Cu")
		(net "PWRGD_PCH_PWROK")
	)
	(segment
		(start 38.87216 -57.807098)
		(end 38.1 -58.579258)
		(width 0.08382)
		(layer "In9.Cu")
		(net "PWRGD_PCH_PWROK")
	)
	(segment
		(start 32.34944 -70.996048)
		(end 32.34944 -71.418958)
		(width 0.08382)
		(layer "In9.Cu")
		(net "PWRGD_PCH_PWROK")
	)
	(segment
		(start 33.100518 -70.24497)
		(end 32.34944 -70.996048)
		(width 0.08382)
		(layer "In9.Cu")
		(net "PWRGD_PCH_PWROK")
	)
	(segment
		(start 34.27095 -66.71437)
		(end 34.27095 -67.888612)
		(width 0.08382)
		(layer "In9.Cu")
		(net "PWRGD_PCH_PWROK")
	)
	(segment
		(start 42.875454 -52.1462)
		(end 42.579544 -51.85029)
		(width 0.08382)
		(layer "In9.Cu")
		(net "PWRGD_PCH_PWROK")
	)
	(segment
		(start 35.02787 -60.230004)
		(end 35.027108 -60.230258)
		(width 0.08382)
		(layer "In9.Cu")
		(net "PWRGD_PCH_PWROK")
	)
	(segment
		(start 29.848556 -73.919842)
		(end 29.848556 -75.507342)
		(width 0.08382)
		(layer "In9.Cu")
		(net "PWRGD_PCH_PWROK")
	)
	(segment
		(start 35.077654 -64.9986)
		(end 35.0774 -64.998854)
		(width 0.08382)
		(layer "In9.Cu")
		(net "PWRGD_PCH_PWROK")
	)
	(segment
		(start 34.08553 -69.731382)
		(end 33.571942 -70.24497)
		(width 0.08382)
		(layer "In9.Cu")
		(net "PWRGD_PCH_PWROK")
	)
	(segment
		(start 26.820114 -89.3572)
		(end 27.05481 -89.591896)
		(width 0.08382)
		(layer "In9.Cu")
		(net "PWRGD_PCH_PWROK")
	)
	(segment
		(start 36.61029 -59.574684)
		(end 35.287458 -60.122054)
		(width 0.08382)
		(layer "In9.Cu")
		(net "PWRGD_PCH_PWROK")
	)
	(segment
		(start 27.04592 -84.582)
		(end 27.04592 -85.856826)
		(width 0.08382)
		(layer "In9.Cu")
		(net "PWRGD_PCH_PWROK")
	)
	(segment
		(start 35.287458 -60.122054)
		(end 35.287204 -60.122562)
		(width 0.08382)
		(layer "In9.Cu")
		(net "PWRGD_PCH_PWROK")
	)
	(segment
		(start 35.027108 -60.230258)
		(end 35.013392 -60.235846)
		(width 0.08382)
		(layer "In9.Cu")
		(net "PWRGD_PCH_PWROK")
	)
	(segment
		(start 28.213558 -77.700886)
		(end 28.213558 -83.414362)
		(width 0.08382)
		(layer "In9.Cu")
		(net "PWRGD_PCH_PWROK")
	)
	(segment
		(start 33.571942 -70.24497)
		(end 33.100518 -70.24497)
		(width 0.08382)
		(layer "In9.Cu")
		(net "PWRGD_PCH_PWROK")
	)
	(segment
		(start 40.505126 -52.89423)
		(end 40.505126 -54.038754)
		(width 0.08382)
		(layer "In9.Cu")
		(net "PWRGD_PCH_PWROK")
	)
	(segment
		(start 46.5074 -52.1462)
		(end 42.875454 -52.1462)
		(width 0.08382)
		(layer "In9.Cu")
		(net "PWRGD_PCH_PWROK")
	)
	(segment
		(start 33.853628 -61.60643)
		(end 33.853628 -63.256922)
		(width 0.08382)
		(layer "In9.Cu")
		(net "PWRGD_PCH_PWROK")
	)
	(segment
		(start 35.0774 -65.90792)
		(end 34.27095 -66.71437)
		(width 0.08382)
		(layer "In9.Cu")
		(net "PWRGD_PCH_PWROK")
	)
	(segment
		(start 42.579544 -51.85029)
		(end 42.027602 -51.85029)
		(width 0.08382)
		(layer "In9.Cu")
		(net "PWRGD_PCH_PWROK")
	)
	(segment
		(start 29.454348 -76.460096)
		(end 28.213558 -77.700886)
		(width 0.08382)
		(layer "In9.Cu")
		(net "PWRGD_PCH_PWROK")
	)
	(segment
		(start 34.67608 -60.3758)
		(end 33.853628 -61.60643)
		(width 0.08382)
		(layer "In9.Cu")
		(net "PWRGD_PCH_PWROK")
	)
	(segment
		(start 46.89983 -51.76647)
		(end 46.88713 -51.76647)
		(width 0.08382)
		(layer "In9.Cu")
		(net "PWRGD_PCH_PWROK")
	)
	(segment
		(start 34.27095 -67.888612)
		(end 34.08553 -68.074032)
		(width 0.08382)
		(layer "In9.Cu")
		(net "PWRGD_PCH_PWROK")
	)
	(segment
		(start 25.8572 -87.045546)
		(end 25.8572 -89.027)
		(width 0.08382)
		(layer "In9.Cu")
		(net "PWRGD_PCH_PWROK")
	)
	(segment
		(start 33.853628 -63.256922)
		(end 35.077654 -64.480948)
		(width 0.08382)
		(layer "In9.Cu")
		(net "PWRGD_PCH_PWROK")
	)
	(segment
		(start 35.077654 -64.480948)
		(end 35.077654 -64.9986)
		(width 0.08382)
		(layer "In9.Cu")
		(net "PWRGD_PCH_PWROK")
	)
	(segment
		(start 35.013392 -60.235846)
		(end 35.012884 -60.2361)
		(width 0.08382)
		(layer "In9.Cu")
		(net "PWRGD_PCH_PWROK")
	)
	(segment
		(start 40.21836 -55.215536)
		(end 39.855394 -56.091836)
		(width 0.08382)
		(layer "In9.Cu")
		(net "PWRGD_PCH_PWROK")
	)
	(segment
		(start 39.855394 -56.091836)
		(end 38.872922 -57.073292)
		(width 0.08382)
		(layer "In9.Cu")
		(net "PWRGD_PCH_PWROK")
	)
	(segment
		(start 19.064224 -89.591896)
		(end 19.459448 -89.98712)
		(width 0.11684)
		(layer "F.Cu")
		(net "IRQ_CPU1_VRHOT_N")
	)
	(segment
		(start 45.695108 -52.171346)
		(end 45.299884 -52.56657)
		(width 0.11684)
		(layer "F.Cu")
		(net "IRQ_CPU1_VRHOT_N")
	)
	(via
		(at 19.064224 -89.591896)
		(size 0.4572)
		(drill 0.254)
		(layers "F.Cu" "B.Cu")
		(net "IRQ_CPU1_VRHOT_N")
	)
	(via
		(at 45.299884 -52.56657)
		(size 0.4572)
		(drill 0.254)
		(layers "F.Cu" "B.Cu")
		(net "IRQ_CPU1_VRHOT_N")
	)
	(segment
		(start 42.709338 -54.471824)
		(end 40.955976 -54.471824)
		(width 0.08382)
		(layer "In9.Cu")
		(net "IRQ_CPU1_VRHOT_N")
	)
	(segment
		(start 26.4414 -90.019632)
		(end 25.626568 -89.2048)
		(width 0.08382)
		(layer "In9.Cu")
		(net "IRQ_CPU1_VRHOT_N")
	)
	(segment
		(start 43.129962 -54.0512)
		(end 42.709338 -54.471824)
		(width 0.08382)
		(layer "In9.Cu")
		(net "IRQ_CPU1_VRHOT_N")
	)
	(segment
		(start 44.873164 -52.99329)
		(end 44.346622 -52.99329)
		(width 0.08382)
		(layer "In9.Cu")
		(net "IRQ_CPU1_VRHOT_N")
	)
	(segment
		(start 27.72156 -86.197186)
		(end 27.439366 -86.47938)
		(width 0.08382)
		(layer "In9.Cu")
		(net "IRQ_CPU1_VRHOT_N")
	)
	(segment
		(start 40.8432 -54.5846)
		(end 40.8432 -55.35422)
		(width 0.08382)
		(layer "In9.Cu")
		(net "IRQ_CPU1_VRHOT_N")
	)
	(segment
		(start 40.8432 -55.35422)
		(end 40.395144 -56.436006)
		(width 0.08382)
		(layer "In9.Cu")
		(net "IRQ_CPU1_VRHOT_N")
	)
	(segment
		(start 34.544 -62.992254)
		(end 36.44519 -64.893444)
		(width 0.08382)
		(layer "In9.Cu")
		(net "IRQ_CPU1_VRHOT_N")
	)
	(segment
		(start 35.108642 -60.873386)
		(end 35.10788 -60.873386)
		(width 0.08382)
		(layer "In9.Cu")
		(net "IRQ_CPU1_VRHOT_N")
	)
	(segment
		(start 31.08071 -74.727562)
		(end 31.079694 -74.728578)
		(width 0.08382)
		(layer "In9.Cu")
		(net "IRQ_CPU1_VRHOT_N")
	)
	(segment
		(start 33.9217 -70.779132)
		(end 33.9217 -71.2089)
		(width 0.08382)
		(layer "In9.Cu")
		(net "IRQ_CPU1_VRHOT_N")
	)
	(segment
		(start 27.72156 -84.79028)
		(end 27.72156 -86.197186)
		(width 0.08382)
		(layer "In9.Cu")
		(net "IRQ_CPU1_VRHOT_N")
	)
	(segment
		(start 31.08071 -74.355706)
		(end 31.08071 -74.727562)
		(width 0.08382)
		(layer "In9.Cu")
		(net "IRQ_CPU1_VRHOT_N")
	)
	(segment
		(start 36.44519 -65.43421)
		(end 35.34029 -66.53911)
		(width 0.08382)
		(layer "In9.Cu")
		(net "IRQ_CPU1_VRHOT_N")
	)
	(segment
		(start 29.984446 -76.814426)
		(end 28.838398 -77.960474)
		(width 0.08382)
		(layer "In9.Cu")
		(net "IRQ_CPU1_VRHOT_N")
	)
	(segment
		(start 31.079694 -74.730864)
		(end 30.680914 -75.129644)
		(width 0.08382)
		(layer "In9.Cu")
		(net "IRQ_CPU1_VRHOT_N")
	)
	(segment
		(start 40.955976 -54.471824)
		(end 40.8432 -54.5846)
		(width 0.08382)
		(layer "In9.Cu")
		(net "IRQ_CPU1_VRHOT_N")
	)
	(segment
		(start 36.44519 -64.893444)
		(end 36.44519 -65.43421)
		(width 0.08382)
		(layer "In9.Cu")
		(net "IRQ_CPU1_VRHOT_N")
	)
	(segment
		(start 19.45132 -89.2048)
		(end 19.064224 -89.591896)
		(width 0.08382)
		(layer "In9.Cu")
		(net "IRQ_CPU1_VRHOT_N")
	)
	(segment
		(start 34.5313 -70.169532)
		(end 33.9217 -70.779132)
		(width 0.08382)
		(layer "In9.Cu")
		(net "IRQ_CPU1_VRHOT_N")
	)
	(segment
		(start 31.079694 -74.728578)
		(end 31.079694 -74.730864)
		(width 0.08382)
		(layer "In9.Cu")
		(net "IRQ_CPU1_VRHOT_N")
	)
	(segment
		(start 44.0944 -53.368956)
		(end 44.0944 -53.7464)
		(width 0.08382)
		(layer "In9.Cu")
		(net "IRQ_CPU1_VRHOT_N")
	)
	(segment
		(start 30.680914 -75.129644)
		(end 29.984446 -76.814426)
		(width 0.08382)
		(layer "In9.Cu")
		(net "IRQ_CPU1_VRHOT_N")
	)
	(segment
		(start 44.0944 -53.7464)
		(end 43.7896 -54.0512)
		(width 0.08382)
		(layer "In9.Cu")
		(net "IRQ_CPU1_VRHOT_N")
	)
	(segment
		(start 39.497 -58.066178)
		(end 38.49624 -59.066938)
		(width 0.08382)
		(layer "In9.Cu")
		(net "IRQ_CPU1_VRHOT_N")
	)
	(segment
		(start 31.079694 -74.35469)
		(end 31.08071 -74.355706)
		(width 0.08382)
		(layer "In9.Cu")
		(net "IRQ_CPU1_VRHOT_N")
	)
	(segment
		(start 35.34029 -66.53911)
		(end 35.34029 -69.862446)
		(width 0.08382)
		(layer "In9.Cu")
		(net "IRQ_CPU1_VRHOT_N")
	)
	(segment
		(start 33.9217 -71.2089)
		(end 31.079694 -74.050906)
		(width 0.08382)
		(layer "In9.Cu")
		(net "IRQ_CPU1_VRHOT_N")
	)
	(segment
		(start 35.34029 -69.862446)
		(end 35.033204 -70.169532)
		(width 0.08382)
		(layer "In9.Cu")
		(net "IRQ_CPU1_VRHOT_N")
	)
	(segment
		(start 28.838398 -77.960474)
		(end 28.838398 -83.673442)
		(width 0.08382)
		(layer "In9.Cu")
		(net "IRQ_CPU1_VRHOT_N")
	)
	(segment
		(start 27.439366 -86.47938)
		(end 27.439366 -89.733882)
		(width 0.08382)
		(layer "In9.Cu")
		(net "IRQ_CPU1_VRHOT_N")
	)
	(segment
		(start 44.204128 -53.135784)
		(end 44.169584 -53.187346)
		(width 0.08382)
		(layer "In9.Cu")
		(net "IRQ_CPU1_VRHOT_N")
	)
	(segment
		(start 45.299884 -52.56657)
		(end 44.873164 -52.99329)
		(width 0.08382)
		(layer "In9.Cu")
		(net "IRQ_CPU1_VRHOT_N")
	)
	(segment
		(start 35.10788 -60.873386)
		(end 35.090608 -60.880752)
		(width 0.08382)
		(layer "In9.Cu")
		(net "IRQ_CPU1_VRHOT_N")
	)
	(segment
		(start 44.169584 -53.187346)
		(end 44.0944 -53.368956)
		(width 0.08382)
		(layer "In9.Cu")
		(net "IRQ_CPU1_VRHOT_N")
	)
	(segment
		(start 38.49624 -59.066938)
		(end 37.010848 -60.059316)
		(width 0.08382)
		(layer "In9.Cu")
		(net "IRQ_CPU1_VRHOT_N")
	)
	(segment
		(start 28.838398 -83.673442)
		(end 27.72156 -84.79028)
		(width 0.08382)
		(layer "In9.Cu")
		(net "IRQ_CPU1_VRHOT_N")
	)
	(segment
		(start 37.010848 -60.059316)
		(end 36.99764 -60.091066)
		(width 0.08382)
		(layer "In9.Cu")
		(net "IRQ_CPU1_VRHOT_N")
	)
	(segment
		(start 35.090608 -60.880752)
		(end 34.544 -61.698632)
		(width 0.08382)
		(layer "In9.Cu")
		(net "IRQ_CPU1_VRHOT_N")
	)
	(segment
		(start 25.626568 -89.2048)
		(end 19.45132 -89.2048)
		(width 0.08382)
		(layer "In9.Cu")
		(net "IRQ_CPU1_VRHOT_N")
	)
	(segment
		(start 36.99764 -60.091066)
		(end 35.108642 -60.873386)
		(width 0.08382)
		(layer "In9.Cu")
		(net "IRQ_CPU1_VRHOT_N")
	)
	(segment
		(start 44.346622 -52.99329)
		(end 44.204128 -53.135784)
		(width 0.08382)
		(layer "In9.Cu")
		(net "IRQ_CPU1_VRHOT_N")
	)
	(segment
		(start 39.497 -57.333388)
		(end 39.497 -58.066178)
		(width 0.08382)
		(layer "In9.Cu")
		(net "IRQ_CPU1_VRHOT_N")
	)
	(segment
		(start 35.033204 -70.169532)
		(end 34.5313 -70.169532)
		(width 0.08382)
		(layer "In9.Cu")
		(net "IRQ_CPU1_VRHOT_N")
	)
	(segment
		(start 34.544 -61.698632)
		(end 34.544 -62.992254)
		(width 0.08382)
		(layer "In9.Cu")
		(net "IRQ_CPU1_VRHOT_N")
	)
	(segment
		(start 27.439366 -89.733882)
		(end 27.153616 -90.019632)
		(width 0.08382)
		(layer "In9.Cu")
		(net "IRQ_CPU1_VRHOT_N")
	)
	(segment
		(start 27.153616 -90.019632)
		(end 26.4414 -90.019632)
		(width 0.08382)
		(layer "In9.Cu")
		(net "IRQ_CPU1_VRHOT_N")
	)
	(segment
		(start 40.395144 -56.436006)
		(end 39.497 -57.333388)
		(width 0.08382)
		(layer "In9.Cu")
		(net "IRQ_CPU1_VRHOT_N")
	)
	(segment
		(start 43.7896 -54.0512)
		(end 43.129962 -54.0512)
		(width 0.08382)
		(layer "In9.Cu")
		(net "IRQ_CPU1_VRHOT_N")
	)
	(segment
		(start 31.079694 -74.050906)
		(end 31.079694 -74.35469)
		(width 0.08382)
		(layer "In9.Cu")
		(net "IRQ_CPU1_VRHOT_N")
	)
	(segment
		(start 19.864324 -91.191842)
		(end 20.259548 -91.587066)
		(width 0.11684)
		(layer "F.Cu")
		(net "IRQ_CPU0_VRHOT_N")
	)
	(segment
		(start 44.895008 -52.971192)
		(end 44.499784 -53.366416)
		(width 0.11684)
		(layer "F.Cu")
		(net "IRQ_CPU0_VRHOT_N")
	)
	(via
		(at 19.864324 -91.191842)
		(size 0.4572)
		(drill 0.254)
		(layers "F.Cu" "B.Cu")
		(net "IRQ_CPU0_VRHOT_N")
	)
	(via
		(at 44.499784 -53.366416)
		(size 0.4572)
		(drill 0.254)
		(layers "F.Cu" "B.Cu")
		(net "IRQ_CPU0_VRHOT_N")
	)
	(via
		(at 31.231078 -76.451714)
		(size 0.508)
		(drill 0.254)
		(layers "F.Cu" "B.Cu")
		(net "IRQ_CPU0_VRHOT_N")
	)
	(segment
		(start 29.463238 -78.219554)
		(end 31.231078 -76.451714)
		(width 0.08382)
		(layer "In9.Cu")
		(net "IRQ_CPU0_VRHOT_N")
	)
	(segment
		(start 44.8818 -54.5846)
		(end 44.8818 -53.748432)
		(width 0.08382)
		(layer "In9.Cu")
		(net "IRQ_CPU0_VRHOT_N")
	)
	(segment
		(start 28.3464 -85.04936)
		(end 29.463238 -83.932522)
		(width 0.08382)
		(layer "In9.Cu")
		(net "IRQ_CPU0_VRHOT_N")
	)
	(segment
		(start 37.13353 -66.086228)
		(end 37.65423 -65.565528)
		(width 0.08382)
		(layer "In9.Cu")
		(net "IRQ_CPU0_VRHOT_N")
	)
	(segment
		(start 35.8267 -61.632592)
		(end 36.176966 -61.108336)
		(width 0.08382)
		(layer "In9.Cu")
		(net "IRQ_CPU0_VRHOT_N")
	)
	(segment
		(start 42.02049 -56.319928)
		(end 42.766488 -55.57393)
		(width 0.08382)
		(layer "In9.Cu")
		(net "IRQ_CPU0_VRHOT_N")
	)
	(segment
		(start 37.65423 -64.766444)
		(end 37.175186 -64.2874)
		(width 0.08382)
		(layer "In9.Cu")
		(net "IRQ_CPU0_VRHOT_N")
	)
	(segment
		(start 36.176966 -61.108336)
		(end 36.595812 -60.9346)
		(width 0.08382)
		(layer "In9.Cu")
		(net "IRQ_CPU0_VRHOT_N")
	)
	(segment
		(start 36.757102 -64.2874)
		(end 35.8267 -63.356998)
		(width 0.08382)
		(layer "In9.Cu")
		(net "IRQ_CPU0_VRHOT_N")
	)
	(segment
		(start 28.0162 -89.95918)
		(end 28.0162 -86.842346)
		(width 0.08382)
		(layer "In9.Cu")
		(net "IRQ_CPU0_VRHOT_N")
	)
	(segment
		(start 40.4495 -59.91098)
		(end 40.4495 -58.2803)
		(width 0.08382)
		(layer "In9.Cu")
		(net "IRQ_CPU0_VRHOT_N")
	)
	(segment
		(start 40.4495 -58.2803)
		(end 42.02049 -56.70931)
		(width 0.08382)
		(layer "In9.Cu")
		(net "IRQ_CPU0_VRHOT_N")
	)
	(segment
		(start 20.251166 -90.805)
		(end 27.17038 -90.805)
		(width 0.08382)
		(layer "In9.Cu")
		(net "IRQ_CPU0_VRHOT_N")
	)
	(segment
		(start 19.864324 -91.191842)
		(end 20.251166 -90.805)
		(width 0.08382)
		(layer "In9.Cu")
		(net "IRQ_CPU0_VRHOT_N")
	)
	(segment
		(start 39.564056 -60.48629)
		(end 39.87419 -60.48629)
		(width 0.08382)
		(layer "In9.Cu")
		(net "IRQ_CPU0_VRHOT_N")
	)
	(segment
		(start 35.69462 -70.82409)
		(end 35.69462 -70.392036)
		(width 0.08382)
		(layer "In9.Cu")
		(net "IRQ_CPU0_VRHOT_N")
	)
	(segment
		(start 31.231078 -76.451714)
		(end 32.086296 -75.596496)
		(width 0.08382)
		(layer "In9.Cu")
		(net "IRQ_CPU0_VRHOT_N")
	)
	(segment
		(start 28.0162 -86.842346)
		(end 28.3464 -86.512146)
		(width 0.08382)
		(layer "In9.Cu")
		(net "IRQ_CPU0_VRHOT_N")
	)
	(segment
		(start 34.685478 -71.833232)
		(end 35.69462 -70.82409)
		(width 0.08382)
		(layer "In9.Cu")
		(net "IRQ_CPU0_VRHOT_N")
	)
	(segment
		(start 36.076128 -70.010528)
		(end 36.076128 -68.621402)
		(width 0.08382)
		(layer "In9.Cu")
		(net "IRQ_CPU0_VRHOT_N")
	)
	(segment
		(start 35.69462 -70.392036)
		(end 36.076128 -70.010528)
		(width 0.08382)
		(layer "In9.Cu")
		(net "IRQ_CPU0_VRHOT_N")
	)
	(segment
		(start 37.13353 -67.564)
		(end 37.13353 -66.086228)
		(width 0.08382)
		(layer "In9.Cu")
		(net "IRQ_CPU0_VRHOT_N")
	)
	(segment
		(start 37.175186 -64.2874)
		(end 36.757102 -64.2874)
		(width 0.08382)
		(layer "In9.Cu")
		(net "IRQ_CPU0_VRHOT_N")
	)
	(segment
		(start 44.273978 -54.94909)
		(end 44.51731 -54.94909)
		(width 0.08382)
		(layer "In9.Cu")
		(net "IRQ_CPU0_VRHOT_N")
	)
	(segment
		(start 44.8818 -53.748432)
		(end 44.499784 -53.366416)
		(width 0.08382)
		(layer "In9.Cu")
		(net "IRQ_CPU0_VRHOT_N")
	)
	(segment
		(start 44.51731 -54.94909)
		(end 44.8818 -54.5846)
		(width 0.08382)
		(layer "In9.Cu")
		(net "IRQ_CPU0_VRHOT_N")
	)
	(segment
		(start 39.87419 -60.48629)
		(end 40.4495 -59.91098)
		(width 0.08382)
		(layer "In9.Cu")
		(net "IRQ_CPU0_VRHOT_N")
	)
	(segment
		(start 35.8267 -63.356998)
		(end 35.8267 -61.632592)
		(width 0.08382)
		(layer "In9.Cu")
		(net "IRQ_CPU0_VRHOT_N")
	)
	(segment
		(start 32.086296 -75.596496)
		(end 32.086296 -74.146664)
		(width 0.08382)
		(layer "In9.Cu")
		(net "IRQ_CPU0_VRHOT_N")
	)
	(segment
		(start 36.076128 -68.621402)
		(end 37.13353 -67.564)
		(width 0.08382)
		(layer "In9.Cu")
		(net "IRQ_CPU0_VRHOT_N")
	)
	(segment
		(start 37.65423 -65.565528)
		(end 37.65423 -64.766444)
		(width 0.08382)
		(layer "In9.Cu")
		(net "IRQ_CPU0_VRHOT_N")
	)
	(segment
		(start 29.463238 -83.932522)
		(end 29.463238 -78.219554)
		(width 0.08382)
		(layer "In9.Cu")
		(net "IRQ_CPU0_VRHOT_N")
	)
	(segment
		(start 28.3464 -86.512146)
		(end 28.3464 -85.04936)
		(width 0.08382)
		(layer "In9.Cu")
		(net "IRQ_CPU0_VRHOT_N")
	)
	(segment
		(start 27.17038 -90.805)
		(end 28.0162 -89.95918)
		(width 0.08382)
		(layer "In9.Cu")
		(net "IRQ_CPU0_VRHOT_N")
	)
	(segment
		(start 32.086296 -74.146664)
		(end 34.399728 -71.833232)
		(width 0.08382)
		(layer "In9.Cu")
		(net "IRQ_CPU0_VRHOT_N")
	)
	(segment
		(start 39.115746 -60.9346)
		(end 39.564056 -60.48629)
		(width 0.08382)
		(layer "In9.Cu")
		(net "IRQ_CPU0_VRHOT_N")
	)
	(segment
		(start 36.595812 -60.9346)
		(end 39.115746 -60.9346)
		(width 0.08382)
		(layer "In9.Cu")
		(net "IRQ_CPU0_VRHOT_N")
	)
	(segment
		(start 42.02049 -56.70931)
		(end 42.02049 -56.319928)
		(width 0.08382)
		(layer "In9.Cu")
		(net "IRQ_CPU0_VRHOT_N")
	)
	(segment
		(start 34.399728 -71.833232)
		(end 34.685478 -71.833232)
		(width 0.08382)
		(layer "In9.Cu")
		(net "IRQ_CPU0_VRHOT_N")
	)
	(segment
		(start 42.766488 -55.57393)
		(end 44.273978 -54.94909)
		(width 0.08382)
		(layer "In9.Cu")
		(net "IRQ_CPU0_VRHOT_N")
	)
	(segment
		(start 46.494954 -52.971192)
		(end 46.494954 -52.961794)
		(width 0.11684)
		(layer "F.Cu")
		(net "IRQ_OC_DETECT_EN_N")
	)
	(segment
		(start 46.494954 -52.961794)
		(end 46.09973 -52.56657)
		(width 0.11684)
		(layer "F.Cu")
		(net "IRQ_OC_DETECT_EN_N")
	)
	(segment
		(start 17.464278 -87.99195)
		(end 17.859502 -88.387174)
		(width 0.11684)
		(layer "F.Cu")
		(net "IRQ_OC_DETECT_EN_N")
	)
	(via
		(at 46.09973 -52.56657)
		(size 0.4572)
		(drill 0.254)
		(layers "F.Cu" "B.Cu")
		(net "IRQ_OC_DETECT_EN_N")
	)
	(via
		(at 17.464278 -87.99195)
		(size 0.4572)
		(drill 0.254)
		(layers "F.Cu" "B.Cu")
		(net "IRQ_OC_DETECT_EN_N")
	)
	(segment
		(start 27.345132 -92.419678)
		(end 18.073878 -92.419678)
		(width 0.08382)
		(layer "In9.Cu")
		(net "IRQ_OC_DETECT_EN_N")
	)
	(segment
		(start 31.047436 -80.816704)
		(end 30.13456 -81.72958)
		(width 0.08382)
		(layer "In9.Cu")
		(net "IRQ_OC_DETECT_EN_N")
	)
	(segment
		(start 17.8562 -92.202)
		(end 17.8562 -90.0938)
		(width 0.08382)
		(layer "In9.Cu")
		(net "IRQ_OC_DETECT_EN_N")
	)
	(segment
		(start 29.6164 -90.26398)
		(end 29.21 -90.67038)
		(width 0.08382)
		(layer "In9.Cu")
		(net "IRQ_OC_DETECT_EN_N")
	)
	(segment
		(start 42.9006 -59.182)
		(end 42.9006 -59.854338)
		(width 0.08382)
		(layer "In9.Cu")
		(net "IRQ_OC_DETECT_EN_N")
	)
	(segment
		(start 38.59149 -65.954148)
		(end 38.37686 -66.168778)
		(width 0.08382)
		(layer "In9.Cu")
		(net "IRQ_OC_DETECT_EN_N")
	)
	(segment
		(start 29.6164 -87.274146)
		(end 29.6164 -90.26398)
		(width 0.08382)
		(layer "In9.Cu")
		(net "IRQ_OC_DETECT_EN_N")
	)
	(segment
		(start 38.37686 -66.168778)
		(end 38.37686 -68.619116)
		(width 0.08382)
		(layer "In9.Cu")
		(net "IRQ_OC_DETECT_EN_N")
	)
	(segment
		(start 29.21 -92.71)
		(end 28.65882 -93.26118)
		(width 0.08382)
		(layer "In9.Cu")
		(net "IRQ_OC_DETECT_EN_N")
	)
	(segment
		(start 39.591488 -63.16345)
		(end 39.380414 -63.16345)
		(width 0.08382)
		(layer "In9.Cu")
		(net "IRQ_OC_DETECT_EN_N")
	)
	(segment
		(start 31.047436 -78.859126)
		(end 31.047436 -80.816704)
		(width 0.08382)
		(layer "In9.Cu")
		(net "IRQ_OC_DETECT_EN_N")
	)
	(segment
		(start 33.023556 -74.535284)
		(end 33.023556 -76.883006)
		(width 0.08382)
		(layer "In9.Cu")
		(net "IRQ_OC_DETECT_EN_N")
	)
	(segment
		(start 30.0228 -86.867746)
		(end 29.6164 -87.274146)
		(width 0.08382)
		(layer "In9.Cu")
		(net "IRQ_OC_DETECT_EN_N")
	)
	(segment
		(start 39.380414 -63.16345)
		(end 38.59149 -63.952374)
		(width 0.08382)
		(layer "In9.Cu")
		(net "IRQ_OC_DETECT_EN_N")
	)
	(segment
		(start 30.0228 -84.262214)
		(end 30.0228 -86.867746)
		(width 0.08382)
		(layer "In9.Cu")
		(net "IRQ_OC_DETECT_EN_N")
	)
	(segment
		(start 34.788348 -72.770492)
		(end 33.023556 -74.535284)
		(width 0.08382)
		(layer "In9.Cu")
		(net "IRQ_OC_DETECT_EN_N")
	)
	(segment
		(start 46.52264 -55.1053)
		(end 46.25086 -55.37708)
		(width 0.08382)
		(layer "In9.Cu")
		(net "IRQ_OC_DETECT_EN_N")
	)
	(segment
		(start 43.551602 -58.530998)
		(end 42.9006 -59.182)
		(width 0.08382)
		(layer "In9.Cu")
		(net "IRQ_OC_DETECT_EN_N")
	)
	(segment
		(start 30.13456 -81.72958)
		(end 30.13456 -84.150454)
		(width 0.08382)
		(layer "In9.Cu")
		(net "IRQ_OC_DETECT_EN_N")
	)
	(segment
		(start 17.092168 -89.789)
		(end 17.092168 -88.36406)
		(width 0.08382)
		(layer "In9.Cu")
		(net "IRQ_OC_DETECT_EN_N")
	)
	(segment
		(start 38.37686 -68.619116)
		(end 36.63188 -70.364096)
		(width 0.08382)
		(layer "In9.Cu")
		(net "IRQ_OC_DETECT_EN_N")
	)
	(segment
		(start 28.65882 -93.26118)
		(end 28.186634 -93.26118)
		(width 0.08382)
		(layer "In9.Cu")
		(net "IRQ_OC_DETECT_EN_N")
	)
	(segment
		(start 36.63188 -71.21271)
		(end 35.074098 -72.770492)
		(width 0.08382)
		(layer "In9.Cu")
		(net "IRQ_OC_DETECT_EN_N")
	)
	(segment
		(start 17.7292 -89.9668)
		(end 17.269968 -89.9668)
		(width 0.08382)
		(layer "In9.Cu")
		(net "IRQ_OC_DETECT_EN_N")
	)
	(segment
		(start 43.69689 -57.072022)
		(end 43.551602 -57.422034)
		(width 0.08382)
		(layer "In9.Cu")
		(net "IRQ_OC_DETECT_EN_N")
	)
	(segment
		(start 45.84192 -55.37708)
		(end 44.41571 -56.80329)
		(width 0.08382)
		(layer "In9.Cu")
		(net "IRQ_OC_DETECT_EN_N")
	)
	(segment
		(start 35.074098 -72.770492)
		(end 34.788348 -72.770492)
		(width 0.08382)
		(layer "In9.Cu")
		(net "IRQ_OC_DETECT_EN_N")
	)
	(segment
		(start 43.551602 -57.422034)
		(end 43.551602 -58.530998)
		(width 0.08382)
		(layer "In9.Cu")
		(net "IRQ_OC_DETECT_EN_N")
	)
	(segment
		(start 38.59149 -63.952374)
		(end 38.59149 -65.954148)
		(width 0.08382)
		(layer "In9.Cu")
		(net "IRQ_OC_DETECT_EN_N")
	)
	(segment
		(start 29.21 -90.67038)
		(end 29.21 -92.71)
		(width 0.08382)
		(layer "In9.Cu")
		(net "IRQ_OC_DETECT_EN_N")
	)
	(segment
		(start 36.63188 -70.364096)
		(end 36.63188 -71.21271)
		(width 0.08382)
		(layer "In9.Cu")
		(net "IRQ_OC_DETECT_EN_N")
	)
	(segment
		(start 42.9006 -59.854338)
		(end 39.591488 -63.16345)
		(width 0.08382)
		(layer "In9.Cu")
		(net "IRQ_OC_DETECT_EN_N")
	)
	(segment
		(start 30.13456 -84.150454)
		(end 30.0228 -84.262214)
		(width 0.08382)
		(layer "In9.Cu")
		(net "IRQ_OC_DETECT_EN_N")
	)
	(segment
		(start 17.8562 -90.0938)
		(end 17.7292 -89.9668)
		(width 0.08382)
		(layer "In9.Cu")
		(net "IRQ_OC_DETECT_EN_N")
	)
	(segment
		(start 46.25086 -55.37708)
		(end 45.84192 -55.37708)
		(width 0.08382)
		(layer "In9.Cu")
		(net "IRQ_OC_DETECT_EN_N")
	)
	(segment
		(start 28.186634 -93.26118)
		(end 27.345132 -92.419678)
		(width 0.08382)
		(layer "In9.Cu")
		(net "IRQ_OC_DETECT_EN_N")
	)
	(segment
		(start 17.092168 -88.36406)
		(end 17.464278 -87.99195)
		(width 0.08382)
		(layer "In9.Cu")
		(net "IRQ_OC_DETECT_EN_N")
	)
	(segment
		(start 44.41571 -56.80329)
		(end 43.979592 -56.80329)
		(width 0.08382)
		(layer "In9.Cu")
		(net "IRQ_OC_DETECT_EN_N")
	)
	(segment
		(start 46.09973 -54.166262)
		(end 46.52264 -54.589172)
		(width 0.08382)
		(layer "In9.Cu")
		(net "IRQ_OC_DETECT_EN_N")
	)
	(segment
		(start 18.073878 -92.419678)
		(end 17.8562 -92.202)
		(width 0.08382)
		(layer "In9.Cu")
		(net "IRQ_OC_DETECT_EN_N")
	)
	(segment
		(start 46.09973 -52.56657)
		(end 46.09973 -54.166262)
		(width 0.08382)
		(layer "In9.Cu")
		(net "IRQ_OC_DETECT_EN_N")
	)
	(segment
		(start 33.023556 -76.883006)
		(end 31.047436 -78.859126)
		(width 0.08382)
		(layer "In9.Cu")
		(net "IRQ_OC_DETECT_EN_N")
	)
	(segment
		(start 43.979592 -56.80329)
		(end 43.945048 -56.817514)
		(width 0.08382)
		(layer "In9.Cu")
		(net "IRQ_OC_DETECT_EN_N")
	)
	(segment
		(start 46.52264 -54.589172)
		(end 46.52264 -55.1053)
		(width 0.08382)
		(layer "In9.Cu")
		(net "IRQ_OC_DETECT_EN_N")
	)
	(segment
		(start 43.701462 -57.0611)
		(end 43.69689 -57.072022)
		(width 0.08382)
		(layer "In9.Cu")
		(net "IRQ_OC_DETECT_EN_N")
	)
	(segment
		(start 17.269968 -89.9668)
		(end 17.092168 -89.789)
		(width 0.08382)
		(layer "In9.Cu")
		(net "IRQ_OC_DETECT_EN_N")
	)
	(segment
		(start 43.945048 -56.817514)
		(end 43.701462 -57.0611)
		(width 0.08382)
		(layer "In9.Cu")
		(net "IRQ_OC_DETECT_EN_N")
	)
	(segment
		(start 22.257512 -86.722712)
		(end 22.257512 -87.985346)
		(width 0.11684)
		(layer "F.Cu")
		(net "IRQ_UV_DETECT_N")
	)
	(segment
		(start 20.8026 -85.6234)
		(end 21.1582 -85.6234)
		(width 0.11684)
		(layer "F.Cu")
		(net "IRQ_UV_DETECT_N")
	)
	(segment
		(start 21.1582 -85.6234)
		(end 22.257512 -86.722712)
		(width 0.11684)
		(layer "F.Cu")
		(net "IRQ_UV_DETECT_N")
	)
	(segment
		(start 46.494954 -52.161694)
		(end 46.494954 -52.171346)
		(width 0.11684)
		(layer "F.Cu")
		(net "IRQ_UV_DETECT_N")
	)
	(segment
		(start 46.09973 -51.76647)
		(end 46.494954 -52.161694)
		(width 0.11684)
		(layer "F.Cu")
		(net "IRQ_UV_DETECT_N")
	)
	(segment
		(start 22.257512 -87.985346)
		(end 22.65934 -88.387174)
		(width 0.11684)
		(layer "F.Cu")
		(net "IRQ_UV_DETECT_N")
	)
	(via
		(at 20.8026 -85.6234)
		(size 0.508)
		(drill 0.254)
		(layers "F.Cu" "B.Cu")
		(net "IRQ_UV_DETECT_N")
	)
	(via
		(at 46.09973 -51.76647)
		(size 0.4572)
		(drill 0.254)
		(layers "F.Cu" "B.Cu")
		(net "IRQ_UV_DETECT_N")
	)
	(segment
		(start 27.588718 -83.155282)
		(end 27.588718 -77.441552)
		(width 0.08382)
		(layer "In9.Cu")
		(net "IRQ_UV_DETECT_N")
	)
	(segment
		(start 39.880286 -53.744368)
		(end 39.880286 -52.63515)
		(width 0.08382)
		(layer "In9.Cu")
		(net "IRQ_UV_DETECT_N")
	)
	(segment
		(start 33.752282 -60.633102)
		(end 34.26206 -59.87034)
		(width 0.08382)
		(layer "In9.Cu")
		(net "IRQ_UV_DETECT_N")
	)
	(segment
		(start 39.575486 -54.049168)
		(end 39.880286 -53.744368)
		(width 0.08382)
		(layer "In9.Cu")
		(net "IRQ_UV_DETECT_N")
	)
	(segment
		(start 25.7048 -86.2076)
		(end 25.7048 -85.0392)
		(width 0.08382)
		(layer "In9.Cu")
		(net "IRQ_UV_DETECT_N")
	)
	(segment
		(start 34.840418 -59.630818)
		(end 34.840926 -59.630056)
		(width 0.08382)
		(layer "In9.Cu")
		(net "IRQ_UV_DETECT_N")
	)
	(segment
		(start 33.228788 -63.516002)
		(end 33.228788 -61.416184)
		(width 0.08382)
		(layer "In9.Cu")
		(net "IRQ_UV_DETECT_N")
	)
	(segment
		(start 27.588718 -77.441552)
		(end 28.880308 -76.149962)
		(width 0.08382)
		(layer "In9.Cu")
		(net "IRQ_UV_DETECT_N")
	)
	(segment
		(start 39.575486 -55.133748)
		(end 39.575486 -54.049168)
		(width 0.08382)
		(layer "In9.Cu")
		(net "IRQ_UV_DETECT_N")
	)
	(segment
		(start 22.1107 -86.9315)
		(end 24.9809 -86.9315)
		(width 0.08382)
		(layer "In9.Cu")
		(net "IRQ_UV_DETECT_N")
	)
	(segment
		(start 24.9809 -86.9315)
		(end 25.7048 -86.2076)
		(width 0.08382)
		(layer "In9.Cu")
		(net "IRQ_UV_DETECT_N")
	)
	(segment
		(start 29.223716 -73.660762)
		(end 31.7246 -71.159878)
		(width 0.08382)
		(layer "In9.Cu")
		(net "IRQ_UV_DETECT_N")
	)
	(segment
		(start 28.880308 -76.149962)
		(end 29.223716 -75.320652)
		(width 0.08382)
		(layer "In9.Cu")
		(net "IRQ_UV_DETECT_N")
	)
	(segment
		(start 29.223716 -75.320652)
		(end 29.223716 -73.660762)
		(width 0.08382)
		(layer "In9.Cu")
		(net "IRQ_UV_DETECT_N")
	)
	(segment
		(start 40.75938 -51.756056)
		(end 40.75938 -51.294538)
		(width 0.08382)
		(layer "In9.Cu")
		(net "IRQ_UV_DETECT_N")
	)
	(segment
		(start 32.2326 -69.043042)
		(end 33.64611 -67.629532)
		(width 0.08382)
		(layer "In9.Cu")
		(net "IRQ_UV_DETECT_N")
	)
	(segment
		(start 31.7246 -71.159878)
		(end 31.7246 -70.6628)
		(width 0.08382)
		(layer "In9.Cu")
		(net "IRQ_UV_DETECT_N")
	)
	(segment
		(start 38.24732 -56.773826)
		(end 39.355014 -55.666132)
		(width 0.08382)
		(layer "In9.Cu")
		(net "IRQ_UV_DETECT_N")
	)
	(segment
		(start 31.7246 -70.6628)
		(end 32.2326 -70.1548)
		(width 0.08382)
		(layer "In9.Cu")
		(net "IRQ_UV_DETECT_N")
	)
	(segment
		(start 20.8026 -85.6234)
		(end 22.1107 -86.9315)
		(width 0.08382)
		(layer "In9.Cu")
		(net "IRQ_UV_DETECT_N")
	)
	(segment
		(start 39.880286 -52.63515)
		(end 40.75938 -51.756056)
		(width 0.08382)
		(layer "In9.Cu")
		(net "IRQ_UV_DETECT_N")
	)
	(segment
		(start 40.75938 -51.294538)
		(end 41.691052 -50.362866)
		(width 0.08382)
		(layer "In9.Cu")
		(net "IRQ_UV_DETECT_N")
	)
	(segment
		(start 33.64611 -66.45529)
		(end 34.45256 -65.64884)
		(width 0.08382)
		(layer "In9.Cu")
		(net "IRQ_UV_DETECT_N")
	)
	(segment
		(start 45.72762 -51.39436)
		(end 46.09973 -51.76647)
		(width 0.08382)
		(layer "In9.Cu")
		(net "IRQ_UV_DETECT_N")
	)
	(segment
		(start 36.316158 -59.019186)
		(end 37.702236 -58.093102)
		(width 0.08382)
		(layer "In9.Cu")
		(net "IRQ_UV_DETECT_N")
	)
	(segment
		(start 42.3926 -50.362866)
		(end 43.424094 -51.39436)
		(width 0.08382)
		(layer "In9.Cu")
		(net "IRQ_UV_DETECT_N")
	)
	(segment
		(start 41.691052 -50.362866)
		(end 42.3926 -50.362866)
		(width 0.08382)
		(layer "In9.Cu")
		(net "IRQ_UV_DETECT_N")
	)
	(segment
		(start 25.7048 -85.0392)
		(end 27.588718 -83.155282)
		(width 0.08382)
		(layer "In9.Cu")
		(net "IRQ_UV_DETECT_N")
	)
	(segment
		(start 34.26206 -59.87034)
		(end 34.840418 -59.630818)
		(width 0.08382)
		(layer "In9.Cu")
		(net "IRQ_UV_DETECT_N")
	)
	(segment
		(start 33.228788 -61.416184)
		(end 33.752282 -60.633102)
		(width 0.08382)
		(layer "In9.Cu")
		(net "IRQ_UV_DETECT_N")
	)
	(segment
		(start 33.64611 -67.629532)
		(end 33.64611 -66.45529)
		(width 0.08382)
		(layer "In9.Cu")
		(net "IRQ_UV_DETECT_N")
	)
	(segment
		(start 32.2326 -70.1548)
		(end 32.2326 -69.043042)
		(width 0.08382)
		(layer "In9.Cu")
		(net "IRQ_UV_DETECT_N")
	)
	(segment
		(start 39.355014 -55.666132)
		(end 39.575486 -55.133748)
		(width 0.08382)
		(layer "In9.Cu")
		(net "IRQ_UV_DETECT_N")
	)
	(segment
		(start 34.45256 -64.739774)
		(end 33.228788 -63.516002)
		(width 0.08382)
		(layer "In9.Cu")
		(net "IRQ_UV_DETECT_N")
	)
	(segment
		(start 34.840926 -59.630056)
		(end 36.316158 -59.019186)
		(width 0.08382)
		(layer "In9.Cu")
		(net "IRQ_UV_DETECT_N")
	)
	(segment
		(start 38.24732 -57.548018)
		(end 38.24732 -56.773826)
		(width 0.08382)
		(layer "In9.Cu")
		(net "IRQ_UV_DETECT_N")
	)
	(segment
		(start 37.702236 -58.093102)
		(end 38.24732 -57.548018)
		(width 0.08382)
		(layer "In9.Cu")
		(net "IRQ_UV_DETECT_N")
	)
	(segment
		(start 43.424094 -51.39436)
		(end 45.72762 -51.39436)
		(width 0.08382)
		(layer "In9.Cu")
		(net "IRQ_UV_DETECT_N")
	)
	(segment
		(start 34.45256 -65.64884)
		(end 34.45256 -64.739774)
		(width 0.08382)
		(layer "In9.Cu")
		(net "IRQ_UV_DETECT_N")
	)
	(segment
		(start 45.695108 -52.971192)
		(end 45.299884 -53.366416)
		(width 0.11684)
		(layer "F.Cu")
		(net "IRQ_OC_DETECT_N")
	)
	(segment
		(start 19.064224 -87.99195)
		(end 19.459448 -88.387174)
		(width 0.11684)
		(layer "F.Cu")
		(net "IRQ_OC_DETECT_N")
	)
	(via
		(at 19.064224 -87.99195)
		(size 0.4572)
		(drill 0.254)
		(layers "F.Cu" "B.Cu")
		(net "IRQ_OC_DETECT_N")
	)
	(via
		(at 45.299884 -53.366416)
		(size 0.4572)
		(drill 0.254)
		(layers "F.Cu" "B.Cu")
		(net "IRQ_OC_DETECT_N")
	)
	(segment
		(start 36.00704 -70.521576)
		(end 36.474908 -70.053708)
		(width 0.08382)
		(layer "In9.Cu")
		(net "IRQ_OC_DETECT_N")
	)
	(segment
		(start 37.304726 -63.97498)
		(end 36.886642 -63.97498)
		(width 0.08382)
		(layer "In9.Cu")
		(net "IRQ_OC_DETECT_N")
	)
	(segment
		(start 29.82214 -81.15808)
		(end 30.422596 -80.557624)
		(width 0.08382)
		(layer "In9.Cu")
		(net "IRQ_OC_DETECT_N")
	)
	(segment
		(start 44.1198 -55.753)
		(end 44.6024 -55.753)
		(width 0.08382)
		(layer "In9.Cu")
		(net "IRQ_OC_DETECT_N")
	)
	(segment
		(start 32.398716 -74.276204)
		(end 34.529268 -72.145652)
		(width 0.08382)
		(layer "In9.Cu")
		(net "IRQ_OC_DETECT_N")
	)
	(segment
		(start 30.422596 -80.557624)
		(end 30.422596 -78.859126)
		(width 0.08382)
		(layer "In9.Cu")
		(net "IRQ_OC_DETECT_N")
	)
	(segment
		(start 28.3464 -90.142568)
		(end 28.3464 -87.071454)
		(width 0.08382)
		(layer "In9.Cu")
		(net "IRQ_OC_DETECT_N")
	)
	(segment
		(start 28.7274 -86.690454)
		(end 28.7274 -85.115654)
		(width 0.08382)
		(layer "In9.Cu")
		(net "IRQ_OC_DETECT_N")
	)
	(segment
		(start 36.384484 -61.360558)
		(end 36.615624 -61.2648)
		(width 0.08382)
		(layer "In9.Cu")
		(net "IRQ_OC_DETECT_N")
	)
	(segment
		(start 36.13912 -63.227458)
		(end 36.13912 -61.727588)
		(width 0.08382)
		(layer "In9.Cu")
		(net "IRQ_OC_DETECT_N")
	)
	(segment
		(start 41.4782 -59.386216)
		(end 42.690542 -58.173874)
		(width 0.08382)
		(layer "In9.Cu")
		(net "IRQ_OC_DETECT_N")
	)
	(segment
		(start 34.529268 -72.145652)
		(end 34.815018 -72.145652)
		(width 0.08382)
		(layer "In9.Cu")
		(net "IRQ_OC_DETECT_N")
	)
	(segment
		(start 44.6024 -55.753)
		(end 45.72 -54.6354)
		(width 0.08382)
		(layer "In9.Cu")
		(net "IRQ_OC_DETECT_N")
	)
	(segment
		(start 34.815018 -72.145652)
		(end 36.00704 -70.95363)
		(width 0.08382)
		(layer "In9.Cu")
		(net "IRQ_OC_DETECT_N")
	)
	(segment
		(start 43.603672 -55.60949)
		(end 43.97629 -55.60949)
		(width 0.08382)
		(layer "In9.Cu")
		(net "IRQ_OC_DETECT_N")
	)
	(segment
		(start 41.4782 -60.365386)
		(end 41.4782 -59.386216)
		(width 0.08382)
		(layer "In9.Cu")
		(net "IRQ_OC_DETECT_N")
	)
	(segment
		(start 17.8562 -88.4428)
		(end 17.8562 -89.7382)
		(width 0.08382)
		(layer "In9.Cu")
		(net "IRQ_OC_DETECT_N")
	)
	(segment
		(start 45.72 -54.6354)
		(end 45.72 -53.786532)
		(width 0.08382)
		(layer "In9.Cu")
		(net "IRQ_OC_DETECT_N")
	)
	(segment
		(start 29.82214 -84.020914)
		(end 29.82214 -81.15808)
		(width 0.08382)
		(layer "In9.Cu")
		(net "IRQ_OC_DETECT_N")
	)
	(segment
		(start 18.669 -91.4146)
		(end 18.818352 -91.563952)
		(width 0.08382)
		(layer "In9.Cu")
		(net "IRQ_OC_DETECT_N")
	)
	(segment
		(start 18.818352 -91.563952)
		(end 26.925016 -91.563952)
		(width 0.08382)
		(layer "In9.Cu")
		(net "IRQ_OC_DETECT_N")
	)
	(segment
		(start 45.72 -53.786532)
		(end 45.299884 -53.366416)
		(width 0.08382)
		(layer "In9.Cu")
		(net "IRQ_OC_DETECT_N")
	)
	(segment
		(start 30.422596 -78.859126)
		(end 30.422342 -78.858872)
		(width 0.08382)
		(layer "In9.Cu")
		(net "IRQ_OC_DETECT_N")
	)
	(segment
		(start 37.96665 -65.695068)
		(end 37.96665 -64.636904)
		(width 0.08382)
		(layer "In9.Cu")
		(net "IRQ_OC_DETECT_N")
	)
	(segment
		(start 26.925016 -91.563952)
		(end 28.3464 -90.142568)
		(width 0.08382)
		(layer "In9.Cu")
		(net "IRQ_OC_DETECT_N")
	)
	(segment
		(start 37.44595 -66.215768)
		(end 37.96665 -65.695068)
		(width 0.08382)
		(layer "In9.Cu")
		(net "IRQ_OC_DETECT_N")
	)
	(segment
		(start 28.7274 -85.115654)
		(end 29.82214 -84.020914)
		(width 0.08382)
		(layer "In9.Cu")
		(net "IRQ_OC_DETECT_N")
	)
	(segment
		(start 18.4912 -89.9668)
		(end 18.669 -90.1446)
		(width 0.08382)
		(layer "In9.Cu")
		(net "IRQ_OC_DETECT_N")
	)
	(segment
		(start 38.25494 -61.2648)
		(end 39.080948 -62.090808)
		(width 0.08382)
		(layer "In9.Cu")
		(net "IRQ_OC_DETECT_N")
	)
	(segment
		(start 39.752778 -62.090808)
		(end 41.4782 -60.365386)
		(width 0.08382)
		(layer "In9.Cu")
		(net "IRQ_OC_DETECT_N")
	)
	(segment
		(start 36.13912 -61.727588)
		(end 36.384484 -61.360558)
		(width 0.08382)
		(layer "In9.Cu")
		(net "IRQ_OC_DETECT_N")
	)
	(segment
		(start 36.615624 -61.2648)
		(end 38.25494 -61.2648)
		(width 0.08382)
		(layer "In9.Cu")
		(net "IRQ_OC_DETECT_N")
	)
	(segment
		(start 37.96665 -64.636904)
		(end 37.304726 -63.97498)
		(width 0.08382)
		(layer "In9.Cu")
		(net "IRQ_OC_DETECT_N")
	)
	(segment
		(start 36.00704 -70.95363)
		(end 36.00704 -70.521576)
		(width 0.08382)
		(layer "In9.Cu")
		(net "IRQ_OC_DETECT_N")
	)
	(segment
		(start 42.690542 -57.195466)
		(end 43.165776 -56.047386)
		(width 0.08382)
		(layer "In9.Cu")
		(net "IRQ_OC_DETECT_N")
	)
	(segment
		(start 19.064224 -87.99195)
		(end 18.30705 -87.99195)
		(width 0.08382)
		(layer "In9.Cu")
		(net "IRQ_OC_DETECT_N")
	)
	(segment
		(start 17.8562 -89.7382)
		(end 18.0848 -89.9668)
		(width 0.08382)
		(layer "In9.Cu")
		(net "IRQ_OC_DETECT_N")
	)
	(segment
		(start 32.398716 -76.623926)
		(end 32.398716 -74.276204)
		(width 0.08382)
		(layer "In9.Cu")
		(net "IRQ_OC_DETECT_N")
	)
	(segment
		(start 36.474908 -70.053708)
		(end 36.474908 -68.712842)
		(width 0.08382)
		(layer "In9.Cu")
		(net "IRQ_OC_DETECT_N")
	)
	(segment
		(start 28.3464 -87.071454)
		(end 28.7274 -86.690454)
		(width 0.08382)
		(layer "In9.Cu")
		(net "IRQ_OC_DETECT_N")
	)
	(segment
		(start 36.886642 -63.97498)
		(end 36.13912 -63.227458)
		(width 0.08382)
		(layer "In9.Cu")
		(net "IRQ_OC_DETECT_N")
	)
	(segment
		(start 30.422342 -78.6003)
		(end 32.398716 -76.623926)
		(width 0.08382)
		(layer "In9.Cu")
		(net "IRQ_OC_DETECT_N")
	)
	(segment
		(start 18.30705 -87.99195)
		(end 17.8562 -88.4428)
		(width 0.08382)
		(layer "In9.Cu")
		(net "IRQ_OC_DETECT_N")
	)
	(segment
		(start 37.44595 -67.7418)
		(end 37.44595 -66.215768)
		(width 0.08382)
		(layer "In9.Cu")
		(net "IRQ_OC_DETECT_N")
	)
	(segment
		(start 36.474908 -68.712842)
		(end 37.44595 -67.7418)
		(width 0.08382)
		(layer "In9.Cu")
		(net "IRQ_OC_DETECT_N")
	)
	(segment
		(start 18.0848 -89.9668)
		(end 18.4912 -89.9668)
		(width 0.08382)
		(layer "In9.Cu")
		(net "IRQ_OC_DETECT_N")
	)
	(segment
		(start 43.97629 -55.60949)
		(end 44.1198 -55.753)
		(width 0.08382)
		(layer "In9.Cu")
		(net "IRQ_OC_DETECT_N")
	)
	(segment
		(start 30.422342 -78.858872)
		(end 30.422342 -78.6003)
		(width 0.08382)
		(layer "In9.Cu")
		(net "IRQ_OC_DETECT_N")
	)
	(segment
		(start 39.080948 -62.090808)
		(end 39.752778 -62.090808)
		(width 0.08382)
		(layer "In9.Cu")
		(net "IRQ_OC_DETECT_N")
	)
	(segment
		(start 18.669 -90.1446)
		(end 18.669 -91.4146)
		(width 0.08382)
		(layer "In9.Cu")
		(net "IRQ_OC_DETECT_N")
	)
	(segment
		(start 43.165776 -56.047386)
		(end 43.603672 -55.60949)
		(width 0.08382)
		(layer "In9.Cu")
		(net "IRQ_OC_DETECT_N")
	)
	(segment
		(start 42.690542 -58.173874)
		(end 42.690542 -57.195466)
		(width 0.08382)
		(layer "In9.Cu")
		(net "IRQ_OC_DETECT_N")
	)
	(via
		(at 47.890684 -82.894424)
		(size 0.762)
		(drill 0.254)
		(layers "F.Cu" "B.Cu")
		(net "SMB_BMC_ALERT9_N")
	)
	(via
		(at 49.420018 -64.843152)
		(size 0.508)
		(drill 0.254)
		(layers "F.Cu" "B.Cu")
		(net "SMB_BMC_ALERT9_N")
	)
	(via
		(at 11.303 -87.376)
		(size 0.508)
		(drill 0.254)
		(layers "F.Cu" "B.Cu")
		(net "SMB_BMC_ALERT9_N")
	)
	(segment
		(start 48.13554 -66.06286)
		(end 48.13554 -66.534792)
		(width 0.11684)
		(layer "B.Cu")
		(net "SMB_BMC_ALERT9_N")
	)
	(segment
		(start 49.65446 -65.077594)
		(end 49.65446 -65.62598)
		(width 0.11684)
		(layer "B.Cu")
		(net "SMB_BMC_ALERT9_N")
	)
	(segment
		(start 48.34636 -65.85204)
		(end 48.13554 -66.06286)
		(width 0.11684)
		(layer "B.Cu")
		(net "SMB_BMC_ALERT9_N")
	)
	(segment
		(start 49.4284 -65.85204)
		(end 48.34636 -65.85204)
		(width 0.11684)
		(layer "B.Cu")
		(net "SMB_BMC_ALERT9_N")
	)
	(segment
		(start 48.32731 -66.99758)
		(end 48.32731 -67.818)
		(width 0.11684)
		(layer "B.Cu")
		(net "SMB_BMC_ALERT9_N")
	)
	(segment
		(start 49.65446 -65.62598)
		(end 49.4284 -65.85204)
		(width 0.11684)
		(layer "B.Cu")
		(net "SMB_BMC_ALERT9_N")
	)
	(segment
		(start 48.895254 -64.728852)
		(end 48.895254 -64.346328)
		(width 0.11684)
		(layer "B.Cu")
		(net "SMB_BMC_ALERT9_N")
	)
	(segment
		(start 49.420018 -64.843152)
		(end 49.009554 -64.843152)
		(width 0.11684)
		(layer "B.Cu")
		(net "SMB_BMC_ALERT9_N")
	)
	(segment
		(start 49.009554 -64.843152)
		(end 48.895254 -64.728852)
		(width 0.11684)
		(layer "B.Cu")
		(net "SMB_BMC_ALERT9_N")
	)
	(segment
		(start 48.13554 -66.534792)
		(end 48.32731 -66.99758)
		(width 0.11684)
		(layer "B.Cu")
		(net "SMB_BMC_ALERT9_N")
	)
	(segment
		(start 11.91895 -87.376)
		(end 11.303 -87.376)
		(width 0.11684)
		(layer "B.Cu")
		(net "SMB_BMC_ALERT9_N")
	)
	(segment
		(start 49.420018 -64.843152)
		(end 49.65446 -65.077594)
		(width 0.11684)
		(layer "B.Cu")
		(net "SMB_BMC_ALERT9_N")
	)
	(segment
		(start 31.35376 -84.6074)
		(end 31.12262 -84.83854)
		(width 0.08382)
		(layer "In2.Cu")
		(net "SMB_BMC_ALERT9_N")
	)
	(segment
		(start 26.505154 -86.3854)
		(end 25.52827 -85.408516)
		(width 0.08382)
		(layer "In2.Cu")
		(net "SMB_BMC_ALERT9_N")
	)
	(segment
		(start 22.530054 -85.09)
		(end 21.666454 -84.2264)
		(width 0.08382)
		(layer "In2.Cu")
		(net "SMB_BMC_ALERT9_N")
	)
	(segment
		(start 34.3662 -83.4898)
		(end 33.2486 -84.6074)
		(width 0.08382)
		(layer "In2.Cu")
		(net "SMB_BMC_ALERT9_N")
	)
	(segment
		(start 29.856176 -86.31174)
		(end 29.782516 -86.3854)
		(width 0.08382)
		(layer "In2.Cu")
		(net "SMB_BMC_ALERT9_N")
	)
	(segment
		(start 33.2486 -84.6074)
		(end 31.35376 -84.6074)
		(width 0.08382)
		(layer "In2.Cu")
		(net "SMB_BMC_ALERT9_N")
	)
	(segment
		(start 19.921982 -84.72678)
		(end 19.18462 -84.72678)
		(width 0.08382)
		(layer "In2.Cu")
		(net "SMB_BMC_ALERT9_N")
	)
	(segment
		(start 21.666454 -84.2264)
		(end 20.422362 -84.2264)
		(width 0.08382)
		(layer "In2.Cu")
		(net "SMB_BMC_ALERT9_N")
	)
	(segment
		(start 46.088046 -82.345784)
		(end 45.49648 -82.93735)
		(width 0.08382)
		(layer "In2.Cu")
		(net "SMB_BMC_ALERT9_N")
	)
	(segment
		(start 17.69872 -85.43036)
		(end 17.30248 -85.8266)
		(width 0.08382)
		(layer "In2.Cu")
		(net "SMB_BMC_ALERT9_N")
	)
	(segment
		(start 17.30248 -85.8266)
		(end 13.716 -85.8266)
		(width 0.08382)
		(layer "In2.Cu")
		(net "SMB_BMC_ALERT9_N")
	)
	(segment
		(start 25.08504 -84.8614)
		(end 24.882094 -84.777326)
		(width 0.08382)
		(layer "In2.Cu")
		(net "SMB_BMC_ALERT9_N")
	)
	(segment
		(start 25.52827 -85.30463)
		(end 25.08504 -84.8614)
		(width 0.08382)
		(layer "In2.Cu")
		(net "SMB_BMC_ALERT9_N")
	)
	(segment
		(start 31.12262 -85.66658)
		(end 30.47746 -86.31174)
		(width 0.08382)
		(layer "In2.Cu")
		(net "SMB_BMC_ALERT9_N")
	)
	(segment
		(start 25.52827 -85.408516)
		(end 25.52827 -85.30463)
		(width 0.08382)
		(layer "In2.Cu")
		(net "SMB_BMC_ALERT9_N")
	)
	(segment
		(start 19.18462 -84.72678)
		(end 18.48104 -85.43036)
		(width 0.08382)
		(layer "In2.Cu")
		(net "SMB_BMC_ALERT9_N")
	)
	(segment
		(start 47.890684 -82.894424)
		(end 47.342044 -82.345784)
		(width 0.08382)
		(layer "In2.Cu")
		(net "SMB_BMC_ALERT9_N")
	)
	(segment
		(start 31.12262 -84.83854)
		(end 31.12262 -85.66658)
		(width 0.08382)
		(layer "In2.Cu")
		(net "SMB_BMC_ALERT9_N")
	)
	(segment
		(start 24.2824 -85.09)
		(end 22.530054 -85.09)
		(width 0.08382)
		(layer "In2.Cu")
		(net "SMB_BMC_ALERT9_N")
	)
	(segment
		(start 12.1666 -87.376)
		(end 11.303 -87.376)
		(width 0.08382)
		(layer "In2.Cu")
		(net "SMB_BMC_ALERT9_N")
	)
	(segment
		(start 45.49648 -82.93735)
		(end 43.208194 -82.93735)
		(width 0.08382)
		(layer "In2.Cu")
		(net "SMB_BMC_ALERT9_N")
	)
	(segment
		(start 42.655744 -83.4898)
		(end 34.3662 -83.4898)
		(width 0.08382)
		(layer "In2.Cu")
		(net "SMB_BMC_ALERT9_N")
	)
	(segment
		(start 30.47746 -86.31174)
		(end 29.856176 -86.31174)
		(width 0.08382)
		(layer "In2.Cu")
		(net "SMB_BMC_ALERT9_N")
	)
	(segment
		(start 24.882094 -84.777326)
		(end 24.595074 -84.777326)
		(width 0.08382)
		(layer "In2.Cu")
		(net "SMB_BMC_ALERT9_N")
	)
	(segment
		(start 24.595074 -84.777326)
		(end 24.2824 -85.09)
		(width 0.08382)
		(layer "In2.Cu")
		(net "SMB_BMC_ALERT9_N")
	)
	(segment
		(start 13.716 -85.8266)
		(end 12.1666 -87.376)
		(width 0.08382)
		(layer "In2.Cu")
		(net "SMB_BMC_ALERT9_N")
	)
	(segment
		(start 43.208194 -82.93735)
		(end 42.655744 -83.4898)
		(width 0.08382)
		(layer "In2.Cu")
		(net "SMB_BMC_ALERT9_N")
	)
	(segment
		(start 47.342044 -82.345784)
		(end 46.088046 -82.345784)
		(width 0.08382)
		(layer "In2.Cu")
		(net "SMB_BMC_ALERT9_N")
	)
	(segment
		(start 29.782516 -86.3854)
		(end 26.505154 -86.3854)
		(width 0.08382)
		(layer "In2.Cu")
		(net "SMB_BMC_ALERT9_N")
	)
	(segment
		(start 20.422362 -84.2264)
		(end 19.921982 -84.72678)
		(width 0.08382)
		(layer "In2.Cu")
		(net "SMB_BMC_ALERT9_N")
	)
	(segment
		(start 18.48104 -85.43036)
		(end 17.69872 -85.43036)
		(width 0.08382)
		(layer "In2.Cu")
		(net "SMB_BMC_ALERT9_N")
	)
	(segment
		(start 49.9364 -67.83832)
		(end 49.9364 -65.359534)
		(width 0.10668)
		(layer "In4.Cu")
		(net "SMB_BMC_ALERT9_N")
	)
	(segment
		(start 50.87874 -68.942458)
		(end 50.76444 -68.66636)
		(width 0.10668)
		(layer "In4.Cu")
		(net "SMB_BMC_ALERT9_N")
	)
	(segment
		(start 50.76444 -68.66636)
		(end 49.9364 -67.83832)
		(width 0.10668)
		(layer "In4.Cu")
		(net "SMB_BMC_ALERT9_N")
	)
	(segment
		(start 48.0822 -82.268568)
		(end 48.0822 -77.61224)
		(width 0.10668)
		(layer "In4.Cu")
		(net "SMB_BMC_ALERT9_N")
	)
	(segment
		(start 48.0822 -77.61224)
		(end 49.11852 -76.57592)
		(width 0.10668)
		(layer "In4.Cu")
		(net "SMB_BMC_ALERT9_N")
	)
	(segment
		(start 50.87874 -72.531732)
		(end 50.87874 -68.942458)
		(width 0.10668)
		(layer "In4.Cu")
		(net "SMB_BMC_ALERT9_N")
	)
	(segment
		(start 47.93488 -74.647298)
		(end 47.93488 -73.748138)
		(width 0.10668)
		(layer "In4.Cu")
		(net "SMB_BMC_ALERT9_N")
	)
	(segment
		(start 49.11852 -76.57592)
		(end 49.11852 -75.830938)
		(width 0.10668)
		(layer "In4.Cu")
		(net "SMB_BMC_ALERT9_N")
	)
	(segment
		(start 49.11852 -75.830938)
		(end 47.93488 -74.647298)
		(width 0.10668)
		(layer "In4.Cu")
		(net "SMB_BMC_ALERT9_N")
	)
	(segment
		(start 49.9364 -65.359534)
		(end 49.420018 -64.843152)
		(width 0.10668)
		(layer "In4.Cu")
		(net "SMB_BMC_ALERT9_N")
	)
	(segment
		(start 47.890684 -82.894424)
		(end 47.890684 -82.460084)
		(width 0.10668)
		(layer "In4.Cu")
		(net "SMB_BMC_ALERT9_N")
	)
	(segment
		(start 50.319432 -73.09104)
		(end 50.87874 -72.531732)
		(width 0.10668)
		(layer "In4.Cu")
		(net "SMB_BMC_ALERT9_N")
	)
	(segment
		(start 47.93488 -73.748138)
		(end 48.591978 -73.09104)
		(width 0.10668)
		(layer "In4.Cu")
		(net "SMB_BMC_ALERT9_N")
	)
	(segment
		(start 48.591978 -73.09104)
		(end 50.319432 -73.09104)
		(width 0.10668)
		(layer "In4.Cu")
		(net "SMB_BMC_ALERT9_N")
	)
	(segment
		(start 47.890684 -82.460084)
		(end 48.0822 -82.268568)
		(width 0.10668)
		(layer "In4.Cu")
		(net "SMB_BMC_ALERT9_N")
	)
	(segment
		(start 52.094892 -56.971184)
		(end 51.699668 -57.366408)
		(width 0.11684)
		(layer "F.Cu")
		(net "SMB_BMC_ALERT16_N")
	)
	(segment
		(start 16.002 -103.7336)
		(end 16.0528 -103.7844)
		(width 0.11684)
		(layer "F.Cu")
		(net "SMB_BMC_ALERT16_N")
	)
	(segment
		(start 16.002 -103.14305)
		(end 16.002 -103.7336)
		(width 0.11684)
		(layer "F.Cu")
		(net "SMB_BMC_ALERT16_N")
	)
	(via
		(at 72.009 -22.733)
		(size 0.508)
		(drill 0.254)
		(layers "F.Cu" "B.Cu")
		(net "SMB_BMC_ALERT16_N")
	)
	(via
		(at 76.3778 -86.6902)
		(size 0.508)
		(drill 0.254)
		(layers "F.Cu" "B.Cu")
		(net "SMB_BMC_ALERT16_N")
	)
	(via
		(at 26.5684 -12.827254)
		(size 0.508)
		(drill 0.254)
		(layers "F.Cu" "B.Cu")
		(net "SMB_BMC_ALERT16_N")
	)
	(via
		(at 31.1404 -100.2284)
		(size 0.508)
		(drill 0.254)
		(layers "F.Cu" "B.Cu")
		(net "SMB_BMC_ALERT16_N")
	)
	(via
		(at 37.465 -73.50887)
		(size 0.508)
		(drill 0.254)
		(layers "F.Cu" "B.Cu")
		(net "SMB_BMC_ALERT16_N")
	)
	(via
		(at 16.0528 -103.7844)
		(size 0.508)
		(drill 0.254)
		(layers "F.Cu" "B.Cu")
		(net "SMB_BMC_ALERT16_N")
	)
	(via
		(at 51.699668 -57.366408)
		(size 0.4572)
		(drill 0.254)
		(layers "F.Cu" "B.Cu")
		(net "SMB_BMC_ALERT16_N")
	)
	(via
		(at 21.463 -16.891)
		(size 0.508)
		(drill 0.254)
		(layers "F.Cu" "B.Cu")
		(net "SMB_BMC_ALERT16_N")
	)
	(segment
		(start 51.699668 -57.366408)
		(end 51.293014 -57.773062)
		(width 0.11684)
		(layer "B.Cu")
		(net "SMB_BMC_ALERT16_N")
	)
	(segment
		(start 50.505106 -58.410348)
		(end 50.352452 -58.563002)
		(width 0.11684)
		(layer "B.Cu")
		(net "SMB_BMC_ALERT16_N")
	)
	(segment
		(start 48.21428 -60.322968)
		(end 48.436022 -60.8584)
		(width 0.11684)
		(layer "B.Cu")
		(net "SMB_BMC_ALERT16_N")
	)
	(segment
		(start 49.711102 -59.161934)
		(end 49.488852 -59.384184)
		(width 0.11684)
		(layer "B.Cu")
		(net "SMB_BMC_ALERT16_N")
	)
	(segment
		(start 51.293014 -57.773062)
		(end 50.619406 -57.773062)
		(width 0.11684)
		(layer "B.Cu")
		(net "SMB_BMC_ALERT16_N")
	)
	(segment
		(start 49.919636 -58.563002)
		(end 49.711102 -58.771536)
		(width 0.11684)
		(layer "B.Cu")
		(net "SMB_BMC_ALERT16_N")
	)
	(segment
		(start 50.352452 -58.563002)
		(end 49.919636 -58.563002)
		(width 0.11684)
		(layer "B.Cu")
		(net "SMB_BMC_ALERT16_N")
	)
	(segment
		(start 48.436022 -60.8584)
		(end 48.436022 -61.716412)
		(width 0.11684)
		(layer "B.Cu")
		(net "SMB_BMC_ALERT16_N")
	)
	(segment
		(start 21.463 -17.79905)
		(end 20.955 -18.30705)
		(width 0.11684)
		(layer "B.Cu")
		(net "SMB_BMC_ALERT16_N")
	)
	(segment
		(start 50.505106 -57.887362)
		(end 50.505106 -58.410348)
		(width 0.11684)
		(layer "B.Cu")
		(net "SMB_BMC_ALERT16_N")
	)
	(segment
		(start 50.619406 -57.773062)
		(end 50.505106 -57.887362)
		(width 0.11684)
		(layer "B.Cu")
		(net "SMB_BMC_ALERT16_N")
	)
	(segment
		(start 49.711102 -58.771536)
		(end 49.711102 -59.161934)
		(width 0.11684)
		(layer "B.Cu")
		(net "SMB_BMC_ALERT16_N")
	)
	(segment
		(start 21.463 -16.891)
		(end 21.463 -17.79905)
		(width 0.11684)
		(layer "B.Cu")
		(net "SMB_BMC_ALERT16_N")
	)
	(segment
		(start 49.488852 -59.384184)
		(end 48.642016 -59.384184)
		(width 0.11684)
		(layer "B.Cu")
		(net "SMB_BMC_ALERT16_N")
	)
	(segment
		(start 48.21428 -59.81192)
		(end 48.21428 -60.322968)
		(width 0.11684)
		(layer "B.Cu")
		(net "SMB_BMC_ALERT16_N")
	)
	(segment
		(start 48.642016 -59.384184)
		(end 48.21428 -59.81192)
		(width 0.11684)
		(layer "B.Cu")
		(net "SMB_BMC_ALERT16_N")
	)
	(segment
		(start 21.199856 -101.976174)
		(end 21.27631 -101.89972)
		(width 0.08382)
		(layer "In2.Cu")
		(net "SMB_BMC_ALERT16_N")
	)
	(segment
		(start 64.70904 -78.2066)
		(end 62.28588 -78.2066)
		(width 0.08382)
		(layer "In2.Cu")
		(net "SMB_BMC_ALERT16_N")
	)
	(segment
		(start 41.5544 -75.184)
		(end 38.735762 -75.184)
		(width 0.08382)
		(layer "In2.Cu")
		(net "SMB_BMC_ALERT16_N")
	)
	(segment
		(start 28.473654 -101.346)
		(end 29.464254 -100.3554)
		(width 0.08382)
		(layer "In2.Cu")
		(net "SMB_BMC_ALERT16_N")
	)
	(segment
		(start 76.3778 -86.6902)
		(end 74.8792 -85.1916)
		(width 0.08382)
		(layer "In2.Cu")
		(net "SMB_BMC_ALERT16_N")
	)
	(segment
		(start 50.874168 -76.49718)
		(end 49.8856 -76.49718)
		(width 0.08382)
		(layer "In2.Cu")
		(net "SMB_BMC_ALERT16_N")
	)
	(segment
		(start 62.11697 -78.37551)
		(end 60.736734 -78.37551)
		(width 0.08382)
		(layer "In2.Cu")
		(net "SMB_BMC_ALERT16_N")
	)
	(segment
		(start 16.002 -103.7336)
		(end 16.002 -103.46944)
		(width 0.08382)
		(layer "In2.Cu")
		(net "SMB_BMC_ALERT16_N")
	)
	(segment
		(start 47.634906 -74.246486)
		(end 42.491914 -74.246486)
		(width 0.08382)
		(layer "In2.Cu")
		(net "SMB_BMC_ALERT16_N")
	)
	(segment
		(start 17.42694 -102.8446)
		(end 18.295366 -101.976174)
		(width 0.08382)
		(layer "In2.Cu")
		(net "SMB_BMC_ALERT16_N")
	)
	(segment
		(start 31.0134 -100.3554)
		(end 31.1404 -100.2284)
		(width 0.08382)
		(layer "In2.Cu")
		(net "SMB_BMC_ALERT16_N")
	)
	(segment
		(start 42.491914 -74.246486)
		(end 41.5544 -75.184)
		(width 0.08382)
		(layer "In2.Cu")
		(net "SMB_BMC_ALERT16_N")
	)
	(segment
		(start 57.155842 -78.395322)
		(end 54.89448 -76.13396)
		(width 0.08382)
		(layer "In2.Cu")
		(net "SMB_BMC_ALERT16_N")
	)
	(segment
		(start 37.465 -73.913238)
		(end 37.465 -73.50887)
		(width 0.08382)
		(layer "In2.Cu")
		(net "SMB_BMC_ALERT16_N")
	)
	(segment
		(start 18.295366 -101.976174)
		(end 21.199856 -101.976174)
		(width 0.08382)
		(layer "In2.Cu")
		(net "SMB_BMC_ALERT16_N")
	)
	(segment
		(start 74.8792 -79.9338)
		(end 74.33818 -79.39278)
		(width 0.08382)
		(layer "In2.Cu")
		(net "SMB_BMC_ALERT16_N")
	)
	(segment
		(start 16.0528 -103.7844)
		(end 16.002 -103.7336)
		(width 0.08382)
		(layer "In2.Cu")
		(net "SMB_BMC_ALERT16_N")
	)
	(segment
		(start 60.497212 -78.135988)
		(end 59.740292 -78.135988)
		(width 0.08382)
		(layer "In2.Cu")
		(net "SMB_BMC_ALERT16_N")
	)
	(segment
		(start 65.32626 -77.58938)
		(end 64.70904 -78.2066)
		(width 0.08382)
		(layer "In2.Cu")
		(net "SMB_BMC_ALERT16_N")
	)
	(segment
		(start 71.50862 -77.58938)
		(end 65.32626 -77.58938)
		(width 0.08382)
		(layer "In2.Cu")
		(net "SMB_BMC_ALERT16_N")
	)
	(segment
		(start 54.89448 -76.13396)
		(end 53.965094 -76.13396)
		(width 0.08382)
		(layer "In2.Cu")
		(net "SMB_BMC_ALERT16_N")
	)
	(segment
		(start 62.28588 -78.2066)
		(end 62.11697 -78.37551)
		(width 0.08382)
		(layer "In2.Cu")
		(net "SMB_BMC_ALERT16_N")
	)
	(segment
		(start 59.740292 -78.135988)
		(end 59.480958 -78.395322)
		(width 0.08382)
		(layer "In2.Cu")
		(net "SMB_BMC_ALERT16_N")
	)
	(segment
		(start 51.637438 -77.26045)
		(end 50.874168 -76.49718)
		(width 0.08382)
		(layer "In2.Cu")
		(net "SMB_BMC_ALERT16_N")
	)
	(segment
		(start 29.464254 -100.3554)
		(end 31.0134 -100.3554)
		(width 0.08382)
		(layer "In2.Cu")
		(net "SMB_BMC_ALERT16_N")
	)
	(segment
		(start 59.480958 -78.395322)
		(end 57.155842 -78.395322)
		(width 0.08382)
		(layer "In2.Cu")
		(net "SMB_BMC_ALERT16_N")
	)
	(segment
		(start 74.8792 -85.1916)
		(end 74.8792 -79.9338)
		(width 0.08382)
		(layer "In2.Cu")
		(net "SMB_BMC_ALERT16_N")
	)
	(segment
		(start 53.965094 -76.13396)
		(end 52.838604 -77.26045)
		(width 0.08382)
		(layer "In2.Cu")
		(net "SMB_BMC_ALERT16_N")
	)
	(segment
		(start 23.9014 -101.346)
		(end 28.473654 -101.346)
		(width 0.08382)
		(layer "In2.Cu")
		(net "SMB_BMC_ALERT16_N")
	)
	(segment
		(start 60.736734 -78.37551)
		(end 60.497212 -78.135988)
		(width 0.08382)
		(layer "In2.Cu")
		(net "SMB_BMC_ALERT16_N")
	)
	(segment
		(start 52.838604 -77.26045)
		(end 51.637438 -77.26045)
		(width 0.08382)
		(layer "In2.Cu")
		(net "SMB_BMC_ALERT16_N")
	)
	(segment
		(start 73.31202 -79.39278)
		(end 71.50862 -77.58938)
		(width 0.08382)
		(layer "In2.Cu")
		(net "SMB_BMC_ALERT16_N")
	)
	(segment
		(start 74.33818 -79.39278)
		(end 73.31202 -79.39278)
		(width 0.08382)
		(layer "In2.Cu")
		(net "SMB_BMC_ALERT16_N")
	)
	(segment
		(start 23.34768 -101.89972)
		(end 23.9014 -101.346)
		(width 0.08382)
		(layer "In2.Cu")
		(net "SMB_BMC_ALERT16_N")
	)
	(segment
		(start 16.62684 -102.8446)
		(end 17.42694 -102.8446)
		(width 0.08382)
		(layer "In2.Cu")
		(net "SMB_BMC_ALERT16_N")
	)
	(segment
		(start 21.27631 -101.89972)
		(end 23.34768 -101.89972)
		(width 0.08382)
		(layer "In2.Cu")
		(net "SMB_BMC_ALERT16_N")
	)
	(segment
		(start 49.8856 -76.49718)
		(end 47.634906 -74.246486)
		(width 0.08382)
		(layer "In2.Cu")
		(net "SMB_BMC_ALERT16_N")
	)
	(segment
		(start 16.002 -103.46944)
		(end 16.62684 -102.8446)
		(width 0.08382)
		(layer "In2.Cu")
		(net "SMB_BMC_ALERT16_N")
	)
	(segment
		(start 38.735762 -75.184)
		(end 37.465 -73.913238)
		(width 0.08382)
		(layer "In2.Cu")
		(net "SMB_BMC_ALERT16_N")
	)
	(segment
		(start 33.10636 -99.65944)
		(end 32.2326 -100.5332)
		(width 0.10668)
		(layer "In4.Cu")
		(net "SMB_BMC_ALERT16_N")
	)
	(segment
		(start 32.2326 -100.5332)
		(end 31.4452 -100.5332)
		(width 0.10668)
		(layer "In4.Cu")
		(net "SMB_BMC_ALERT16_N")
	)
	(segment
		(start 80.8228 -25.811734)
		(end 80.8228 -24.680418)
		(width 0.10668)
		(layer "In4.Cu")
		(net "SMB_BMC_ALERT16_N")
	)
	(segment
		(start 79.566262 -22.96668)
		(end 74.177906 -22.96668)
		(width 0.10668)
		(layer "In4.Cu")
		(net "SMB_BMC_ALERT16_N")
	)
	(segment
		(start 32.88538 -84.436966)
		(end 32.88538 -89.671144)
		(width 0.10668)
		(layer "In4.Cu")
		(net "SMB_BMC_ALERT16_N")
	)
	(segment
		(start 80.15732 -23.557738)
		(end 79.566262 -22.96668)
		(width 0.10668)
		(layer "In4.Cu")
		(net "SMB_BMC_ALERT16_N")
	)
	(segment
		(start 87.747602 -30.165802)
		(end 86.8934 -29.3116)
		(width 0.10668)
		(layer "In4.Cu")
		(net "SMB_BMC_ALERT16_N")
	)
	(segment
		(start 35.606228 -73.803002)
		(end 34.564828 -73.803002)
		(width 0.10668)
		(layer "In4.Cu")
		(net "SMB_BMC_ALERT16_N")
	)
	(segment
		(start 37.465 -73.50887)
		(end 35.900614 -73.50887)
		(width 0.10668)
		(layer "In4.Cu")
		(net "SMB_BMC_ALERT16_N")
	)
	(segment
		(start 34.564828 -73.803002)
		(end 33.9979 -74.36993)
		(width 0.10668)
		(layer "In4.Cu")
		(net "SMB_BMC_ALERT16_N")
	)
	(segment
		(start 32.92348 -89.709244)
		(end 32.92348 -89.836244)
		(width 0.10668)
		(layer "In4.Cu")
		(net "SMB_BMC_ALERT16_N")
	)
	(segment
		(start 35.317938 -80.75168)
		(end 34.68116 -80.75168)
		(width 0.10668)
		(layer "In4.Cu")
		(net "SMB_BMC_ALERT16_N")
	)
	(segment
		(start 85.114384 -80.564736)
		(end 87.747602 -77.931518)
		(width 0.10668)
		(layer "In4.Cu")
		(net "SMB_BMC_ALERT16_N")
	)
	(segment
		(start 31.4452 -100.5332)
		(end 31.1404 -100.2284)
		(width 0.10668)
		(layer "In4.Cu")
		(net "SMB_BMC_ALERT16_N")
	)
	(segment
		(start 36.369244 -78.089506)
		(end 36.83508 -78.555342)
		(width 0.10668)
		(layer "In4.Cu")
		(net "SMB_BMC_ALERT16_N")
	)
	(segment
		(start 76.3778 -86.6902)
		(end 76.3778 -97.1296)
		(width 0.10668)
		(layer "In4.Cu")
		(net "SMB_BMC_ALERT16_N")
	)
	(segment
		(start 32.88538 -89.671144)
		(end 32.92348 -89.709244)
		(width 0.10668)
		(layer "In4.Cu")
		(net "SMB_BMC_ALERT16_N")
	)
	(segment
		(start 33.10636 -97.097088)
		(end 33.10636 -99.65944)
		(width 0.10668)
		(layer "In4.Cu")
		(net "SMB_BMC_ALERT16_N")
	)
	(segment
		(start 87.747602 -77.931518)
		(end 87.747602 -30.165802)
		(width 0.10668)
		(layer "In4.Cu")
		(net "SMB_BMC_ALERT16_N")
	)
	(segment
		(start 76.3778 -97.1296)
		(end 77.216 -97.9678)
		(width 0.10668)
		(layer "In4.Cu")
		(net "SMB_BMC_ALERT16_N")
	)
	(segment
		(start 80.5688 -97.9678)
		(end 82.4738 -99.8728)
		(width 0.10668)
		(layer "In4.Cu")
		(net "SMB_BMC_ALERT16_N")
	)
	(segment
		(start 73.944226 -22.733)
		(end 72.009 -22.733)
		(width 0.10668)
		(layer "In4.Cu")
		(net "SMB_BMC_ALERT16_N")
	)
	(segment
		(start 33.9979 -76.153772)
		(end 35.933634 -78.089506)
		(width 0.10668)
		(layer "In4.Cu")
		(net "SMB_BMC_ALERT16_N")
	)
	(segment
		(start 86.8934 -29.3116)
		(end 84.322666 -29.3116)
		(width 0.10668)
		(layer "In4.Cu")
		(net "SMB_BMC_ALERT16_N")
	)
	(segment
		(start 33.32226 -94.113604)
		(end 32.26308 -95.172784)
		(width 0.10668)
		(layer "In4.Cu")
		(net "SMB_BMC_ALERT16_N")
	)
	(segment
		(start 33.32226 -90.235024)
		(end 33.32226 -94.113604)
		(width 0.10668)
		(layer "In4.Cu")
		(net "SMB_BMC_ALERT16_N")
	)
	(segment
		(start 74.177906 -22.96668)
		(end 73.944226 -22.733)
		(width 0.10668)
		(layer "In4.Cu")
		(net "SMB_BMC_ALERT16_N")
	)
	(segment
		(start 86.8934 -98.806)
		(end 88.0618 -97.6376)
		(width 0.10668)
		(layer "In4.Cu")
		(net "SMB_BMC_ALERT16_N")
	)
	(segment
		(start 80.15732 -24.014938)
		(end 80.15732 -23.557738)
		(width 0.10668)
		(layer "In4.Cu")
		(net "SMB_BMC_ALERT16_N")
	)
	(segment
		(start 77.216 -97.9678)
		(end 80.5688 -97.9678)
		(width 0.10668)
		(layer "In4.Cu")
		(net "SMB_BMC_ALERT16_N")
	)
	(segment
		(start 34.68116 -80.75168)
		(end 34.1376 -81.29524)
		(width 0.10668)
		(layer "In4.Cu")
		(net "SMB_BMC_ALERT16_N")
	)
	(segment
		(start 84.1756 -98.806)
		(end 86.8934 -98.806)
		(width 0.10668)
		(layer "In4.Cu")
		(net "SMB_BMC_ALERT16_N")
	)
	(segment
		(start 34.1376 -83.184746)
		(end 32.88538 -84.436966)
		(width 0.10668)
		(layer "In4.Cu")
		(net "SMB_BMC_ALERT16_N")
	)
	(segment
		(start 33.9979 -74.36993)
		(end 33.9979 -76.153772)
		(width 0.10668)
		(layer "In4.Cu")
		(net "SMB_BMC_ALERT16_N")
	)
	(segment
		(start 34.1376 -81.29524)
		(end 34.1376 -83.184746)
		(width 0.10668)
		(layer "In4.Cu")
		(net "SMB_BMC_ALERT16_N")
	)
	(segment
		(start 88.0618 -97.6376)
		(end 88.0618 -89.4842)
		(width 0.10668)
		(layer "In4.Cu")
		(net "SMB_BMC_ALERT16_N")
	)
	(segment
		(start 84.322666 -29.3116)
		(end 80.8228 -25.811734)
		(width 0.10668)
		(layer "In4.Cu")
		(net "SMB_BMC_ALERT16_N")
	)
	(segment
		(start 83.1088 -99.8728)
		(end 84.1756 -98.806)
		(width 0.10668)
		(layer "In4.Cu")
		(net "SMB_BMC_ALERT16_N")
	)
	(segment
		(start 88.0618 -89.4842)
		(end 85.114384 -86.536784)
		(width 0.10668)
		(layer "In4.Cu")
		(net "SMB_BMC_ALERT16_N")
	)
	(segment
		(start 80.8228 -24.680418)
		(end 80.15732 -24.014938)
		(width 0.10668)
		(layer "In4.Cu")
		(net "SMB_BMC_ALERT16_N")
	)
	(segment
		(start 35.900614 -73.50887)
		(end 35.606228 -73.803002)
		(width 0.10668)
		(layer "In4.Cu")
		(net "SMB_BMC_ALERT16_N")
	)
	(segment
		(start 36.83508 -78.555342)
		(end 36.83508 -79.234538)
		(width 0.10668)
		(layer "In4.Cu")
		(net "SMB_BMC_ALERT16_N")
	)
	(segment
		(start 35.933634 -78.089506)
		(end 36.369244 -78.089506)
		(width 0.10668)
		(layer "In4.Cu")
		(net "SMB_BMC_ALERT16_N")
	)
	(segment
		(start 82.4738 -99.8728)
		(end 83.1088 -99.8728)
		(width 0.10668)
		(layer "In4.Cu")
		(net "SMB_BMC_ALERT16_N")
	)
	(segment
		(start 36.83508 -79.234538)
		(end 35.317938 -80.75168)
		(width 0.10668)
		(layer "In4.Cu")
		(net "SMB_BMC_ALERT16_N")
	)
	(segment
		(start 85.114384 -86.536784)
		(end 85.114384 -80.564736)
		(width 0.10668)
		(layer "In4.Cu")
		(net "SMB_BMC_ALERT16_N")
	)
	(segment
		(start 32.26308 -96.253808)
		(end 33.10636 -97.097088)
		(width 0.10668)
		(layer "In4.Cu")
		(net "SMB_BMC_ALERT16_N")
	)
	(segment
		(start 32.92348 -89.836244)
		(end 33.32226 -90.235024)
		(width 0.10668)
		(layer "In4.Cu")
		(net "SMB_BMC_ALERT16_N")
	)
	(segment
		(start 32.26308 -95.172784)
		(end 32.26308 -96.253808)
		(width 0.10668)
		(layer "In4.Cu")
		(net "SMB_BMC_ALERT16_N")
	)
	(segment
		(start 56.1594 -16.4846)
		(end 51.3588 -16.4846)
		(width 0.10668)
		(layer "In7.Cu")
		(net "SMB_BMC_ALERT16_N")
	)
	(segment
		(start 37.592 -13.5382)
		(end 35.3568 -13.5382)
		(width 0.10668)
		(layer "In7.Cu")
		(net "SMB_BMC_ALERT16_N")
	)
	(segment
		(start 27.972004 -11.801856)
		(end 26.89606 -12.8778)
		(width 0.10668)
		(layer "In7.Cu")
		(net "SMB_BMC_ALERT16_N")
	)
	(segment
		(start 26.618946 -12.8778)
		(end 26.5684 -12.827254)
		(width 0.10668)
		(layer "In7.Cu")
		(net "SMB_BMC_ALERT16_N")
	)
	(segment
		(start 31.73984 -10.543286)
		(end 30.48127 -11.801856)
		(width 0.10668)
		(layer "In7.Cu")
		(net "SMB_BMC_ALERT16_N")
	)
	(segment
		(start 26.89606 -12.8778)
		(end 26.618946 -12.8778)
		(width 0.10668)
		(layer "In7.Cu")
		(net "SMB_BMC_ALERT16_N")
	)
	(segment
		(start 56.51754 -16.84274)
		(end 56.1594 -16.4846)
		(width 0.10668)
		(layer "In7.Cu")
		(net "SMB_BMC_ALERT16_N")
	)
	(segment
		(start 35.3568 -13.5382)
		(end 33.95853 -12.13993)
		(width 0.10668)
		(layer "In7.Cu")
		(net "SMB_BMC_ALERT16_N")
	)
	(segment
		(start 72.009 -22.733)
		(end 71.1454 -21.8694)
		(width 0.10668)
		(layer "In7.Cu")
		(net "SMB_BMC_ALERT16_N")
	)
	(segment
		(start 51.3588 -16.4846)
		(end 46.99 -12.1158)
		(width 0.10668)
		(layer "In7.Cu")
		(net "SMB_BMC_ALERT16_N")
	)
	(segment
		(start 66.7258 -20.1676)
		(end 63.103506 -20.1676)
		(width 0.10668)
		(layer "In7.Cu")
		(net "SMB_BMC_ALERT16_N")
	)
	(segment
		(start 39.0144 -12.1158)
		(end 37.592 -13.5382)
		(width 0.10668)
		(layer "In7.Cu")
		(net "SMB_BMC_ALERT16_N")
	)
	(segment
		(start 33.95853 -11.563858)
		(end 32.937958 -10.543286)
		(width 0.10668)
		(layer "In7.Cu")
		(net "SMB_BMC_ALERT16_N")
	)
	(segment
		(start 46.99 -12.1158)
		(end 39.0144 -12.1158)
		(width 0.10668)
		(layer "In7.Cu")
		(net "SMB_BMC_ALERT16_N")
	)
	(segment
		(start 59.778646 -16.84274)
		(end 56.51754 -16.84274)
		(width 0.10668)
		(layer "In7.Cu")
		(net "SMB_BMC_ALERT16_N")
	)
	(segment
		(start 30.48127 -11.801856)
		(end 27.972004 -11.801856)
		(width 0.10668)
		(layer "In7.Cu")
		(net "SMB_BMC_ALERT16_N")
	)
	(segment
		(start 32.937958 -10.543286)
		(end 31.73984 -10.543286)
		(width 0.10668)
		(layer "In7.Cu")
		(net "SMB_BMC_ALERT16_N")
	)
	(segment
		(start 68.4276 -21.8694)
		(end 66.7258 -20.1676)
		(width 0.10668)
		(layer "In7.Cu")
		(net "SMB_BMC_ALERT16_N")
	)
	(segment
		(start 63.103506 -20.1676)
		(end 59.778646 -16.84274)
		(width 0.10668)
		(layer "In7.Cu")
		(net "SMB_BMC_ALERT16_N")
	)
	(segment
		(start 71.1454 -21.8694)
		(end 68.4276 -21.8694)
		(width 0.10668)
		(layer "In7.Cu")
		(net "SMB_BMC_ALERT16_N")
	)
	(segment
		(start 33.95853 -12.13993)
		(end 33.95853 -11.563858)
		(width 0.10668)
		(layer "In7.Cu")
		(net "SMB_BMC_ALERT16_N")
	)
	(segment
		(start 38.972998 -73.0504)
		(end 37.92347 -73.0504)
		(width 0.08382)
		(layer "In9.Cu")
		(net "SMB_BMC_ALERT16_N")
	)
	(segment
		(start 43.30065 -65.67805)
		(end 42.747438 -66.231262)
		(width 0.08382)
		(layer "In9.Cu")
		(net "SMB_BMC_ALERT16_N")
	)
	(segment
		(start 49.195482 -57.738518)
		(end 48.895 -58.039)
		(width 0.08382)
		(layer "In9.Cu")
		(net "SMB_BMC_ALERT16_N")
	)
	(segment
		(start 49.671986 -57.262014)
		(end 49.671986 -57.520586)
		(width 0.08382)
		(layer "In9.Cu")
		(net "SMB_BMC_ALERT16_N")
	)
	(segment
		(start 21.463 -16.14551)
		(end 21.463 -16.891)
		(width 0.08382)
		(layer "In9.Cu")
		(net "SMB_BMC_ALERT16_N")
	)
	(segment
		(start 22.875494 -14.733016)
		(end 21.463 -16.14551)
		(width 0.08382)
		(layer "In9.Cu")
		(net "SMB_BMC_ALERT16_N")
	)
	(segment
		(start 48.895 -58.402728)
		(end 47.806864 -59.490864)
		(width 0.08382)
		(layer "In9.Cu")
		(net "SMB_BMC_ALERT16_N")
	)
	(segment
		(start 37.92347 -73.0504)
		(end 37.465 -73.50887)
		(width 0.08382)
		(layer "In9.Cu")
		(net "SMB_BMC_ALERT16_N")
	)
	(segment
		(start 49.671986 -57.520586)
		(end 49.454054 -57.738518)
		(width 0.08382)
		(layer "In9.Cu")
		(net "SMB_BMC_ALERT16_N")
	)
	(segment
		(start 51.30546 -56.9722)
		(end 49.9618 -56.9722)
		(width 0.08382)
		(layer "In9.Cu")
		(net "SMB_BMC_ALERT16_N")
	)
	(segment
		(start 43.30065 -62.866778)
		(end 43.30065 -65.67805)
		(width 0.08382)
		(layer "In9.Cu")
		(net "SMB_BMC_ALERT16_N")
	)
	(segment
		(start 26.5684 -12.827254)
		(end 26.5684 -12.8778)
		(width 0.08382)
		(layer "In9.Cu")
		(net "SMB_BMC_ALERT16_N")
	)
	(segment
		(start 45.615606 -62.283594)
		(end 43.883834 -62.283594)
		(width 0.08382)
		(layer "In9.Cu")
		(net "SMB_BMC_ALERT16_N")
	)
	(segment
		(start 49.454054 -57.738518)
		(end 49.195482 -57.738518)
		(width 0.08382)
		(layer "In9.Cu")
		(net "SMB_BMC_ALERT16_N")
	)
	(segment
		(start 24.713184 -14.733016)
		(end 22.875494 -14.733016)
		(width 0.08382)
		(layer "In9.Cu")
		(net "SMB_BMC_ALERT16_N")
	)
	(segment
		(start 51.699668 -57.366408)
		(end 51.30546 -56.9722)
		(width 0.08382)
		(layer "In9.Cu")
		(net "SMB_BMC_ALERT16_N")
	)
	(segment
		(start 47.806864 -60.092336)
		(end 45.615606 -62.283594)
		(width 0.08382)
		(layer "In9.Cu")
		(net "SMB_BMC_ALERT16_N")
	)
	(segment
		(start 49.9618 -56.9722)
		(end 49.671986 -57.262014)
		(width 0.08382)
		(layer "In9.Cu")
		(net "SMB_BMC_ALERT16_N")
	)
	(segment
		(start 40.6146 -70.275196)
		(end 40.6146 -71.408798)
		(width 0.08382)
		(layer "In9.Cu")
		(net "SMB_BMC_ALERT16_N")
	)
	(segment
		(start 42.747438 -66.231262)
		(end 42.747438 -68.142358)
		(width 0.08382)
		(layer "In9.Cu")
		(net "SMB_BMC_ALERT16_N")
	)
	(segment
		(start 40.6146 -71.408798)
		(end 38.972998 -73.0504)
		(width 0.08382)
		(layer "In9.Cu")
		(net "SMB_BMC_ALERT16_N")
	)
	(segment
		(start 43.883834 -62.283594)
		(end 43.30065 -62.866778)
		(width 0.08382)
		(layer "In9.Cu")
		(net "SMB_BMC_ALERT16_N")
	)
	(segment
		(start 47.806864 -59.490864)
		(end 47.806864 -60.092336)
		(width 0.08382)
		(layer "In9.Cu")
		(net "SMB_BMC_ALERT16_N")
	)
	(segment
		(start 48.895 -58.039)
		(end 48.895 -58.402728)
		(width 0.08382)
		(layer "In9.Cu")
		(net "SMB_BMC_ALERT16_N")
	)
	(segment
		(start 26.5684 -12.8778)
		(end 24.713184 -14.733016)
		(width 0.08382)
		(layer "In9.Cu")
		(net "SMB_BMC_ALERT16_N")
	)
	(segment
		(start 42.747438 -68.142358)
		(end 40.6146 -70.275196)
		(width 0.08382)
		(layer "In9.Cu")
		(net "SMB_BMC_ALERT16_N")
	)
	(segment
		(start 18.264124 -95.982282)
		(end 18.659348 -95.587058)
		(width 0.11684)
		(layer "F.Cu")
		(net "FM_BMC_EN_DET_R")
	)
	(segment
		(start 52.894992 -55.371238)
		(end 52.499768 -55.766462)
		(width 0.11684)
		(layer "F.Cu")
		(net "FM_BMC_EN_DET_R")
	)
	(via
		(at 48.690022 -60.03798)
		(size 0.508)
		(drill 0.254)
		(layers "F.Cu" "B.Cu")
		(net "FM_BMC_EN_DET_R")
	)
	(via
		(at 52.499768 -55.766462)
		(size 0.4572)
		(drill 0.254)
		(layers "F.Cu" "B.Cu")
		(net "FM_BMC_EN_DET_R")
	)
	(via
		(at 18.264124 -95.982282)
		(size 0.4572)
		(drill 0.254)
		(layers "F.Cu" "B.Cu")
		(net "FM_BMC_EN_DET_R")
	)
	(segment
		(start 49.461166 -61.716412)
		(end 49.461166 -61.425582)
		(width 0.11684)
		(layer "B.Cu")
		(net "FM_BMC_EN_DET_R")
	)
	(segment
		(start 48.9204 -60.293758)
		(end 48.690022 -60.06338)
		(width 0.11684)
		(layer "B.Cu")
		(net "FM_BMC_EN_DET_R")
	)
	(segment
		(start 49.036478 -61.000894)
		(end 48.9204 -60.720732)
		(width 0.11684)
		(layer "B.Cu")
		(net "FM_BMC_EN_DET_R")
	)
	(segment
		(start 48.9204 -60.720732)
		(end 48.9204 -60.293758)
		(width 0.11684)
		(layer "B.Cu")
		(net "FM_BMC_EN_DET_R")
	)
	(segment
		(start 48.690022 -60.06338)
		(end 48.690022 -60.03798)
		(width 0.11684)
		(layer "B.Cu")
		(net "FM_BMC_EN_DET_R")
	)
	(segment
		(start 49.461166 -61.425582)
		(end 49.036478 -61.000894)
		(width 0.11684)
		(layer "B.Cu")
		(net "FM_BMC_EN_DET_R")
	)
	(segment
		(start 34.8996 -78.612492)
		(end 35.788092 -77.724)
		(width 0.08382)
		(layer "In9.Cu")
		(net "FM_BMC_EN_DET_R")
	)
	(segment
		(start 21.5392 -97.2058)
		(end 22.3774 -96.3676)
		(width 0.08382)
		(layer "In9.Cu")
		(net "FM_BMC_EN_DET_R")
	)
	(segment
		(start 35.788092 -77.724)
		(end 38.332664 -77.724)
		(width 0.08382)
		(layer "In9.Cu")
		(net "FM_BMC_EN_DET_R")
	)
	(segment
		(start 30.402784 -97.201228)
		(end 31.059882 -97.201228)
		(width 0.08382)
		(layer "In9.Cu")
		(net "FM_BMC_EN_DET_R")
	)
	(segment
		(start 22.3774 -96.3676)
		(end 26.3144 -96.3676)
		(width 0.08382)
		(layer "In9.Cu")
		(net "FM_BMC_EN_DET_R")
	)
	(segment
		(start 32.93237 -88.526366)
		(end 33.37433 -88.084406)
		(width 0.08382)
		(layer "In9.Cu")
		(net "FM_BMC_EN_DET_R")
	)
	(segment
		(start 44.1198 -67.6656)
		(end 44.72178 -67.06362)
		(width 0.08382)
		(layer "In9.Cu")
		(net "FM_BMC_EN_DET_R")
	)
	(segment
		(start 49.671986 -59.395868)
		(end 49.671986 -58.710068)
		(width 0.08382)
		(layer "In9.Cu")
		(net "FM_BMC_EN_DET_R")
	)
	(segment
		(start 31.768034 -97.90938)
		(end 32.504126 -97.90938)
		(width 0.08382)
		(layer "In9.Cu")
		(net "FM_BMC_EN_DET_R")
	)
	(segment
		(start 32.93237 -90.54846)
		(end 32.93237 -88.526366)
		(width 0.08382)
		(layer "In9.Cu")
		(net "FM_BMC_EN_DET_R")
	)
	(segment
		(start 43.133518 -70.353682)
		(end 43.541188 -69.369432)
		(width 0.08382)
		(layer "In9.Cu")
		(net "FM_BMC_EN_DET_R")
	)
	(segment
		(start 52.647342 -58.547)
		(end 52.873148 -58.321194)
		(width 0.08382)
		(layer "In9.Cu")
		(net "FM_BMC_EN_DET_R")
	)
	(segment
		(start 18.669 -96.387158)
		(end 18.669 -96.9518)
		(width 0.08382)
		(layer "In9.Cu")
		(net "FM_BMC_EN_DET_R")
	)
	(segment
		(start 40.2336 -75.0316)
		(end 40.2336 -73.8886)
		(width 0.08382)
		(layer "In9.Cu")
		(net "FM_BMC_EN_DET_R")
	)
	(segment
		(start 43.541188 -69.369432)
		(end 43.541188 -67.925188)
		(width 0.08382)
		(layer "In9.Cu")
		(net "FM_BMC_EN_DET_R")
	)
	(segment
		(start 32.77489 -97.638616)
		(end 32.77489 -96.829626)
		(width 0.08382)
		(layer "In9.Cu")
		(net "FM_BMC_EN_DET_R")
	)
	(segment
		(start 41.63822 -70.5612)
		(end 42.926 -70.5612)
		(width 0.08382)
		(layer "In9.Cu")
		(net "FM_BMC_EN_DET_R")
	)
	(segment
		(start 48.690022 -60.03798)
		(end 49.029874 -60.03798)
		(width 0.08382)
		(layer "In9.Cu")
		(net "FM_BMC_EN_DET_R")
	)
	(segment
		(start 33.02127 -92.91066)
		(end 32.78505 -92.67444)
		(width 0.08382)
		(layer "In9.Cu")
		(net "FM_BMC_EN_DET_R")
	)
	(segment
		(start 27.85618 -97.90938)
		(end 29.694632 -97.90938)
		(width 0.08382)
		(layer "In9.Cu")
		(net "FM_BMC_EN_DET_R")
	)
	(segment
		(start 49.835054 -58.547)
		(end 52.647342 -58.547)
		(width 0.08382)
		(layer "In9.Cu")
		(net "FM_BMC_EN_DET_R")
	)
	(segment
		(start 43.541188 -67.925188)
		(end 43.800776 -67.6656)
		(width 0.08382)
		(layer "In9.Cu")
		(net "FM_BMC_EN_DET_R")
	)
	(segment
		(start 32.78505 -92.67444)
		(end 32.78505 -90.69578)
		(width 0.08382)
		(layer "In9.Cu")
		(net "FM_BMC_EN_DET_R")
	)
	(segment
		(start 39.19982 -76.856844)
		(end 39.19982 -76.06538)
		(width 0.08382)
		(layer "In9.Cu")
		(net "FM_BMC_EN_DET_R")
	)
	(segment
		(start 49.029874 -60.03798)
		(end 49.671986 -59.395868)
		(width 0.08382)
		(layer "In9.Cu")
		(net "FM_BMC_EN_DET_R")
	)
	(segment
		(start 18.923 -97.2058)
		(end 21.5392 -97.2058)
		(width 0.08382)
		(layer "In9.Cu")
		(net "FM_BMC_EN_DET_R")
	)
	(segment
		(start 31.059882 -97.201228)
		(end 31.768034 -97.90938)
		(width 0.08382)
		(layer "In9.Cu")
		(net "FM_BMC_EN_DET_R")
	)
	(segment
		(start 48.637444 -60.03798)
		(end 48.690022 -60.03798)
		(width 0.08382)
		(layer "In9.Cu")
		(net "FM_BMC_EN_DET_R")
	)
	(segment
		(start 29.694632 -97.90938)
		(end 30.402784 -97.201228)
		(width 0.08382)
		(layer "In9.Cu")
		(net "FM_BMC_EN_DET_R")
	)
	(segment
		(start 52.873148 -58.321194)
		(end 52.873148 -56.139842)
		(width 0.08382)
		(layer "In9.Cu")
		(net "FM_BMC_EN_DET_R")
	)
	(segment
		(start 39.19982 -76.06538)
		(end 40.2336 -75.0316)
		(width 0.08382)
		(layer "In9.Cu")
		(net "FM_BMC_EN_DET_R")
	)
	(segment
		(start 33.37433 -83.999324)
		(end 34.8996 -82.474054)
		(width 0.08382)
		(layer "In9.Cu")
		(net "FM_BMC_EN_DET_R")
	)
	(segment
		(start 26.3144 -96.3676)
		(end 27.85618 -97.90938)
		(width 0.08382)
		(layer "In9.Cu")
		(net "FM_BMC_EN_DET_R")
	)
	(segment
		(start 49.671986 -58.710068)
		(end 49.835054 -58.547)
		(width 0.08382)
		(layer "In9.Cu")
		(net "FM_BMC_EN_DET_R")
	)
	(segment
		(start 32.77489 -96.829626)
		(end 32.139128 -96.193864)
		(width 0.08382)
		(layer "In9.Cu")
		(net "FM_BMC_EN_DET_R")
	)
	(segment
		(start 18.264124 -95.982282)
		(end 18.669 -96.387158)
		(width 0.08382)
		(layer "In9.Cu")
		(net "FM_BMC_EN_DET_R")
	)
	(segment
		(start 44.72178 -65.82029)
		(end 43.84929 -64.9478)
		(width 0.08382)
		(layer "In9.Cu")
		(net "FM_BMC_EN_DET_R")
	)
	(segment
		(start 38.332664 -77.724)
		(end 39.19982 -76.856844)
		(width 0.08382)
		(layer "In9.Cu")
		(net "FM_BMC_EN_DET_R")
	)
	(segment
		(start 44.72178 -67.06362)
		(end 44.72178 -65.82029)
		(width 0.08382)
		(layer "In9.Cu")
		(net "FM_BMC_EN_DET_R")
	)
	(segment
		(start 40.2336 -73.8886)
		(end 41.18102 -72.94118)
		(width 0.08382)
		(layer "In9.Cu")
		(net "FM_BMC_EN_DET_R")
	)
	(segment
		(start 32.78505 -90.69578)
		(end 32.93237 -90.54846)
		(width 0.08382)
		(layer "In9.Cu")
		(net "FM_BMC_EN_DET_R")
	)
	(segment
		(start 32.139128 -96.193864)
		(end 32.139128 -94.978474)
		(width 0.08382)
		(layer "In9.Cu")
		(net "FM_BMC_EN_DET_R")
	)
	(segment
		(start 32.504126 -97.90938)
		(end 32.77489 -97.638616)
		(width 0.08382)
		(layer "In9.Cu")
		(net "FM_BMC_EN_DET_R")
	)
	(segment
		(start 44.111672 -62.832234)
		(end 45.84319 -62.832234)
		(width 0.08382)
		(layer "In9.Cu")
		(net "FM_BMC_EN_DET_R")
	)
	(segment
		(start 41.18102 -72.94118)
		(end 41.18102 -71.0184)
		(width 0.08382)
		(layer "In9.Cu")
		(net "FM_BMC_EN_DET_R")
	)
	(segment
		(start 42.926 -70.5612)
		(end 43.133518 -70.353682)
		(width 0.08382)
		(layer "In9.Cu")
		(net "FM_BMC_EN_DET_R")
	)
	(segment
		(start 32.139128 -94.978474)
		(end 33.02127 -94.096332)
		(width 0.08382)
		(layer "In9.Cu")
		(net "FM_BMC_EN_DET_R")
	)
	(segment
		(start 52.873148 -56.139842)
		(end 52.499768 -55.766462)
		(width 0.08382)
		(layer "In9.Cu")
		(net "FM_BMC_EN_DET_R")
	)
	(segment
		(start 41.18102 -71.0184)
		(end 41.63822 -70.5612)
		(width 0.08382)
		(layer "In9.Cu")
		(net "FM_BMC_EN_DET_R")
	)
	(segment
		(start 33.02127 -94.096332)
		(end 33.02127 -92.91066)
		(width 0.08382)
		(layer "In9.Cu")
		(net "FM_BMC_EN_DET_R")
	)
	(segment
		(start 34.8996 -82.474054)
		(end 34.8996 -78.612492)
		(width 0.08382)
		(layer "In9.Cu")
		(net "FM_BMC_EN_DET_R")
	)
	(segment
		(start 43.84929 -64.9478)
		(end 43.84929 -63.094616)
		(width 0.08382)
		(layer "In9.Cu")
		(net "FM_BMC_EN_DET_R")
	)
	(segment
		(start 43.800776 -67.6656)
		(end 44.1198 -67.6656)
		(width 0.08382)
		(layer "In9.Cu")
		(net "FM_BMC_EN_DET_R")
	)
	(segment
		(start 45.84319 -62.832234)
		(end 48.637444 -60.03798)
		(width 0.08382)
		(layer "In9.Cu")
		(net "FM_BMC_EN_DET_R")
	)
	(segment
		(start 18.669 -96.9518)
		(end 18.923 -97.2058)
		(width 0.08382)
		(layer "In9.Cu")
		(net "FM_BMC_EN_DET_R")
	)
	(segment
		(start 33.37433 -88.084406)
		(end 33.37433 -83.999324)
		(width 0.08382)
		(layer "In9.Cu")
		(net "FM_BMC_EN_DET_R")
	)
	(segment
		(start 43.84929 -63.094616)
		(end 44.111672 -62.832234)
		(width 0.08382)
		(layer "In9.Cu")
		(net "FM_BMC_EN_DET_R")
	)
	(segment
		(start 17.059402 -95.587058)
		(end 16.664178 -95.982282)
		(width 0.11684)
		(layer "F.Cu")
		(net "SMB_BMC_ALERT12_N")
	)
	(segment
		(start 16.664178 -95.982282)
		(end 16.664178 -96.782382)
		(width 0.11684)
		(layer "F.Cu")
		(net "SMB_BMC_ALERT12_N")
	)
	(segment
		(start 52.894992 -58.57113)
		(end 52.499768 -58.966354)
		(width 0.11684)
		(layer "F.Cu")
		(net "SMB_BMC_ALERT12_N")
	)
	(via
		(at 52.499768 -58.966354)
		(size 0.4572)
		(drill 0.254)
		(layers "F.Cu" "B.Cu")
		(net "SMB_BMC_ALERT12_N")
	)
	(via
		(at 52.73294 -61.69914)
		(size 0.6604)
		(drill 0.3302)
		(layers "F.Cu" "B.Cu")
		(net "SMB_BMC_ALERT12_N")
	)
	(via
		(at 16.664178 -96.782382)
		(size 0.4572)
		(drill 0.254)
		(layers "F.Cu" "B.Cu")
		(net "SMB_BMC_ALERT12_N")
	)
	(segment
		(start 52.32654 -62.10554)
		(end 52.73294 -61.69914)
		(width 0.11684)
		(layer "B.Cu")
		(net "SMB_BMC_ALERT12_N")
	)
	(segment
		(start 52.630578 -59.282076)
		(end 52.499768 -58.966354)
		(width 0.11684)
		(layer "B.Cu")
		(net "SMB_BMC_ALERT12_N")
	)
	(segment
		(start 50.91684 -63.54699)
		(end 51.47183 -62.992)
		(width 0.11684)
		(layer "B.Cu")
		(net "SMB_BMC_ALERT12_N")
	)
	(segment
		(start 52.838858 -60.904882)
		(end 52.838858 -59.490356)
		(width 0.11684)
		(layer "B.Cu")
		(net "SMB_BMC_ALERT12_N")
	)
	(segment
		(start 52.73294 -61.0108)
		(end 52.838858 -60.904882)
		(width 0.11684)
		(layer "B.Cu")
		(net "SMB_BMC_ALERT12_N")
	)
	(segment
		(start 52.838858 -59.490356)
		(end 52.630578 -59.282076)
		(width 0.11684)
		(layer "B.Cu")
		(net "SMB_BMC_ALERT12_N")
	)
	(segment
		(start 51.656742 -62.992)
		(end 52.32654 -62.322202)
		(width 0.11684)
		(layer "B.Cu")
		(net "SMB_BMC_ALERT12_N")
	)
	(segment
		(start 52.73294 -61.69914)
		(end 52.73294 -61.0108)
		(width 0.11684)
		(layer "B.Cu")
		(net "SMB_BMC_ALERT12_N")
	)
	(segment
		(start 51.47183 -62.992)
		(end 51.656742 -62.992)
		(width 0.11684)
		(layer "B.Cu")
		(net "SMB_BMC_ALERT12_N")
	)
	(segment
		(start 52.32654 -62.322202)
		(end 52.32654 -62.10554)
		(width 0.11684)
		(layer "B.Cu")
		(net "SMB_BMC_ALERT12_N")
	)
	(segment
		(start 35.51682 -78.771496)
		(end 35.51682 -82.93862)
		(width 0.08382)
		(layer "In9.Cu")
		(net "SMB_BMC_ALERT12_N")
	)
	(segment
		(start 33.9852 -86.36)
		(end 33.9852 -86.8426)
		(width 0.08382)
		(layer "In9.Cu")
		(net "SMB_BMC_ALERT12_N")
	)
	(segment
		(start 35.51682 -82.93862)
		(end 35.33013 -83.12531)
		(width 0.08382)
		(layer "In9.Cu")
		(net "SMB_BMC_ALERT12_N")
	)
	(segment
		(start 33.90519 -89.46769)
		(end 33.90519 -90.37701)
		(width 0.08382)
		(layer "In9.Cu")
		(net "SMB_BMC_ALERT12_N")
	)
	(segment
		(start 52.499768 -58.966354)
		(end 52.499768 -59.971432)
		(width 0.08382)
		(layer "In9.Cu")
		(net "SMB_BMC_ALERT12_N")
	)
	(segment
		(start 31.590488 -98.45929)
		(end 31.582868 -98.45167)
		(width 0.08382)
		(layer "In9.Cu")
		(net "SMB_BMC_ALERT12_N")
	)
	(segment
		(start 33.56991 -92.472764)
		(end 33.56991 -94.830392)
		(width 0.08382)
		(layer "In9.Cu")
		(net "SMB_BMC_ALERT12_N")
	)
	(segment
		(start 39.82339 -77.15885)
		(end 38.61562 -78.36662)
		(width 0.08382)
		(layer "In9.Cu")
		(net "SMB_BMC_ALERT12_N")
	)
	(segment
		(start 27.23642 -98.45802)
		(end 26.7716 -97.9932)
		(width 0.08382)
		(layer "In9.Cu")
		(net "SMB_BMC_ALERT12_N")
	)
	(segment
		(start 35.921696 -78.36662)
		(end 35.51682 -78.771496)
		(width 0.08382)
		(layer "In9.Cu")
		(net "SMB_BMC_ALERT12_N")
	)
	(segment
		(start 33.56991 -94.830392)
		(end 33.32353 -95.424752)
		(width 0.08382)
		(layer "In9.Cu")
		(net "SMB_BMC_ALERT12_N")
	)
	(segment
		(start 34.12871 -86.98611)
		(end 34.12871 -89.24417)
		(width 0.08382)
		(layer "In9.Cu")
		(net "SMB_BMC_ALERT12_N")
	)
	(segment
		(start 39.87038 -76.30922)
		(end 39.82339 -76.35621)
		(width 0.08382)
		(layer "In9.Cu")
		(net "SMB_BMC_ALERT12_N")
	)
	(segment
		(start 17.036288 -97.154492)
		(end 16.664178 -96.782382)
		(width 0.08382)
		(layer "In9.Cu")
		(net "SMB_BMC_ALERT12_N")
	)
	(segment
		(start 31.582868 -98.45167)
		(end 30.951932 -98.45167)
		(width 0.08382)
		(layer "In9.Cu")
		(net "SMB_BMC_ALERT12_N")
	)
	(segment
		(start 33.90519 -90.37701)
		(end 33.33369 -90.94851)
		(width 0.08382)
		(layer "In9.Cu")
		(net "SMB_BMC_ALERT12_N")
	)
	(segment
		(start 33.9852 -86.8426)
		(end 34.12871 -86.98611)
		(width 0.08382)
		(layer "In9.Cu")
		(net "SMB_BMC_ALERT12_N")
	)
	(segment
		(start 33.32353 -97.8662)
		(end 32.73044 -98.45929)
		(width 0.08382)
		(layer "In9.Cu")
		(net "SMB_BMC_ALERT12_N")
	)
	(segment
		(start 44.250356 -71.243444)
		(end 44.250356 -71.919084)
		(width 0.08382)
		(layer "In9.Cu")
		(net "SMB_BMC_ALERT12_N")
	)
	(segment
		(start 26.7716 -97.9932)
		(end 17.120108 -97.9932)
		(width 0.08382)
		(layer "In9.Cu")
		(net "SMB_BMC_ALERT12_N")
	)
	(segment
		(start 38.61562 -78.36662)
		(end 35.921696 -78.36662)
		(width 0.08382)
		(layer "In9.Cu")
		(net "SMB_BMC_ALERT12_N")
	)
	(segment
		(start 33.33369 -92.236544)
		(end 33.56991 -92.472764)
		(width 0.08382)
		(layer "In9.Cu")
		(net "SMB_BMC_ALERT12_N")
	)
	(segment
		(start 39.82339 -76.35621)
		(end 39.82339 -77.15885)
		(width 0.08382)
		(layer "In9.Cu")
		(net "SMB_BMC_ALERT12_N")
	)
	(segment
		(start 32.73044 -98.45929)
		(end 31.590488 -98.45929)
		(width 0.08382)
		(layer "In9.Cu")
		(net "SMB_BMC_ALERT12_N")
	)
	(segment
		(start 34.12871 -89.24417)
		(end 33.90519 -89.46769)
		(width 0.08382)
		(layer "In9.Cu")
		(net "SMB_BMC_ALERT12_N")
	)
	(segment
		(start 30.945582 -98.45802)
		(end 27.23642 -98.45802)
		(width 0.08382)
		(layer "In9.Cu")
		(net "SMB_BMC_ALERT12_N")
	)
	(segment
		(start 44.250356 -71.919084)
		(end 39.87038 -76.29906)
		(width 0.08382)
		(layer "In9.Cu")
		(net "SMB_BMC_ALERT12_N")
	)
	(segment
		(start 46.7614 -63.2206)
		(end 46.7614 -65.053718)
		(width 0.08382)
		(layer "In9.Cu")
		(net "SMB_BMC_ALERT12_N")
	)
	(segment
		(start 35.33013 -85.47227)
		(end 34.7472 -86.0552)
		(width 0.08382)
		(layer "In9.Cu")
		(net "SMB_BMC_ALERT12_N")
	)
	(segment
		(start 45.4406 -67.996308)
		(end 45.4406 -70.0532)
		(width 0.08382)
		(layer "In9.Cu")
		(net "SMB_BMC_ALERT12_N")
	)
	(segment
		(start 17.036288 -97.90938)
		(end 17.036288 -97.154492)
		(width 0.08382)
		(layer "In9.Cu")
		(net "SMB_BMC_ALERT12_N")
	)
	(segment
		(start 34.29 -86.0552)
		(end 33.9852 -86.36)
		(width 0.08382)
		(layer "In9.Cu")
		(net "SMB_BMC_ALERT12_N")
	)
	(segment
		(start 47.0154 -66.421508)
		(end 45.4406 -67.996308)
		(width 0.08382)
		(layer "In9.Cu")
		(net "SMB_BMC_ALERT12_N")
	)
	(segment
		(start 46.7614 -65.053718)
		(end 47.0154 -65.667128)
		(width 0.08382)
		(layer "In9.Cu")
		(net "SMB_BMC_ALERT12_N")
	)
	(segment
		(start 47.093632 -62.888368)
		(end 46.7614 -63.2206)
		(width 0.08382)
		(layer "In9.Cu")
		(net "SMB_BMC_ALERT12_N")
	)
	(segment
		(start 51.341528 -61.129672)
		(end 47.093632 -62.888368)
		(width 0.08382)
		(layer "In9.Cu")
		(net "SMB_BMC_ALERT12_N")
	)
	(segment
		(start 17.120108 -97.9932)
		(end 17.036288 -97.90938)
		(width 0.08382)
		(layer "In9.Cu")
		(net "SMB_BMC_ALERT12_N")
	)
	(segment
		(start 45.4406 -70.0532)
		(end 44.250356 -71.243444)
		(width 0.08382)
		(layer "In9.Cu")
		(net "SMB_BMC_ALERT12_N")
	)
	(segment
		(start 34.7472 -86.0552)
		(end 34.29 -86.0552)
		(width 0.08382)
		(layer "In9.Cu")
		(net "SMB_BMC_ALERT12_N")
	)
	(segment
		(start 30.951932 -98.45167)
		(end 30.945582 -98.45802)
		(width 0.08382)
		(layer "In9.Cu")
		(net "SMB_BMC_ALERT12_N")
	)
	(segment
		(start 39.87038 -76.29906)
		(end 39.87038 -76.30922)
		(width 0.08382)
		(layer "In9.Cu")
		(net "SMB_BMC_ALERT12_N")
	)
	(segment
		(start 33.33369 -90.94851)
		(end 33.33369 -92.236544)
		(width 0.08382)
		(layer "In9.Cu")
		(net "SMB_BMC_ALERT12_N")
	)
	(segment
		(start 47.0154 -65.667128)
		(end 47.0154 -66.421508)
		(width 0.08382)
		(layer "In9.Cu")
		(net "SMB_BMC_ALERT12_N")
	)
	(segment
		(start 33.32353 -95.424752)
		(end 33.32353 -97.8662)
		(width 0.08382)
		(layer "In9.Cu")
		(net "SMB_BMC_ALERT12_N")
	)
	(segment
		(start 35.33013 -83.12531)
		(end 35.33013 -85.47227)
		(width 0.08382)
		(layer "In9.Cu")
		(net "SMB_BMC_ALERT12_N")
	)
	(segment
		(start 52.499768 -59.971432)
		(end 51.341528 -61.129672)
		(width 0.08382)
		(layer "In9.Cu")
		(net "SMB_BMC_ALERT12_N")
	)
	(segment
		(start 43.01998 -95.16618)
		(end 44.2214 -96.3676)
		(width 0.11684)
		(layer "F.Cu")
		(net "SMB_BMC_ALERT10_N")
	)
	(segment
		(start 39.55288 -91.97848)
		(end 39.55288 -94.67342)
		(width 0.11684)
		(layer "F.Cu")
		(net "SMB_BMC_ALERT10_N")
	)
	(segment
		(start 44.2214 -96.3676)
		(end 47.5996 -96.3676)
		(width 0.11684)
		(layer "F.Cu")
		(net "SMB_BMC_ALERT10_N")
	)
	(segment
		(start 39.09695 -91.52255)
		(end 39.55288 -91.97848)
		(width 0.11684)
		(layer "F.Cu")
		(net "SMB_BMC_ALERT10_N")
	)
	(segment
		(start 39.55288 -94.67342)
		(end 40.04564 -95.16618)
		(width 0.11684)
		(layer "F.Cu")
		(net "SMB_BMC_ALERT10_N")
	)
	(segment
		(start 40.04564 -95.16618)
		(end 43.01998 -95.16618)
		(width 0.11684)
		(layer "F.Cu")
		(net "SMB_BMC_ALERT10_N")
	)
	(segment
		(start 38.3286 -91.52255)
		(end 39.09695 -91.52255)
		(width 0.11684)
		(layer "F.Cu")
		(net "SMB_BMC_ALERT10_N")
	)
	(via
		(at 49.043336 -65.3796)
		(size 0.508)
		(drill 0.254)
		(layers "F.Cu" "B.Cu")
		(net "SMB_BMC_ALERT10_N")
	)
	(via
		(at 11.30935 -93.472)
		(size 0.508)
		(drill 0.254)
		(layers "F.Cu" "B.Cu")
		(net "SMB_BMC_ALERT10_N")
	)
	(via
		(at 47.5996 -96.3676)
		(size 0.508)
		(drill 0.254)
		(layers "F.Cu" "B.Cu")
		(net "SMB_BMC_ALERT10_N")
	)
	(via
		(at 38.3286 -91.52255)
		(size 0.508)
		(drill 0.254)
		(layers "F.Cu" "B.Cu")
		(net "SMB_BMC_ALERT10_N")
	)
	(segment
		(start 47.879 -64.516254)
		(end 48.0822 -64.719454)
		(width 0.11684)
		(layer "B.Cu")
		(net "SMB_BMC_ALERT10_N")
	)
	(segment
		(start 48.4632 -65.23736)
		(end 48.60544 -65.3796)
		(width 0.11684)
		(layer "B.Cu")
		(net "SMB_BMC_ALERT10_N")
	)
	(segment
		(start 47.879 -64.34455)
		(end 47.879 -64.516254)
		(width 0.11684)
		(layer "B.Cu")
		(net "SMB_BMC_ALERT10_N")
	)
	(segment
		(start 11.30935 -93.808296)
		(end 11.30935 -93.472)
		(width 0.11684)
		(layer "B.Cu")
		(net "SMB_BMC_ALERT10_N")
	)
	(segment
		(start 48.06315 -64.34455)
		(end 48.4632 -64.7446)
		(width 0.11684)
		(layer "B.Cu")
		(net "SMB_BMC_ALERT10_N")
	)
	(segment
		(start 48.60544 -65.3796)
		(end 49.043336 -65.3796)
		(width 0.11684)
		(layer "B.Cu")
		(net "SMB_BMC_ALERT10_N")
	)
	(segment
		(start 48.4632 -64.7446)
		(end 48.4632 -65.23736)
		(width 0.11684)
		(layer "B.Cu")
		(net "SMB_BMC_ALERT10_N")
	)
	(segment
		(start 47.879 -64.34455)
		(end 48.06315 -64.34455)
		(width 0.11684)
		(layer "B.Cu")
		(net "SMB_BMC_ALERT10_N")
	)
	(segment
		(start 11.91895 -94.488)
		(end 11.91895 -94.417896)
		(width 0.11684)
		(layer "B.Cu")
		(net "SMB_BMC_ALERT10_N")
	)
	(segment
		(start 47.71771 -65.87109)
		(end 47.51578 -65.87109)
		(width 0.11684)
		(layer "B.Cu")
		(net "SMB_BMC_ALERT10_N")
	)
	(segment
		(start 48.0822 -65.5066)
		(end 47.71771 -65.87109)
		(width 0.11684)
		(layer "B.Cu")
		(net "SMB_BMC_ALERT10_N")
	)
	(segment
		(start 48.0822 -64.719454)
		(end 48.0822 -65.5066)
		(width 0.11684)
		(layer "B.Cu")
		(net "SMB_BMC_ALERT10_N")
	)
	(segment
		(start 11.91895 -94.417896)
		(end 11.30935 -93.808296)
		(width 0.11684)
		(layer "B.Cu")
		(net "SMB_BMC_ALERT10_N")
	)
	(segment
		(start 11.75766 -90.1319)
		(end 11.75766 -90.62974)
		(width 0.08382)
		(layer "In2.Cu")
		(net "SMB_BMC_ALERT10_N")
	)
	(segment
		(start 21.150072 -88.374728)
		(end 13.514832 -88.374728)
		(width 0.08382)
		(layer "In2.Cu")
		(net "SMB_BMC_ALERT10_N")
	)
	(segment
		(start 21.6154 -87.9094)
		(end 21.150072 -88.374728)
		(width 0.08382)
		(layer "In2.Cu")
		(net "SMB_BMC_ALERT10_N")
	)
	(segment
		(start 30.99816 -89.0524)
		(end 29.52623 -87.58047)
		(width 0.08382)
		(layer "In2.Cu")
		(net "SMB_BMC_ALERT10_N")
	)
	(segment
		(start 33.866328 -88.47455)
		(end 33.494472 -88.47455)
		(width 0.08382)
		(layer "In2.Cu")
		(net "SMB_BMC_ALERT10_N")
	)
	(segment
		(start 13.514832 -88.374728)
		(end 11.75766 -90.1319)
		(width 0.08382)
		(layer "In2.Cu")
		(net "SMB_BMC_ALERT10_N")
	)
	(segment
		(start 29.52623 -87.58047)
		(end 27.568652 -87.58047)
		(width 0.08382)
		(layer "In2.Cu")
		(net "SMB_BMC_ALERT10_N")
	)
	(segment
		(start 33.494472 -88.47455)
		(end 32.916622 -89.0524)
		(width 0.08382)
		(layer "In2.Cu")
		(net "SMB_BMC_ALERT10_N")
	)
	(segment
		(start 34.12871 -88.93175)
		(end 34.12871 -88.736932)
		(width 0.08382)
		(layer "In2.Cu")
		(net "SMB_BMC_ALERT10_N")
	)
	(segment
		(start 10.8204 -92.98305)
		(end 11.30935 -93.472)
		(width 0.08382)
		(layer "In2.Cu")
		(net "SMB_BMC_ALERT10_N")
	)
	(segment
		(start 32.916622 -89.0524)
		(end 30.99816 -89.0524)
		(width 0.08382)
		(layer "In2.Cu")
		(net "SMB_BMC_ALERT10_N")
	)
	(segment
		(start 11.75766 -90.62974)
		(end 11.4554 -90.932)
		(width 0.08382)
		(layer "In2.Cu")
		(net "SMB_BMC_ALERT10_N")
	)
	(segment
		(start 35.69589 -91.67749)
		(end 34.33318 -90.31478)
		(width 0.08382)
		(layer "In2.Cu")
		(net "SMB_BMC_ALERT10_N")
	)
	(segment
		(start 10.96264 -90.932)
		(end 10.8204 -91.07424)
		(width 0.08382)
		(layer "In2.Cu")
		(net "SMB_BMC_ALERT10_N")
	)
	(segment
		(start 38.3286 -91.52255)
		(end 38.17366 -91.67749)
		(width 0.08382)
		(layer "In2.Cu")
		(net "SMB_BMC_ALERT10_N")
	)
	(segment
		(start 24.586946 -87.9094)
		(end 21.6154 -87.9094)
		(width 0.08382)
		(layer "In2.Cu")
		(net "SMB_BMC_ALERT10_N")
	)
	(segment
		(start 34.33318 -89.13622)
		(end 34.12871 -88.93175)
		(width 0.08382)
		(layer "In2.Cu")
		(net "SMB_BMC_ALERT10_N")
	)
	(segment
		(start 34.12871 -88.736932)
		(end 33.866328 -88.47455)
		(width 0.08382)
		(layer "In2.Cu")
		(net "SMB_BMC_ALERT10_N")
	)
	(segment
		(start 38.17366 -91.67749)
		(end 35.69589 -91.67749)
		(width 0.08382)
		(layer "In2.Cu")
		(net "SMB_BMC_ALERT10_N")
	)
	(segment
		(start 27.313382 -87.3252)
		(end 25.171146 -87.3252)
		(width 0.08382)
		(layer "In2.Cu")
		(net "SMB_BMC_ALERT10_N")
	)
	(segment
		(start 27.568652 -87.58047)
		(end 27.313382 -87.3252)
		(width 0.08382)
		(layer "In2.Cu")
		(net "SMB_BMC_ALERT10_N")
	)
	(segment
		(start 10.8204 -91.07424)
		(end 10.8204 -92.98305)
		(width 0.08382)
		(layer "In2.Cu")
		(net "SMB_BMC_ALERT10_N")
	)
	(segment
		(start 34.33318 -90.31478)
		(end 34.33318 -89.13622)
		(width 0.08382)
		(layer "In2.Cu")
		(net "SMB_BMC_ALERT10_N")
	)
	(segment
		(start 11.4554 -90.932)
		(end 10.96264 -90.932)
		(width 0.08382)
		(layer "In2.Cu")
		(net "SMB_BMC_ALERT10_N")
	)
	(segment
		(start 25.171146 -87.3252)
		(end 24.586946 -87.9094)
		(width 0.08382)
		(layer "In2.Cu")
		(net "SMB_BMC_ALERT10_N")
	)
	(segment
		(start 50.49266 -69.027548)
		(end 50.431192 -68.879212)
		(width 0.10668)
		(layer "In4.Cu")
		(net "SMB_BMC_ALERT10_N")
	)
	(segment
		(start 47.746666 -81.567274)
		(end 47.74692 -81.567274)
		(width 0.10668)
		(layer "In4.Cu")
		(net "SMB_BMC_ALERT10_N")
	)
	(segment
		(start 47.5996 -96.3676)
		(end 48.0314 -95.9358)
		(width 0.10668)
		(layer "In4.Cu")
		(net "SMB_BMC_ALERT10_N")
	)
	(segment
		(start 48.45304 -72.75576)
		(end 50.18024 -72.75576)
		(width 0.10668)
		(layer "In4.Cu")
		(net "SMB_BMC_ALERT10_N")
	)
	(segment
		(start 47.117508 -86.36635)
		(end 47.117508 -82.196432)
		(width 0.10668)
		(layer "In4.Cu")
		(net "SMB_BMC_ALERT10_N")
	)
	(segment
		(start 47.5996 -74.786236)
		(end 47.5996 -73.6092)
		(width 0.10668)
		(layer "In4.Cu")
		(net "SMB_BMC_ALERT10_N")
	)
	(segment
		(start 50.18024 -72.75576)
		(end 50.49266 -72.44334)
		(width 0.10668)
		(layer "In4.Cu")
		(net "SMB_BMC_ALERT10_N")
	)
	(segment
		(start 48.17364 -75.360276)
		(end 47.5996 -74.786236)
		(width 0.10668)
		(layer "In4.Cu")
		(net "SMB_BMC_ALERT10_N")
	)
	(segment
		(start 47.117508 -82.196432)
		(end 47.746666 -81.567274)
		(width 0.10668)
		(layer "In4.Cu")
		(net "SMB_BMC_ALERT10_N")
	)
	(segment
		(start 47.5996 -73.6092)
		(end 48.45304 -72.75576)
		(width 0.10668)
		(layer "In4.Cu")
		(net "SMB_BMC_ALERT10_N")
	)
	(segment
		(start 49.4792 -65.815464)
		(end 49.043336 -65.3796)
		(width 0.10668)
		(layer "In4.Cu")
		(net "SMB_BMC_ALERT10_N")
	)
	(segment
		(start 48.17364 -75.931014)
		(end 48.17364 -75.360276)
		(width 0.10668)
		(layer "In4.Cu")
		(net "SMB_BMC_ALERT10_N")
	)
	(segment
		(start 48.0314 -95.9358)
		(end 48.0314 -89.916254)
		(width 0.10668)
		(layer "In4.Cu")
		(net "SMB_BMC_ALERT10_N")
	)
	(segment
		(start 50.431192 -68.879212)
		(end 49.4792 -67.92722)
		(width 0.10668)
		(layer "In4.Cu")
		(net "SMB_BMC_ALERT10_N")
	)
	(segment
		(start 47.74692 -81.567274)
		(end 47.74692 -76.357734)
		(width 0.10668)
		(layer "In4.Cu")
		(net "SMB_BMC_ALERT10_N")
	)
	(segment
		(start 47.55388 -89.438734)
		(end 47.55388 -86.802722)
		(width 0.10668)
		(layer "In4.Cu")
		(net "SMB_BMC_ALERT10_N")
	)
	(segment
		(start 47.55388 -86.802722)
		(end 47.117508 -86.36635)
		(width 0.10668)
		(layer "In4.Cu")
		(net "SMB_BMC_ALERT10_N")
	)
	(segment
		(start 48.0314 -89.916254)
		(end 47.55388 -89.438734)
		(width 0.10668)
		(layer "In4.Cu")
		(net "SMB_BMC_ALERT10_N")
	)
	(segment
		(start 50.49266 -72.44334)
		(end 50.49266 -69.027548)
		(width 0.10668)
		(layer "In4.Cu")
		(net "SMB_BMC_ALERT10_N")
	)
	(segment
		(start 47.74692 -76.357734)
		(end 48.17364 -75.931014)
		(width 0.10668)
		(layer "In4.Cu")
		(net "SMB_BMC_ALERT10_N")
	)
	(segment
		(start 49.4792 -67.92722)
		(end 49.4792 -65.815464)
		(width 0.10668)
		(layer "In4.Cu")
		(net "SMB_BMC_ALERT10_N")
	)
	(segment
		(start 15.130272 -95.182182)
		(end 15.864332 -95.182182)
		(width 0.11684)
		(layer "F.Cu")
		(net "PWRGD_SYS_PWROK_PLD")
	)
	(segment
		(start 13.521436 -97.08642)
		(end 14.1478 -96.460056)
		(width 0.11684)
		(layer "F.Cu")
		(net "PWRGD_SYS_PWROK_PLD")
	)
	(segment
		(start 15.864332 -95.182182)
		(end 16.259556 -94.786958)
		(width 0.11684)
		(layer "F.Cu")
		(net "PWRGD_SYS_PWROK_PLD")
	)
	(segment
		(start 14.1478 -96.164654)
		(end 15.130272 -95.182182)
		(width 0.11684)
		(layer "F.Cu")
		(net "PWRGD_SYS_PWROK_PLD")
	)
	(segment
		(start 14.1478 -96.460056)
		(end 14.1478 -96.164654)
		(width 0.11684)
		(layer "F.Cu")
		(net "PWRGD_SYS_PWROK_PLD")
	)
	(segment
		(start 13.16863 -97.08642)
		(end 13.521436 -97.08642)
		(width 0.11684)
		(layer "F.Cu")
		(net "PWRGD_SYS_PWROK_PLD")
	)
	(segment
		(start 12.71905 -97.536)
		(end 13.16863 -97.08642)
		(width 0.11684)
		(layer "F.Cu")
		(net "PWRGD_SYS_PWROK_PLD")
	)
	(segment
		(start 57.2262 -31.37535)
		(end 57.1119 -31.26105)
		(width 0.11684)
		(layer "F.Cu")
		(net "PWRGD_SYS_PWROK_BMC")
	)
	(segment
		(start 57.2262 -31.8008)
		(end 57.2262 -31.37535)
		(width 0.11684)
		(layer "F.Cu")
		(net "PWRGD_SYS_PWROK_BMC")
	)
	(segment
		(start 57.1119 -31.26105)
		(end 56.7182 -31.26105)
		(width 0.11684)
		(layer "F.Cu")
		(net "PWRGD_SYS_PWROK_BMC")
	)
	(segment
		(start 56.094884 -40.17137)
		(end 56.490108 -39.776146)
		(width 0.11684)
		(layer "F.Cu")
		(net "PWRGD_SYS_PWROK_BMC")
	)
	(via
		(at 57.2262 -31.8008)
		(size 0.508)
		(drill 0.254)
		(layers "F.Cu" "B.Cu")
		(net "PWRGD_SYS_PWROK_BMC")
	)
	(via
		(at 56.490108 -39.776146)
		(size 0.4572)
		(drill 0.254)
		(layers "F.Cu" "B.Cu")
		(net "PWRGD_SYS_PWROK_BMC")
	)
	(segment
		(start 57.71642 -32.67202)
		(end 57.2262 -32.1818)
		(width 0.10668)
		(layer "In7.Cu")
		(net "PWRGD_SYS_PWROK_BMC")
	)
	(segment
		(start 57.2262 -32.1818)
		(end 57.2262 -31.8008)
		(width 0.10668)
		(layer "In7.Cu")
		(net "PWRGD_SYS_PWROK_BMC")
	)
	(segment
		(start 56.490108 -39.776146)
		(end 56.490108 -36.268152)
		(width 0.10668)
		(layer "In7.Cu")
		(net "PWRGD_SYS_PWROK_BMC")
	)
	(segment
		(start 57.71642 -35.04184)
		(end 57.71642 -32.67202)
		(width 0.10668)
		(layer "In7.Cu")
		(net "PWRGD_SYS_PWROK_BMC")
	)
	(segment
		(start 56.490108 -36.268152)
		(end 57.71642 -35.04184)
		(width 0.10668)
		(layer "In7.Cu")
		(net "PWRGD_SYS_PWROK_BMC")
	)
	(segment
		(start 24.654764 -88.791796)
		(end 24.25954 -89.18702)
		(width 0.11684)
		(layer "F.Cu")
		(net "PWRGD_PSU_AC_PWROK_PLD")
	)
	(via
		(at 24.987758 -86.746842)
		(size 0.6604)
		(drill 0.3302)
		(layers "F.Cu" "B.Cu")
		(net "PWRGD_PSU_AC_PWROK_PLD")
	)
	(via
		(at 24.654764 -88.791796)
		(size 0.4572)
		(drill 0.254)
		(layers "F.Cu" "B.Cu")
		(net "PWRGD_PSU_AC_PWROK_PLD")
	)
	(segment
		(start 26.93035 -85.7758)
		(end 26.516076 -85.7758)
		(width 0.11684)
		(layer "B.Cu")
		(net "PWRGD_PSU_AC_PWROK_PLD")
	)
	(segment
		(start 25.545034 -86.746842)
		(end 24.987758 -86.746842)
		(width 0.11684)
		(layer "B.Cu")
		(net "PWRGD_PSU_AC_PWROK_PLD")
	)
	(segment
		(start 26.516076 -85.7758)
		(end 25.545034 -86.746842)
		(width 0.11684)
		(layer "B.Cu")
		(net "PWRGD_PSU_AC_PWROK_PLD")
	)
	(segment
		(start 24.654764 -87.079836)
		(end 24.987758 -86.746842)
		(width 0.11684)
		(layer "B.Cu")
		(net "PWRGD_PSU_AC_PWROK_PLD")
	)
	(segment
		(start 24.654764 -88.791796)
		(end 24.654764 -87.079836)
		(width 0.11684)
		(layer "B.Cu")
		(net "PWRGD_PSU_AC_PWROK_PLD")
	)
	(segment
		(start 56.482742 -38.983412)
		(end 56.094884 -39.37127)
		(width 0.11684)
		(layer "F.Cu")
		(net "PWRGD_PSU_AC_PWROK_BMC")
	)
	(segment
		(start 57.785 -37.058854)
		(end 56.482742 -38.361112)
		(width 0.11684)
		(layer "F.Cu")
		(net "PWRGD_PSU_AC_PWROK_BMC")
	)
	(segment
		(start 58.0644 -31.26105)
		(end 58.0644 -32.2834)
		(width 0.11684)
		(layer "F.Cu")
		(net "PWRGD_PSU_AC_PWROK_BMC")
	)
	(segment
		(start 57.785 -32.5628)
		(end 57.785 -37.058854)
		(width 0.11684)
		(layer "F.Cu")
		(net "PWRGD_PSU_AC_PWROK_BMC")
	)
	(segment
		(start 58.0644 -32.2834)
		(end 57.785 -32.5628)
		(width 0.11684)
		(layer "F.Cu")
		(net "PWRGD_PSU_AC_PWROK_BMC")
	)
	(segment
		(start 56.482742 -38.361112)
		(end 56.482742 -38.983412)
		(width 0.11684)
		(layer "F.Cu")
		(net "PWRGD_PSU_AC_PWROK_BMC")
	)
	(segment
		(start 17.464278 -92.791788)
		(end 17.859502 -93.187012)
		(width 0.11684)
		(layer "F.Cu")
		(net "FM_ESPI_PLD_R_EN")
	)
	(via
		(at 13.843 -90.17)
		(size 0.6604)
		(drill 0.3302)
		(layers "F.Cu" "B.Cu")
		(net "FM_ESPI_PLD_R_EN")
	)
	(via
		(at 17.464278 -92.791788)
		(size 0.4572)
		(drill 0.254)
		(layers "F.Cu" "B.Cu")
		(net "FM_ESPI_PLD_R_EN")
	)
	(segment
		(start 17.602454 -91.580462)
		(end 17.852898 -91.830906)
		(width 0.11684)
		(layer "B.Cu")
		(net "FM_ESPI_PLD_R_EN")
	)
	(segment
		(start 17.852898 -91.830906)
		(end 17.852898 -92.403168)
		(width 0.11684)
		(layer "B.Cu")
		(net "FM_ESPI_PLD_R_EN")
	)
	(segment
		(start 13.843 -90.17)
		(end 14.3256 -90.17)
		(width 0.11684)
		(layer "B.Cu")
		(net "FM_ESPI_PLD_R_EN")
	)
	(segment
		(start 14.3256 -90.17)
		(end 15.2146 -91.059)
		(width 0.11684)
		(layer "B.Cu")
		(net "FM_ESPI_PLD_R_EN")
	)
	(segment
		(start 13.843254 -90.169746)
		(end 13.843 -90.17)
		(width 0.11684)
		(layer "B.Cu")
		(net "FM_ESPI_PLD_R_EN")
	)
	(segment
		(start 13.843254 -89.243154)
		(end 13.843254 -90.169746)
		(width 0.11684)
		(layer "B.Cu")
		(net "FM_ESPI_PLD_R_EN")
	)
	(segment
		(start 12.71905 -88.392)
		(end 12.9921 -88.392)
		(width 0.11684)
		(layer "B.Cu")
		(net "FM_ESPI_PLD_R_EN")
	)
	(segment
		(start 12.9921 -88.392)
		(end 13.843254 -89.243154)
		(width 0.11684)
		(layer "B.Cu")
		(net "FM_ESPI_PLD_R_EN")
	)
	(segment
		(start 17.852898 -92.403168)
		(end 17.464278 -92.791788)
		(width 0.11684)
		(layer "B.Cu")
		(net "FM_ESPI_PLD_R_EN")
	)
	(segment
		(start 16.421862 -91.580462)
		(end 17.602454 -91.580462)
		(width 0.11684)
		(layer "B.Cu")
		(net "FM_ESPI_PLD_R_EN")
	)
	(segment
		(start 15.9004 -91.059)
		(end 16.421862 -91.580462)
		(width 0.11684)
		(layer "B.Cu")
		(net "FM_ESPI_PLD_R_EN")
	)
	(segment
		(start 15.2146 -91.059)
		(end 15.9004 -91.059)
		(width 0.11684)
		(layer "B.Cu")
		(net "FM_ESPI_PLD_R_EN")
	)
	(segment
		(start 68.961 -106.2482)
		(end 68.58635 -105.87355)
		(width 0.11684)
		(layer "F.Cu")
		(net "FM_VIRTUAL_RESEAT_BMC")
	)
	(segment
		(start 55.295038 -40.17137)
		(end 55.690262 -39.776146)
		(width 0.11684)
		(layer "F.Cu")
		(net "FM_VIRTUAL_RESEAT_BMC")
	)
	(segment
		(start 68.58635 -105.87355)
		(end 67.818 -105.87355)
		(width 0.11684)
		(layer "F.Cu")
		(net "FM_VIRTUAL_RESEAT_BMC")
	)
	(via
		(at 55.690262 -39.776146)
		(size 0.4572)
		(drill 0.254)
		(layers "F.Cu" "B.Cu")
		(net "FM_VIRTUAL_RESEAT_BMC")
	)
	(via
		(at 68.961 -106.2482)
		(size 0.508)
		(drill 0.254)
		(layers "F.Cu" "B.Cu")
		(net "FM_VIRTUAL_RESEAT_BMC")
	)
	(via
		(at 70.27164 -80.4926)
		(size 0.508)
		(drill 0.254)
		(layers "F.Cu" "B.Cu")
		(net "FM_VIRTUAL_RESEAT_BMC")
	)
	(via
		(at 62.899798 -57.366408)
		(size 0.4572)
		(drill 0.254)
		(layers "F.Cu" "B.Cu")
		(net "FM_VIRTUAL_RESEAT_BMC")
	)
	(segment
		(start 66.36766 -102.077012)
		(end 68.02628 -103.735632)
		(width 0.10668)
		(layer "In4.Cu")
		(net "FM_VIRTUAL_RESEAT_BMC")
	)
	(segment
		(start 70.612 -84.9884)
		(end 70.231 -85.3694)
		(width 0.10668)
		(layer "In4.Cu")
		(net "FM_VIRTUAL_RESEAT_BMC")
	)
	(segment
		(start 68.02628 -103.735632)
		(end 68.02628 -105.31348)
		(width 0.10668)
		(layer "In4.Cu")
		(net "FM_VIRTUAL_RESEAT_BMC")
	)
	(segment
		(start 67.94246 -88.796876)
		(end 66.36766 -90.371676)
		(width 0.10668)
		(layer "In4.Cu")
		(net "FM_VIRTUAL_RESEAT_BMC")
	)
	(segment
		(start 69.257418 -85.3694)
		(end 67.94246 -86.684358)
		(width 0.10668)
		(layer "In4.Cu")
		(net "FM_VIRTUAL_RESEAT_BMC")
	)
	(segment
		(start 70.612 -83.1342)
		(end 70.612 -84.9884)
		(width 0.10668)
		(layer "In4.Cu")
		(net "FM_VIRTUAL_RESEAT_BMC")
	)
	(segment
		(start 67.94246 -86.684358)
		(end 67.94246 -88.796876)
		(width 0.10668)
		(layer "In4.Cu")
		(net "FM_VIRTUAL_RESEAT_BMC")
	)
	(segment
		(start 66.36766 -90.371676)
		(end 66.36766 -102.077012)
		(width 0.10668)
		(layer "In4.Cu")
		(net "FM_VIRTUAL_RESEAT_BMC")
	)
	(segment
		(start 68.02628 -105.31348)
		(end 68.961 -106.2482)
		(width 0.10668)
		(layer "In4.Cu")
		(net "FM_VIRTUAL_RESEAT_BMC")
	)
	(segment
		(start 70.231 -85.3694)
		(end 69.257418 -85.3694)
		(width 0.10668)
		(layer "In4.Cu")
		(net "FM_VIRTUAL_RESEAT_BMC")
	)
	(segment
		(start 70.27164 -80.4926)
		(end 70.27164 -82.79384)
		(width 0.10668)
		(layer "In4.Cu")
		(net "FM_VIRTUAL_RESEAT_BMC")
	)
	(segment
		(start 70.27164 -82.79384)
		(end 70.612 -83.1342)
		(width 0.10668)
		(layer "In4.Cu")
		(net "FM_VIRTUAL_RESEAT_BMC")
	)
	(segment
		(start 67.4624 -65.1256)
		(end 66.421 -64.0842)
		(width 0.10668)
		(layer "In7.Cu")
		(net "FM_VIRTUAL_RESEAT_BMC")
	)
	(segment
		(start 65.6844 -58.5724)
		(end 63.5 -58.5724)
		(width 0.10668)
		(layer "In7.Cu")
		(net "FM_VIRTUAL_RESEAT_BMC")
	)
	(segment
		(start 73.9648 -70.485)
		(end 77.4192 -70.485)
		(width 0.10668)
		(layer "In7.Cu")
		(net "FM_VIRTUAL_RESEAT_BMC")
	)
	(segment
		(start 70.27164 -72.789034)
		(end 71.483474 -71.5772)
		(width 0.10668)
		(layer "In7.Cu")
		(net "FM_VIRTUAL_RESEAT_BMC")
	)
	(segment
		(start 65.913 -62.2808)
		(end 65.913 -58.801)
		(width 0.10668)
		(layer "In7.Cu")
		(net "FM_VIRTUAL_RESEAT_BMC")
	)
	(segment
		(start 76.1492 -65.1256)
		(end 67.4624 -65.1256)
		(width 0.10668)
		(layer "In7.Cu")
		(net "FM_VIRTUAL_RESEAT_BMC")
	)
	(segment
		(start 77.4192 -70.485)
		(end 78.2574 -69.6468)
		(width 0.10668)
		(layer "In7.Cu")
		(net "FM_VIRTUAL_RESEAT_BMC")
	)
	(segment
		(start 78.2574 -67.2338)
		(end 76.1492 -65.1256)
		(width 0.10668)
		(layer "In7.Cu")
		(net "FM_VIRTUAL_RESEAT_BMC")
	)
	(segment
		(start 63.5 -58.5724)
		(end 62.899798 -57.972198)
		(width 0.10668)
		(layer "In7.Cu")
		(net "FM_VIRTUAL_RESEAT_BMC")
	)
	(segment
		(start 70.27164 -80.4926)
		(end 70.27164 -72.789034)
		(width 0.10668)
		(layer "In7.Cu")
		(net "FM_VIRTUAL_RESEAT_BMC")
	)
	(segment
		(start 66.421 -64.0842)
		(end 66.421 -62.7888)
		(width 0.10668)
		(layer "In7.Cu")
		(net "FM_VIRTUAL_RESEAT_BMC")
	)
	(segment
		(start 65.913 -58.801)
		(end 65.6844 -58.5724)
		(width 0.10668)
		(layer "In7.Cu")
		(net "FM_VIRTUAL_RESEAT_BMC")
	)
	(segment
		(start 72.8726 -71.5772)
		(end 73.9648 -70.485)
		(width 0.10668)
		(layer "In7.Cu")
		(net "FM_VIRTUAL_RESEAT_BMC")
	)
	(segment
		(start 78.2574 -69.6468)
		(end 78.2574 -67.2338)
		(width 0.10668)
		(layer "In7.Cu")
		(net "FM_VIRTUAL_RESEAT_BMC")
	)
	(segment
		(start 62.899798 -57.972198)
		(end 62.899798 -57.366408)
		(width 0.10668)
		(layer "In7.Cu")
		(net "FM_VIRTUAL_RESEAT_BMC")
	)
	(segment
		(start 66.421 -62.7888)
		(end 65.913 -62.2808)
		(width 0.10668)
		(layer "In7.Cu")
		(net "FM_VIRTUAL_RESEAT_BMC")
	)
	(segment
		(start 71.483474 -71.5772)
		(end 72.8726 -71.5772)
		(width 0.10668)
		(layer "In7.Cu")
		(net "FM_VIRTUAL_RESEAT_BMC")
	)
	(segment
		(start 57.16397 -42.577766)
		(end 57.420002 -42.577766)
		(width 0.08382)
		(layer "In9.Cu")
		(net "FM_VIRTUAL_RESEAT_BMC")
	)
	(segment
		(start 61.571124 -56.16321)
		(end 61.71057 -56.302656)
		(width 0.08382)
		(layer "In9.Cu")
		(net "FM_VIRTUAL_RESEAT_BMC")
	)
	(segment
		(start 59.304936 -49.169574)
		(end 60.201302 -50.06594)
		(width 0.08382)
		(layer "In9.Cu")
		(net "FM_VIRTUAL_RESEAT_BMC")
	)
	(segment
		(start 60.201302 -50.06594)
		(end 60.201302 -54.747922)
		(width 0.08382)
		(layer "In9.Cu")
		(net "FM_VIRTUAL_RESEAT_BMC")
	)
	(segment
		(start 61.71057 -56.302656)
		(end 61.71057 -56.82742)
		(width 0.08382)
		(layer "In9.Cu")
		(net "FM_VIRTUAL_RESEAT_BMC")
	)
	(segment
		(start 60.899294 -56.052212)
		(end 61.010292 -56.16321)
		(width 0.08382)
		(layer "In9.Cu")
		(net "FM_VIRTUAL_RESEAT_BMC")
	)
	(segment
		(start 60.899294 -55.445914)
		(end 60.899294 -56.052212)
		(width 0.08382)
		(layer "In9.Cu")
		(net "FM_VIRTUAL_RESEAT_BMC")
	)
	(segment
		(start 59.304936 -46.376336)
		(end 59.304936 -49.169574)
		(width 0.08382)
		(layer "In9.Cu")
		(net "FM_VIRTUAL_RESEAT_BMC")
	)
	(segment
		(start 55.690262 -39.776146)
		(end 56.086502 -40.172386)
		(width 0.08382)
		(layer "In9.Cu")
		(net "FM_VIRTUAL_RESEAT_BMC")
	)
	(segment
		(start 56.881268 -40.439086)
		(end 56.881268 -42.295064)
		(width 0.08382)
		(layer "In9.Cu")
		(net "FM_VIRTUAL_RESEAT_BMC")
	)
	(segment
		(start 57.703212 -42.860976)
		(end 57.703212 -44.375832)
		(width 0.08382)
		(layer "In9.Cu")
		(net "FM_VIRTUAL_RESEAT_BMC")
	)
	(segment
		(start 61.71057 -56.82742)
		(end 61.86551 -56.98236)
		(width 0.08382)
		(layer "In9.Cu")
		(net "FM_VIRTUAL_RESEAT_BMC")
	)
	(segment
		(start 62.51575 -56.98236)
		(end 62.899798 -57.366408)
		(width 0.08382)
		(layer "In9.Cu")
		(net "FM_VIRTUAL_RESEAT_BMC")
	)
	(segment
		(start 58.4708 -45.14342)
		(end 58.4708 -45.5422)
		(width 0.08382)
		(layer "In9.Cu")
		(net "FM_VIRTUAL_RESEAT_BMC")
	)
	(segment
		(start 56.086502 -40.172386)
		(end 56.614568 -40.172386)
		(width 0.08382)
		(layer "In9.Cu")
		(net "FM_VIRTUAL_RESEAT_BMC")
	)
	(segment
		(start 58.4708 -45.5422)
		(end 59.304936 -46.376336)
		(width 0.08382)
		(layer "In9.Cu")
		(net "FM_VIRTUAL_RESEAT_BMC")
	)
	(segment
		(start 61.86551 -56.98236)
		(end 62.51575 -56.98236)
		(width 0.08382)
		(layer "In9.Cu")
		(net "FM_VIRTUAL_RESEAT_BMC")
	)
	(segment
		(start 61.010292 -56.16321)
		(end 61.571124 -56.16321)
		(width 0.08382)
		(layer "In9.Cu")
		(net "FM_VIRTUAL_RESEAT_BMC")
	)
	(segment
		(start 56.614568 -40.172386)
		(end 56.881268 -40.439086)
		(width 0.08382)
		(layer "In9.Cu")
		(net "FM_VIRTUAL_RESEAT_BMC")
	)
	(segment
		(start 60.201302 -54.747922)
		(end 60.899294 -55.445914)
		(width 0.08382)
		(layer "In9.Cu")
		(net "FM_VIRTUAL_RESEAT_BMC")
	)
	(segment
		(start 57.420002 -42.577766)
		(end 57.703212 -42.860976)
		(width 0.08382)
		(layer "In9.Cu")
		(net "FM_VIRTUAL_RESEAT_BMC")
	)
	(segment
		(start 56.881268 -42.295064)
		(end 57.16397 -42.577766)
		(width 0.08382)
		(layer "In9.Cu")
		(net "FM_VIRTUAL_RESEAT_BMC")
	)
	(segment
		(start 57.703212 -44.375832)
		(end 58.4708 -45.14342)
		(width 0.08382)
		(layer "In9.Cu")
		(net "FM_VIRTUAL_RESEAT_BMC")
	)
	(segment
		(start 18.264124 -92.791788)
		(end 18.659348 -93.187012)
		(width 0.11684)
		(layer "F.Cu")
		(net "RST_ROT_CPU_R_N")
	)
	(via
		(at 18.264124 -92.791788)
		(size 0.4572)
		(drill 0.254)
		(layers "F.Cu" "B.Cu")
		(net "RST_ROT_CPU_R_N")
	)
	(segment
		(start 13.21816 -93.23324)
		(end 13.21816 -93.231462)
		(width 0.11684)
		(layer "B.Cu")
		(net "RST_ROT_CPU_R_N")
	)
	(segment
		(start 15.748254 -91.694)
		(end 17.234662 -93.180408)
		(width 0.11684)
		(layer "B.Cu")
		(net "RST_ROT_CPU_R_N")
	)
	(segment
		(start 12.71905 -93.472)
		(end 12.9794 -93.472)
		(width 0.11684)
		(layer "B.Cu")
		(net "RST_ROT_CPU_R_N")
	)
	(segment
		(start 17.875504 -93.180408)
		(end 18.264124 -92.791788)
		(width 0.11684)
		(layer "B.Cu")
		(net "RST_ROT_CPU_R_N")
	)
	(segment
		(start 12.9794 -93.472)
		(end 13.21816 -93.23324)
		(width 0.11684)
		(layer "B.Cu")
		(net "RST_ROT_CPU_R_N")
	)
	(segment
		(start 14.755622 -91.694)
		(end 15.748254 -91.694)
		(width 0.11684)
		(layer "B.Cu")
		(net "RST_ROT_CPU_R_N")
	)
	(segment
		(start 13.21816 -93.231462)
		(end 14.755622 -91.694)
		(width 0.11684)
		(layer "B.Cu")
		(net "RST_ROT_CPU_R_N")
	)
	(segment
		(start 17.234662 -93.180408)
		(end 17.875504 -93.180408)
		(width 0.11684)
		(layer "B.Cu")
		(net "RST_ROT_CPU_R_N")
	)
	(segment
		(start 31.5849 -89.8017)
		(end 31.5849 -89.5223)
		(width 0.11684)
		(layer "F.Cu")
		(net "RST_ROT_CPU_N")
	)
	(segment
		(start 34.7091 -86.7791)
		(end 34.544 -86.614)
		(width 0.11684)
		(layer "F.Cu")
		(net "RST_ROT_CPU_N")
	)
	(segment
		(start 38.968426 -86.862412)
		(end 38.704012 -86.862412)
		(width 0.11684)
		(layer "F.Cu")
		(net "RST_ROT_CPU_N")
	)
	(segment
		(start 46.7614 -29.843476)
		(end 46.6852 -29.919676)
		(width 0.11684)
		(layer "F.Cu")
		(net "RST_ROT_CPU_N")
	)
	(segment
		(start 33.147 -86.614)
		(end 32.29356 -87.46744)
		(width 0.11684)
		(layer "F.Cu")
		(net "RST_ROT_CPU_N")
	)
	(segment
		(start 46.6852 -29.919676)
		(end 46.6852 -30.46095)
		(width 0.11684)
		(layer "F.Cu")
		(net "RST_ROT_CPU_N")
	)
	(segment
		(start 32.29356 -87.46744)
		(end 32.29356 -88.81364)
		(width 0.11684)
		(layer "F.Cu")
		(net "RST_ROT_CPU_N")
	)
	(segment
		(start 46.7614 -29.578046)
		(end 46.7614 -29.843476)
		(width 0.11684)
		(layer "F.Cu")
		(net "RST_ROT_CPU_N")
	)
	(segment
		(start 30.292294 -90.551)
		(end 30.8356 -90.551)
		(width 0.11684)
		(layer "F.Cu")
		(net "RST_ROT_CPU_N")
	)
	(segment
		(start 38.704012 -86.862412)
		(end 38.6207 -86.7791)
		(width 0.11684)
		(layer "F.Cu")
		(net "RST_ROT_CPU_N")
	)
	(segment
		(start 32.29356 -88.81364)
		(end 31.5849 -89.5223)
		(width 0.11684)
		(layer "F.Cu")
		(net "RST_ROT_CPU_N")
	)
	(segment
		(start 30.8356 -90.551)
		(end 31.5849 -89.8017)
		(width 0.11684)
		(layer "F.Cu")
		(net "RST_ROT_CPU_N")
	)
	(segment
		(start 30.1752 -90.74785)
		(end 30.1752 -90.668094)
		(width 0.11684)
		(layer "F.Cu")
		(net "RST_ROT_CPU_N")
	)
	(segment
		(start 34.544 -86.614)
		(end 33.147 -86.614)
		(width 0.11684)
		(layer "F.Cu")
		(net "RST_ROT_CPU_N")
	)
	(segment
		(start 46.921166 -29.41828)
		(end 46.7614 -29.578046)
		(width 0.11684)
		(layer "F.Cu")
		(net "RST_ROT_CPU_N")
	)
	(segment
		(start 38.6207 -86.7791)
		(end 34.7091 -86.7791)
		(width 0.11684)
		(layer "F.Cu")
		(net "RST_ROT_CPU_N")
	)
	(segment
		(start 30.1752 -90.668094)
		(end 30.292294 -90.551)
		(width 0.11684)
		(layer "F.Cu")
		(net "RST_ROT_CPU_N")
	)
	(via
		(at 34.544 -86.614)
		(size 0.508)
		(drill 0.254)
		(layers "F.Cu" "B.Cu")
		(net "RST_ROT_CPU_N")
	)
	(via
		(at 22.3012 -104.2162)
		(size 0.508)
		(drill 0.254)
		(layers "F.Cu" "B.Cu")
		(net "RST_ROT_CPU_N")
	)
	(via
		(at 22.733 -109.728)
		(size 0.6604)
		(drill 0.3302)
		(layers "F.Cu" "B.Cu")
		(net "RST_ROT_CPU_N")
	)
	(via
		(at 46.921166 -29.41828)
		(size 0.508)
		(drill 0.254)
		(layers "F.Cu" "B.Cu")
		(net "RST_ROT_CPU_N")
	)
	(via
		(at 38.968426 -86.862412)
		(size 0.508)
		(drill 0.254)
		(layers "F.Cu" "B.Cu")
		(net "RST_ROT_CPU_N")
	)
	(via
		(at 31.5849 -89.5223)
		(size 0.508)
		(drill 0.254)
		(layers "F.Cu" "B.Cu")
		(net "RST_ROT_CPU_N")
	)
	(via
		(at 11.30935 -92.456)
		(size 0.508)
		(drill 0.254)
		(layers "F.Cu" "B.Cu")
		(net "RST_ROT_CPU_N")
	)
	(segment
		(start 21.9583 -110.5027)
		(end 22.733 -109.728)
		(width 0.11684)
		(layer "B.Cu")
		(net "RST_ROT_CPU_N")
	)
	(segment
		(start 24.545036 -116.170964)
		(end 25.26792 -115.44808)
		(width 0.11684)
		(layer "B.Cu")
		(net "RST_ROT_CPU_N")
	)
	(segment
		(start 25.02408 -113.792)
		(end 24.332692 -113.792)
		(width 0.11684)
		(layer "B.Cu")
		(net "RST_ROT_CPU_N")
	)
	(segment
		(start 21.68398 -106.3625)
		(end 22.22373 -106.90225)
		(width 0.11684)
		(layer "B.Cu")
		(net "RST_ROT_CPU_N")
	)
	(segment
		(start 11.91895 -93.427296)
		(end 11.77417 -93.282516)
		(width 0.11684)
		(layer "B.Cu")
		(net "RST_ROT_CPU_N")
	)
	(segment
		(start 24.332692 -113.792)
		(end 21.9583 -111.417608)
		(width 0.11684)
		(layer "B.Cu")
		(net "RST_ROT_CPU_N")
	)
	(segment
		(start 22.5552 -107.315)
		(end 22.5552 -106.90225)
		(width 0.11684)
		(layer "B.Cu")
		(net "RST_ROT_CPU_N")
	)
	(segment
		(start 11.30935 -92.814394)
		(end 11.30935 -92.456)
		(width 0.11684)
		(layer "B.Cu")
		(net "RST_ROT_CPU_N")
	)
	(segment
		(start 25.26792 -114.03584)
		(end 25.02408 -113.792)
		(width 0.11684)
		(layer "B.Cu")
		(net "RST_ROT_CPU_N")
	)
	(segment
		(start 24.545036 -118.25986)
		(end 24.545036 -116.170964)
		(width 0.11684)
		(layer "B.Cu")
		(net "RST_ROT_CPU_N")
	)
	(segment
		(start 22.3012 -104.2162)
		(end 21.68398 -104.83342)
		(width 0.11684)
		(layer "B.Cu")
		(net "RST_ROT_CPU_N")
	)
	(segment
		(start 21.68398 -104.83342)
		(end 21.68398 -106.3625)
		(width 0.11684)
		(layer "B.Cu")
		(net "RST_ROT_CPU_N")
	)
	(segment
		(start 21.9583 -111.417608)
		(end 21.9583 -110.5027)
		(width 0.11684)
		(layer "B.Cu")
		(net "RST_ROT_CPU_N")
	)
	(segment
		(start 11.77417 -93.282516)
		(end 11.77417 -93.279214)
		(width 0.11684)
		(layer "B.Cu")
		(net "RST_ROT_CPU_N")
	)
	(segment
		(start 22.733 -109.728)
		(end 21.9583 -108.9533)
		(width 0.11684)
		(layer "B.Cu")
		(net "RST_ROT_CPU_N")
	)
	(segment
		(start 25.26792 -115.44808)
		(end 25.26792 -114.03584)
		(width 0.11684)
		(layer "B.Cu")
		(net "RST_ROT_CPU_N")
	)
	(segment
		(start 22.22373 -106.90225)
		(end 22.5552 -106.90225)
		(width 0.11684)
		(layer "B.Cu")
		(net "RST_ROT_CPU_N")
	)
	(segment
		(start 21.9583 -108.9533)
		(end 21.9583 -107.9119)
		(width 0.11684)
		(layer "B.Cu")
		(net "RST_ROT_CPU_N")
	)
	(segment
		(start 21.9583 -107.9119)
		(end 22.5552 -107.315)
		(width 0.11684)
		(layer "B.Cu")
		(net "RST_ROT_CPU_N")
	)
	(segment
		(start 11.91895 -93.472)
		(end 11.91895 -93.427296)
		(width 0.11684)
		(layer "B.Cu")
		(net "RST_ROT_CPU_N")
	)
	(segment
		(start 11.77417 -93.279214)
		(end 11.30935 -92.814394)
		(width 0.11684)
		(layer "B.Cu")
		(net "RST_ROT_CPU_N")
	)
	(segment
		(start 12.07008 -91.69527)
		(end 11.30935 -92.456)
		(width 0.08382)
		(layer "In2.Cu")
		(net "RST_ROT_CPU_N")
	)
	(segment
		(start 12.928346 -90.424)
		(end 12.07008 -91.282266)
		(width 0.08382)
		(layer "In2.Cu")
		(net "RST_ROT_CPU_N")
	)
	(segment
		(start 12.07008 -91.282266)
		(end 12.07008 -91.69527)
		(width 0.08382)
		(layer "In2.Cu")
		(net "RST_ROT_CPU_N")
	)
	(segment
		(start 27.49169 -87.76589)
		(end 27.280362 -87.554562)
		(width 0.08382)
		(layer "In2.Cu")
		(net "RST_ROT_CPU_N")
	)
	(segment
		(start 14.5288 -89.1794)
		(end 13.2842 -90.424)
		(width 0.08382)
		(layer "In2.Cu")
		(net "RST_ROT_CPU_N")
	)
	(segment
		(start 31.0261 -89.5223)
		(end 29.26969 -87.76589)
		(width 0.08382)
		(layer "In2.Cu")
		(net "RST_ROT_CPU_N")
	)
	(segment
		(start 29.26969 -87.76589)
		(end 27.49169 -87.76589)
		(width 0.08382)
		(layer "In2.Cu")
		(net "RST_ROT_CPU_N")
	)
	(segment
		(start 24.732742 -88.11641)
		(end 21.94179 -88.11641)
		(width 0.08382)
		(layer "In2.Cu")
		(net "RST_ROT_CPU_N")
	)
	(segment
		(start 31.5849 -89.5223)
		(end 31.0261 -89.5223)
		(width 0.08382)
		(layer "In2.Cu")
		(net "RST_ROT_CPU_N")
	)
	(segment
		(start 20.8788 -89.1794)
		(end 14.5288 -89.1794)
		(width 0.08382)
		(layer "In2.Cu")
		(net "RST_ROT_CPU_N")
	)
	(segment
		(start 13.2842 -90.424)
		(end 12.928346 -90.424)
		(width 0.08382)
		(layer "In2.Cu")
		(net "RST_ROT_CPU_N")
	)
	(segment
		(start 25.29459 -87.554562)
		(end 24.732742 -88.11641)
		(width 0.08382)
		(layer "In2.Cu")
		(net "RST_ROT_CPU_N")
	)
	(segment
		(start 21.94179 -88.11641)
		(end 20.8788 -89.1794)
		(width 0.08382)
		(layer "In2.Cu")
		(net "RST_ROT_CPU_N")
	)
	(segment
		(start 27.280362 -87.554562)
		(end 25.29459 -87.554562)
		(width 0.08382)
		(layer "In2.Cu")
		(net "RST_ROT_CPU_N")
	)
	(segment
		(start 26.96718 -60.189872)
		(end 26.96718 -61.37402)
		(width 0.10668)
		(layer "In7.Cu")
		(net "RST_ROT_CPU_N")
	)
	(segment
		(start 29.71038 -75.81773)
		(end 30.77464 -76.88199)
		(width 0.10668)
		(layer "In7.Cu")
		(net "RST_ROT_CPU_N")
	)
	(segment
		(start 32.3342 -37.921438)
		(end 30.25013 -40.005508)
		(width 0.10668)
		(layer "In7.Cu")
		(net "RST_ROT_CPU_N")
	)
	(segment
		(start 25.88768 -63.959232)
		(end 25.88768 -65.105026)
		(width 0.10668)
		(layer "In7.Cu")
		(net "RST_ROT_CPU_N")
	)
	(segment
		(start 25.88768 -65.105026)
		(end 26.5684 -65.785746)
		(width 0.10668)
		(layer "In7.Cu")
		(net "RST_ROT_CPU_N")
	)
	(segment
		(start 40.514524 -26.78176)
		(end 37.794692 -26.78176)
		(width 0.10668)
		(layer "In7.Cu")
		(net "RST_ROT_CPU_N")
	)
	(segment
		(start 35.320986 -28.429204)
		(end 35.320986 -29.258768)
		(width 0.10668)
		(layer "In7.Cu")
		(net "RST_ROT_CPU_N")
	)
	(segment
		(start 22.89556 -55.01132)
		(end 23.99284 -56.1086)
		(width 0.10668)
		(layer "In7.Cu")
		(net "RST_ROT_CPU_N")
	)
	(segment
		(start 27.065224 -70.6501)
		(end 27.065478 -70.650354)
		(width 0.10668)
		(layer "In7.Cu")
		(net "RST_ROT_CPU_N")
	)
	(segment
		(start 27.559 -70.6501)
		(end 27.8638 -70.9549)
		(width 0.10668)
		(layer "In7.Cu")
		(net "RST_ROT_CPU_N")
	)
	(segment
		(start 46.53788 -28.0162)
		(end 41.748964 -28.0162)
		(width 0.10668)
		(layer "In7.Cu")
		(net "RST_ROT_CPU_N")
	)
	(segment
		(start 26.12136 -62.21984)
		(end 26.12136 -63.725552)
		(width 0.10668)
		(layer "In7.Cu")
		(net "RST_ROT_CPU_N")
	)
	(segment
		(start 22.89556 -53.17744)
		(end 22.89556 -55.01132)
		(width 0.10668)
		(layer "In7.Cu")
		(net "RST_ROT_CPU_N")
	)
	(segment
		(start 34.3281 -30.251654)
		(end 34.3281 -31.085028)
		(width 0.10668)
		(layer "In7.Cu")
		(net "RST_ROT_CPU_N")
	)
	(segment
		(start 29.71038 -73.337166)
		(end 29.71038 -75.81773)
		(width 0.10668)
		(layer "In7.Cu")
		(net "RST_ROT_CPU_N")
	)
	(segment
		(start 26.5684 -70.153276)
		(end 26.5684 -70.15353)
		(width 0.10668)
		(layer "In7.Cu")
		(net "RST_ROT_CPU_N")
	)
	(segment
		(start 46.921166 -28.399486)
		(end 46.53788 -28.0162)
		(width 0.10668)
		(layer "In7.Cu")
		(net "RST_ROT_CPU_N")
	)
	(segment
		(start 30.25013 -40.005508)
		(end 30.25013 -40.79367)
		(width 0.10668)
		(layer "In7.Cu")
		(net "RST_ROT_CPU_N")
	)
	(segment
		(start 27.342846 -70.650354)
		(end 27.3431 -70.6501)
		(width 0.10668)
		(layer "In7.Cu")
		(net "RST_ROT_CPU_N")
	)
	(segment
		(start 30.77464 -77.148182)
		(end 32.941768 -79.31531)
		(width 0.10668)
		(layer "In7.Cu")
		(net "RST_ROT_CPU_N")
	)
	(segment
		(start 36.62807 -84.328)
		(end 38.3032 -84.328)
		(width 0.10668)
		(layer "In7.Cu")
		(net "RST_ROT_CPU_N")
	)
	(segment
		(start 26.96718 -61.37402)
		(end 26.12136 -62.21984)
		(width 0.10668)
		(layer "In7.Cu")
		(net "RST_ROT_CPU_N")
	)
	(segment
		(start 34.3281 -31.085028)
		(end 32.3342 -33.078928)
		(width 0.10668)
		(layer "In7.Cu")
		(net "RST_ROT_CPU_N")
	)
	(segment
		(start 27.03068 -41.9862)
		(end 24.047196 -44.969684)
		(width 0.10668)
		(layer "In7.Cu")
		(net "RST_ROT_CPU_N")
	)
	(segment
		(start 23.5966 -46.057058)
		(end 23.5966 -52.4764)
		(width 0.10668)
		(layer "In7.Cu")
		(net "RST_ROT_CPU_N")
	)
	(segment
		(start 26.5684 -68.886324)
		(end 26.4033 -69.051424)
		(width 0.10668)
		(layer "In7.Cu")
		(net "RST_ROT_CPU_N")
	)
	(segment
		(start 27.8638 -70.9549)
		(end 27.8638 -72.328278)
		(width 0.10668)
		(layer "In7.Cu")
		(net "RST_ROT_CPU_N")
	)
	(segment
		(start 27.8638 -72.328278)
		(end 28.14955 -72.614028)
		(width 0.10668)
		(layer "In7.Cu")
		(net "RST_ROT_CPU_N")
	)
	(segment
		(start 35.607498 -28.142692)
		(end 35.320986 -28.429204)
		(width 0.10668)
		(layer "In7.Cu")
		(net "RST_ROT_CPU_N")
	)
	(segment
		(start 28.987242 -72.614028)
		(end 29.71038 -73.337166)
		(width 0.10668)
		(layer "In7.Cu")
		(net "RST_ROT_CPU_N")
	)
	(segment
		(start 38.3032 -84.328)
		(end 38.968426 -84.993226)
		(width 0.10668)
		(layer "In7.Cu")
		(net "RST_ROT_CPU_N")
	)
	(segment
		(start 26.5684 -65.785746)
		(end 26.5684 -68.886324)
		(width 0.10668)
		(layer "In7.Cu")
		(net "RST_ROT_CPU_N")
	)
	(segment
		(start 27.06497 -70.6501)
		(end 27.065224 -70.6501)
		(width 0.10668)
		(layer "In7.Cu")
		(net "RST_ROT_CPU_N")
	)
	(segment
		(start 37.794692 -26.78176)
		(end 36.43376 -28.142692)
		(width 0.10668)
		(layer "In7.Cu")
		(net "RST_ROT_CPU_N")
	)
	(segment
		(start 23.5966 -52.4764)
		(end 22.89556 -53.17744)
		(width 0.10668)
		(layer "In7.Cu")
		(net "RST_ROT_CPU_N")
	)
	(segment
		(start 23.99284 -57.215532)
		(end 26.96718 -60.189872)
		(width 0.10668)
		(layer "In7.Cu")
		(net "RST_ROT_CPU_N")
	)
	(segment
		(start 32.3342 -33.078928)
		(end 32.3342 -37.921438)
		(width 0.10668)
		(layer "In7.Cu")
		(net "RST_ROT_CPU_N")
	)
	(segment
		(start 27.065478 -70.650354)
		(end 27.342846 -70.650354)
		(width 0.10668)
		(layer "In7.Cu")
		(net "RST_ROT_CPU_N")
	)
	(segment
		(start 46.921166 -29.41828)
		(end 46.921166 -28.399486)
		(width 0.10668)
		(layer "In7.Cu")
		(net "RST_ROT_CPU_N")
	)
	(segment
		(start 27.3431 -70.6501)
		(end 27.559 -70.6501)
		(width 0.10668)
		(layer "In7.Cu")
		(net "RST_ROT_CPU_N")
	)
	(segment
		(start 32.941768 -79.31531)
		(end 32.941768 -80.641698)
		(width 0.10668)
		(layer "In7.Cu")
		(net "RST_ROT_CPU_N")
	)
	(segment
		(start 38.968426 -84.993226)
		(end 38.968426 -86.862412)
		(width 0.10668)
		(layer "In7.Cu")
		(net "RST_ROT_CPU_N")
	)
	(segment
		(start 26.4033 -69.051424)
		(end 26.4033 -69.988176)
		(width 0.10668)
		(layer "In7.Cu")
		(net "RST_ROT_CPU_N")
	)
	(segment
		(start 36.43376 -28.142692)
		(end 35.607498 -28.142692)
		(width 0.10668)
		(layer "In7.Cu")
		(net "RST_ROT_CPU_N")
	)
	(segment
		(start 26.4033 -69.988176)
		(end 26.5684 -70.153276)
		(width 0.10668)
		(layer "In7.Cu")
		(net "RST_ROT_CPU_N")
	)
	(segment
		(start 30.77464 -76.88199)
		(end 30.77464 -77.148182)
		(width 0.10668)
		(layer "In7.Cu")
		(net "RST_ROT_CPU_N")
	)
	(segment
		(start 32.941768 -80.641698)
		(end 36.62807 -84.328)
		(width 0.10668)
		(layer "In7.Cu")
		(net "RST_ROT_CPU_N")
	)
	(segment
		(start 26.5684 -70.15353)
		(end 27.06497 -70.6501)
		(width 0.10668)
		(layer "In7.Cu")
		(net "RST_ROT_CPU_N")
	)
	(segment
		(start 28.14955 -72.614028)
		(end 28.987242 -72.614028)
		(width 0.10668)
		(layer "In7.Cu")
		(net "RST_ROT_CPU_N")
	)
	(segment
		(start 30.25013 -40.79367)
		(end 29.0576 -41.9862)
		(width 0.10668)
		(layer "In7.Cu")
		(net "RST_ROT_CPU_N")
	)
	(segment
		(start 26.12136 -63.725552)
		(end 25.88768 -63.959232)
		(width 0.10668)
		(layer "In7.Cu")
		(net "RST_ROT_CPU_N")
	)
	(segment
		(start 23.99284 -56.1086)
		(end 23.99284 -57.215532)
		(width 0.10668)
		(layer "In7.Cu")
		(net "RST_ROT_CPU_N")
	)
	(segment
		(start 29.0576 -41.9862)
		(end 27.03068 -41.9862)
		(width 0.10668)
		(layer "In7.Cu")
		(net "RST_ROT_CPU_N")
	)
	(segment
		(start 41.748964 -28.0162)
		(end 40.514524 -26.78176)
		(width 0.10668)
		(layer "In7.Cu")
		(net "RST_ROT_CPU_N")
	)
	(segment
		(start 24.047196 -44.969684)
		(end 23.5966 -46.057058)
		(width 0.10668)
		(layer "In7.Cu")
		(net "RST_ROT_CPU_N")
	)
	(segment
		(start 35.320986 -29.258768)
		(end 34.3281 -30.251654)
		(width 0.10668)
		(layer "In7.Cu")
		(net "RST_ROT_CPU_N")
	)
	(segment
		(start 31.04769 -98.77171)
		(end 31.073852 -98.77171)
		(width 0.08382)
		(layer "In9.Cu")
		(net "RST_ROT_CPU_N")
	)
	(segment
		(start 22.3012 -104.2162)
		(end 22.3012 -104.4194)
		(width 0.08382)
		(layer "In9.Cu")
		(net "RST_ROT_CPU_N")
	)
	(segment
		(start 23.4696 -104.6226)
		(end 23.94331 -104.14889)
		(width 0.08382)
		(layer "In9.Cu")
		(net "RST_ROT_CPU_N")
	)
	(segment
		(start 23.94331 -104.14889)
		(end 23.94331 -102.87889)
		(width 0.08382)
		(layer "In9.Cu")
		(net "RST_ROT_CPU_N")
	)
	(segment
		(start 31.453328 -98.76409)
		(end 31.460948 -98.77171)
		(width 0.08382)
		(layer "In9.Cu")
		(net "RST_ROT_CPU_N")
	)
	(segment
		(start 32.85998 -98.77171)
		(end 33.63595 -97.99574)
		(width 0.08382)
		(layer "In9.Cu")
		(net "RST_ROT_CPU_N")
	)
	(segment
		(start 34.44113 -86.71687)
		(end 34.544 -86.614)
		(width 0.08382)
		(layer "In9.Cu")
		(net "RST_ROT_CPU_N")
	)
	(segment
		(start 33.88233 -94.89313)
		(end 33.88233 -92.432124)
		(width 0.08382)
		(layer "In9.Cu")
		(net "RST_ROT_CPU_N")
	)
	(segment
		(start 22.5044 -104.6226)
		(end 23.4696 -104.6226)
		(width 0.08382)
		(layer "In9.Cu")
		(net "RST_ROT_CPU_N")
	)
	(segment
		(start 34.25571 -90.78341)
		(end 34.21761 -90.74531)
		(width 0.08382)
		(layer "In9.Cu")
		(net "RST_ROT_CPU_N")
	)
	(segment
		(start 27.364182 -99.458018)
		(end 30.539182 -99.458018)
		(width 0.08382)
		(layer "In9.Cu")
		(net "RST_ROT_CPU_N")
	)
	(segment
		(start 34.21761 -90.74531)
		(end 34.21761 -89.59723)
		(width 0.08382)
		(layer "In9.Cu")
		(net "RST_ROT_CPU_N")
	)
	(segment
		(start 34.21761 -89.59723)
		(end 34.44113 -89.37371)
		(width 0.08382)
		(layer "In9.Cu")
		(net "RST_ROT_CPU_N")
	)
	(segment
		(start 30.8102 -99.0092)
		(end 31.04769 -98.77171)
		(width 0.08382)
		(layer "In9.Cu")
		(net "RST_ROT_CPU_N")
	)
	(segment
		(start 34.44113 -89.37371)
		(end 34.44113 -86.71687)
		(width 0.08382)
		(layer "In9.Cu")
		(net "RST_ROT_CPU_N")
	)
	(segment
		(start 23.94331 -102.87889)
		(end 27.364182 -99.458018)
		(width 0.08382)
		(layer "In9.Cu")
		(net "RST_ROT_CPU_N")
	)
	(segment
		(start 30.8102 -99.187)
		(end 30.8102 -99.0092)
		(width 0.08382)
		(layer "In9.Cu")
		(net "RST_ROT_CPU_N")
	)
	(segment
		(start 33.63595 -97.99574)
		(end 33.63595 -95.487998)
		(width 0.08382)
		(layer "In9.Cu")
		(net "RST_ROT_CPU_N")
	)
	(segment
		(start 33.63595 -95.487998)
		(end 33.88233 -94.89313)
		(width 0.08382)
		(layer "In9.Cu")
		(net "RST_ROT_CPU_N")
	)
	(segment
		(start 30.539182 -99.458018)
		(end 30.8102 -99.187)
		(width 0.08382)
		(layer "In9.Cu")
		(net "RST_ROT_CPU_N")
	)
	(segment
		(start 34.25571 -92.058744)
		(end 34.25571 -90.78341)
		(width 0.08382)
		(layer "In9.Cu")
		(net "RST_ROT_CPU_N")
	)
	(segment
		(start 31.081472 -98.76409)
		(end 31.453328 -98.76409)
		(width 0.08382)
		(layer "In9.Cu")
		(net "RST_ROT_CPU_N")
	)
	(segment
		(start 31.073852 -98.77171)
		(end 31.081472 -98.76409)
		(width 0.08382)
		(layer "In9.Cu")
		(net "RST_ROT_CPU_N")
	)
	(segment
		(start 33.88233 -92.432124)
		(end 34.25571 -92.058744)
		(width 0.08382)
		(layer "In9.Cu")
		(net "RST_ROT_CPU_N")
	)
	(segment
		(start 22.3012 -104.4194)
		(end 22.5044 -104.6226)
		(width 0.08382)
		(layer "In9.Cu")
		(net "RST_ROT_CPU_N")
	)
	(segment
		(start 31.460948 -98.77171)
		(end 32.85998 -98.77171)
		(width 0.08382)
		(layer "In9.Cu")
		(net "RST_ROT_CPU_N")
	)
	(segment
		(start 68.5546 -108.203746)
		(end 68.332096 -108.42625)
		(width 0.11684)
		(layer "F.Cu")
		(net "FM_VIRTUAL_RESEAT")
	)
	(segment
		(start 68.345304 -106.67365)
		(end 68.5546 -106.882946)
		(width 0.11684)
		(layer "F.Cu")
		(net "FM_VIRTUAL_RESEAT")
	)
	(segment
		(start 66.3956 -109.245146)
		(end 66.3956 -110.0074)
		(width 0.11684)
		(layer "F.Cu")
		(net "FM_VIRTUAL_RESEAT")
	)
	(segment
		(start 68.5546 -106.882946)
		(end 68.5546 -108.203746)
		(width 0.11684)
		(layer "F.Cu")
		(net "FM_VIRTUAL_RESEAT")
	)
	(segment
		(start 66.9798 -110.5916)
		(end 66.9798 -110.744)
		(width 0.11684)
		(layer "F.Cu")
		(net "FM_VIRTUAL_RESEAT")
	)
	(segment
		(start 66.3956 -110.0074)
		(end 66.9798 -110.5916)
		(width 0.11684)
		(layer "F.Cu")
		(net "FM_VIRTUAL_RESEAT")
	)
	(segment
		(start 66.9798 -110.744)
		(end 67.34302 -111.10722)
		(width 0.11684)
		(layer "F.Cu")
		(net "FM_VIRTUAL_RESEAT")
	)
	(segment
		(start 67.214496 -108.42625)
		(end 66.3956 -109.245146)
		(width 0.11684)
		(layer "F.Cu")
		(net "FM_VIRTUAL_RESEAT")
	)
	(segment
		(start 68.332096 -108.42625)
		(end 68.072 -108.42625)
		(width 0.11684)
		(layer "F.Cu")
		(net "FM_VIRTUAL_RESEAT")
	)
	(segment
		(start 67.818 -106.67365)
		(end 68.345304 -106.67365)
		(width 0.11684)
		(layer "F.Cu")
		(net "FM_VIRTUAL_RESEAT")
	)
	(segment
		(start 68.072 -108.42625)
		(end 67.214496 -108.42625)
		(width 0.11684)
		(layer "F.Cu")
		(net "FM_VIRTUAL_RESEAT")
	)
	(segment
		(start 67.34302 -111.10722)
		(end 67.34302 -111.77778)
		(width 0.11684)
		(layer "F.Cu")
		(net "FM_VIRTUAL_RESEAT")
	)
	(via
		(at 66.3956 -110.0074)
		(size 0.762)
		(drill 0.381)
		(layers "F.Cu" "B.Cu")
		(net "FM_VIRTUAL_RESEAT")
	)
	(via
		(at 67.34302 -111.77778)
		(size 0.508)
		(drill 0.254)
		(layers "F.Cu" "B.Cu")
		(net "FM_VIRTUAL_RESEAT")
	)
	(segment
		(start 67.861434 -117.23878)
		(end 67.861434 -118.458488)
		(width 0.11684)
		(layer "B.Cu")
		(net "FM_VIRTUAL_RESEAT")
	)
	(segment
		(start 67.4624 -113.3348)
		(end 67.4624 -116.839746)
		(width 0.11684)
		(layer "B.Cu")
		(net "FM_VIRTUAL_RESEAT")
	)
	(segment
		(start 67.2084 -113.0808)
		(end 67.4624 -113.3348)
		(width 0.11684)
		(layer "B.Cu")
		(net "FM_VIRTUAL_RESEAT")
	)
	(segment
		(start 67.861434 -118.458488)
		(end 67.85991 -118.460012)
		(width 0.11684)
		(layer "B.Cu")
		(net "FM_VIRTUAL_RESEAT")
	)
	(segment
		(start 67.4624 -116.839746)
		(end 67.861434 -117.23878)
		(width 0.11684)
		(layer "B.Cu")
		(net "FM_VIRTUAL_RESEAT")
	)
	(segment
		(start 67.34302 -111.77778)
		(end 67.2084 -111.9124)
		(width 0.11684)
		(layer "B.Cu")
		(net "FM_VIRTUAL_RESEAT")
	)
	(segment
		(start 67.2084 -111.9124)
		(end 67.2084 -113.0808)
		(width 0.11684)
		(layer "B.Cu")
		(net "FM_VIRTUAL_RESEAT")
	)
	(segment
		(start 72.02805 -105.7148)
		(end 72.1614 -105.84815)
		(width 0.11684)
		(layer "F.Cu")
		(net "FM_PRSNT_1_N")
	)
	(segment
		(start 71.4502 -105.7148)
		(end 72.02805 -105.7148)
		(width 0.11684)
		(layer "F.Cu")
		(net "FM_PRSNT_1_N")
	)
	(via
		(at 18.4912 -111.2266)
		(size 0.508)
		(drill 0.254)
		(layers "F.Cu" "B.Cu")
		(net "FM_PRSNT_1_N")
	)
	(via
		(at 71.4502 -105.7148)
		(size 0.508)
		(drill 0.254)
		(layers "F.Cu" "B.Cu")
		(net "FM_PRSNT_1_N")
	)
	(segment
		(start 22.17547 -117.333776)
		(end 22.17547 -118.22938)
		(width 0.11684)
		(layer "B.Cu")
		(net "FM_PRSNT_1_N")
	)
	(segment
		(start 22.17547 -118.22938)
		(end 22.14499 -118.25986)
		(width 0.11684)
		(layer "B.Cu")
		(net "FM_PRSNT_1_N")
	)
	(segment
		(start 21.336 -115.5954)
		(end 21.336 -115.6716)
		(width 0.11684)
		(layer "B.Cu")
		(net "FM_PRSNT_1_N")
	)
	(segment
		(start 22.07006 -117.228366)
		(end 22.17547 -117.333776)
		(width 0.11684)
		(layer "B.Cu")
		(net "FM_PRSNT_1_N")
	)
	(segment
		(start 18.4912 -111.2266)
		(end 19.43608 -112.17148)
		(width 0.11684)
		(layer "B.Cu")
		(net "FM_PRSNT_1_N")
	)
	(segment
		(start 19.43608 -113.69548)
		(end 21.336 -115.5954)
		(width 0.11684)
		(layer "B.Cu")
		(net "FM_PRSNT_1_N")
	)
	(segment
		(start 22.07006 -116.40566)
		(end 22.07006 -117.228366)
		(width 0.11684)
		(layer "B.Cu")
		(net "FM_PRSNT_1_N")
	)
	(segment
		(start 21.336 -115.6716)
		(end 22.07006 -116.40566)
		(width 0.11684)
		(layer "B.Cu")
		(net "FM_PRSNT_1_N")
	)
	(segment
		(start 19.43608 -112.17148)
		(end 19.43608 -113.69548)
		(width 0.11684)
		(layer "B.Cu")
		(net "FM_PRSNT_1_N")
	)
	(segment
		(start 59.0296 -111.0234)
		(end 58.70829 -111.34471)
		(width 0.08382)
		(layer "In2.Cu")
		(net "FM_PRSNT_1_N")
	)
	(segment
		(start 51.537616 -111.9886)
		(end 48.221392 -111.9886)
		(width 0.08382)
		(layer "In2.Cu")
		(net "FM_PRSNT_1_N")
	)
	(segment
		(start 71.4502 -105.7148)
		(end 70.236588 -106.928412)
		(width 0.08382)
		(layer "In2.Cu")
		(net "FM_PRSNT_1_N")
	)
	(segment
		(start 48.221392 -111.9886)
		(end 47.334932 -111.10214)
		(width 0.08382)
		(layer "In2.Cu")
		(net "FM_PRSNT_1_N")
	)
	(segment
		(start 53.153056 -111.31931)
		(end 51.537616 -111.9886)
		(width 0.08382)
		(layer "In2.Cu")
		(net "FM_PRSNT_1_N")
	)
	(segment
		(start 43.7896 -111.10214)
		(end 43.482768 -111.408972)
		(width 0.08382)
		(layer "In2.Cu")
		(net "FM_PRSNT_1_N")
	)
	(segment
		(start 61.442346 -111.0234)
		(end 59.0296 -111.0234)
		(width 0.08382)
		(layer "In2.Cu")
		(net "FM_PRSNT_1_N")
	)
	(segment
		(start 55.52821 -111.31931)
		(end 53.153056 -111.31931)
		(width 0.08382)
		(layer "In2.Cu")
		(net "FM_PRSNT_1_N")
	)
	(segment
		(start 69.60362 -106.928412)
		(end 68.251832 -108.2802)
		(width 0.08382)
		(layer "In2.Cu")
		(net "FM_PRSNT_1_N")
	)
	(segment
		(start 43.482768 -111.408972)
		(end 37.836856 -111.408972)
		(width 0.08382)
		(layer "In2.Cu")
		(net "FM_PRSNT_1_N")
	)
	(segment
		(start 70.236588 -106.928412)
		(end 69.60362 -106.928412)
		(width 0.08382)
		(layer "In2.Cu")
		(net "FM_PRSNT_1_N")
	)
	(segment
		(start 25.83307 -111.25327)
		(end 24.99233 -110.41253)
		(width 0.08382)
		(layer "In2.Cu")
		(net "FM_PRSNT_1_N")
	)
	(segment
		(start 58.70829 -111.34471)
		(end 55.55361 -111.34471)
		(width 0.08382)
		(layer "In2.Cu")
		(net "FM_PRSNT_1_N")
	)
	(segment
		(start 47.334932 -111.10214)
		(end 43.7896 -111.10214)
		(width 0.08382)
		(layer "In2.Cu")
		(net "FM_PRSNT_1_N")
	)
	(segment
		(start 37.836856 -111.408972)
		(end 36.311078 -110.77702)
		(width 0.08382)
		(layer "In2.Cu")
		(net "FM_PRSNT_1_N")
	)
	(segment
		(start 64.185546 -108.2802)
		(end 61.442346 -111.0234)
		(width 0.08382)
		(layer "In2.Cu")
		(net "FM_PRSNT_1_N")
	)
	(segment
		(start 19.30527 -110.41253)
		(end 18.4912 -111.2266)
		(width 0.08382)
		(layer "In2.Cu")
		(net "FM_PRSNT_1_N")
	)
	(segment
		(start 36.311078 -110.77702)
		(end 29.147008 -110.77702)
		(width 0.08382)
		(layer "In2.Cu")
		(net "FM_PRSNT_1_N")
	)
	(segment
		(start 29.147008 -110.77702)
		(end 28.670758 -111.25327)
		(width 0.08382)
		(layer "In2.Cu")
		(net "FM_PRSNT_1_N")
	)
	(segment
		(start 28.670758 -111.25327)
		(end 25.83307 -111.25327)
		(width 0.08382)
		(layer "In2.Cu")
		(net "FM_PRSNT_1_N")
	)
	(segment
		(start 24.99233 -110.41253)
		(end 19.30527 -110.41253)
		(width 0.08382)
		(layer "In2.Cu")
		(net "FM_PRSNT_1_N")
	)
	(segment
		(start 68.251832 -108.2802)
		(end 64.185546 -108.2802)
		(width 0.08382)
		(layer "In2.Cu")
		(net "FM_PRSNT_1_N")
	)
	(segment
		(start 55.55361 -111.34471)
		(end 55.52821 -111.31931)
		(width 0.08382)
		(layer "In2.Cu")
		(net "FM_PRSNT_1_N")
	)
	(segment
		(start 72.1614 -106.64825)
		(end 72.57542 -107.06227)
		(width 0.11684)
		(layer "F.Cu")
		(net "FM_PRSNT_0_R_N")
	)
	(segment
		(start 72.517 -108.2294)
		(end 72.517 -108.7374)
		(width 0.11684)
		(layer "F.Cu")
		(net "FM_PRSNT_0_R_N")
	)
	(segment
		(start 74.624184 -112.927384)
		(end 74.624184 -117.201442)
		(width 0.11684)
		(layer "F.Cu")
		(net "FM_PRSNT_0_R_N")
	)
	(segment
		(start 72.517 -108.7374)
		(end 72.9488 -109.1692)
		(width 0.11684)
		(layer "F.Cu")
		(net "FM_PRSNT_0_R_N")
	)
	(segment
		(start 72.9488 -111.252)
		(end 74.624184 -112.927384)
		(width 0.11684)
		(layer "F.Cu")
		(net "FM_PRSNT_0_R_N")
	)
	(segment
		(start 74.624184 -117.201442)
		(end 74.4601 -117.365526)
		(width 0.11684)
		(layer "F.Cu")
		(net "FM_PRSNT_0_R_N")
	)
	(segment
		(start 72.57542 -107.06227)
		(end 72.57542 -107.660186)
		(width 0.11684)
		(layer "F.Cu")
		(net "FM_PRSNT_0_R_N")
	)
	(segment
		(start 72.9488 -109.1692)
		(end 72.9488 -111.252)
		(width 0.11684)
		(layer "F.Cu")
		(net "FM_PRSNT_0_R_N")
	)
	(segment
		(start 72.57542 -107.660186)
		(end 72.517 -107.718606)
		(width 0.11684)
		(layer "F.Cu")
		(net "FM_PRSNT_0_R_N")
	)
	(segment
		(start 72.517 -107.718606)
		(end 72.517 -108.2294)
		(width 0.11684)
		(layer "F.Cu")
		(net "FM_PRSNT_0_R_N")
	)
	(segment
		(start 74.4601 -117.365526)
		(end 74.4601 -118.460012)
		(width 0.11684)
		(layer "F.Cu")
		(net "FM_PRSNT_0_R_N")
	)
	(via
		(at 72.517 -108.2294)
		(size 0.762)
		(drill 0.381)
		(layers "F.Cu" "B.Cu")
		(net "FM_PRSNT_0_R_N")
	)
	(via
		(at 99.588574 29.28239)
		(size 0.508)
		(drill 0.254)
		(layers "F.Cu" "B.Cu")
		(net "GND_P1")
	)
	(via
		(at 100.1903 -65.654428)
		(size 0.508)
		(drill 0.254)
		(layers "F.Cu" "B.Cu")
		(net "GND_P1")
	)
	(via
		(at 96.223836 42.887138)
		(size 0.508)
		(drill 0.254)
		(layers "F.Cu" "B.Cu")
		(net "GND_P1")
	)
	(via
		(at 100.1903 17.98066)
		(size 0.508)
		(drill 0.254)
		(layers "F.Cu" "B.Cu")
		(net "GND_P1")
	)
	(via
		(at 94.556834 -97.607374)
		(size 0.508)
		(drill 0.254)
		(layers "F.Cu" "B.Cu")
		(net "GND_P1")
	)
	(via
		(at 97.628202 -98.379534)
		(size 0.508)
		(drill 0.254)
		(layers "F.Cu" "B.Cu")
		(net "GND_P1")
	)
	(via
		(at 94.541594 -16.688562)
		(size 0.508)
		(drill 0.254)
		(layers "F.Cu" "B.Cu")
		(net "GND_P1")
	)
	(via
		(at 102.8573 -54.382924)
		(size 0.508)
		(drill 0.254)
		(layers "F.Cu" "B.Cu")
		(net "GND_P1")
	)
	(via
		(at 95.591884 -15.09014)
		(size 0.508)
		(drill 0.254)
		(layers "F.Cu" "B.Cu")
		(net "GND_P1")
	)
	(via
		(at 103.6447 -55.205376)
		(size 0.508)
		(drill 0.254)
		(layers "F.Cu" "B.Cu")
		(net "GND_P1")
	)
	(via
		(at 102.8573 -104.744012)
		(size 0.508)
		(drill 0.254)
		(layers "F.Cu" "B.Cu")
		(net "GND_P1")
	)
	(via
		(at 96.974152 -15.916402)
		(size 0.508)
		(drill 0.254)
		(layers "F.Cu" "B.Cu")
		(net "GND_P1")
	)
	(via
		(at 94.84868 -15.916402)
		(size 0.508)
		(drill 0.254)
		(layers "F.Cu" "B.Cu")
		(net "GND_P1")
	)
	(via
		(at 97.274126 41.292526)
		(size 0.508)
		(drill 0.254)
		(layers "F.Cu" "B.Cu")
		(net "GND_P1")
	)
	(via
		(at 97.628202 53.396642)
		(size 0.508)
		(drill 0.254)
		(layers "F.Cu" "B.Cu")
		(net "GND_P1")
	)
	(via
		(at 101.4603 18.803112)
		(size 0.508)
		(drill 0.254)
		(layers "F.Cu" "B.Cu")
		(net "GND_P1")
	)
	(via
		(at 94.22511 -98.379534)
		(size 0.508)
		(drill 0.254)
		(layers "F.Cu" "B.Cu")
		(net "GND_P1")
	)
	(via
		(at 96.989392 -99.205796)
		(size 0.508)
		(drill 0.254)
		(layers "F.Cu" "B.Cu")
		(net "GND_P1")
	)
	(via
		(at 97.60585 42.064686)
		(size 0.508)
		(drill 0.254)
		(layers "F.Cu" "B.Cu")
		(net "GND_P1")
	)
	(via
		(at 96.989392 -98.379534)
		(size 0.508)
		(drill 0.254)
		(layers "F.Cu" "B.Cu")
		(net "GND_P1")
	)
	(via
		(at 95.165164 -2.464054)
		(size 0.508)
		(drill 0.254)
		(layers "F.Cu" "B.Cu")
		(net "GND_P1")
	)
	(via
		(at 102.02926 117.24513)
		(size 0.508)
		(drill 0.254)
		(layers "F.Cu" "B.Cu")
		(net "GND_P1")
	)
	(via
		(at 94.20987 -15.09014)
		(size 0.508)
		(drill 0.254)
		(layers "F.Cu" "B.Cu")
		(net "GND_P1")
	)
	(via
		(at 102.969314 119.365522)
		(size 0.508)
		(drill 0.254)
		(layers "F.Cu" "B.Cu")
		(net "GND_P1")
	)
	(via
		(at 104.9147 17.98066)
		(size 0.508)
		(drill 0.254)
		(layers "F.Cu" "B.Cu")
		(net "GND_P1")
	)
	(via
		(at 97.612962 -15.916402)
		(size 0.508)
		(drill 0.254)
		(layers "F.Cu" "B.Cu")
		(net "GND_P1")
	)
	(via
		(at 94.556834 54.168802)
		(size 0.508)
		(drill 0.254)
		(layers "F.Cu" "B.Cu")
		(net "GND_P1")
	)
	(via
		(at 102.352856 28.456128)
		(size 0.508)
		(drill 0.254)
		(layers "F.Cu" "B.Cu")
		(net "GND_P1")
	)
	(via
		(at 102.991666 28.456128)
		(size 0.508)
		(drill 0.254)
		(layers "F.Cu" "B.Cu")
		(net "GND_P1")
	)
	(via
		(at 94.20987 112.745774)
		(size 0.508)
		(drill 0.254)
		(layers "F.Cu" "B.Cu")
		(net "GND_P1")
	)
	(via
		(at 102.525322 17.2085)
		(size 0.508)
		(drill 0.254)
		(layers "F.Cu" "B.Cu")
		(net "GND_P1")
	)
	(via
		(at 94.841568 42.064686)
		(size 0.508)
		(drill 0.254)
		(layers "F.Cu" "B.Cu")
		(net "GND_P1")
	)
	(via
		(at 102.330504 119.365522)
		(size 0.508)
		(drill 0.254)
		(layers "F.Cu" "B.Cu")
		(net "GND_P1")
	)
	(via
		(at 97.612962 112.745774)
		(size 0.508)
		(drill 0.254)
		(layers "F.Cu" "B.Cu")
		(net "GND_P1")
	)
	(via
		(at 96.989392 -5.410708)
		(size 0.508)
		(drill 0.254)
		(layers "F.Cu" "B.Cu")
		(net "GND_P1")
	)
	(via
		(at 101.957886 31.441644)
		(size 0.508)
		(drill 0.254)
		(layers "F.Cu" "B.Cu")
		(net "GND_P1")
	)
	(via
		(at 99.912678 -103.971852)
		(size 0.508)
		(drill 0.254)
		(layers "F.Cu" "B.Cu")
		(net "GND_P1")
	)
	(via
		(at 102.8827 -64.828166)
		(size 0.508)
		(drill 0.254)
		(layers "F.Cu" "B.Cu")
		(net "GND_P1")
	)
	(via
		(at 102.8827 17.98066)
		(size 0.508)
		(drill 0.254)
		(layers "F.Cu" "B.Cu")
		(net "GND_P1")
	)
	(via
		(at 102.659942 30.05455)
		(size 0.508)
		(drill 0.254)
		(layers "F.Cu" "B.Cu")
		(net "GND_P1")
	)
	(via
		(at 97.60585 42.890948)
		(size 0.508)
		(drill 0.254)
		(layers "F.Cu" "B.Cu")
		(net "GND_P1")
	)
	(via
		(at 96.96704 42.064686)
		(size 0.508)
		(drill 0.254)
		(layers "F.Cu" "B.Cu")
		(net "GND_P1")
	)
	(via
		(at 100.528628 31.402782)
		(size 0.508)
		(drill 0.254)
		(layers "F.Cu" "B.Cu")
		(net "GND_P1")
	)
	(via
		(at 104.9147 -105.570274)
		(size 0.508)
		(drill 0.254)
		(layers "F.Cu" "B.Cu")
		(net "GND_P1")
	)
	(via
		(at 96.989392 -4.584446)
		(size 0.508)
		(drill 0.254)
		(layers "F.Cu" "B.Cu")
		(net "GND_P1")
	)
	(via
		(at 94.841568 42.890948)
		(size 0.508)
		(drill 0.254)
		(layers "F.Cu" "B.Cu")
		(net "GND_P1")
	)
	(via
		(at 95.24365 110.58652)
		(size 0.508)
		(drill 0.254)
		(layers "F.Cu" "B.Cu")
		(net "GND_P1")
	)
	(via
		(at 94.202758 42.064686)
		(size 0.508)
		(drill 0.254)
		(layers "F.Cu" "B.Cu")
		(net "GND_P1")
	)
	(via
		(at 96.672908 -18.036794)
		(size 0.508)
		(drill 0.254)
		(layers "F.Cu" "B.Cu")
		(net "GND_P1")
	)
	(via
		(at 94.22511 53.396642)
		(size 0.508)
		(drill 0.254)
		(layers "F.Cu" "B.Cu")
		(net "GND_P1")
	)
	(via
		(at 102.2477 -65.654428)
		(size 0.508)
		(drill 0.254)
		(layers "F.Cu" "B.Cu")
		(net "GND_P1")
	)
	(via
		(at 105.5497 18.806922)
		(size 0.508)
		(drill 0.254)
		(layers "F.Cu" "B.Cu")
		(net "GND_P1")
	)
	(via
		(at 94.22511 -4.584446)
		(size 0.508)
		(drill 0.254)
		(layers "F.Cu" "B.Cu")
		(net "GND_P1")
	)
	(via
		(at 103.6447 18.803112)
		(size 0.508)
		(drill 0.254)
		(layers "F.Cu" "B.Cu")
		(net "GND_P1")
	)
	(via
		(at 97.296478 54.168802)
		(size 0.508)
		(drill 0.254)
		(layers "F.Cu" "B.Cu")
		(net "GND_P1")
	)
	(via
		(at 104.9147 -104.744012)
		(size 0.508)
		(drill 0.254)
		(layers "F.Cu" "B.Cu")
		(net "GND_P1")
	)
	(via
		(at 100.948236 120.191784)
		(size 0.508)
		(drill 0.254)
		(layers "F.Cu" "B.Cu")
		(net "GND_P1")
	)
	(via
		(at 99.912678 17.2085)
		(size 0.508)
		(drill 0.254)
		(layers "F.Cu" "B.Cu")
		(net "GND_P1")
	)
	(via
		(at 97.612962 113.572036)
		(size 0.508)
		(drill 0.254)
		(layers "F.Cu" "B.Cu")
		(net "GND_P1")
	)
	(via
		(at 96.974152 112.745774)
		(size 0.508)
		(drill 0.254)
		(layers "F.Cu" "B.Cu")
		(net "GND_P1")
	)
	(via
		(at 94.202758 42.890948)
		(size 0.508)
		(drill 0.254)
		(layers "F.Cu" "B.Cu")
		(net "GND_P1")
	)
	(via
		(at 105.5497 -55.209186)
		(size 0.508)
		(drill 0.254)
		(layers "F.Cu" "B.Cu")
		(net "GND_P1")
	)
	(via
		(at 100.205032 119.365522)
		(size 0.508)
		(drill 0.254)
		(layers "F.Cu" "B.Cu")
		(net "GND_P1")
	)
	(via
		(at 100.1903 -64.828166)
		(size 0.508)
		(drill 0.254)
		(layers "F.Cu" "B.Cu")
		(net "GND_P1")
	)
	(via
		(at 100.8253 -64.828166)
		(size 0.508)
		(drill 0.254)
		(layers "F.Cu" "B.Cu")
		(net "GND_P1")
	)
	(via
		(at 102.8573 -55.209186)
		(size 0.508)
		(drill 0.254)
		(layers "F.Cu" "B.Cu")
		(net "GND_P1")
	)
	(via
		(at 102.2477 -64.828166)
		(size 0.508)
		(drill 0.254)
		(layers "F.Cu" "B.Cu")
		(net "GND_P1")
	)
	(via
		(at 102.579678 -103.971852)
		(size 0.508)
		(drill 0.254)
		(layers "F.Cu" "B.Cu")
		(net "GND_P1")
	)
	(via
		(at 95.584772 42.890948)
		(size 0.508)
		(drill 0.254)
		(layers "F.Cu" "B.Cu")
		(net "GND_P1")
	)
	(via
		(at 96.989392 52.57038)
		(size 0.508)
		(drill 0.254)
		(layers "F.Cu" "B.Cu")
		(net "GND_P1")
	)
	(via
		(at 97.628202 52.57038)
		(size 0.508)
		(drill 0.254)
		(layers "F.Cu" "B.Cu")
		(net "GND_P1")
	)
	(via
		(at 94.84868 -15.09014)
		(size 0.508)
		(drill 0.254)
		(layers "F.Cu" "B.Cu")
		(net "GND_P1")
	)
	(via
		(at 100.205032 120.191784)
		(size 0.508)
		(drill 0.254)
		(layers "F.Cu" "B.Cu")
		(net "GND_P1")
	)
	(via
		(at 101.4603 -64.831976)
		(size 0.508)
		(drill 0.254)
		(layers "F.Cu" "B.Cu")
		(net "GND_P1")
	)
	(via
		(at 99.897946 118.593362)
		(size 0.508)
		(drill 0.254)
		(layers "F.Cu" "B.Cu")
		(net "GND_P1")
	)
	(via
		(at 94.534482 41.292526)
		(size 0.508)
		(drill 0.254)
		(layers "F.Cu" "B.Cu")
		(net "GND_P1")
	)
	(via
		(at 95.607124 -99.201986)
		(size 0.508)
		(drill 0.254)
		(layers "F.Cu" "B.Cu")
		(net "GND_P1")
	)
	(via
		(at 102.330504 120.191784)
		(size 0.508)
		(drill 0.254)
		(layers "F.Cu" "B.Cu")
		(net "GND_P1")
	)
	(via
		(at 94.86392 52.57038)
		(size 0.508)
		(drill 0.254)
		(layers "F.Cu" "B.Cu")
		(net "GND_P1")
	)
	(via
		(at 100.1903 -55.209186)
		(size 0.508)
		(drill 0.254)
		(layers "F.Cu" "B.Cu")
		(net "GND_P1")
	)
	(via
		(at 96.594422 -2.425192)
		(size 0.508)
		(drill 0.254)
		(layers "F.Cu" "B.Cu")
		(net "GND_P1")
	)
	(via
		(at 102.2223 -104.744012)
		(size 0.508)
		(drill 0.254)
		(layers "F.Cu" "B.Cu")
		(net "GND_P1")
	)
	(via
		(at 96.246188 -5.410708)
		(size 0.508)
		(drill 0.254)
		(layers "F.Cu" "B.Cu")
		(net "GND_P1")
	)
	(via
		(at 104.9147 -65.654428)
		(size 0.508)
		(drill 0.254)
		(layers "F.Cu" "B.Cu")
		(net "GND_P1")
	)
	(via
		(at 101.609652 28.456128)
		(size 0.508)
		(drill 0.254)
		(layers "F.Cu" "B.Cu")
		(net "GND_P1")
	)
	(via
		(at 102.352856 29.28239)
		(size 0.508)
		(drill 0.254)
		(layers "F.Cu" "B.Cu")
		(net "GND_P1")
	)
	(via
		(at 105.192322 -103.971852)
		(size 0.508)
		(drill 0.254)
		(layers "F.Cu" "B.Cu")
		(net "GND_P1")
	)
	(via
		(at 103.6447 -105.566464)
		(size 0.508)
		(drill 0.254)
		(layers "F.Cu" "B.Cu")
		(net "GND_P1")
	)
	(via
		(at 94.22511 52.57038)
		(size 0.508)
		(drill 0.254)
		(layers "F.Cu" "B.Cu")
		(net "GND_P1")
	)
	(via
		(at 102.2477 17.98066)
		(size 0.508)
		(drill 0.254)
		(layers "F.Cu" "B.Cu")
		(net "GND_P1")
	)
	(via
		(at 100.8253 -55.209186)
		(size 0.508)
		(drill 0.254)
		(layers "F.Cu" "B.Cu")
		(net "GND_P1")
	)
	(via
		(at 101.5873 120.187974)
		(size 0.508)
		(drill 0.254)
		(layers "F.Cu" "B.Cu")
		(net "GND_P1")
	)
	(via
		(at 94.20987 -15.916402)
		(size 0.508)
		(drill 0.254)
		(layers "F.Cu" "B.Cu")
		(net "GND_P1")
	)
	(via
		(at 96.665796 39.944294)
		(size 0.508)
		(drill 0.254)
		(layers "F.Cu" "B.Cu")
		(net "GND_P1")
	)
	(via
		(at 102.525322 -66.426588)
		(size 0.508)
		(drill 0.254)
		(layers "F.Cu" "B.Cu")
		(net "GND_P1")
	)
	(via
		(at 102.63759 118.593362)
		(size 0.508)
		(drill 0.254)
		(layers "F.Cu" "B.Cu")
		(net "GND_P1")
	)
	(via
		(at 102.2223 -54.382924)
		(size 0.508)
		(drill 0.254)
		(layers "F.Cu" "B.Cu")
		(net "GND_P1")
	)
	(via
		(at 99.5553 18.806922)
		(size 0.508)
		(drill 0.254)
		(layers "F.Cu" "B.Cu")
		(net "GND_P1")
	)
	(via
		(at 102.991666 29.28239)
		(size 0.508)
		(drill 0.254)
		(layers "F.Cu" "B.Cu")
		(net "GND_P1")
	)
	(via
		(at 99.912678 -53.610764)
		(size 0.508)
		(drill 0.254)
		(layers "F.Cu" "B.Cu")
		(net "GND_P1")
	)
	(via
		(at 96.246188 52.57038)
		(size 0.508)
		(drill 0.254)
		(layers "F.Cu" "B.Cu")
		(net "GND_P1")
	)
	(via
		(at 96.594422 55.555896)
		(size 0.508)
		(drill 0.254)
		(layers "F.Cu" "B.Cu")
		(net "GND_P1")
	)
	(via
		(at 105.192322 -66.426588)
		(size 0.508)
		(drill 0.254)
		(layers "F.Cu" "B.Cu")
		(net "GND_P1")
	)
	(via
		(at 96.989392 53.396642)
		(size 0.508)
		(drill 0.254)
		(layers "F.Cu" "B.Cu")
		(net "GND_P1")
	)
	(via
		(at 101.4603 -55.205376)
		(size 0.508)
		(drill 0.254)
		(layers "F.Cu" "B.Cu")
		(net "GND_P1")
	)
	(via
		(at 96.246188 -99.205796)
		(size 0.508)
		(drill 0.254)
		(layers "F.Cu" "B.Cu")
		(net "GND_P1")
	)
	(via
		(at 102.2223 -55.209186)
		(size 0.508)
		(drill 0.254)
		(layers "F.Cu" "B.Cu")
		(net "GND_P1")
	)
	(via
		(at 94.86392 53.396642)
		(size 0.508)
		(drill 0.254)
		(layers "F.Cu" "B.Cu")
		(net "GND_P1")
	)
	(via
		(at 94.86392 -98.379534)
		(size 0.508)
		(drill 0.254)
		(layers "F.Cu" "B.Cu")
		(net "GND_P1")
	)
	(via
		(at 102.8573 -105.570274)
		(size 0.508)
		(drill 0.254)
		(layers "F.Cu" "B.Cu")
		(net "GND_P1")
	)
	(via
		(at 105.5497 -65.654428)
		(size 0.508)
		(drill 0.254)
		(layers "F.Cu" "B.Cu")
		(net "GND_P1")
	)
	(via
		(at 97.612962 -15.09014)
		(size 0.508)
		(drill 0.254)
		(layers "F.Cu" "B.Cu")
		(net "GND_P1")
	)
	(via
		(at 102.2477 18.806922)
		(size 0.508)
		(drill 0.254)
		(layers "F.Cu" "B.Cu")
		(net "GND_P1")
	)
	(via
		(at 104.9147 -55.209186)
		(size 0.508)
		(drill 0.254)
		(layers "F.Cu" "B.Cu")
		(net "GND_P1")
	)
	(via
		(at 97.281238 111.973614)
		(size 0.508)
		(drill 0.254)
		(layers "F.Cu" "B.Cu")
		(net "GND_P1")
	)
	(via
		(at 100.8253 18.806922)
		(size 0.508)
		(drill 0.254)
		(layers "F.Cu" "B.Cu")
		(net "GND_P1")
	)
	(via
		(at 97.296478 -3.812286)
		(size 0.508)
		(drill 0.254)
		(layers "F.Cu" "B.Cu")
		(net "GND_P1")
	)
	(via
		(at 94.86392 -99.205796)
		(size 0.508)
		(drill 0.254)
		(layers "F.Cu" "B.Cu")
		(net "GND_P1")
	)
	(via
		(at 100.600002 117.206268)
		(size 0.508)
		(drill 0.254)
		(layers "F.Cu" "B.Cu")
		(net "GND_P1")
	)
	(via
		(at 97.628202 -99.205796)
		(size 0.508)
		(drill 0.254)
		(layers "F.Cu" "B.Cu")
		(net "GND_P1")
	)
	(via
		(at 104.9147 -54.382924)
		(size 0.508)
		(drill 0.254)
		(layers "F.Cu" "B.Cu")
		(net "GND_P1")
	)
	(via
		(at 99.5553 -65.654428)
		(size 0.508)
		(drill 0.254)
		(layers "F.Cu" "B.Cu")
		(net "GND_P1")
	)
	(via
		(at 103.6447 -64.831976)
		(size 0.508)
		(drill 0.254)
		(layers "F.Cu" "B.Cu")
		(net "GND_P1")
	)
	(via
		(at 94.541594 111.973614)
		(size 0.508)
		(drill 0.254)
		(layers "F.Cu" "B.Cu")
		(net "GND_P1")
	)
	(via
		(at 100.970588 28.459938)
		(size 0.508)
		(drill 0.254)
		(layers "F.Cu" "B.Cu")
		(net "GND_P1")
	)
	(via
		(at 96.96704 42.890948)
		(size 0.508)
		(drill 0.254)
		(layers "F.Cu" "B.Cu")
		(net "GND_P1")
	)
	(via
		(at 95.607124 -5.406898)
		(size 0.508)
		(drill 0.254)
		(layers "F.Cu" "B.Cu")
		(net "GND_P1")
	)
	(via
		(at 95.591884 113.572036)
		(size 0.508)
		(drill 0.254)
		(layers "F.Cu" "B.Cu")
		(net "GND_P1")
	)
	(via
		(at 96.230948 113.568226)
		(size 0.508)
		(drill 0.254)
		(layers "F.Cu" "B.Cu")
		(net "GND_P1")
	)
	(via
		(at 104.2797 -105.570274)
		(size 0.508)
		(drill 0.254)
		(layers "F.Cu" "B.Cu")
		(net "GND_P1")
	)
	(via
		(at 94.84868 113.572036)
		(size 0.508)
		(drill 0.254)
		(layers "F.Cu" "B.Cu")
		(net "GND_P1")
	)
	(via
		(at 94.22511 -5.410708)
		(size 0.508)
		(drill 0.254)
		(layers "F.Cu" "B.Cu")
		(net "GND_P1")
	)
	(via
		(at 104.2797 18.806922)
		(size 0.508)
		(drill 0.254)
		(layers "F.Cu" "B.Cu")
		(net "GND_P1")
	)
	(via
		(at 99.5553 -64.828166)
		(size 0.508)
		(drill 0.254)
		(layers "F.Cu" "B.Cu")
		(net "GND_P1")
	)
	(via
		(at 94.556834 -3.812286)
		(size 0.508)
		(drill 0.254)
		(layers "F.Cu" "B.Cu")
		(net "GND_P1")
	)
	(via
		(at 100.227384 29.28239)
		(size 0.508)
		(drill 0.254)
		(layers "F.Cu" "B.Cu")
		(net "GND_P1")
	)
	(via
		(at 95.165164 -96.259142)
		(size 0.508)
		(drill 0.254)
		(layers "F.Cu" "B.Cu")
		(net "GND_P1")
	)
	(via
		(at 94.86392 -5.410708)
		(size 0.508)
		(drill 0.254)
		(layers "F.Cu" "B.Cu")
		(net "GND_P1")
	)
	(via
		(at 94.84868 112.745774)
		(size 0.508)
		(drill 0.254)
		(layers "F.Cu" "B.Cu")
		(net "GND_P1")
	)
	(via
		(at 94.86392 -4.584446)
		(size 0.508)
		(drill 0.254)
		(layers "F.Cu" "B.Cu")
		(net "GND_P1")
	)
	(via
		(at 95.165164 55.517034)
		(size 0.508)
		(drill 0.254)
		(layers "F.Cu" "B.Cu")
		(net "GND_P1")
	)
	(via
		(at 100.1903 -54.382924)
		(size 0.508)
		(drill 0.254)
		(layers "F.Cu" "B.Cu")
		(net "GND_P1")
	)
	(via
		(at 104.9147 18.806922)
		(size 0.508)
		(drill 0.254)
		(layers "F.Cu" "B.Cu")
		(net "GND_P1")
	)
	(via
		(at 96.230948 -15.09395)
		(size 0.508)
		(drill 0.254)
		(layers "F.Cu" "B.Cu")
		(net "GND_P1")
	)
	(via
		(at 99.5553 -105.570274)
		(size 0.508)
		(drill 0.254)
		(layers "F.Cu" "B.Cu")
		(net "GND_P1")
	)
	(via
		(at 97.628202 -4.584446)
		(size 0.508)
		(drill 0.254)
		(layers "F.Cu" "B.Cu")
		(net "GND_P1")
	)
	(via
		(at 104.2797 -55.209186)
		(size 0.508)
		(drill 0.254)
		(layers "F.Cu" "B.Cu")
		(net "GND_P1")
	)
	(via
		(at 95.607124 52.57419)
		(size 0.508)
		(drill 0.254)
		(layers "F.Cu" "B.Cu")
		(net "GND_P1")
	)
	(via
		(at 102.8827 -65.654428)
		(size 0.508)
		(drill 0.254)
		(layers "F.Cu" "B.Cu")
		(net "GND_P1")
	)
	(via
		(at 97.296478 -97.607374)
		(size 0.508)
		(drill 0.254)
		(layers "F.Cu" "B.Cu")
		(net "GND_P1")
	)
	(via
		(at 102.2223 -105.570274)
		(size 0.508)
		(drill 0.254)
		(layers "F.Cu" "B.Cu")
		(net "GND_P1")
	)
	(via
		(at 105.5497 17.98066)
		(size 0.508)
		(drill 0.254)
		(layers "F.Cu" "B.Cu")
		(net "GND_P1")
	)
	(via
		(at 99.5553 17.98066)
		(size 0.508)
		(drill 0.254)
		(layers "F.Cu" "B.Cu")
		(net "GND_P1")
	)
	(via
		(at 97.628202 -5.410708)
		(size 0.508)
		(drill 0.254)
		(layers "F.Cu" "B.Cu")
		(net "GND_P1")
	)
	(via
		(at 100.1903 -105.570274)
		(size 0.508)
		(drill 0.254)
		(layers "F.Cu" "B.Cu")
		(net "GND_P1")
	)
	(via
		(at 105.5497 -54.382924)
		(size 0.508)
		(drill 0.254)
		(layers "F.Cu" "B.Cu")
		(net "GND_P1")
	)
	(via
		(at 96.974152 -15.09014)
		(size 0.508)
		(drill 0.254)
		(layers "F.Cu" "B.Cu")
		(net "GND_P1")
	)
	(via
		(at 96.594422 -96.22028)
		(size 0.508)
		(drill 0.254)
		(layers "F.Cu" "B.Cu")
		(net "GND_P1")
	)
	(via
		(at 102.8827 18.806922)
		(size 0.508)
		(drill 0.254)
		(layers "F.Cu" "B.Cu")
		(net "GND_P1")
	)
	(via
		(at 95.24365 -18.075656)
		(size 0.508)
		(drill 0.254)
		(layers "F.Cu" "B.Cu")
		(net "GND_P1")
	)
	(via
		(at 104.9147 -64.828166)
		(size 0.508)
		(drill 0.254)
		(layers "F.Cu" "B.Cu")
		(net "GND_P1")
	)
	(via
		(at 99.5553 -104.744012)
		(size 0.508)
		(drill 0.254)
		(layers "F.Cu" "B.Cu")
		(net "GND_P1")
	)
	(via
		(at 105.5497 -105.570274)
		(size 0.508)
		(drill 0.254)
		(layers "F.Cu" "B.Cu")
		(net "GND_P1")
	)
	(via
		(at 94.22511 -99.205796)
		(size 0.508)
		(drill 0.254)
		(layers "F.Cu" "B.Cu")
		(net "GND_P1")
	)
	(via
		(at 99.566222 120.191784)
		(size 0.508)
		(drill 0.254)
		(layers "F.Cu" "B.Cu")
		(net "GND_P1")
	)
	(via
		(at 96.672908 110.625382)
		(size 0.508)
		(drill 0.254)
		(layers "F.Cu" "B.Cu")
		(net "GND_P1")
	)
	(via
		(at 100.227384 28.456128)
		(size 0.508)
		(drill 0.254)
		(layers "F.Cu" "B.Cu")
		(net "GND_P1")
	)
	(via
		(at 97.281238 -16.688562)
		(size 0.508)
		(drill 0.254)
		(layers "F.Cu" "B.Cu")
		(net "GND_P1")
	)
	(via
		(at 102.579678 -53.610764)
		(size 0.508)
		(drill 0.254)
		(layers "F.Cu" "B.Cu")
		(net "GND_P1")
	)
	(via
		(at 102.969314 120.191784)
		(size 0.508)
		(drill 0.254)
		(layers "F.Cu" "B.Cu")
		(net "GND_P1")
	)
	(via
		(at 100.8253 -105.570274)
		(size 0.508)
		(drill 0.254)
		(layers "F.Cu" "B.Cu")
		(net "GND_P1")
	)
	(via
		(at 95.236538 39.905432)
		(size 0.508)
		(drill 0.254)
		(layers "F.Cu" "B.Cu")
		(net "GND_P1")
	)
	(via
		(at 99.920298 30.05455)
		(size 0.508)
		(drill 0.254)
		(layers "F.Cu" "B.Cu")
		(net "GND_P1")
	)
	(via
		(at 99.5553 -54.382924)
		(size 0.508)
		(drill 0.254)
		(layers "F.Cu" "B.Cu")
		(net "GND_P1")
	)
	(via
		(at 96.974152 113.572036)
		(size 0.508)
		(drill 0.254)
		(layers "F.Cu" "B.Cu")
		(net "GND_P1")
	)
	(via
		(at 99.566222 119.365522)
		(size 0.508)
		(drill 0.254)
		(layers "F.Cu" "B.Cu")
		(net "GND_P1")
	)
	(via
		(at 99.5553 -55.209186)
		(size 0.508)
		(drill 0.254)
		(layers "F.Cu" "B.Cu")
		(net "GND_P1")
	)
	(via
		(at 100.1903 -104.744012)
		(size 0.508)
		(drill 0.254)
		(layers "F.Cu" "B.Cu")
		(net "GND_P1")
	)
	(via
		(at 104.2797 -64.828166)
		(size 0.508)
		(drill 0.254)
		(layers "F.Cu" "B.Cu")
		(net "GND_P1")
	)
	(via
		(at 100.1903 18.806922)
		(size 0.508)
		(drill 0.254)
		(layers "F.Cu" "B.Cu")
		(net "GND_P1")
	)
	(via
		(at 105.192322 -53.610764)
		(size 0.508)
		(drill 0.254)
		(layers "F.Cu" "B.Cu")
		(net "GND_P1")
	)
	(via
		(at 101.4603 -105.566464)
		(size 0.508)
		(drill 0.254)
		(layers "F.Cu" "B.Cu")
		(net "GND_P1")
	)
	(via
		(at 94.20987 113.572036)
		(size 0.508)
		(drill 0.254)
		(layers "F.Cu" "B.Cu")
		(net "GND_P1")
	)
	(via
		(at 105.5497 -64.828166)
		(size 0.508)
		(drill 0.254)
		(layers "F.Cu" "B.Cu")
		(net "GND_P1")
	)
	(via
		(at 99.912678 -66.426588)
		(size 0.508)
		(drill 0.254)
		(layers "F.Cu" "B.Cu")
		(net "GND_P1")
	)
	(via
		(at 99.588574 28.456128)
		(size 0.508)
		(drill 0.254)
		(layers "F.Cu" "B.Cu")
		(net "GND_P1")
	)
	(via
		(at 105.192322 17.2085)
		(size 0.508)
		(drill 0.254)
		(layers "F.Cu" "B.Cu")
		(net "GND_P1")
	)
	(via
		(at 105.5497 -104.744012)
		(size 0.508)
		(drill 0.254)
		(layers "F.Cu" "B.Cu")
		(net "GND_P1")
	)
	(segment
		(start 100.627688 -46.531784)
		(end 100.462842 -47.465996)
		(width 0.14224)
		(layer "F.Cu")
		(net "85_10INCH_TOP_DP")
	)
	(segment
		(start 100.99167 -34.821368)
		(end 100.662232 -35.052)
		(width 0.14224)
		(layer "F.Cu")
		(net "85_10INCH_TOP_DP")
	)
	(segment
		(start 106.39679 0.464566)
		(end 106.178858 -0.769366)
		(width 0.14224)
		(layer "F.Cu")
		(net "85_10INCH_TOP_DP")
	)
	(segment
		(start 104.185212 -48.918368)
		(end 104.00665 -49.92878)
		(width 0.14224)
		(layer "F.Cu")
		(net "85_10INCH_TOP_DP")
	)
	(segment
		(start 107.13212 -37.444426)
		(end 107.538012 -38.023546)
		(width 0.14224)
		(layer "F.Cu")
		(net "85_10INCH_TOP_DP")
	)
	(segment
		(start 100.957126 -46.301152)
		(end 100.627688 -46.531784)
		(width 0.14224)
		(layer "F.Cu")
		(net "85_10INCH_TOP_DP")
	)
	(segment
		(start 101.675184 -1.735582)
		(end 101.905816 -2.064766)
		(width 0.14224)
		(layer "F.Cu")
		(net "85_10INCH_TOP_DP")
	)
	(segment
		(start 101.68128 2.091944)
		(end 101.911912 1.76276)
		(width 0.14224)
		(layer "F.Cu")
		(net "85_10INCH_TOP_DP")
	)
	(segment
		(start 100.497386 -35.986212)
		(end 100.728018 -36.315142)
		(width 0.14224)
		(layer "F.Cu")
		(net "85_10INCH_TOP_DP")
	)
	(segment
		(start 100.418646 -16.82877)
		(end 100.649278 -17.157954)
		(width 0.14224)
		(layer "F.Cu")
		(net "85_10INCH_TOP_DP")
	)
	(segment
		(start 100.84435 -9.534906)
		(end 107.154726 -10.64768)
		(width 0.14224)
		(layer "F.Cu")
		(net "85_10INCH_TOP_DP")
	)
	(segment
		(start 101.846126 3.026156)
		(end 101.68128 2.091944)
		(width 0.14224)
		(layer "F.Cu")
		(net "85_10INCH_TOP_DP")
	)
	(segment
		(start 107.38485 -43.09745)
		(end 106.805476 -43.503596)
		(width 0.14224)
		(layer "F.Cu")
		(net "85_10INCH_TOP_DP")
	)
	(segment
		(start 107.66298 -18.902172)
		(end 107.445048 -20.136104)
		(width 0.14224)
		(layer "F.Cu")
		(net "85_10INCH_TOP_DP")
	)
	(segment
		(start 106.216196 3.052572)
		(end 105.636822 2.646426)
		(width 0.14224)
		(layer "F.Cu")
		(net "85_10INCH_TOP_DP")
	)
	(segment
		(start 106.178858 -0.769366)
		(end 105.599484 -1.175512)
		(width 0.14224)
		(layer "F.Cu")
		(net "85_10INCH_TOP_DP")
	)
	(segment
		(start 105.972102 8.704326)
		(end 106.377994 8.125206)
		(width 0.14224)
		(layer "F.Cu")
		(net "85_10INCH_TOP_DP")
	)
	(segment
		(start 100.51542 -27.368754)
		(end 100.350574 -28.302966)
		(width 0.14224)
		(layer "F.Cu")
		(net "85_10INCH_TOP_DP")
	)
	(segment
		(start 104.438704 12.803378)
		(end 106.011218 12.52601)
		(width 0.14224)
		(layer "F.Cu")
		(net "85_10INCH_TOP_DP")
	)
	(segment
		(start 100.621084 -19.729958)
		(end 100.456238 -20.66417)
		(width 0.14224)
		(layer "F.Cu")
		(net "85_10INCH_TOP_DP")
	)
	(segment
		(start 106.774488 -47.326804)
		(end 100.957126 -46.301152)
		(width 0.14224)
		(layer "F.Cu")
		(net "85_10INCH_TOP_DP")
	)
	(segment
		(start 100.414836 -24.4856)
		(end 100.645468 -24.814784)
		(width 0.14224)
		(layer "F.Cu")
		(net "85_10INCH_TOP_DP")
	)
	(segment
		(start 107.445048 -20.136104)
		(end 106.865674 -20.54225)
		(width 0.14224)
		(layer "F.Cu")
		(net "85_10INCH_TOP_DP")
	)
	(segment
		(start 105.580688 6.485128)
		(end 102.149148 7.090156)
		(width 0.14224)
		(layer "F.Cu")
		(net "85_10INCH_TOP_DP")
	)
	(segment
		(start 100.379022 -39.793926)
		(end 100.609654 -40.122856)
		(width 0.14224)
		(layer "F.Cu")
		(net "85_10INCH_TOP_DP")
	)
	(segment
		(start 100.628196 -31.217108)
		(end 100.46335 -32.15132)
		(width 0.14224)
		(layer "F.Cu")
		(net "85_10INCH_TOP_DP")
	)
	(segment
		(start 107.630468 -34.21126)
		(end 107.412536 -35.445192)
		(width 0.14224)
		(layer "F.Cu")
		(net "85_10INCH_TOP_DP")
	)
	(segment
		(start 106.795316 -16.701262)
		(end 100.91293 -15.663926)
		(width 0.14224)
		(layer "F.Cu")
		(net "85_10INCH_TOP_DP")
	)
	(segment
		(start 107.412536 -35.445192)
		(end 106.833162 -35.851338)
		(width 0.14224)
		(layer "F.Cu")
		(net "85_10INCH_TOP_DP")
	)
	(segment
		(start 106.833162 -35.851338)
		(end 100.99167 -34.821368)
		(width 0.14224)
		(layer "F.Cu")
		(net "85_10INCH_TOP_DP")
	)
	(segment
		(start 100.424996 -43.630596)
		(end 100.655628 -43.95978)
		(width 0.14224)
		(layer "F.Cu")
		(net "85_10INCH_TOP_DP")
	)
	(segment
		(start 100.693982 -32.480758)
		(end 107.22483 -33.631378)
		(width 0.14224)
		(layer "F.Cu")
		(net "85_10INCH_TOP_DP")
	)
	(segment
		(start 104.00665 -53.354986)
		(end 104.072436 -53.420772)
		(width 0.14224)
		(layer "F.Cu")
		(net "85_10INCH_TOP_DP")
	)
	(segment
		(start 107.56773 -30.371288)
		(end 107.349798 -31.60522)
		(width 0.14224)
		(layer "F.Cu")
		(net "85_10INCH_TOP_DP")
	)
	(segment
		(start 101.908102 -5.893816)
		(end 106.000042 -6.615176)
		(width 0.14224)
		(layer "F.Cu")
		(net "85_10INCH_TOP_DP")
	)
	(segment
		(start 107.32008 -39.257478)
		(end 106.740706 -39.663624)
		(width 0.14224)
		(layer "F.Cu")
		(net "85_10INCH_TOP_DP")
	)
	(segment
		(start 107.165902 -45.107606)
		(end 107.571794 -45.686726)
		(width 0.14224)
		(layer "F.Cu")
		(net "85_10INCH_TOP_DP")
	)
	(segment
		(start 100.649278 -17.157954)
		(end 107.257088 -18.323052)
		(width 0.14224)
		(layer "F.Cu")
		(net "85_10INCH_TOP_DP")
	)
	(segment
		(start 107.226354 -25.975056)
		(end 107.632246 -26.554176)
		(width 0.14224)
		(layer "F.Cu")
		(net "85_10INCH_TOP_DP")
	)
	(segment
		(start 104.00665 16.952722)
		(end 104.00665 13.235432)
		(width 0.14224)
		(layer "F.Cu")
		(net "85_10INCH_TOP_DP")
	)
	(segment
		(start 102.169468 -0.570738)
		(end 101.84003 -0.80137)
		(width 0.14224)
		(layer "F.Cu")
		(net "85_10INCH_TOP_DP")
	)
	(segment
		(start 102.149148 7.090156)
		(end 101.81971 6.859524)
		(width 0.14224)
		(layer "F.Cu")
		(net "85_10INCH_TOP_DP")
	)
	(segment
		(start 101.108002 -8.040878)
		(end 100.778564 -8.27151)
		(width 0.14224)
		(layer "F.Cu")
		(net "85_10INCH_TOP_DP")
	)
	(segment
		(start 104.00665 -49.92878)
		(end 104.00665 -53.354986)
		(width 0.14224)
		(layer "F.Cu")
		(net "85_10INCH_TOP_DP")
	)
	(segment
		(start 107.610148 -22.72157)
		(end 107.392216 -23.955502)
		(width 0.14224)
		(layer "F.Cu")
		(net "85_10INCH_TOP_DP")
	)
	(segment
		(start 107.349798 -31.60522)
		(end 106.770424 -32.011366)
		(width 0.14224)
		(layer "F.Cu")
		(net "85_10INCH_TOP_DP")
	)
	(segment
		(start 106.18978 -4.600194)
		(end 105.610406 -5.00634)
		(width 0.14224)
		(layer "F.Cu")
		(net "85_10INCH_TOP_DP")
	)
	(segment
		(start 102.175564 3.256788)
		(end 101.846126 3.026156)
		(width 0.14224)
		(layer "F.Cu")
		(net "85_10INCH_TOP_DP")
	)
	(segment
		(start 102.18547 10.912348)
		(end 101.855778 10.681716)
		(width 0.14224)
		(layer "F.Cu")
		(net "85_10INCH_TOP_DP")
	)
	(segment
		(start 101.654864 5.925312)
		(end 101.885496 5.596382)
		(width 0.14224)
		(layer "F.Cu")
		(net "85_10INCH_TOP_DP")
	)
	(segment
		(start 106.002074 -2.786634)
		(end 106.407712 -3.366262)
		(width 0.14224)
		(layer "F.Cu")
		(net "85_10INCH_TOP_DP")
	)
	(segment
		(start 107.19689 -41.284398)
		(end 107.602782 -41.863518)
		(width 0.14224)
		(layer "F.Cu")
		(net "85_10INCH_TOP_DP")
	)
	(segment
		(start 106.160062 6.891274)
		(end 105.580688 6.485128)
		(width 0.14224)
		(layer "F.Cu")
		(net "85_10INCH_TOP_DP")
	)
	(segment
		(start 100.91293 -15.663926)
		(end 100.583492 -15.894558)
		(width 0.14224)
		(layer "F.Cu")
		(net "85_10INCH_TOP_DP")
	)
	(segment
		(start 106.865674 -20.54225)
		(end 100.950522 -19.499326)
		(width 0.14224)
		(layer "F.Cu")
		(net "85_10INCH_TOP_DP")
	)
	(segment
		(start 107.353862 -46.920658)
		(end 106.774488 -47.326804)
		(width 0.14224)
		(layer "F.Cu")
		(net "85_10INCH_TOP_DP")
	)
	(segment
		(start 106.011218 12.52601)
		(end 106.41711 11.94689)
		(width 0.14224)
		(layer "F.Cu")
		(net "85_10INCH_TOP_DP")
	)
	(segment
		(start 100.462842 -47.465996)
		(end 100.693474 -47.79518)
		(width 0.14224)
		(layer "F.Cu")
		(net "85_10INCH_TOP_DP")
	)
	(segment
		(start 106.770424 -32.011366)
		(end 100.957634 -30.986476)
		(width 0.14224)
		(layer "F.Cu")
		(net "85_10INCH_TOP_DP")
	)
	(segment
		(start 100.583492 -15.894558)
		(end 100.418646 -16.82877)
		(width 0.14224)
		(layer "F.Cu")
		(net "85_10INCH_TOP_DP")
	)
	(segment
		(start 106.434128 4.286504)
		(end 106.216196 3.052572)
		(width 0.14224)
		(layer "F.Cu")
		(net "85_10INCH_TOP_DP")
	)
	(segment
		(start 100.350574 -28.302966)
		(end 100.580952 -28.631896)
		(width 0.14224)
		(layer "F.Cu")
		(net "85_10INCH_TOP_DP")
	)
	(segment
		(start 105.636822 2.646426)
		(end 102.175564 3.256788)
		(width 0.14224)
		(layer "F.Cu")
		(net "85_10INCH_TOP_DP")
	)
	(segment
		(start 106.188002 -8.428228)
		(end 105.608628 -8.834374)
		(width 0.14224)
		(layer "F.Cu")
		(net "85_10INCH_TOP_DP")
	)
	(segment
		(start 101.911912 1.76276)
		(end 105.990898 1.043686)
		(width 0.14224)
		(layer "F.Cu")
		(net "85_10INCH_TOP_DP")
	)
	(segment
		(start 106.41711 11.94689)
		(end 106.199178 10.712958)
		(width 0.14224)
		(layer "F.Cu")
		(net "85_10INCH_TOP_DP")
	)
	(segment
		(start 100.662232 -35.052)
		(end 100.497386 -35.986212)
		(width 0.14224)
		(layer "F.Cu")
		(net "85_10INCH_TOP_DP")
	)
	(segment
		(start 106.377994 8.125206)
		(end 106.160062 6.891274)
		(width 0.14224)
		(layer "F.Cu")
		(net "85_10INCH_TOP_DP")
	)
	(segment
		(start 101.81971 6.859524)
		(end 101.654864 5.925312)
		(width 0.14224)
		(layer "F.Cu")
		(net "85_10INCH_TOP_DP")
	)
	(segment
		(start 107.632246 -26.554176)
		(end 107.414314 -27.788108)
		(width 0.14224)
		(layer "F.Cu")
		(net "85_10INCH_TOP_DP")
	)
	(segment
		(start 106.805476 -43.503596)
		(end 100.91928 -42.465752)
		(width 0.14224)
		(layer "F.Cu")
		(net "85_10INCH_TOP_DP")
	)
	(segment
		(start 101.690932 9.747504)
		(end 101.92131 9.418574)
		(width 0.14224)
		(layer "F.Cu")
		(net "85_10INCH_TOP_DP")
	)
	(segment
		(start 107.560618 -11.2268)
		(end 107.342686 -12.460732)
		(width 0.14224)
		(layer "F.Cu")
		(net "85_10INCH_TOP_DP")
	)
	(segment
		(start 100.957634 -30.986476)
		(end 100.628196 -31.217108)
		(width 0.14224)
		(layer "F.Cu")
		(net "85_10INCH_TOP_DP")
	)
	(segment
		(start 100.655628 -43.95978)
		(end 107.165902 -45.107606)
		(width 0.14224)
		(layer "F.Cu")
		(net "85_10INCH_TOP_DP")
	)
	(segment
		(start 107.602782 -41.863518)
		(end 107.38485 -43.09745)
		(width 0.14224)
		(layer "F.Cu")
		(net "85_10INCH_TOP_DP")
	)
	(segment
		(start 107.22483 -33.631378)
		(end 107.630468 -34.21126)
		(width 0.14224)
		(layer "F.Cu")
		(net "85_10INCH_TOP_DP")
	)
	(segment
		(start 100.579682 -23.551388)
		(end 100.414836 -24.4856)
		(width 0.14224)
		(layer "F.Cu")
		(net "85_10INCH_TOP_DP")
	)
	(segment
		(start 100.950522 -19.499326)
		(end 100.621084 -19.729958)
		(width 0.14224)
		(layer "F.Cu")
		(net "85_10INCH_TOP_DP")
	)
	(segment
		(start 107.18673 -14.482064)
		(end 107.592622 -15.061184)
		(width 0.14224)
		(layer "F.Cu")
		(net "85_10INCH_TOP_DP")
	)
	(segment
		(start 106.02849 4.866132)
		(end 106.434128 4.286504)
		(width 0.14224)
		(layer "F.Cu")
		(net "85_10INCH_TOP_DP")
	)
	(segment
		(start 100.68687 -20.993354)
		(end 107.204256 -22.14245)
		(width 0.14224)
		(layer "F.Cu")
		(net "85_10INCH_TOP_DP")
	)
	(segment
		(start 100.589842 -42.696384)
		(end 100.424996 -43.630596)
		(width 0.14224)
		(layer "F.Cu")
		(net "85_10INCH_TOP_DP")
	)
	(segment
		(start 107.161838 -29.792168)
		(end 107.56773 -30.371288)
		(width 0.14224)
		(layer "F.Cu")
		(net "85_10INCH_TOP_DP")
	)
	(segment
		(start 100.778564 -8.27151)
		(end 100.613718 -9.205722)
		(width 0.14224)
		(layer "F.Cu")
		(net "85_10INCH_TOP_DP")
	)
	(segment
		(start 100.645468 -24.814784)
		(end 107.226354 -25.975056)
		(width 0.14224)
		(layer "F.Cu")
		(net "85_10INCH_TOP_DP")
	)
	(segment
		(start 106.740706 -39.663624)
		(end 100.873306 -38.629082)
		(width 0.14224)
		(layer "F.Cu")
		(net "85_10INCH_TOP_DP")
	)
	(segment
		(start 100.457 -13.006832)
		(end 100.687632 -13.336016)
		(width 0.14224)
		(layer "F.Cu")
		(net "85_10INCH_TOP_DP")
	)
	(segment
		(start 107.571794 -45.686726)
		(end 107.353862 -46.920658)
		(width 0.14224)
		(layer "F.Cu")
		(net "85_10INCH_TOP_DP")
	)
	(segment
		(start 106.763312 -12.866878)
		(end 100.951284 -11.841988)
		(width 0.14224)
		(layer "F.Cu")
		(net "85_10INCH_TOP_DP")
	)
	(segment
		(start 105.599484 -1.175512)
		(end 102.169468 -0.570738)
		(width 0.14224)
		(layer "F.Cu")
		(net "85_10INCH_TOP_DP")
	)
	(segment
		(start 100.951284 -11.841988)
		(end 100.621846 -12.07262)
		(width 0.14224)
		(layer "F.Cu")
		(net "85_10INCH_TOP_DP")
	)
	(segment
		(start 106.000042 -6.615176)
		(end 106.405934 -7.194296)
		(width 0.14224)
		(layer "F.Cu")
		(net "85_10INCH_TOP_DP")
	)
	(segment
		(start 100.873306 -38.629082)
		(end 100.543868 -38.859714)
		(width 0.14224)
		(layer "F.Cu")
		(net "85_10INCH_TOP_DP")
	)
	(segment
		(start 101.84257 -4.630674)
		(end 101.677724 -5.564886)
		(width 0.14224)
		(layer "F.Cu")
		(net "85_10INCH_TOP_DP")
	)
	(segment
		(start 106.83494 -28.194254)
		(end 100.844858 -27.138122)
		(width 0.14224)
		(layer "F.Cu")
		(net "85_10INCH_TOP_DP")
	)
	(segment
		(start 105.990898 1.043686)
		(end 106.39679 0.464566)
		(width 0.14224)
		(layer "F.Cu")
		(net "85_10INCH_TOP_DP")
	)
	(segment
		(start 101.677724 -5.564886)
		(end 101.908102 -5.893816)
		(width 0.14224)
		(layer "F.Cu")
		(net "85_10INCH_TOP_DP")
	)
	(segment
		(start 101.92131 9.418574)
		(end 105.972102 8.704326)
		(width 0.14224)
		(layer "F.Cu")
		(net "85_10INCH_TOP_DP")
	)
	(segment
		(start 100.693474 -47.79518)
		(end 103.77932 -48.339248)
		(width 0.14224)
		(layer "F.Cu")
		(net "85_10INCH_TOP_DP")
	)
	(segment
		(start 107.204256 -22.14245)
		(end 107.610148 -22.72157)
		(width 0.14224)
		(layer "F.Cu")
		(net "85_10INCH_TOP_DP")
	)
	(segment
		(start 104.072436 -53.420772)
		(end 104.072436 -53.578252)
		(width 0.14224)
		(layer "F.Cu")
		(net "85_10INCH_TOP_DP")
	)
	(segment
		(start 105.619804 10.306812)
		(end 102.18547 10.912348)
		(width 0.14224)
		(layer "F.Cu")
		(net "85_10INCH_TOP_DP")
	)
	(segment
		(start 101.885496 5.596382)
		(end 106.02849 4.866132)
		(width 0.14224)
		(layer "F.Cu")
		(net "85_10INCH_TOP_DP")
	)
	(segment
		(start 104.072436 17.018508)
		(end 104.00665 16.952722)
		(width 0.14224)
		(layer "F.Cu")
		(net "85_10INCH_TOP_DP")
	)
	(segment
		(start 100.456238 -20.66417)
		(end 100.68687 -20.993354)
		(width 0.14224)
		(layer "F.Cu")
		(net "85_10INCH_TOP_DP")
	)
	(segment
		(start 106.199178 10.712958)
		(end 105.619804 10.306812)
		(width 0.14224)
		(layer "F.Cu")
		(net "85_10INCH_TOP_DP")
	)
	(segment
		(start 101.855778 10.681716)
		(end 101.690932 9.747504)
		(width 0.14224)
		(layer "F.Cu")
		(net "85_10INCH_TOP_DP")
	)
	(segment
		(start 107.342686 -12.460732)
		(end 106.763312 -12.866878)
		(width 0.14224)
		(layer "F.Cu")
		(net "85_10INCH_TOP_DP")
	)
	(segment
		(start 104.00665 13.235432)
		(end 104.438704 12.803378)
		(width 0.14224)
		(layer "F.Cu")
		(net "85_10INCH_TOP_DP")
	)
	(segment
		(start 100.728018 -36.315142)
		(end 107.13212 -37.444426)
		(width 0.14224)
		(layer "F.Cu")
		(net "85_10INCH_TOP_DP")
	)
	(segment
		(start 102.172008 -4.400042)
		(end 101.84257 -4.630674)
		(width 0.14224)
		(layer "F.Cu")
		(net "85_10INCH_TOP_DP")
	)
	(segment
		(start 100.687632 -13.336016)
		(end 107.18673 -14.482064)
		(width 0.14224)
		(layer "F.Cu")
		(net "85_10INCH_TOP_DP")
	)
	(segment
		(start 101.84003 -0.80137)
		(end 101.675184 -1.735582)
		(width 0.14224)
		(layer "F.Cu")
		(net "85_10INCH_TOP_DP")
	)
	(segment
		(start 101.905816 -2.064766)
		(end 106.002074 -2.786634)
		(width 0.14224)
		(layer "F.Cu")
		(net "85_10INCH_TOP_DP")
	)
	(segment
		(start 103.77932 -48.339248)
		(end 104.185212 -48.918368)
		(width 0.14224)
		(layer "F.Cu")
		(net "85_10INCH_TOP_DP")
	)
	(segment
		(start 105.608628 -8.834374)
		(end 101.108002 -8.040878)
		(width 0.14224)
		(layer "F.Cu")
		(net "85_10INCH_TOP_DP")
	)
	(segment
		(start 100.46335 -32.15132)
		(end 100.693982 -32.480758)
		(width 0.14224)
		(layer "F.Cu")
		(net "85_10INCH_TOP_DP")
	)
	(segment
		(start 106.405934 -7.194296)
		(end 106.188002 -8.428228)
		(width 0.14224)
		(layer "F.Cu")
		(net "85_10INCH_TOP_DP")
	)
	(segment
		(start 107.257088 -18.323052)
		(end 107.66298 -18.902172)
		(width 0.14224)
		(layer "F.Cu")
		(net "85_10INCH_TOP_DP")
	)
	(segment
		(start 104.072436 17.175988)
		(end 104.072436 17.018508)
		(width 0.14224)
		(layer "F.Cu")
		(net "85_10INCH_TOP_DP")
	)
	(segment
		(start 106.407712 -3.366262)
		(end 106.18978 -4.600194)
		(width 0.14224)
		(layer "F.Cu")
		(net "85_10INCH_TOP_DP")
	)
	(segment
		(start 100.613718 -9.205722)
		(end 100.84435 -9.534906)
		(width 0.14224)
		(layer "F.Cu")
		(net "85_10INCH_TOP_DP")
	)
	(segment
		(start 105.610406 -5.00634)
		(end 102.172008 -4.400042)
		(width 0.14224)
		(layer "F.Cu")
		(net "85_10INCH_TOP_DP")
	)
	(segment
		(start 107.154726 -10.64768)
		(end 107.560618 -11.2268)
		(width 0.14224)
		(layer "F.Cu")
		(net "85_10INCH_TOP_DP")
	)
	(segment
		(start 100.543868 -38.859714)
		(end 100.379022 -39.793926)
		(width 0.14224)
		(layer "F.Cu")
		(net "85_10INCH_TOP_DP")
	)
	(segment
		(start 100.609654 -40.122856)
		(end 107.19689 -41.284398)
		(width 0.14224)
		(layer "F.Cu")
		(net "85_10INCH_TOP_DP")
	)
	(segment
		(start 107.37469 -16.295116)
		(end 106.795316 -16.701262)
		(width 0.14224)
		(layer "F.Cu")
		(net "85_10INCH_TOP_DP")
	)
	(segment
		(start 100.90912 -23.320756)
		(end 100.579682 -23.551388)
		(width 0.14224)
		(layer "F.Cu")
		(net "85_10INCH_TOP_DP")
	)
	(segment
		(start 100.621846 -12.07262)
		(end 100.457 -13.006832)
		(width 0.14224)
		(layer "F.Cu")
		(net "85_10INCH_TOP_DP")
	)
	(segment
		(start 100.580952 -28.631896)
		(end 107.161838 -29.792168)
		(width 0.14224)
		(layer "F.Cu")
		(net "85_10INCH_TOP_DP")
	)
	(segment
		(start 100.844858 -27.138122)
		(end 100.51542 -27.368754)
		(width 0.14224)
		(layer "F.Cu")
		(net "85_10INCH_TOP_DP")
	)
	(segment
		(start 100.91928 -42.465752)
		(end 100.589842 -42.696384)
		(width 0.14224)
		(layer "F.Cu")
		(net "85_10INCH_TOP_DP")
	)
	(segment
		(start 106.812842 -24.361648)
		(end 100.90912 -23.320756)
		(width 0.14224)
		(layer "F.Cu")
		(net "85_10INCH_TOP_DP")
	)
	(segment
		(start 107.414314 -27.788108)
		(end 106.83494 -28.194254)
		(width 0.14224)
		(layer "F.Cu")
		(net "85_10INCH_TOP_DP")
	)
	(segment
		(start 107.592622 -15.061184)
		(end 107.37469 -16.295116)
		(width 0.14224)
		(layer "F.Cu")
		(net "85_10INCH_TOP_DP")
	)
	(segment
		(start 107.392216 -23.955502)
		(end 106.812842 -24.361648)
		(width 0.14224)
		(layer "F.Cu")
		(net "85_10INCH_TOP_DP")
	)
	(segment
		(start 107.538012 -38.023546)
		(end 107.32008 -39.257478)
		(width 0.14224)
		(layer "F.Cu")
		(net "85_10INCH_TOP_DP")
	)
	(segment
		(start 100.247196 -15.680182)
		(end 100.029264 -16.91513)
		(width 0.14224)
		(layer "F.Cu")
		(net "85_10INCH_TOP_DN")
	)
	(segment
		(start 100.82657 -15.274544)
		(end 100.247196 -15.680182)
		(width 0.14224)
		(layer "F.Cu")
		(net "85_10INCH_TOP_DN")
	)
	(segment
		(start 103.565198 -48.675544)
		(end 103.79583 -49.004728)
		(width 0.14224)
		(layer "F.Cu")
		(net "85_10INCH_TOP_DN")
	)
	(segment
		(start 105.522268 -8.444992)
		(end 101.021642 -7.651496)
		(width 0.14224)
		(layer "F.Cu")
		(net "85_10INCH_TOP_DN")
	)
	(segment
		(start 99.98964 -39.88054)
		(end 100.395532 -40.459152)
		(width 0.14224)
		(layer "F.Cu")
		(net "85_10INCH_TOP_DN")
	)
	(segment
		(start 100.435156 -17.49425)
		(end 107.042966 -18.659348)
		(width 0.14224)
		(layer "F.Cu")
		(net "85_10INCH_TOP_DN")
	)
	(segment
		(start 105.797096 12.189714)
		(end 106.027728 11.86053)
		(width 0.14224)
		(layer "F.Cu")
		(net "85_10INCH_TOP_DN")
	)
	(segment
		(start 104.260396 12.460732)
		(end 105.797096 12.189714)
		(width 0.14224)
		(layer "F.Cu")
		(net "85_10INCH_TOP_DN")
	)
	(segment
		(start 102.083108 -0.181356)
		(end 101.503734 -0.586994)
		(width 0.14224)
		(layer "F.Cu")
		(net "85_10INCH_TOP_DN")
	)
	(segment
		(start 100.83292 -42.07637)
		(end 100.253546 -42.482262)
		(width 0.14224)
		(layer "F.Cu")
		(net "85_10INCH_TOP_DN")
	)
	(segment
		(start 107.042966 -18.659348)
		(end 107.273598 -18.988532)
		(width 0.14224)
		(layer "F.Cu")
		(net "85_10INCH_TOP_DN")
	)
	(segment
		(start 106.007408 0.378206)
		(end 105.842562 -0.555244)
		(width 0.14224)
		(layer "F.Cu")
		(net "85_10INCH_TOP_DN")
	)
	(segment
		(start 106.726482 -23.972266)
		(end 100.82276 -22.931374)
		(width 0.14224)
		(layer "F.Cu")
		(net "85_10INCH_TOP_DN")
	)
	(segment
		(start 105.550462 3.035808)
		(end 102.089204 3.64617)
		(width 0.14224)
		(layer "F.Cu")
		(net "85_10INCH_TOP_DN")
	)
	(segment
		(start 107.00639 -12.24661)
		(end 106.676952 -12.477496)
		(width 0.14224)
		(layer "F.Cu")
		(net "85_10INCH_TOP_DN")
	)
	(segment
		(start 105.988612 8.038846)
		(end 105.823766 7.105396)
		(width 0.14224)
		(layer "F.Cu")
		(net "85_10INCH_TOP_DN")
	)
	(segment
		(start 100.073968 -32.23768)
		(end 100.47986 -32.817054)
		(width 0.14224)
		(layer "F.Cu")
		(net "85_10INCH_TOP_DN")
	)
	(segment
		(start 100.025454 -24.57196)
		(end 100.431346 -25.15108)
		(width 0.14224)
		(layer "F.Cu")
		(net "85_10INCH_TOP_DN")
	)
	(segment
		(start 107.178348 -30.457648)
		(end 107.013502 -31.391098)
		(width 0.14224)
		(layer "F.Cu")
		(net "85_10INCH_TOP_DN")
	)
	(segment
		(start 105.776776 0.70739)
		(end 106.007408 0.378206)
		(width 0.14224)
		(layer "F.Cu")
		(net "85_10INCH_TOP_DN")
	)
	(segment
		(start 107.012232 -26.311352)
		(end 107.242864 -26.640536)
		(width 0.14224)
		(layer "F.Cu")
		(net "85_10INCH_TOP_DN")
	)
	(segment
		(start 100.431346 -25.15108)
		(end 107.012232 -26.311352)
		(width 0.14224)
		(layer "F.Cu")
		(net "85_10INCH_TOP_DN")
	)
	(segment
		(start 106.972608 -14.81836)
		(end 107.20324 -15.147544)
		(width 0.14224)
		(layer "F.Cu")
		(net "85_10INCH_TOP_DN")
	)
	(segment
		(start 107.241086 -34.297366)
		(end 107.07624 -35.23107)
		(width 0.14224)
		(layer "F.Cu")
		(net "85_10INCH_TOP_DN")
	)
	(segment
		(start 106.684064 -31.621984)
		(end 100.871274 -30.597094)
		(width 0.14224)
		(layer "F.Cu")
		(net "85_10INCH_TOP_DN")
	)
	(segment
		(start 100.395532 -40.459152)
		(end 106.982768 -41.620694)
		(width 0.14224)
		(layer "F.Cu")
		(net "85_10INCH_TOP_DN")
	)
	(segment
		(start 101.506274 -4.416298)
		(end 101.288342 -5.651246)
		(width 0.14224)
		(layer "F.Cu")
		(net "85_10INCH_TOP_DN")
	)
	(segment
		(start 106.983784 -39.043356)
		(end 106.654346 -39.274242)
		(width 0.14224)
		(layer "F.Cu")
		(net "85_10INCH_TOP_DN")
	)
	(segment
		(start 100.870766 -45.91177)
		(end 100.291392 -46.317408)
		(width 0.14224)
		(layer "F.Cu")
		(net "85_10INCH_TOP_DN")
	)
	(segment
		(start 100.291392 -46.317408)
		(end 100.07346 -47.552356)
		(width 0.14224)
		(layer "F.Cu")
		(net "85_10INCH_TOP_DN")
	)
	(segment
		(start 100.108004 -36.072826)
		(end 100.513896 -36.651438)
		(width 0.14224)
		(layer "F.Cu")
		(net "85_10INCH_TOP_DN")
	)
	(segment
		(start 102.089204 3.64617)
		(end 101.50983 3.240532)
		(width 0.14224)
		(layer "F.Cu")
		(net "85_10INCH_TOP_DN")
	)
	(segment
		(start 101.69779 1.426464)
		(end 105.776776 0.70739)
		(width 0.14224)
		(layer "F.Cu")
		(net "85_10INCH_TOP_DN")
	)
	(segment
		(start 106.917998 -37.780722)
		(end 107.14863 -38.109906)
		(width 0.14224)
		(layer "F.Cu")
		(net "85_10INCH_TOP_DN")
	)
	(segment
		(start 101.671374 5.260086)
		(end 105.814114 4.529582)
		(width 0.14224)
		(layer "F.Cu")
		(net "85_10INCH_TOP_DN")
	)
	(segment
		(start 106.676952 -12.477496)
		(end 100.864924 -11.452606)
		(width 0.14224)
		(layer "F.Cu")
		(net "85_10INCH_TOP_DN")
	)
	(segment
		(start 107.220766 -22.80793)
		(end 107.05592 -23.74138)
		(width 0.14224)
		(layer "F.Cu")
		(net "85_10INCH_TOP_DN")
	)
	(segment
		(start 100.36683 -28.968192)
		(end 106.947716 -30.128464)
		(width 0.14224)
		(layer "F.Cu")
		(net "85_10INCH_TOP_DN")
	)
	(segment
		(start 100.067618 -13.093192)
		(end 100.47351 -13.672312)
		(width 0.14224)
		(layer "F.Cu")
		(net "85_10INCH_TOP_DN")
	)
	(segment
		(start 107.048554 -42.883328)
		(end 106.719116 -43.114214)
		(width 0.14224)
		(layer "F.Cu")
		(net "85_10INCH_TOP_DN")
	)
	(segment
		(start 106.708956 -16.31188)
		(end 100.82657 -15.274544)
		(width 0.14224)
		(layer "F.Cu")
		(net "85_10INCH_TOP_DN")
	)
	(segment
		(start 100.035614 -43.716956)
		(end 100.441506 -44.296076)
		(width 0.14224)
		(layer "F.Cu")
		(net "85_10INCH_TOP_DN")
	)
	(segment
		(start 100.2919 -31.002732)
		(end 100.073968 -32.23768)
		(width 0.14224)
		(layer "F.Cu")
		(net "85_10INCH_TOP_DN")
	)
	(segment
		(start 105.862882 10.92708)
		(end 105.533444 10.696194)
		(width 0.14224)
		(layer "F.Cu")
		(net "85_10INCH_TOP_DN")
	)
	(segment
		(start 102.09911 11.30173)
		(end 101.519482 10.896092)
		(width 0.14224)
		(layer "F.Cu")
		(net "85_10INCH_TOP_DN")
	)
	(segment
		(start 106.027728 11.86053)
		(end 105.862882 10.92708)
		(width 0.14224)
		(layer "F.Cu")
		(net "85_10INCH_TOP_DN")
	)
	(segment
		(start 103.63835 13.082778)
		(end 104.260396 12.460732)
		(width 0.14224)
		(layer "F.Cu")
		(net "85_10INCH_TOP_DN")
	)
	(segment
		(start 106.654346 -39.274242)
		(end 100.786946 -38.2397)
		(width 0.14224)
		(layer "F.Cu")
		(net "85_10INCH_TOP_DN")
	)
	(segment
		(start 101.503734 -0.586994)
		(end 101.285802 -1.821942)
		(width 0.14224)
		(layer "F.Cu")
		(net "85_10INCH_TOP_DN")
	)
	(segment
		(start 105.787698 -3.123184)
		(end 106.01833 -3.452622)
		(width 0.14224)
		(layer "F.Cu")
		(net "85_10INCH_TOP_DN")
	)
	(segment
		(start 107.108752 -19.921982)
		(end 106.779314 -20.152868)
		(width 0.14224)
		(layer "F.Cu")
		(net "85_10INCH_TOP_DN")
	)
	(segment
		(start 107.273598 -18.988532)
		(end 107.108752 -19.921982)
		(width 0.14224)
		(layer "F.Cu")
		(net "85_10INCH_TOP_DN")
	)
	(segment
		(start 106.940604 -10.983976)
		(end 107.171236 -11.31316)
		(width 0.14224)
		(layer "F.Cu")
		(net "85_10INCH_TOP_DN")
	)
	(segment
		(start 105.851706 -8.214106)
		(end 105.522268 -8.444992)
		(width 0.14224)
		(layer "F.Cu")
		(net "85_10INCH_TOP_DN")
	)
	(segment
		(start 100.786946 -38.2397)
		(end 100.207572 -38.645592)
		(width 0.14224)
		(layer "F.Cu")
		(net "85_10INCH_TOP_DN")
	)
	(segment
		(start 103.572564 -53.420772)
		(end 103.572564 -53.578252)
		(width 0.14224)
		(layer "F.Cu")
		(net "85_10INCH_TOP_DN")
	)
	(segment
		(start 107.182412 -45.773086)
		(end 107.017566 -46.706536)
		(width 0.14224)
		(layer "F.Cu")
		(net "85_10INCH_TOP_DN")
	)
	(segment
		(start 106.016552 -7.280656)
		(end 105.851706 -8.214106)
		(width 0.14224)
		(layer "F.Cu")
		(net "85_10INCH_TOP_DN")
	)
	(segment
		(start 100.442268 -8.057134)
		(end 100.224336 -9.292082)
		(width 0.14224)
		(layer "F.Cu")
		(net "85_10INCH_TOP_DN")
	)
	(segment
		(start 103.63835 -49.896268)
		(end 103.63835 -53.354986)
		(width 0.14224)
		(layer "F.Cu")
		(net "85_10INCH_TOP_DN")
	)
	(segment
		(start 106.982768 -41.620694)
		(end 107.2134 -41.949878)
		(width 0.14224)
		(layer "F.Cu")
		(net "85_10INCH_TOP_DN")
	)
	(segment
		(start 106.746802 -35.461956)
		(end 100.90531 -34.431986)
		(width 0.14224)
		(layer "F.Cu")
		(net "85_10INCH_TOP_DN")
	)
	(segment
		(start 100.513896 -36.651438)
		(end 106.917998 -37.780722)
		(width 0.14224)
		(layer "F.Cu")
		(net "85_10INCH_TOP_DN")
	)
	(segment
		(start 105.853484 -4.386072)
		(end 105.524046 -4.616958)
		(width 0.14224)
		(layer "F.Cu")
		(net "85_10INCH_TOP_DN")
	)
	(segment
		(start 102.085648 -4.01066)
		(end 101.506274 -4.416298)
		(width 0.14224)
		(layer "F.Cu")
		(net "85_10INCH_TOP_DN")
	)
	(segment
		(start 100.243386 -23.337012)
		(end 100.025454 -24.57196)
		(width 0.14224)
		(layer "F.Cu")
		(net "85_10INCH_TOP_DN")
	)
	(segment
		(start 105.823766 7.105396)
		(end 105.494328 6.87451)
		(width 0.14224)
		(layer "F.Cu")
		(net "85_10INCH_TOP_DN")
	)
	(segment
		(start 100.472748 -21.32965)
		(end 106.990134 -22.478746)
		(width 0.14224)
		(layer "F.Cu")
		(net "85_10INCH_TOP_DN")
	)
	(segment
		(start 105.842562 -0.555244)
		(end 105.513124 -0.78613)
		(width 0.14224)
		(layer "F.Cu")
		(net "85_10INCH_TOP_DN")
	)
	(segment
		(start 103.572564 17.018508)
		(end 103.63835 16.952722)
		(width 0.14224)
		(layer "F.Cu")
		(net "85_10INCH_TOP_DN")
	)
	(segment
		(start 100.864924 -11.452606)
		(end 100.28555 -11.858244)
		(width 0.14224)
		(layer "F.Cu")
		(net "85_10INCH_TOP_DN")
	)
	(segment
		(start 100.441506 -44.296076)
		(end 106.95178 -45.443902)
		(width 0.14224)
		(layer "F.Cu")
		(net "85_10INCH_TOP_DN")
	)
	(segment
		(start 107.017566 -46.706536)
		(end 106.688128 -46.937422)
		(width 0.14224)
		(layer "F.Cu")
		(net "85_10INCH_TOP_DN")
	)
	(segment
		(start 100.630228 -9.871202)
		(end 106.940604 -10.983976)
		(width 0.14224)
		(layer "F.Cu")
		(net "85_10INCH_TOP_DN")
	)
	(segment
		(start 100.28555 -11.858244)
		(end 100.067618 -13.093192)
		(width 0.14224)
		(layer "F.Cu")
		(net "85_10INCH_TOP_DN")
	)
	(segment
		(start 107.038394 -16.080994)
		(end 106.708956 -16.31188)
		(width 0.14224)
		(layer "F.Cu")
		(net "85_10INCH_TOP_DN")
	)
	(segment
		(start 102.062788 7.479538)
		(end 101.483414 7.0739)
		(width 0.14224)
		(layer "F.Cu")
		(net "85_10INCH_TOP_DN")
	)
	(segment
		(start 100.82276 -22.931374)
		(end 100.243386 -23.337012)
		(width 0.14224)
		(layer "F.Cu")
		(net "85_10INCH_TOP_DN")
	)
	(segment
		(start 106.01833 -3.452622)
		(end 105.853484 -4.386072)
		(width 0.14224)
		(layer "F.Cu")
		(net "85_10INCH_TOP_DN")
	)
	(segment
		(start 107.14863 -38.109906)
		(end 106.983784 -39.043356)
		(width 0.14224)
		(layer "F.Cu")
		(net "85_10INCH_TOP_DN")
	)
	(segment
		(start 103.79583 -49.004728)
		(end 103.63835 -49.896268)
		(width 0.14224)
		(layer "F.Cu")
		(net "85_10INCH_TOP_DN")
	)
	(segment
		(start 100.253546 -42.482262)
		(end 100.035614 -43.716956)
		(width 0.14224)
		(layer "F.Cu")
		(net "85_10INCH_TOP_DN")
	)
	(segment
		(start 107.171236 -11.31316)
		(end 107.00639 -12.24661)
		(width 0.14224)
		(layer "F.Cu")
		(net "85_10INCH_TOP_DN")
	)
	(segment
		(start 99.961192 -28.389326)
		(end 100.36683 -28.968192)
		(width 0.14224)
		(layer "F.Cu")
		(net "85_10INCH_TOP_DN")
	)
	(segment
		(start 107.2134 -41.949878)
		(end 107.048554 -42.883328)
		(width 0.14224)
		(layer "F.Cu")
		(net "85_10INCH_TOP_DN")
	)
	(segment
		(start 107.078018 -27.573986)
		(end 106.74858 -27.804872)
		(width 0.14224)
		(layer "F.Cu")
		(net "85_10INCH_TOP_DN")
	)
	(segment
		(start 100.284788 -19.515582)
		(end 100.066856 -20.75053)
		(width 0.14224)
		(layer "F.Cu")
		(net "85_10INCH_TOP_DN")
	)
	(segment
		(start 100.207572 -38.645592)
		(end 99.98964 -39.88054)
		(width 0.14224)
		(layer "F.Cu")
		(net "85_10INCH_TOP_DN")
	)
	(segment
		(start 106.719116 -43.114214)
		(end 100.83292 -42.07637)
		(width 0.14224)
		(layer "F.Cu")
		(net "85_10INCH_TOP_DN")
	)
	(segment
		(start 105.524046 -4.616958)
		(end 102.085648 -4.01066)
		(width 0.14224)
		(layer "F.Cu")
		(net "85_10INCH_TOP_DN")
	)
	(segment
		(start 100.07346 -47.552356)
		(end 100.479352 -48.131476)
		(width 0.14224)
		(layer "F.Cu")
		(net "85_10INCH_TOP_DN")
	)
	(segment
		(start 100.066856 -20.75053)
		(end 100.472748 -21.32965)
		(width 0.14224)
		(layer "F.Cu")
		(net "85_10INCH_TOP_DN")
	)
	(segment
		(start 106.990134 -22.478746)
		(end 107.220766 -22.80793)
		(width 0.14224)
		(layer "F.Cu")
		(net "85_10INCH_TOP_DN")
	)
	(segment
		(start 107.05592 -23.74138)
		(end 106.726482 -23.972266)
		(width 0.14224)
		(layer "F.Cu")
		(net "85_10INCH_TOP_DN")
	)
	(segment
		(start 100.871274 -30.597094)
		(end 100.2919 -31.002732)
		(width 0.14224)
		(layer "F.Cu")
		(net "85_10INCH_TOP_DN")
	)
	(segment
		(start 100.47351 -13.672312)
		(end 106.972608 -14.81836)
		(width 0.14224)
		(layer "F.Cu")
		(net "85_10INCH_TOP_DN")
	)
	(segment
		(start 101.288342 -5.651246)
		(end 101.69398 -6.230112)
		(width 0.14224)
		(layer "F.Cu")
		(net "85_10INCH_TOP_DN")
	)
	(segment
		(start 105.75798 8.36803)
		(end 105.988612 8.038846)
		(width 0.14224)
		(layer "F.Cu")
		(net "85_10INCH_TOP_DN")
	)
	(segment
		(start 107.010454 -33.967674)
		(end 107.241086 -34.297366)
		(width 0.14224)
		(layer "F.Cu")
		(net "85_10INCH_TOP_DN")
	)
	(segment
		(start 103.63835 16.952722)
		(end 103.63835 13.082778)
		(width 0.14224)
		(layer "F.Cu")
		(net "85_10INCH_TOP_DN")
	)
	(segment
		(start 105.494328 6.87451)
		(end 102.062788 7.479538)
		(width 0.14224)
		(layer "F.Cu")
		(net "85_10INCH_TOP_DN")
	)
	(segment
		(start 103.572564 17.175988)
		(end 103.572564 17.018508)
		(width 0.14224)
		(layer "F.Cu")
		(net "85_10INCH_TOP_DN")
	)
	(segment
		(start 101.021642 -7.651496)
		(end 100.442268 -8.057134)
		(width 0.14224)
		(layer "F.Cu")
		(net "85_10INCH_TOP_DN")
	)
	(segment
		(start 105.814114 4.529582)
		(end 106.044746 4.200144)
		(width 0.14224)
		(layer "F.Cu")
		(net "85_10INCH_TOP_DN")
	)
	(segment
		(start 101.483414 7.0739)
		(end 101.265482 5.838952)
		(width 0.14224)
		(layer "F.Cu")
		(net "85_10INCH_TOP_DN")
	)
	(segment
		(start 101.69398 -6.230112)
		(end 105.78592 -6.951472)
		(width 0.14224)
		(layer "F.Cu")
		(net "85_10INCH_TOP_DN")
	)
	(segment
		(start 105.8799 3.266694)
		(end 105.550462 3.035808)
		(width 0.14224)
		(layer "F.Cu")
		(net "85_10INCH_TOP_DN")
	)
	(segment
		(start 100.325936 -34.837624)
		(end 100.108004 -36.072826)
		(width 0.14224)
		(layer "F.Cu")
		(net "85_10INCH_TOP_DN")
	)
	(segment
		(start 106.95178 -45.443902)
		(end 107.182412 -45.773086)
		(width 0.14224)
		(layer "F.Cu")
		(net "85_10INCH_TOP_DN")
	)
	(segment
		(start 101.285802 -1.821942)
		(end 101.691694 -2.401062)
		(width 0.14224)
		(layer "F.Cu")
		(net "85_10INCH_TOP_DN")
	)
	(segment
		(start 101.265482 5.838952)
		(end 101.671374 5.260086)
		(width 0.14224)
		(layer "F.Cu")
		(net "85_10INCH_TOP_DN")
	)
	(segment
		(start 100.224336 -9.292082)
		(end 100.630228 -9.871202)
		(width 0.14224)
		(layer "F.Cu")
		(net "85_10INCH_TOP_DN")
	)
	(segment
		(start 107.20324 -15.147544)
		(end 107.038394 -16.080994)
		(width 0.14224)
		(layer "F.Cu")
		(net "85_10INCH_TOP_DN")
	)
	(segment
		(start 106.688128 -46.937422)
		(end 100.870766 -45.91177)
		(width 0.14224)
		(layer "F.Cu")
		(net "85_10INCH_TOP_DN")
	)
	(segment
		(start 106.044746 4.200144)
		(end 105.8799 3.266694)
		(width 0.14224)
		(layer "F.Cu")
		(net "85_10INCH_TOP_DN")
	)
	(segment
		(start 101.707188 9.082278)
		(end 105.75798 8.36803)
		(width 0.14224)
		(layer "F.Cu")
		(net "85_10INCH_TOP_DN")
	)
	(segment
		(start 106.779314 -20.152868)
		(end 100.864162 -19.109944)
		(width 0.14224)
		(layer "F.Cu")
		(net "85_10INCH_TOP_DN")
	)
	(segment
		(start 100.179124 -27.154378)
		(end 99.961192 -28.389326)
		(width 0.14224)
		(layer "F.Cu")
		(net "85_10INCH_TOP_DN")
	)
	(segment
		(start 107.07624 -35.23107)
		(end 106.746802 -35.461956)
		(width 0.14224)
		(layer "F.Cu")
		(net "85_10INCH_TOP_DN")
	)
	(segment
		(start 101.291898 2.005584)
		(end 101.69779 1.426464)
		(width 0.14224)
		(layer "F.Cu")
		(net "85_10INCH_TOP_DN")
	)
	(segment
		(start 106.947716 -30.128464)
		(end 107.178348 -30.457648)
		(width 0.14224)
		(layer "F.Cu")
		(net "85_10INCH_TOP_DN")
	)
	(segment
		(start 100.029264 -16.91513)
		(end 100.435156 -17.49425)
		(width 0.14224)
		(layer "F.Cu")
		(net "85_10INCH_TOP_DN")
	)
	(segment
		(start 101.30155 9.661144)
		(end 101.707188 9.082278)
		(width 0.14224)
		(layer "F.Cu")
		(net "85_10INCH_TOP_DN")
	)
	(segment
		(start 101.691694 -2.401062)
		(end 105.787698 -3.123184)
		(width 0.14224)
		(layer "F.Cu")
		(net "85_10INCH_TOP_DN")
	)
	(segment
		(start 100.758498 -26.74874)
		(end 100.179124 -27.154378)
		(width 0.14224)
		(layer "F.Cu")
		(net "85_10INCH_TOP_DN")
	)
	(segment
		(start 103.63835 -53.354986)
		(end 103.572564 -53.420772)
		(width 0.14224)
		(layer "F.Cu")
		(net "85_10INCH_TOP_DN")
	)
	(segment
		(start 107.242864 -26.640536)
		(end 107.078018 -27.573986)
		(width 0.14224)
		(layer "F.Cu")
		(net "85_10INCH_TOP_DN")
	)
	(segment
		(start 100.47986 -32.817054)
		(end 107.010454 -33.967674)
		(width 0.14224)
		(layer "F.Cu")
		(net "85_10INCH_TOP_DN")
	)
	(segment
		(start 105.533444 10.696194)
		(end 102.09911 11.30173)
		(width 0.14224)
		(layer "F.Cu")
		(net "85_10INCH_TOP_DN")
	)
	(segment
		(start 105.78592 -6.951472)
		(end 106.016552 -7.280656)
		(width 0.14224)
		(layer "F.Cu")
		(net "85_10INCH_TOP_DN")
	)
	(segment
		(start 101.519482 10.896092)
		(end 101.30155 9.661144)
		(width 0.14224)
		(layer "F.Cu")
		(net "85_10INCH_TOP_DN")
	)
	(segment
		(start 107.013502 -31.391098)
		(end 106.684064 -31.621984)
		(width 0.14224)
		(layer "F.Cu")
		(net "85_10INCH_TOP_DN")
	)
	(segment
		(start 100.864162 -19.109944)
		(end 100.284788 -19.515582)
		(width 0.14224)
		(layer "F.Cu")
		(net "85_10INCH_TOP_DN")
	)
	(segment
		(start 105.513124 -0.78613)
		(end 102.083108 -0.181356)
		(width 0.14224)
		(layer "F.Cu")
		(net "85_10INCH_TOP_DN")
	)
	(segment
		(start 101.50983 3.240532)
		(end 101.291898 2.005584)
		(width 0.14224)
		(layer "F.Cu")
		(net "85_10INCH_TOP_DN")
	)
	(segment
		(start 106.74858 -27.804872)
		(end 100.758498 -26.74874)
		(width 0.14224)
		(layer "F.Cu")
		(net "85_10INCH_TOP_DN")
	)
	(segment
		(start 100.90531 -34.431986)
		(end 100.325936 -34.837624)
		(width 0.14224)
		(layer "F.Cu")
		(net "85_10INCH_TOP_DN")
	)
	(segment
		(start 100.479352 -48.131476)
		(end 103.565198 -48.675544)
		(width 0.14224)
		(layer "F.Cu")
		(net "85_10INCH_TOP_DN")
	)
	(segment
		(start 95.67672 -97.574862)
		(end 95.494856 -96.92259)
		(width 0.12954)
		(layer "F.Cu")
		(net "85_10INCH_IN4_DP")
	)
	(segment
		(start 95.66148 -16.721074)
		(end 95.479616 -17.373346)
		(width 0.12954)
		(layer "F.Cu")
		(net "85_10INCH_IN4_DP")
	)
	(via
		(at 95.479616 -17.373346)
		(size 0.508)
		(drill 0.254)
		(layers "F.Cu" "B.Cu")
		(net "85_10INCH_IN4_DP")
	)
	(via
		(at 95.494856 -96.92259)
		(size 0.508)
		(drill 0.254)
		(layers "F.Cu" "B.Cu")
		(net "85_10INCH_IN4_DP")
	)
	(segment
		(start 93.848174 -54.718458)
		(end 93.355922 -55.062882)
		(width 0.1143)
		(layer "In9.Cu")
		(net "85_10INCH_IN4_DP")
	)
	(segment
		(start 98.880676 -90.298524)
		(end 98.674682 -91.464384)
		(width 0.1143)
		(layer "In9.Cu")
		(net "85_10INCH_IN4_DP")
	)
	(segment
		(start 93.87586 -22.610318)
		(end 93.383608 -22.954742)
		(width 0.1143)
		(layer "In9.Cu")
		(net "85_10INCH_IN4_DP")
	)
	(segment
		(start 98.427794 -27.194764)
		(end 98.162872 -27.380184)
		(width 0.1143)
		(layer "In9.Cu")
		(net "85_10INCH_IN4_DP")
	)
	(segment
		(start 98.638868 -42.08653)
		(end 98.433128 -43.25239)
		(width 0.1143)
		(layer "In9.Cu")
		(net "85_10INCH_IN4_DP")
	)
	(segment
		(start 93.383608 -22.954742)
		(end 93.359224 -23.091648)
		(width 0.1143)
		(layer "In9.Cu")
		(net "85_10INCH_IN4_DP")
	)
	(segment
		(start 97.911412 -55.202836)
		(end 97.646998 -55.388256)
		(width 0.1143)
		(layer "In9.Cu")
		(net "85_10INCH_IN4_DP")
	)
	(segment
		(start 98.162872 -27.380184)
		(end 93.88475 -26.626058)
		(width 0.1143)
		(layer "In9.Cu")
		(net "85_10INCH_IN4_DP")
	)
	(segment
		(start 93.420438 -71.130668)
		(end 93.166438 -72.571102)
		(width 0.1143)
		(layer "In9.Cu")
		(net "85_10INCH_IN4_DP")
	)
	(segment
		(start 93.446346 -56.99506)
		(end 97.909888 -57.78246)
		(width 0.1143)
		(layer "In9.Cu")
		(net "85_10INCH_IN4_DP")
	)
	(segment
		(start 93.502734 -40.948864)
		(end 98.453448 -41.821862)
		(width 0.1143)
		(layer "In9.Cu")
		(net "85_10INCH_IN4_DP")
	)
	(segment
		(start 93.118432 -80.590898)
		(end 93.46311 -81.082896)
		(width 0.1143)
		(layer "In9.Cu")
		(net "85_10INCH_IN4_DP")
	)
	(segment
		(start 93.397578 -31.126684)
		(end 93.397832 -31.126684)
		(width 0.1143)
		(layer "In9.Cu")
		(net "85_10INCH_IN4_DP")
	)
	(segment
		(start 93.432376 -35.005772)
		(end 93.178122 -36.446206)
		(width 0.1143)
		(layer "In9.Cu")
		(net "85_10INCH_IN4_DP")
	)
	(segment
		(start 97.909888 -57.78246)
		(end 98.095308 -58.047128)
		(width 0.1143)
		(layer "In9.Cu")
		(net "85_10INCH_IN4_DP")
	)
	(segment
		(start 93.878654 -86.836758)
		(end 93.386656 -87.181436)
		(width 0.1143)
		(layer "In9.Cu")
		(net "85_10INCH_IN4_DP")
	)
	(segment
		(start 93.103192 -92.630752)
		(end 93.44787 -93.12275)
		(width 0.1143)
		(layer "In9.Cu")
		(net "85_10INCH_IN4_DP")
	)
	(segment
		(start 93.158056 -40.456866)
		(end 93.502734 -40.948864)
		(width 0.1143)
		(layer "In9.Cu")
		(net "85_10INCH_IN4_DP")
	)
	(segment
		(start 93.39707 -75.14082)
		(end 93.142816 -76.581)
		(width 0.1143)
		(layer "In9.Cu")
		(net "85_10INCH_IN4_DP")
	)
	(segment
		(start 98.133154 -23.360888)
		(end 93.87586 -22.610318)
		(width 0.1143)
		(layer "In9.Cu")
		(net "85_10INCH_IN4_DP")
	)
	(segment
		(start 93.889068 -74.796142)
		(end 93.39707 -75.14082)
		(width 0.1143)
		(layer "In9.Cu")
		(net "85_10INCH_IN4_DP")
	)
	(segment
		(start 97.91446 -65.811654)
		(end 98.09988 -66.076068)
		(width 0.1143)
		(layer "In9.Cu")
		(net "85_10INCH_IN4_DP")
	)
	(segment
		(start 98.16846 -43.43781)
		(end 93.876114 -42.68089)
		(width 0.1143)
		(layer "In9.Cu")
		(net "85_10INCH_IN4_DP")
	)
	(segment
		(start 93.904308 -38.671754)
		(end 93.41231 -39.016432)
		(width 0.1143)
		(layer "In9.Cu")
		(net "85_10INCH_IN4_DP")
	)
	(segment
		(start 93.362526 -87.318342)
		(end 93.132402 -88.621616)
		(width 0.1143)
		(layer "In9.Cu")
		(net "85_10INCH_IN4_DP")
	)
	(segment
		(start 93.454474 -61.011054)
		(end 97.945956 -61.803026)
		(width 0.1143)
		(layer "In9.Cu")
		(net "85_10INCH_IN4_DP")
	)
	(segment
		(start 98.625406 -83.42757)
		(end 98.360992 -83.61299)
		(width 0.1143)
		(layer "In9.Cu")
		(net "85_10INCH_IN4_DP")
	)
	(segment
		(start 93.129354 -24.394922)
		(end 93.474032 -24.88692)
		(width 0.1143)
		(layer "In9.Cu")
		(net "85_10INCH_IN4_DP")
	)
	(segment
		(start 93.355668 -67.2465)
		(end 93.355922 -67.2465)
		(width 0.1143)
		(layer "In9.Cu")
		(net "85_10INCH_IN4_DP")
	)
	(segment
		(start 97.842832 -71.247254)
		(end 97.578418 -71.432674)
		(width 0.1143)
		(layer "In9.Cu")
		(net "85_10INCH_IN4_DP")
	)
	(segment
		(start 97.578418 -71.432674)
		(end 93.912182 -70.78599)
		(width 0.1143)
		(layer "In9.Cu")
		(net "85_10INCH_IN4_DP")
	)
	(segment
		(start 93.461078 -52.983638)
		(end 97.931986 -53.772308)
		(width 0.1143)
		(layer "In9.Cu")
		(net "85_10INCH_IN4_DP")
	)
	(segment
		(start 98.453448 -41.821862)
		(end 98.638868 -42.08653)
		(width 0.1143)
		(layer "In9.Cu")
		(net "85_10INCH_IN4_DP")
	)
	(segment
		(start 93.386656 -87.181436)
		(end 93.362272 -87.318342)
		(width 0.1143)
		(layer "In9.Cu")
		(net "85_10INCH_IN4_DP")
	)
	(segment
		(start 98.630486 -87.442548)
		(end 98.366072 -87.627968)
		(width 0.1143)
		(layer "In9.Cu")
		(net "85_10INCH_IN4_DP")
	)
	(segment
		(start 95.8342 -93.77553)
		(end 95.759016 -94.200726)
		(width 0.1143)
		(layer "In9.Cu")
		(net "85_10INCH_IN4_DP")
	)
	(segment
		(start 98.09988 -66.076068)
		(end 97.89414 -67.241928)
		(width 0.1143)
		(layer "In9.Cu")
		(net "85_10INCH_IN4_DP")
	)
	(segment
		(start 93.372686 -79.150718)
		(end 93.118432 -80.590898)
		(width 0.1143)
		(layer "In9.Cu")
		(net "85_10INCH_IN4_DP")
	)
	(segment
		(start 97.901252 -51.186842)
		(end 97.636838 -51.372262)
		(width 0.1143)
		(layer "In9.Cu")
		(net "85_10INCH_IN4_DP")
	)
	(segment
		(start 93.147388 -48.483012)
		(end 93.492066 -48.97501)
		(width 0.1143)
		(layer "In9.Cu")
		(net "85_10INCH_IN4_DP")
	)
	(segment
		(start 98.8314 -82.26171)
		(end 98.625406 -83.42757)
		(width 0.1143)
		(layer "In9.Cu")
		(net "85_10INCH_IN4_DP")
	)
	(segment
		(start 93.46311 -81.082896)
		(end 98.64598 -81.997042)
		(width 0.1143)
		(layer "In9.Cu")
		(net "85_10INCH_IN4_DP")
	)
	(segment
		(start 93.178122 -36.446206)
		(end 93.5228 -36.938204)
		(width 0.1143)
		(layer "In9.Cu")
		(net "85_10INCH_IN4_DP")
	)
	(segment
		(start 93.384116 -43.025568)
		(end 93.129862 -44.466002)
		(width 0.1143)
		(layer "In9.Cu")
		(net "85_10INCH_IN4_DP")
	)
	(segment
		(start 93.421962 -30.989778)
		(end 93.397578 -31.126684)
		(width 0.1143)
		(layer "In9.Cu")
		(net "85_10INCH_IN4_DP")
	)
	(segment
		(start 93.856302 -58.733944)
		(end 93.36405 -59.078368)
		(width 0.1143)
		(layer "In9.Cu")
		(net "85_10INCH_IN4_DP")
	)
	(segment
		(start 98.410522 -31.205932)
		(end 98.146108 -31.391352)
		(width 0.1143)
		(layer "In9.Cu")
		(net "85_10INCH_IN4_DP")
	)
	(segment
		(start 98.620834 -79.412592)
		(end 98.35642 -79.598012)
		(width 0.1143)
		(layer "In9.Cu")
		(net "85_10INCH_IN4_DP")
	)
	(segment
		(start 93.88475 -26.626058)
		(end 93.392498 -26.970482)
		(width 0.1143)
		(layer "In9.Cu")
		(net "85_10INCH_IN4_DP")
	)
	(segment
		(start 98.619564 -34.054796)
		(end 98.41357 -35.220656)
		(width 0.1143)
		(layer "In9.Cu")
		(net "85_10INCH_IN4_DP")
	)
	(segment
		(start 93.47454 -44.958)
		(end 98.445828 -45.834554)
		(width 0.1143)
		(layer "In9.Cu")
		(net "85_10INCH_IN4_DP")
	)
	(segment
		(start 98.048572 -70.081394)
		(end 97.842832 -71.247254)
		(width 0.1143)
		(layer "In9.Cu")
		(net "85_10INCH_IN4_DP")
	)
	(segment
		(start 93.11005 -60.518802)
		(end 93.454474 -61.011054)
		(width 0.1143)
		(layer "In9.Cu")
		(net "85_10INCH_IN4_DP")
	)
	(segment
		(start 97.925382 -63.233554)
		(end 97.660968 -63.418974)
		(width 0.1143)
		(layer "In9.Cu")
		(net "85_10INCH_IN4_DP")
	)
	(segment
		(start 93.5228 -36.938204)
		(end 98.441256 -37.805614)
		(width 0.1143)
		(layer "In9.Cu")
		(net "85_10INCH_IN4_DP")
	)
	(segment
		(start 93.44787 -93.12275)
		(end 95.64878 -93.510862)
		(width 0.1143)
		(layer "In9.Cu")
		(net "85_10INCH_IN4_DP")
	)
	(segment
		(start 93.914214 -30.645354)
		(end 93.421962 -30.989778)
		(width 0.1143)
		(layer "In9.Cu")
		(net "85_10INCH_IN4_DP")
	)
	(segment
		(start 93.357446 -91.190318)
		(end 93.103192 -92.630752)
		(width 0.1143)
		(layer "In9.Cu")
		(net "85_10INCH_IN4_DP")
	)
	(segment
		(start 93.377512 -47.179738)
		(end 93.147388 -48.483012)
		(width 0.1143)
		(layer "In9.Cu")
		(net "85_10INCH_IN4_DP")
	)
	(segment
		(start 93.132402 -88.621616)
		(end 93.47708 -89.113614)
		(width 0.1143)
		(layer "In9.Cu")
		(net "85_10INCH_IN4_DP")
	)
	(segment
		(start 93.377258 -47.179738)
		(end 93.377512 -47.179738)
		(width 0.1143)
		(layer "In9.Cu")
		(net "85_10INCH_IN4_DP")
	)
	(segment
		(start 93.401642 -47.042832)
		(end 93.377258 -47.179738)
		(width 0.1143)
		(layer "In9.Cu")
		(net "85_10INCH_IN4_DP")
	)
	(segment
		(start 97.89414 -67.241928)
		(end 97.629218 -67.427348)
		(width 0.1143)
		(layer "In9.Cu")
		(net "85_10INCH_IN4_DP")
	)
	(segment
		(start 98.448114 -25.764236)
		(end 98.633534 -26.028904)
		(width 0.1143)
		(layer "In9.Cu")
		(net "85_10INCH_IN4_DP")
	)
	(segment
		(start 93.492066 -48.97501)
		(end 97.921826 -49.756314)
		(width 0.1143)
		(layer "In9.Cu")
		(net "85_10INCH_IN4_DP")
	)
	(segment
		(start 93.152468 -84.610956)
		(end 93.497146 -85.102954)
		(width 0.1143)
		(layer "In9.Cu")
		(net "85_10INCH_IN4_DP")
	)
	(segment
		(start 98.83648 -86.276688)
		(end 98.630486 -87.442548)
		(width 0.1143)
		(layer "In9.Cu")
		(net "85_10INCH_IN4_DP")
	)
	(segment
		(start 98.65106 -86.01202)
		(end 98.83648 -86.276688)
		(width 0.1143)
		(layer "In9.Cu")
		(net "85_10INCH_IN4_DP")
	)
	(segment
		(start 97.646998 -55.388256)
		(end 93.848174 -54.718458)
		(width 0.1143)
		(layer "In9.Cu")
		(net "85_10INCH_IN4_DP")
	)
	(segment
		(start 98.782124 -74.224642)
		(end 98.57613 -75.390756)
		(width 0.1143)
		(layer "In9.Cu")
		(net "85_10INCH_IN4_DP")
	)
	(segment
		(start 93.362272 -87.318342)
		(end 93.362526 -87.318342)
		(width 0.1143)
		(layer "In9.Cu")
		(net "85_10INCH_IN4_DP")
	)
	(segment
		(start 98.156268 -39.421562)
		(end 93.904308 -38.671754)
		(width 0.1143)
		(layer "In9.Cu")
		(net "85_10INCH_IN4_DP")
	)
	(segment
		(start 93.359224 -23.091648)
		(end 93.359478 -23.091648)
		(width 0.1143)
		(layer "In9.Cu")
		(net "85_10INCH_IN4_DP")
	)
	(segment
		(start 93.47708 -89.113614)
		(end 98.695256 -90.033856)
		(width 0.1143)
		(layer "In9.Cu")
		(net "85_10INCH_IN4_DP")
	)
	(segment
		(start 97.921826 -49.756314)
		(end 98.107246 -50.020982)
		(width 0.1143)
		(layer "In9.Cu")
		(net "85_10INCH_IN4_DP")
	)
	(segment
		(start 93.380052 -67.109594)
		(end 93.355668 -67.2465)
		(width 0.1143)
		(layer "In9.Cu")
		(net "85_10INCH_IN4_DP")
	)
	(segment
		(start 93.89364 -46.698154)
		(end 93.401642 -47.042832)
		(width 0.1143)
		(layer "In9.Cu")
		(net "85_10INCH_IN4_DP")
	)
	(segment
		(start 98.418142 -21.74494)
		(end 98.603562 -22.009608)
		(width 0.1143)
		(layer "In9.Cu")
		(net "85_10INCH_IN4_DP")
	)
	(segment
		(start 93.368368 -27.107388)
		(end 93.138244 -28.410662)
		(width 0.1143)
		(layer "In9.Cu")
		(net "85_10INCH_IN4_DP")
	)
	(segment
		(start 95.759016 -94.200726)
		(end 95.759016 -96.65843)
		(width 0.1143)
		(layer "In9.Cu")
		(net "85_10INCH_IN4_DP")
	)
	(segment
		(start 98.117406 -54.036976)
		(end 97.911412 -55.202836)
		(width 0.1143)
		(layer "In9.Cu")
		(net "85_10INCH_IN4_DP")
	)
	(segment
		(start 97.660968 -63.418974)
		(end 93.854778 -62.747906)
		(width 0.1143)
		(layer "In9.Cu")
		(net "85_10INCH_IN4_DP")
	)
	(segment
		(start 93.359478 -23.091648)
		(end 93.129354 -24.394922)
		(width 0.1143)
		(layer "In9.Cu")
		(net "85_10INCH_IN4_DP")
	)
	(segment
		(start 98.35642 -79.598012)
		(end 93.864938 -78.806294)
		(width 0.1143)
		(layer "In9.Cu")
		(net "85_10INCH_IN4_DP")
	)
	(segment
		(start 98.16084 -47.450502)
		(end 93.89364 -46.698154)
		(width 0.1143)
		(layer "In9.Cu")
		(net "85_10INCH_IN4_DP")
	)
	(segment
		(start 93.497146 -85.102954)
		(end 98.65106 -86.01202)
		(width 0.1143)
		(layer "In9.Cu")
		(net "85_10INCH_IN4_DP")
	)
	(segment
		(start 93.138244 -28.410662)
		(end 93.482922 -28.90266)
		(width 0.1143)
		(layer "In9.Cu")
		(net "85_10INCH_IN4_DP")
	)
	(segment
		(start 98.131376 -62.067694)
		(end 97.925382 -63.233554)
		(width 0.1143)
		(layer "In9.Cu")
		(net "85_10INCH_IN4_DP")
	)
	(segment
		(start 93.382592 -83.307682)
		(end 93.152468 -84.610956)
		(width 0.1143)
		(layer "In9.Cu")
		(net "85_10INCH_IN4_DP")
	)
	(segment
		(start 93.382338 -83.307682)
		(end 93.382592 -83.307682)
		(width 0.1143)
		(layer "In9.Cu")
		(net "85_10INCH_IN4_DP")
	)
	(segment
		(start 93.849444 -90.84564)
		(end 93.357446 -91.190318)
		(width 0.1143)
		(layer "In9.Cu")
		(net "85_10INCH_IN4_DP")
	)
	(segment
		(start 93.397832 -31.126684)
		(end 93.167708 -32.429958)
		(width 0.1143)
		(layer "In9.Cu")
		(net "85_10INCH_IN4_DP")
	)
	(segment
		(start 98.57613 -75.390756)
		(end 98.31197 -75.576176)
		(width 0.1143)
		(layer "In9.Cu")
		(net "85_10INCH_IN4_DP")
	)
	(segment
		(start 97.636838 -51.372262)
		(end 93.862906 -50.707036)
		(width 0.1143)
		(layer "In9.Cu")
		(net "85_10INCH_IN4_DP")
	)
	(segment
		(start 93.876114 -42.68089)
		(end 93.384116 -43.025568)
		(width 0.1143)
		(layer "In9.Cu")
		(net "85_10INCH_IN4_DP")
	)
	(segment
		(start 93.125798 -68.549774)
		(end 93.470476 -69.041772)
		(width 0.1143)
		(layer "In9.Cu")
		(net "85_10INCH_IN4_DP")
	)
	(segment
		(start 98.616516 -30.040072)
		(end 98.410522 -31.205932)
		(width 0.1143)
		(layer "In9.Cu")
		(net "85_10INCH_IN4_DP")
	)
	(segment
		(start 98.445828 -45.834554)
		(end 98.631248 -46.099222)
		(width 0.1143)
		(layer "In9.Cu")
		(net "85_10INCH_IN4_DP")
	)
	(segment
		(start 98.431096 -29.775404)
		(end 98.616516 -30.040072)
		(width 0.1143)
		(layer "In9.Cu")
		(net "85_10INCH_IN4_DP")
	)
	(segment
		(start 93.1164 -52.49164)
		(end 93.461078 -52.983638)
		(width 0.1143)
		(layer "In9.Cu")
		(net "85_10INCH_IN4_DP")
	)
	(segment
		(start 93.864938 -78.806294)
		(end 93.372686 -79.150718)
		(width 0.1143)
		(layer "In9.Cu")
		(net "85_10INCH_IN4_DP")
	)
	(segment
		(start 93.101668 -56.503062)
		(end 93.446346 -56.99506)
		(width 0.1143)
		(layer "In9.Cu")
		(net "85_10INCH_IN4_DP")
	)
	(segment
		(start 93.862906 -50.707036)
		(end 93.370654 -51.05146)
		(width 0.1143)
		(layer "In9.Cu")
		(net "85_10INCH_IN4_DP")
	)
	(segment
		(start 98.149156 -35.406076)
		(end 93.924628 -34.661348)
		(width 0.1143)
		(layer "In9.Cu")
		(net "85_10INCH_IN4_DP")
	)
	(segment
		(start 93.470476 -69.041772)
		(end 97.863152 -69.816726)
		(width 0.1143)
		(layer "In9.Cu")
		(net "85_10INCH_IN4_DP")
	)
	(segment
		(start 93.355922 -55.062882)
		(end 93.101668 -56.503062)
		(width 0.1143)
		(layer "In9.Cu")
		(net "85_10INCH_IN4_DP")
	)
	(segment
		(start 98.366072 -87.627968)
		(end 93.878654 -86.836758)
		(width 0.1143)
		(layer "In9.Cu")
		(net "85_10INCH_IN4_DP")
	)
	(segment
		(start 93.854778 -62.747906)
		(end 93.362526 -63.09233)
		(width 0.1143)
		(layer "In9.Cu")
		(net "85_10INCH_IN4_DP")
	)
	(segment
		(start 98.631248 -46.099222)
		(end 98.425508 -47.265082)
		(width 0.1143)
		(layer "In9.Cu")
		(net "85_10INCH_IN4_DP")
	)
	(segment
		(start 93.912182 -70.78599)
		(end 93.420438 -71.130668)
		(width 0.1143)
		(layer "In9.Cu")
		(net "85_10INCH_IN4_DP")
	)
	(segment
		(start 98.64598 -81.997042)
		(end 98.8314 -82.26171)
		(width 0.1143)
		(layer "In9.Cu")
		(net "85_10INCH_IN4_DP")
	)
	(segment
		(start 98.603562 -22.009608)
		(end 98.397568 -23.175468)
		(width 0.1143)
		(layer "In9.Cu")
		(net "85_10INCH_IN4_DP")
	)
	(segment
		(start 93.370654 -51.05146)
		(end 93.1164 -52.49164)
		(width 0.1143)
		(layer "In9.Cu")
		(net "85_10INCH_IN4_DP")
	)
	(segment
		(start 98.641408 -77.982064)
		(end 98.826828 -78.246732)
		(width 0.1143)
		(layer "In9.Cu")
		(net "85_10INCH_IN4_DP")
	)
	(segment
		(start 95.743776 -20.877276)
		(end 96.224344 -21.357844)
		(width 0.1143)
		(layer "In9.Cu")
		(net "85_10INCH_IN4_DP")
	)
	(segment
		(start 98.146108 -31.391352)
		(end 93.914214 -30.645354)
		(width 0.1143)
		(layer "In9.Cu")
		(net "85_10INCH_IN4_DP")
	)
	(segment
		(start 93.108526 -64.53251)
		(end 93.45295 -65.024762)
		(width 0.1143)
		(layer "In9.Cu")
		(net "85_10INCH_IN4_DP")
	)
	(segment
		(start 98.360992 -83.61299)
		(end 93.89999 -82.826352)
		(width 0.1143)
		(layer "In9.Cu")
		(net "85_10INCH_IN4_DP")
	)
	(segment
		(start 93.129862 -44.466002)
		(end 93.47454 -44.958)
		(width 0.1143)
		(layer "In9.Cu")
		(net "85_10INCH_IN4_DP")
	)
	(segment
		(start 93.392498 -26.970482)
		(end 93.368114 -27.107388)
		(width 0.1143)
		(layer "In9.Cu")
		(net "85_10INCH_IN4_DP")
	)
	(segment
		(start 97.889314 -59.212988)
		(end 97.6249 -59.398408)
		(width 0.1143)
		(layer "In9.Cu")
		(net "85_10INCH_IN4_DP")
	)
	(segment
		(start 93.355922 -67.2465)
		(end 93.125798 -68.549774)
		(width 0.1143)
		(layer "In9.Cu")
		(net "85_10INCH_IN4_DP")
	)
	(segment
		(start 98.410268 -91.649804)
		(end 93.849444 -90.84564)
		(width 0.1143)
		(layer "In9.Cu")
		(net "85_10INCH_IN4_DP")
	)
	(segment
		(start 98.441256 -37.805614)
		(end 98.626676 -38.070282)
		(width 0.1143)
		(layer "In9.Cu")
		(net "85_10INCH_IN4_DP")
	)
	(segment
		(start 93.45295 -65.024762)
		(end 97.91446 -65.811654)
		(width 0.1143)
		(layer "In9.Cu")
		(net "85_10INCH_IN4_DP")
	)
	(segment
		(start 98.31197 -75.576176)
		(end 93.889068 -74.796142)
		(width 0.1143)
		(layer "In9.Cu")
		(net "85_10INCH_IN4_DP")
	)
	(segment
		(start 97.945956 -61.803026)
		(end 98.131376 -62.067694)
		(width 0.1143)
		(layer "In9.Cu")
		(net "85_10INCH_IN4_DP")
	)
	(segment
		(start 98.41357 -35.220656)
		(end 98.149156 -35.406076)
		(width 0.1143)
		(layer "In9.Cu")
		(net "85_10INCH_IN4_DP")
	)
	(segment
		(start 98.695256 -90.033856)
		(end 98.880676 -90.298524)
		(width 0.1143)
		(layer "In9.Cu")
		(net "85_10INCH_IN4_DP")
	)
	(segment
		(start 93.924628 -34.661348)
		(end 93.432376 -35.005772)
		(width 0.1143)
		(layer "In9.Cu")
		(net "85_10INCH_IN4_DP")
	)
	(segment
		(start 93.482922 -28.90266)
		(end 98.431096 -29.775404)
		(width 0.1143)
		(layer "In9.Cu")
		(net "85_10INCH_IN4_DP")
	)
	(segment
		(start 98.633534 -26.028904)
		(end 98.427794 -27.194764)
		(width 0.1143)
		(layer "In9.Cu")
		(net "85_10INCH_IN4_DP")
	)
	(segment
		(start 93.406722 -83.170776)
		(end 93.382338 -83.307682)
		(width 0.1143)
		(layer "In9.Cu")
		(net "85_10INCH_IN4_DP")
	)
	(segment
		(start 97.863152 -69.816726)
		(end 98.048572 -70.081394)
		(width 0.1143)
		(layer "In9.Cu")
		(net "85_10INCH_IN4_DP")
	)
	(segment
		(start 98.425508 -47.265082)
		(end 98.16084 -47.450502)
		(width 0.1143)
		(layer "In9.Cu")
		(net "85_10INCH_IN4_DP")
	)
	(segment
		(start 97.6249 -59.398408)
		(end 93.856302 -58.733944)
		(width 0.1143)
		(layer "In9.Cu")
		(net "85_10INCH_IN4_DP")
	)
	(segment
		(start 93.510862 -73.063354)
		(end 98.596704 -73.95972)
		(width 0.1143)
		(layer "In9.Cu")
		(net "85_10INCH_IN4_DP")
	)
	(segment
		(start 98.095308 -58.047128)
		(end 97.889314 -59.212988)
		(width 0.1143)
		(layer "In9.Cu")
		(net "85_10INCH_IN4_DP")
	)
	(segment
		(start 98.626676 -38.070282)
		(end 98.420936 -39.236142)
		(width 0.1143)
		(layer "In9.Cu")
		(net "85_10INCH_IN4_DP")
	)
	(segment
		(start 98.433128 -43.25239)
		(end 98.16846 -43.43781)
		(width 0.1143)
		(layer "In9.Cu")
		(net "85_10INCH_IN4_DP")
	)
	(segment
		(start 93.362526 -63.09233)
		(end 93.108526 -64.53251)
		(width 0.1143)
		(layer "In9.Cu")
		(net "85_10INCH_IN4_DP")
	)
	(segment
		(start 93.487494 -77.072998)
		(end 98.641408 -77.982064)
		(width 0.1143)
		(layer "In9.Cu")
		(net "85_10INCH_IN4_DP")
	)
	(segment
		(start 98.420936 -39.236142)
		(end 98.156268 -39.421562)
		(width 0.1143)
		(layer "In9.Cu")
		(net "85_10INCH_IN4_DP")
	)
	(segment
		(start 98.107246 -50.020982)
		(end 97.901252 -51.186842)
		(width 0.1143)
		(layer "In9.Cu")
		(net "85_10INCH_IN4_DP")
	)
	(segment
		(start 93.474032 -24.88692)
		(end 98.448114 -25.764236)
		(width 0.1143)
		(layer "In9.Cu")
		(net "85_10INCH_IN4_DP")
	)
	(segment
		(start 93.368114 -27.107388)
		(end 93.368368 -27.107388)
		(width 0.1143)
		(layer "In9.Cu")
		(net "85_10INCH_IN4_DP")
	)
	(segment
		(start 93.872304 -66.76517)
		(end 93.380052 -67.109594)
		(width 0.1143)
		(layer "In9.Cu")
		(net "85_10INCH_IN4_DP")
	)
	(segment
		(start 93.512386 -32.921956)
		(end 98.434144 -33.790128)
		(width 0.1143)
		(layer "In9.Cu")
		(net "85_10INCH_IN4_DP")
	)
	(segment
		(start 93.41231 -39.016432)
		(end 93.158056 -40.456866)
		(width 0.1143)
		(layer "In9.Cu")
		(net "85_10INCH_IN4_DP")
	)
	(segment
		(start 95.759016 -96.65843)
		(end 95.494856 -96.92259)
		(width 0.1143)
		(layer "In9.Cu")
		(net "85_10INCH_IN4_DP")
	)
	(segment
		(start 95.479616 -17.373346)
		(end 95.743776 -17.637506)
		(width 0.1143)
		(layer "In9.Cu")
		(net "85_10INCH_IN4_DP")
	)
	(segment
		(start 98.596704 -73.95972)
		(end 98.782124 -74.224642)
		(width 0.1143)
		(layer "In9.Cu")
		(net "85_10INCH_IN4_DP")
	)
	(segment
		(start 93.89999 -82.826352)
		(end 93.406722 -83.170776)
		(width 0.1143)
		(layer "In9.Cu")
		(net "85_10INCH_IN4_DP")
	)
	(segment
		(start 93.167708 -32.429958)
		(end 93.512386 -32.921956)
		(width 0.1143)
		(layer "In9.Cu")
		(net "85_10INCH_IN4_DP")
	)
	(segment
		(start 95.64878 -93.510862)
		(end 95.8342 -93.77553)
		(width 0.1143)
		(layer "In9.Cu")
		(net "85_10INCH_IN4_DP")
	)
	(segment
		(start 97.931986 -53.772308)
		(end 98.117406 -54.036976)
		(width 0.1143)
		(layer "In9.Cu")
		(net "85_10INCH_IN4_DP")
	)
	(segment
		(start 98.674682 -91.464384)
		(end 98.410268 -91.649804)
		(width 0.1143)
		(layer "In9.Cu")
		(net "85_10INCH_IN4_DP")
	)
	(segment
		(start 96.224344 -21.357844)
		(end 98.418142 -21.74494)
		(width 0.1143)
		(layer "In9.Cu")
		(net "85_10INCH_IN4_DP")
	)
	(segment
		(start 93.166438 -72.571102)
		(end 93.510862 -73.063354)
		(width 0.1143)
		(layer "In9.Cu")
		(net "85_10INCH_IN4_DP")
	)
	(segment
		(start 93.142816 -76.581)
		(end 93.487494 -77.072998)
		(width 0.1143)
		(layer "In9.Cu")
		(net "85_10INCH_IN4_DP")
	)
	(segment
		(start 98.434144 -33.790128)
		(end 98.619564 -34.054796)
		(width 0.1143)
		(layer "In9.Cu")
		(net "85_10INCH_IN4_DP")
	)
	(segment
		(start 97.629218 -67.427348)
		(end 93.872304 -66.76517)
		(width 0.1143)
		(layer "In9.Cu")
		(net "85_10INCH_IN4_DP")
	)
	(segment
		(start 95.743776 -17.637506)
		(end 95.743776 -20.877276)
		(width 0.1143)
		(layer "In9.Cu")
		(net "85_10INCH_IN4_DP")
	)
	(segment
		(start 98.826828 -78.246732)
		(end 98.620834 -79.412592)
		(width 0.1143)
		(layer "In9.Cu")
		(net "85_10INCH_IN4_DP")
	)
	(segment
		(start 98.397568 -23.175468)
		(end 98.133154 -23.360888)
		(width 0.1143)
		(layer "In9.Cu")
		(net "85_10INCH_IN4_DP")
	)
	(segment
		(start 93.36405 -59.078368)
		(end 93.11005 -60.518802)
		(width 0.1143)
		(layer "In9.Cu")
		(net "85_10INCH_IN4_DP")
	)
	(segment
		(start 96.176592 -97.574862)
		(end 96.358456 -96.92259)
		(width 0.12954)
		(layer "F.Cu")
		(net "85_10INCH_IN4_DN")
	)
	(segment
		(start 96.161352 -16.721074)
		(end 96.343216 -17.373346)
		(width 0.12954)
		(layer "F.Cu")
		(net "85_10INCH_IN4_DN")
	)
	(via
		(at 96.343216 -17.373346)
		(size 0.508)
		(drill 0.254)
		(layers "F.Cu" "B.Cu")
		(net "85_10INCH_IN4_DN")
	)
	(via
		(at 96.358456 -96.92259)
		(size 0.508)
		(drill 0.254)
		(layers "F.Cu" "B.Cu")
		(net "85_10INCH_IN4_DN")
	)
	(segment
		(start 93.661992 -55.257954)
		(end 93.456252 -56.424576)
		(width 0.1143)
		(layer "In9.Cu")
		(net "85_10INCH_IN4_DN")
	)
	(segment
		(start 93.507052 -84.53247)
		(end 93.692218 -84.796884)
		(width 0.1143)
		(layer "In9.Cu")
		(net "85_10INCH_IN4_DN")
	)
	(segment
		(start 93.470984 -52.413154)
		(end 93.65615 -52.677568)
		(width 0.1143)
		(layer "In9.Cu")
		(net "85_10INCH_IN4_DN")
	)
	(segment
		(start 93.67012 -59.27344)
		(end 93.46438 -60.440316)
		(width 0.1143)
		(layer "In9.Cu")
		(net "85_10INCH_IN4_DN")
	)
	(segment
		(start 98.727006 -39.431214)
		(end 98.235008 -39.776146)
		(width 0.1143)
		(layer "In9.Cu")
		(net "85_10INCH_IN4_DN")
	)
	(segment
		(start 98.9711 -29.961332)
		(end 98.716846 -31.401004)
		(width 0.1143)
		(layer "In9.Cu")
		(net "85_10INCH_IN4_DN")
	)
	(segment
		(start 93.480382 -68.471288)
		(end 93.665548 -68.735702)
		(width 0.1143)
		(layer "In9.Cu")
		(net "85_10INCH_IN4_DN")
	)
	(segment
		(start 93.690186 -43.22064)
		(end 93.484446 -44.387262)
		(width 0.1143)
		(layer "In9.Cu")
		(net "85_10INCH_IN4_DN")
	)
	(segment
		(start 98.241612 -27.734768)
		(end 93.963236 -26.980388)
		(width 0.1143)
		(layer "In9.Cu")
		(net "85_10INCH_IN4_DN")
	)
	(segment
		(start 97.70364 -59.752992)
		(end 93.934788 -59.088274)
		(width 0.1143)
		(layer "In9.Cu")
		(net "85_10INCH_IN4_DN")
	)
	(segment
		(start 93.70314 -75.335892)
		(end 93.4974 -76.502514)
		(width 0.1143)
		(layer "In9.Cu")
		(net "85_10INCH_IN4_DN")
	)
	(segment
		(start 98.985832 -46.020482)
		(end 98.731578 -47.460154)
		(width 0.1143)
		(layer "In9.Cu")
		(net "85_10INCH_IN4_DN")
	)
	(segment
		(start 98.444812 -87.982552)
		(end 93.957394 -87.191342)
		(width 0.1143)
		(layer "In9.Cu")
		(net "85_10INCH_IN4_DN")
	)
	(segment
		(start 93.501972 -48.404526)
		(end 93.687138 -48.66894)
		(width 0.1143)
		(layer "In9.Cu")
		(net "85_10INCH_IN4_DN")
	)
	(segment
		(start 99.185984 -82.18297)
		(end 98.93173 -83.622642)
		(width 0.1143)
		(layer "In9.Cu")
		(net "85_10INCH_IN4_DN")
	)
	(segment
		(start 99.136708 -74.146156)
		(end 98.882454 -75.585828)
		(width 0.1143)
		(layer "In9.Cu")
		(net "85_10INCH_IN4_DN")
	)
	(segment
		(start 93.689678 -23.149814)
		(end 93.483938 -24.316436)
		(width 0.1143)
		(layer "In9.Cu")
		(net "85_10INCH_IN4_DN")
	)
	(segment
		(start 93.663516 -91.38539)
		(end 93.457776 -92.552012)
		(width 0.1143)
		(layer "In9.Cu")
		(net "85_10INCH_IN4_DN")
	)
	(segment
		(start 94.003114 -35.015678)
		(end 93.738446 -35.200844)
		(width 0.1143)
		(layer "In9.Cu")
		(net "85_10INCH_IN4_DN")
	)
	(segment
		(start 98.2472 -43.792394)
		(end 93.954854 -43.035474)
		(width 0.1143)
		(layer "In9.Cu")
		(net "85_10INCH_IN4_DN")
	)
	(segment
		(start 93.676724 -51.246532)
		(end 93.470984 -52.413154)
		(width 0.1143)
		(layer "In9.Cu")
		(net "85_10INCH_IN4_DN")
	)
	(segment
		(start 98.207576 -51.381914)
		(end 97.715578 -51.726846)
		(width 0.1143)
		(layer "In9.Cu")
		(net "85_10INCH_IN4_DN")
	)
	(segment
		(start 93.978222 -83.180682)
		(end 93.712792 -83.365848)
		(width 0.1143)
		(layer "In9.Cu")
		(net "85_10INCH_IN4_DN")
	)
	(segment
		(start 98.636328 -37.49929)
		(end 98.98126 -37.991542)
		(width 0.1143)
		(layer "In9.Cu")
		(net "85_10INCH_IN4_DN")
	)
	(segment
		(start 93.457776 -92.552012)
		(end 93.642942 -92.816426)
		(width 0.1143)
		(layer "In9.Cu")
		(net "85_10INCH_IN4_DN")
	)
	(segment
		(start 93.687138 -48.66894)
		(end 98.116898 -49.44999)
		(width 0.1143)
		(layer "In9.Cu")
		(net "85_10INCH_IN4_DN")
	)
	(segment
		(start 98.489008 -92.004388)
		(end 93.928184 -91.200224)
		(width 0.1143)
		(layer "In9.Cu")
		(net "85_10INCH_IN4_DN")
	)
	(segment
		(start 98.48596 -61.988954)
		(end 98.231706 -63.428626)
		(width 0.1143)
		(layer "In9.Cu")
		(net "85_10INCH_IN4_DN")
	)
	(segment
		(start 98.731578 -47.460154)
		(end 98.23958 -47.805086)
		(width 0.1143)
		(layer "In9.Cu")
		(net "85_10INCH_IN4_DN")
	)
	(segment
		(start 93.705934 -72.757284)
		(end 98.791776 -73.65365)
		(width 0.1143)
		(layer "In9.Cu")
		(net "85_10INCH_IN4_DN")
	)
	(segment
		(start 98.739198 -43.447462)
		(end 98.2472 -43.792394)
		(width 0.1143)
		(layer "In9.Cu")
		(net "85_10INCH_IN4_DN")
	)
	(segment
		(start 93.707458 -32.615886)
		(end 98.629216 -33.483804)
		(width 0.1143)
		(layer "In9.Cu")
		(net "85_10INCH_IN4_DN")
	)
	(segment
		(start 98.449892 -57.968388)
		(end 98.195638 -59.40806)
		(width 0.1143)
		(layer "In9.Cu")
		(net "85_10INCH_IN4_DN")
	)
	(segment
		(start 98.703892 -23.37054)
		(end 98.211894 -23.715472)
		(width 0.1143)
		(layer "In9.Cu")
		(net "85_10INCH_IN4_DN")
	)
	(segment
		(start 98.629216 -33.483804)
		(end 98.974148 -33.976056)
		(width 0.1143)
		(layer "In9.Cu")
		(net "85_10INCH_IN4_DN")
	)
	(segment
		(start 96.079056 -20.738338)
		(end 96.38665 -21.045932)
		(width 0.1143)
		(layer "In9.Cu")
		(net "85_10INCH_IN4_DN")
	)
	(segment
		(start 98.195638 -59.40806)
		(end 97.70364 -59.752992)
		(width 0.1143)
		(layer "In9.Cu")
		(net "85_10INCH_IN4_DN")
	)
	(segment
		(start 93.520768 -72.492616)
		(end 93.705934 -72.757284)
		(width 0.1143)
		(layer "In9.Cu")
		(net "85_10INCH_IN4_DN")
	)
	(segment
		(start 97.715578 -51.726846)
		(end 93.941392 -51.061366)
		(width 0.1143)
		(layer "In9.Cu")
		(net "85_10INCH_IN4_DN")
	)
	(segment
		(start 98.974148 -33.976056)
		(end 98.719894 -35.415728)
		(width 0.1143)
		(layer "In9.Cu")
		(net "85_10INCH_IN4_DN")
	)
	(segment
		(start 96.094296 -94.23019)
		(end 96.094296 -96.65843)
		(width 0.1143)
		(layer "In9.Cu")
		(net "85_10INCH_IN4_DN")
	)
	(segment
		(start 96.343216 -17.373346)
		(end 96.079056 -17.637506)
		(width 0.1143)
		(layer "In9.Cu")
		(net "85_10INCH_IN4_DN")
	)
	(segment
		(start 98.217736 -55.397908)
		(end 97.725738 -55.74284)
		(width 0.1143)
		(layer "In9.Cu")
		(net "85_10INCH_IN4_DN")
	)
	(segment
		(start 93.990922 -71.140574)
		(end 93.726762 -71.32574)
		(width 0.1143)
		(layer "In9.Cu")
		(net "85_10INCH_IN4_DN")
	)
	(segment
		(start 93.4974 -76.502514)
		(end 93.682566 -76.766928)
		(width 0.1143)
		(layer "In9.Cu")
		(net "85_10INCH_IN4_DN")
	)
	(segment
		(start 93.462856 -64.454024)
		(end 93.648022 -64.718692)
		(width 0.1143)
		(layer "In9.Cu")
		(net "85_10INCH_IN4_DN")
	)
	(segment
		(start 93.484446 -44.387262)
		(end 93.669612 -44.651676)
		(width 0.1143)
		(layer "In9.Cu")
		(net "85_10INCH_IN4_DN")
	)
	(segment
		(start 93.983048 -39.026338)
		(end 93.71838 -39.211504)
		(width 0.1143)
		(layer "In9.Cu")
		(net "85_10INCH_IN4_DN")
	)
	(segment
		(start 98.141028 -61.496702)
		(end 98.48596 -61.988954)
		(width 0.1143)
		(layer "In9.Cu")
		(net "85_10INCH_IN4_DN")
	)
	(segment
		(start 96.094296 -96.65843)
		(end 96.358456 -96.92259)
		(width 0.1143)
		(layer "In9.Cu")
		(net "85_10INCH_IN4_DN")
	)
	(segment
		(start 98.47199 -53.958236)
		(end 98.217736 -55.397908)
		(width 0.1143)
		(layer "In9.Cu")
		(net "85_10INCH_IN4_DN")
	)
	(segment
		(start 93.697806 -40.64254)
		(end 98.64852 -41.515538)
		(width 0.1143)
		(layer "In9.Cu")
		(net "85_10INCH_IN4_DN")
	)
	(segment
		(start 93.658182 -80.776826)
		(end 98.841052 -81.690718)
		(width 0.1143)
		(layer "In9.Cu")
		(net "85_10INCH_IN4_DN")
	)
	(segment
		(start 93.46438 -60.440316)
		(end 93.649546 -60.704984)
		(width 0.1143)
		(layer "In9.Cu")
		(net "85_10INCH_IN4_DN")
	)
	(segment
		(start 93.682566 -76.766928)
		(end 98.83648 -77.67574)
		(width 0.1143)
		(layer "In9.Cu")
		(net "85_10INCH_IN4_DN")
	)
	(segment
		(start 97.725738 -55.74284)
		(end 93.92666 -55.072788)
		(width 0.1143)
		(layer "In9.Cu")
		(net "85_10INCH_IN4_DN")
	)
	(segment
		(start 93.728032 -31.18485)
		(end 93.522292 -32.351472)
		(width 0.1143)
		(layer "In9.Cu")
		(net "85_10INCH_IN4_DN")
	)
	(segment
		(start 93.717872 -36.632134)
		(end 98.636328 -37.49929)
		(width 0.1143)
		(layer "In9.Cu")
		(net "85_10INCH_IN4_DN")
	)
	(segment
		(start 93.522292 -32.351472)
		(end 93.707458 -32.615886)
		(width 0.1143)
		(layer "In9.Cu")
		(net "85_10INCH_IN4_DN")
	)
	(segment
		(start 93.712792 -83.365848)
		(end 93.507052 -84.53247)
		(width 0.1143)
		(layer "In9.Cu")
		(net "85_10INCH_IN4_DN")
	)
	(segment
		(start 93.941392 -51.061366)
		(end 93.676724 -51.246532)
		(width 0.1143)
		(layer "In9.Cu")
		(net "85_10INCH_IN4_DN")
	)
	(segment
		(start 93.97238 -47.052738)
		(end 93.707712 -47.237904)
		(width 0.1143)
		(layer "In9.Cu")
		(net "85_10INCH_IN4_DN")
	)
	(segment
		(start 96.079056 -17.637506)
		(end 96.079056 -20.738338)
		(width 0.1143)
		(layer "In9.Cu")
		(net "85_10INCH_IN4_DN")
	)
	(segment
		(start 93.65615 -52.677568)
		(end 98.127058 -53.465984)
		(width 0.1143)
		(layer "In9.Cu")
		(net "85_10INCH_IN4_DN")
	)
	(segment
		(start 93.71838 -39.211504)
		(end 93.51264 -40.378126)
		(width 0.1143)
		(layer "In9.Cu")
		(net "85_10INCH_IN4_DN")
	)
	(segment
		(start 98.116898 -49.44999)
		(end 98.46183 -49.942242)
		(width 0.1143)
		(layer "In9.Cu")
		(net "85_10INCH_IN4_DN")
	)
	(segment
		(start 93.954854 -43.035474)
		(end 93.690186 -43.22064)
		(width 0.1143)
		(layer "In9.Cu")
		(net "85_10INCH_IN4_DN")
	)
	(segment
		(start 98.716846 -31.401004)
		(end 98.224848 -31.745936)
		(width 0.1143)
		(layer "In9.Cu")
		(net "85_10INCH_IN4_DN")
	)
	(segment
		(start 99.181412 -78.167992)
		(end 98.927158 -79.607664)
		(width 0.1143)
		(layer "In9.Cu")
		(net "85_10INCH_IN4_DN")
	)
	(segment
		(start 93.934788 -59.088274)
		(end 93.67012 -59.27344)
		(width 0.1143)
		(layer "In9.Cu")
		(net "85_10INCH_IN4_DN")
	)
	(segment
		(start 98.993452 -42.00779)
		(end 98.739198 -43.447462)
		(width 0.1143)
		(layer "In9.Cu")
		(net "85_10INCH_IN4_DN")
	)
	(segment
		(start 93.738446 -35.200844)
		(end 93.532706 -36.367466)
		(width 0.1143)
		(layer "In9.Cu")
		(net "85_10INCH_IN4_DN")
	)
	(segment
		(start 93.95079 -67.1195)
		(end 93.686122 -67.304666)
		(width 0.1143)
		(layer "In9.Cu")
		(net "85_10INCH_IN4_DN")
	)
	(segment
		(start 93.669612 -44.651676)
		(end 98.6409 -45.52823)
		(width 0.1143)
		(layer "In9.Cu")
		(net "85_10INCH_IN4_DN")
	)
	(segment
		(start 93.665548 -68.735702)
		(end 98.058224 -69.510402)
		(width 0.1143)
		(layer "In9.Cu")
		(net "85_10INCH_IN4_DN")
	)
	(segment
		(start 98.719894 -35.415728)
		(end 98.227896 -35.76066)
		(width 0.1143)
		(layer "In9.Cu")
		(net "85_10INCH_IN4_DN")
	)
	(segment
		(start 96.38665 -21.045932)
		(end 98.613214 -21.438616)
		(width 0.1143)
		(layer "In9.Cu")
		(net "85_10INCH_IN4_DN")
	)
	(segment
		(start 98.643186 -25.457912)
		(end 98.988118 -25.950164)
		(width 0.1143)
		(layer "In9.Cu")
		(net "85_10INCH_IN4_DN")
	)
	(segment
		(start 96.188784 -93.697044)
		(end 96.094296 -94.23019)
		(width 0.1143)
		(layer "In9.Cu")
		(net "85_10INCH_IN4_DN")
	)
	(segment
		(start 93.532706 -36.367466)
		(end 93.717872 -36.632134)
		(width 0.1143)
		(layer "In9.Cu")
		(net "85_10INCH_IN4_DN")
	)
	(segment
		(start 98.23958 -47.805086)
		(end 93.97238 -47.052738)
		(width 0.1143)
		(layer "In9.Cu")
		(net "85_10INCH_IN4_DN")
	)
	(segment
		(start 99.23526 -90.219784)
		(end 98.981006 -91.659456)
		(width 0.1143)
		(layer "In9.Cu")
		(net "85_10INCH_IN4_DN")
	)
	(segment
		(start 93.648022 -64.718692)
		(end 98.109532 -65.50533)
		(width 0.1143)
		(layer "In9.Cu")
		(net "85_10INCH_IN4_DN")
	)
	(segment
		(start 99.191064 -86.197948)
		(end 98.93681 -87.63762)
		(width 0.1143)
		(layer "In9.Cu")
		(net "85_10INCH_IN4_DN")
	)
	(segment
		(start 98.43516 -79.952596)
		(end 93.943424 -79.160624)
		(width 0.1143)
		(layer "In9.Cu")
		(net "85_10INCH_IN4_DN")
	)
	(segment
		(start 98.64852 -41.515538)
		(end 98.993452 -42.00779)
		(width 0.1143)
		(layer "In9.Cu")
		(net "85_10INCH_IN4_DN")
	)
	(segment
		(start 95.843852 -93.204538)
		(end 96.188784 -93.697044)
		(width 0.1143)
		(layer "In9.Cu")
		(net "85_10INCH_IN4_DN")
	)
	(segment
		(start 93.957394 -87.191342)
		(end 93.692726 -87.376508)
		(width 0.1143)
		(layer "In9.Cu")
		(net "85_10INCH_IN4_DN")
	)
	(segment
		(start 97.739708 -63.773558)
		(end 93.933264 -63.102236)
		(width 0.1143)
		(layer "In9.Cu")
		(net "85_10INCH_IN4_DN")
	)
	(segment
		(start 98.235008 -39.776146)
		(end 93.983048 -39.026338)
		(width 0.1143)
		(layer "In9.Cu")
		(net "85_10INCH_IN4_DN")
	)
	(segment
		(start 98.958146 -21.930868)
		(end 98.703892 -23.37054)
		(width 0.1143)
		(layer "In9.Cu")
		(net "85_10INCH_IN4_DN")
	)
	(segment
		(start 93.928184 -91.200224)
		(end 93.663516 -91.38539)
		(width 0.1143)
		(layer "In9.Cu")
		(net "85_10INCH_IN4_DN")
	)
	(segment
		(start 98.227896 -35.76066)
		(end 94.003114 -35.015678)
		(width 0.1143)
		(layer "In9.Cu")
		(net "85_10INCH_IN4_DN")
	)
	(segment
		(start 98.83648 -77.67574)
		(end 99.181412 -78.167992)
		(width 0.1143)
		(layer "In9.Cu")
		(net "85_10INCH_IN4_DN")
	)
	(segment
		(start 98.149156 -71.442326)
		(end 97.657158 -71.787258)
		(width 0.1143)
		(layer "In9.Cu")
		(net "85_10INCH_IN4_DN")
	)
	(segment
		(start 93.649546 -60.704984)
		(end 98.141028 -61.496702)
		(width 0.1143)
		(layer "In9.Cu")
		(net "85_10INCH_IN4_DN")
	)
	(segment
		(start 97.657158 -71.787258)
		(end 93.990922 -71.140574)
		(width 0.1143)
		(layer "In9.Cu")
		(net "85_10INCH_IN4_DN")
	)
	(segment
		(start 93.473016 -80.512412)
		(end 93.658182 -80.776826)
		(width 0.1143)
		(layer "In9.Cu")
		(net "85_10INCH_IN4_DN")
	)
	(segment
		(start 93.692218 -84.796884)
		(end 98.846132 -85.705696)
		(width 0.1143)
		(layer "In9.Cu")
		(net "85_10INCH_IN4_DN")
	)
	(segment
		(start 93.483938 -24.316436)
		(end 93.669104 -24.58085)
		(width 0.1143)
		(layer "In9.Cu")
		(net "85_10INCH_IN4_DN")
	)
	(segment
		(start 98.46183 -49.942242)
		(end 98.207576 -51.381914)
		(width 0.1143)
		(layer "In9.Cu")
		(net "85_10INCH_IN4_DN")
	)
	(segment
		(start 93.492828 -28.332176)
		(end 93.677994 -28.59659)
		(width 0.1143)
		(layer "In9.Cu")
		(net "85_10INCH_IN4_DN")
	)
	(segment
		(start 98.109532 -65.50533)
		(end 98.454464 -65.997328)
		(width 0.1143)
		(layer "In9.Cu")
		(net "85_10INCH_IN4_DN")
	)
	(segment
		(start 93.672152 -88.807544)
		(end 98.890328 -89.727532)
		(width 0.1143)
		(layer "In9.Cu")
		(net "85_10INCH_IN4_DN")
	)
	(segment
		(start 98.403156 -70.002654)
		(end 98.149156 -71.442326)
		(width 0.1143)
		(layer "In9.Cu")
		(net "85_10INCH_IN4_DN")
	)
	(segment
		(start 93.967808 -75.150726)
		(end 93.70314 -75.335892)
		(width 0.1143)
		(layer "In9.Cu")
		(net "85_10INCH_IN4_DN")
	)
	(segment
		(start 93.92666 -55.072788)
		(end 93.661992 -55.257954)
		(width 0.1143)
		(layer "In9.Cu")
		(net "85_10INCH_IN4_DN")
	)
	(segment
		(start 93.669104 -24.58085)
		(end 98.643186 -25.457912)
		(width 0.1143)
		(layer "In9.Cu")
		(net "85_10INCH_IN4_DN")
	)
	(segment
		(start 98.6409 -45.52823)
		(end 98.985832 -46.020482)
		(width 0.1143)
		(layer "In9.Cu")
		(net "85_10INCH_IN4_DN")
	)
	(segment
		(start 93.641418 -56.68899)
		(end 98.10496 -57.476136)
		(width 0.1143)
		(layer "In9.Cu")
		(net "85_10INCH_IN4_DN")
	)
	(segment
		(start 98.98126 -37.991542)
		(end 98.727006 -39.431214)
		(width 0.1143)
		(layer "In9.Cu")
		(net "85_10INCH_IN4_DN")
	)
	(segment
		(start 93.9927 -30.999684)
		(end 93.728032 -31.18485)
		(width 0.1143)
		(layer "In9.Cu")
		(net "85_10INCH_IN4_DN")
	)
	(segment
		(start 98.10496 -57.476136)
		(end 98.449892 -57.968388)
		(width 0.1143)
		(layer "In9.Cu")
		(net "85_10INCH_IN4_DN")
	)
	(segment
		(start 93.707712 -47.237904)
		(end 93.501972 -48.404526)
		(width 0.1143)
		(layer "In9.Cu")
		(net "85_10INCH_IN4_DN")
	)
	(segment
		(start 93.51264 -40.378126)
		(end 93.697806 -40.64254)
		(width 0.1143)
		(layer "In9.Cu")
		(net "85_10INCH_IN4_DN")
	)
	(segment
		(start 93.686122 -67.304666)
		(end 93.480382 -68.471288)
		(width 0.1143)
		(layer "In9.Cu")
		(net "85_10INCH_IN4_DN")
	)
	(segment
		(start 98.890328 -89.727532)
		(end 99.23526 -90.219784)
		(width 0.1143)
		(layer "In9.Cu")
		(net "85_10INCH_IN4_DN")
	)
	(segment
		(start 98.39071 -75.93076)
		(end 93.967808 -75.150726)
		(width 0.1143)
		(layer "In9.Cu")
		(net "85_10INCH_IN4_DN")
	)
	(segment
		(start 98.626168 -29.46908)
		(end 98.9711 -29.961332)
		(width 0.1143)
		(layer "In9.Cu")
		(net "85_10INCH_IN4_DN")
	)
	(segment
		(start 93.692726 -87.376508)
		(end 93.486986 -88.54313)
		(width 0.1143)
		(layer "In9.Cu")
		(net "85_10INCH_IN4_DN")
	)
	(segment
		(start 97.707704 -67.781678)
		(end 93.95079 -67.1195)
		(width 0.1143)
		(layer "In9.Cu")
		(net "85_10INCH_IN4_DN")
	)
	(segment
		(start 93.486986 -88.54313)
		(end 93.672152 -88.807544)
		(width 0.1143)
		(layer "In9.Cu")
		(net "85_10INCH_IN4_DN")
	)
	(segment
		(start 93.698568 -27.165554)
		(end 93.492828 -28.332176)
		(width 0.1143)
		(layer "In9.Cu")
		(net "85_10INCH_IN4_DN")
	)
	(segment
		(start 98.224848 -31.745936)
		(end 93.9927 -30.999684)
		(width 0.1143)
		(layer "In9.Cu")
		(net "85_10INCH_IN4_DN")
	)
	(segment
		(start 98.058224 -69.510402)
		(end 98.403156 -70.002654)
		(width 0.1143)
		(layer "In9.Cu")
		(net "85_10INCH_IN4_DN")
	)
	(segment
		(start 93.678756 -79.34579)
		(end 93.473016 -80.512412)
		(width 0.1143)
		(layer "In9.Cu")
		(net "85_10INCH_IN4_DN")
	)
	(segment
		(start 98.841052 -81.690718)
		(end 99.185984 -82.18297)
		(width 0.1143)
		(layer "In9.Cu")
		(net "85_10INCH_IN4_DN")
	)
	(segment
		(start 93.668596 -63.287402)
		(end 93.462856 -64.454024)
		(width 0.1143)
		(layer "In9.Cu")
		(net "85_10INCH_IN4_DN")
	)
	(segment
		(start 98.439732 -83.967574)
		(end 93.978222 -83.180682)
		(width 0.1143)
		(layer "In9.Cu")
		(net "85_10INCH_IN4_DN")
	)
	(segment
		(start 98.981006 -91.659456)
		(end 98.489008 -92.004388)
		(width 0.1143)
		(layer "In9.Cu")
		(net "85_10INCH_IN4_DN")
	)
	(segment
		(start 98.733864 -27.389836)
		(end 98.241612 -27.734768)
		(width 0.1143)
		(layer "In9.Cu")
		(net "85_10INCH_IN4_DN")
	)
	(segment
		(start 98.846132 -85.705696)
		(end 99.191064 -86.197948)
		(width 0.1143)
		(layer "In9.Cu")
		(net "85_10INCH_IN4_DN")
	)
	(segment
		(start 98.882454 -75.585828)
		(end 98.39071 -75.93076)
		(width 0.1143)
		(layer "In9.Cu")
		(net "85_10INCH_IN4_DN")
	)
	(segment
		(start 98.211894 -23.715472)
		(end 93.954346 -22.964648)
		(width 0.1143)
		(layer "In9.Cu")
		(net "85_10INCH_IN4_DN")
	)
	(segment
		(start 98.988118 -25.950164)
		(end 98.733864 -27.389836)
		(width 0.1143)
		(layer "In9.Cu")
		(net "85_10INCH_IN4_DN")
	)
	(segment
		(start 98.231706 -63.428626)
		(end 97.739708 -63.773558)
		(width 0.1143)
		(layer "In9.Cu")
		(net "85_10INCH_IN4_DN")
	)
	(segment
		(start 93.456252 -56.424576)
		(end 93.641418 -56.68899)
		(width 0.1143)
		(layer "In9.Cu")
		(net "85_10INCH_IN4_DN")
	)
	(segment
		(start 93.954346 -22.964648)
		(end 93.689678 -23.149814)
		(width 0.1143)
		(layer "In9.Cu")
		(net "85_10INCH_IN4_DN")
	)
	(segment
		(start 93.677994 -28.59659)
		(end 98.626168 -29.46908)
		(width 0.1143)
		(layer "In9.Cu")
		(net "85_10INCH_IN4_DN")
	)
	(segment
		(start 98.93681 -87.63762)
		(end 98.444812 -87.982552)
		(width 0.1143)
		(layer "In9.Cu")
		(net "85_10INCH_IN4_DN")
	)
	(segment
		(start 93.943424 -79.160624)
		(end 93.678756 -79.34579)
		(width 0.1143)
		(layer "In9.Cu")
		(net "85_10INCH_IN4_DN")
	)
	(segment
		(start 98.93173 -83.622642)
		(end 98.439732 -83.967574)
		(width 0.1143)
		(layer "In9.Cu")
		(net "85_10INCH_IN4_DN")
	)
	(segment
		(start 98.20021 -67.437)
		(end 97.707704 -67.781678)
		(width 0.1143)
		(layer "In9.Cu")
		(net "85_10INCH_IN4_DN")
	)
	(segment
		(start 98.927158 -79.607664)
		(end 98.43516 -79.952596)
		(width 0.1143)
		(layer "In9.Cu")
		(net "85_10INCH_IN4_DN")
	)
	(segment
		(start 98.791776 -73.65365)
		(end 99.136708 -74.146156)
		(width 0.1143)
		(layer "In9.Cu")
		(net "85_10INCH_IN4_DN")
	)
	(segment
		(start 93.726762 -71.32574)
		(end 93.520768 -72.492616)
		(width 0.1143)
		(layer "In9.Cu")
		(net "85_10INCH_IN4_DN")
	)
	(segment
		(start 93.963236 -26.980388)
		(end 93.698568 -27.165554)
		(width 0.1143)
		(layer "In9.Cu")
		(net "85_10INCH_IN4_DN")
	)
	(segment
		(start 93.642942 -92.816426)
		(end 95.843852 -93.204538)
		(width 0.1143)
		(layer "In9.Cu")
		(net "85_10INCH_IN4_DN")
	)
	(segment
		(start 93.933264 -63.102236)
		(end 93.668596 -63.287402)
		(width 0.1143)
		(layer "In9.Cu")
		(net "85_10INCH_IN4_DN")
	)
	(segment
		(start 98.127058 -53.465984)
		(end 98.47199 -53.958236)
		(width 0.1143)
		(layer "In9.Cu")
		(net "85_10INCH_IN4_DN")
	)
	(segment
		(start 98.454464 -65.997328)
		(end 98.20021 -67.437)
		(width 0.1143)
		(layer "In9.Cu")
		(net "85_10INCH_IN4_DN")
	)
	(segment
		(start 98.613214 -21.438616)
		(end 98.958146 -21.930868)
		(width 0.1143)
		(layer "In9.Cu")
		(net "85_10INCH_IN4_DN")
	)
	(via
		(at 101.72192 30.739334)
		(size 0.508)
		(drill 0.254)
		(layers "F.Cu" "B.Cu")
		(net "85_10INCH_IN1_DP")
	)
	(via
		(at 101.699568 117.908578)
		(size 0.508)
		(drill 0.254)
		(layers "F.Cu" "B.Cu")
		(net "85_10INCH_IN1_DP")
	)
	(segment
		(start 101.540056 30.087062)
		(end 101.72192 30.739334)
		(width 0.12954)
		(layer "B.Cu")
		(net "85_10INCH_IN1_DP")
	)
	(segment
		(start 101.517704 118.56085)
		(end 101.699568 117.908578)
		(width 0.12954)
		(layer "B.Cu")
		(net "85_10INCH_IN1_DP")
	)
	(segment
		(start 99.786694 58.443876)
		(end 99.52228 58.258456)
		(width 0.1143)
		(layer "In2.Cu")
		(net "85_10INCH_IN1_DP")
	)
	(segment
		(start 99.402392 98.42119)
		(end 99.196398 97.255076)
		(width 0.1143)
		(layer "In2.Cu")
		(net "85_10INCH_IN1_DP")
	)
	(segment
		(start 99.56165 82.336386)
		(end 99.355402 81.170272)
		(width 0.1143)
		(layer "In2.Cu")
		(net "85_10INCH_IN1_DP")
	)
	(segment
		(start 103.200708 65.870328)
		(end 99.782376 66.472816)
		(width 0.1143)
		(layer "In2.Cu")
		(net "85_10INCH_IN1_DP")
	)
	(segment
		(start 99.380548 61.09208)
		(end 99.563682 60.830968)
		(width 0.1143)
		(layer "In2.Cu")
		(net "85_10INCH_IN1_DP")
	)
	(segment
		(start 103.61168 80.188054)
		(end 103.956612 79.696056)
		(width 0.1143)
		(layer "In2.Cu")
		(net "85_10INCH_IN1_DP")
	)
	(segment
		(start 103.299768 81.908904)
		(end 99.826064 82.521806)
		(width 0.1143)
		(layer "In2.Cu")
		(net "85_10INCH_IN1_DP")
	)
	(segment
		(start 104.192832 97.808542)
		(end 99.666806 98.60661)
		(width 0.1143)
		(layer "In2.Cu")
		(net "85_10INCH_IN1_DP")
	)
	(segment
		(start 103.947468 67.655186)
		(end 103.693468 66.214498)
		(width 0.1143)
		(layer "In2.Cu")
		(net "85_10INCH_IN1_DP")
	)
	(segment
		(start 104.661462 110.20044)
		(end 104.168956 109.855762)
		(width 0.1143)
		(layer "In2.Cu")
		(net "85_10INCH_IN1_DP")
	)
	(segment
		(start 99.728528 86.55304)
		(end 99.464114 86.36762)
		(width 0.1143)
		(layer "In2.Cu")
		(net "85_10INCH_IN1_DP")
	)
	(segment
		(start 103.956612 79.696056)
		(end 103.702358 78.255622)
		(width 0.1143)
		(layer "In2.Cu")
		(net "85_10INCH_IN1_DP")
	)
	(segment
		(start 99.517454 66.287396)
		(end 99.311714 65.121282)
		(width 0.1143)
		(layer "In2.Cu")
		(net "85_10INCH_IN1_DP")
	)
	(segment
		(start 104.045766 83.694016)
		(end 103.791512 82.253582)
		(width 0.1143)
		(layer "In2.Cu")
		(net "85_10INCH_IN1_DP")
	)
	(segment
		(start 99.32162 101.303074)
		(end 99.55149 100.974906)
		(width 0.1143)
		(layer "In2.Cu")
		(net "85_10INCH_IN1_DP")
	)
	(segment
		(start 104.105202 88.128856)
		(end 104.449626 87.63762)
		(width 0.1143)
		(layer "In2.Cu")
		(net "85_10INCH_IN1_DP")
	)
	(segment
		(start 99.666806 98.60661)
		(end 99.402392 98.42119)
		(width 0.1143)
		(layer "In2.Cu")
		(net "85_10INCH_IN1_DP")
	)
	(segment
		(start 99.25812 85.201506)
		(end 99.443794 84.937092)
		(width 0.1143)
		(layer "In2.Cu")
		(net "85_10INCH_IN1_DP")
	)
	(segment
		(start 103.667814 60.107322)
		(end 104.012746 59.61507)
		(width 0.1143)
		(layer "In2.Cu")
		(net "85_10INCH_IN1_DP")
	)
	(segment
		(start 99.364546 73.140316)
		(end 99.55022 72.875902)
		(width 0.1143)
		(layer "In2.Cu")
		(net "85_10INCH_IN1_DP")
	)
	(segment
		(start 99.851464 62.446662)
		(end 99.58705 62.261242)
		(width 0.1143)
		(layer "In2.Cu")
		(net "85_10INCH_IN1_DP")
	)
	(segment
		(start 103.996744 55.603902)
		(end 103.74249 54.163976)
		(width 0.1143)
		(layer "In2.Cu")
		(net "85_10INCH_IN1_DP")
	)
	(segment
		(start 104.91597 111.640366)
		(end 104.661462 110.20044)
		(width 0.1143)
		(layer "In2.Cu")
		(net "85_10INCH_IN1_DP")
	)
	(segment
		(start 103.930196 71.672196)
		(end 103.675942 70.232016)
		(width 0.1143)
		(layer "In2.Cu")
		(net "85_10INCH_IN1_DP")
	)
	(segment
		(start 104.050846 92.152724)
		(end 104.39527 91.661488)
		(width 0.1143)
		(layer "In2.Cu")
		(net "85_10INCH_IN1_DP")
	)
	(segment
		(start 104.034844 51.583336)
		(end 103.780844 50.142648)
		(width 0.1143)
		(layer "In2.Cu")
		(net "85_10INCH_IN1_DP")
	)
	(segment
		(start 99.55911 88.930988)
		(end 104.105202 88.128856)
		(width 0.1143)
		(layer "In2.Cu")
		(net "85_10INCH_IN1_DP")
	)
	(segment
		(start 103.288084 49.798478)
		(end 99.83724 50.406808)
		(width 0.1143)
		(layer "In2.Cu")
		(net "85_10INCH_IN1_DP")
	)
	(segment
		(start 103.693468 66.214498)
		(end 103.200708 65.870328)
		(width 0.1143)
		(layer "In2.Cu")
		(net "85_10INCH_IN1_DP")
	)
	(segment
		(start 99.780344 70.487286)
		(end 99.515422 70.301866)
		(width 0.1143)
		(layer "In2.Cu")
		(net "85_10INCH_IN1_DP")
	)
	(segment
		(start 103.602536 68.147184)
		(end 103.947468 67.655186)
		(width 0.1143)
		(layer "In2.Cu")
		(net "85_10INCH_IN1_DP")
	)
	(segment
		(start 99.331526 41.033446)
		(end 99.516946 40.768778)
		(width 0.1143)
		(layer "In2.Cu")
		(net "85_10INCH_IN1_DP")
	)
	(segment
		(start 99.560634 54.237636)
		(end 99.35464 53.071776)
		(width 0.1143)
		(layer "In2.Cu")
		(net "85_10INCH_IN1_DP")
	)
	(segment
		(start 104.9401 99.593654)
		(end 104.685846 98.153474)
		(width 0.1143)
		(layer "In2.Cu")
		(net "85_10INCH_IN1_DP")
	)
	(segment
		(start 99.196398 97.255076)
		(end 99.382072 96.990662)
		(width 0.1143)
		(layer "In2.Cu")
		(net "85_10INCH_IN1_DP")
	)
	(segment
		(start 99.57308 50.221388)
		(end 99.367086 49.055528)
		(width 0.1143)
		(layer "In2.Cu")
		(net "85_10INCH_IN1_DP")
	)
	(segment
		(start 99.37369 89.195402)
		(end 99.55911 88.930988)
		(width 0.1143)
		(layer "In2.Cu")
		(net "85_10INCH_IN1_DP")
	)
	(segment
		(start 99.849432 46.39056)
		(end 99.585018 46.20514)
		(width 0.1143)
		(layer "In2.Cu")
		(net "85_10INCH_IN1_DP")
	)
	(segment
		(start 104.196896 101.82225)
		(end 99.782376 102.600506)
		(width 0.1143)
		(layer "In2.Cu")
		(net "85_10INCH_IN1_DP")
	)
	(segment
		(start 99.316032 57.09285)
		(end 99.502214 56.827928)
		(width 0.1143)
		(layer "In2.Cu")
		(net "85_10INCH_IN1_DP")
	)
	(segment
		(start 104.153462 93.801184)
		(end 99.798632 94.569026)
		(width 0.1143)
		(layer "In2.Cu")
		(net "85_10INCH_IN1_DP")
	)
	(segment
		(start 103.65232 56.095646)
		(end 103.996744 55.603902)
		(width 0.1143)
		(layer "In2.Cu")
		(net "85_10INCH_IN1_DP")
	)
	(segment
		(start 99.782376 66.472816)
		(end 99.517454 66.287396)
		(width 0.1143)
		(layer "In2.Cu")
		(net "85_10INCH_IN1_DP")
	)
	(segment
		(start 103.536242 40.05961)
		(end 103.88092 39.567612)
		(width 0.1143)
		(layer "In2.Cu")
		(net "85_10INCH_IN1_DP")
	)
	(segment
		(start 104.141016 90.2208)
		(end 103.64724 89.876376)
		(width 0.1143)
		(layer "In2.Cu")
		(net "85_10INCH_IN1_DP")
	)
	(segment
		(start 99.406202 37.006276)
		(end 99.591622 36.741862)
		(width 0.1143)
		(layer "In2.Cu")
		(net "85_10INCH_IN1_DP")
	)
	(segment
		(start 99.516946 40.768778)
		(end 103.536242 40.05961)
		(width 0.1143)
		(layer "In2.Cu")
		(net "85_10INCH_IN1_DP")
	)
	(segment
		(start 103.64724 89.876376)
		(end 99.844098 90.546936)
		(width 0.1143)
		(layer "In2.Cu")
		(net "85_10INCH_IN1_DP")
	)
	(segment
		(start 103.183436 69.887338)
		(end 99.780344 70.487286)
		(width 0.1143)
		(layer "In2.Cu")
		(net "85_10INCH_IN1_DP")
	)
	(segment
		(start 104.168956 109.855762)
		(end 99.605084 110.66018)
		(width 0.1143)
		(layer "In2.Cu")
		(net "85_10INCH_IN1_DP")
	)
	(segment
		(start 101.435408 117.644418)
		(end 101.435408 113.03635)
		(width 0.1143)
		(layer "In2.Cu")
		(net "85_10INCH_IN1_DP")
	)
	(segment
		(start 103.601266 74.258932)
		(end 103.109014 73.914508)
		(width 0.1143)
		(layer "In2.Cu")
		(net "85_10INCH_IN1_DP")
	)
	(segment
		(start 99.83724 50.406808)
		(end 99.57308 50.221388)
		(width 0.1143)
		(layer "In2.Cu")
		(net "85_10INCH_IN1_DP")
	)
	(segment
		(start 101.180646 35.8902)
		(end 101.44506 34.389822)
		(width 0.1143)
		(layer "In2.Cu")
		(net "85_10INCH_IN1_DP")
	)
	(segment
		(start 99.611942 38.172136)
		(end 99.405948 37.00653)
		(width 0.1143)
		(layer "In2.Cu")
		(net "85_10INCH_IN1_DP")
	)
	(segment
		(start 104.39527 91.661488)
		(end 104.141016 90.2208)
		(width 0.1143)
		(layer "In2.Cu")
		(net "85_10INCH_IN1_DP")
	)
	(segment
		(start 99.451922 105.006648)
		(end 104.600248 104.098598)
		(width 0.1143)
		(layer "In2.Cu")
		(net "85_10INCH_IN1_DP")
	)
	(segment
		(start 103.702358 78.255622)
		(end 103.209852 77.910944)
		(width 0.1143)
		(layer "In2.Cu")
		(net "85_10INCH_IN1_DP")
	)
	(segment
		(start 103.729282 46.137576)
		(end 103.237284 45.792898)
		(width 0.1143)
		(layer "In2.Cu")
		(net "85_10INCH_IN1_DP")
	)
	(segment
		(start 104.449626 87.63762)
		(end 104.195372 86.19744)
		(width 0.1143)
		(layer "In2.Cu")
		(net "85_10INCH_IN1_DP")
	)
	(segment
		(start 99.798632 94.569026)
		(end 99.534218 94.383606)
		(width 0.1143)
		(layer "In2.Cu")
		(net "85_10INCH_IN1_DP")
	)
	(segment
		(start 99.55022 72.875902)
		(end 103.585518 72.164194)
		(width 0.1143)
		(layer "In2.Cu")
		(net "85_10INCH_IN1_DP")
	)
	(segment
		(start 99.405948 37.00653)
		(end 99.406202 37.006276)
		(width 0.1143)
		(layer "In2.Cu")
		(net "85_10INCH_IN1_DP")
	)
	(segment
		(start 103.74249 54.163976)
		(end 103.250492 53.819298)
		(width 0.1143)
		(layer "In2.Cu")
		(net "85_10INCH_IN1_DP")
	)
	(segment
		(start 99.541076 80.905858)
		(end 103.61168 80.188054)
		(width 0.1143)
		(layer "In2.Cu")
		(net "85_10INCH_IN1_DP")
	)
	(segment
		(start 104.582214 106.199686)
		(end 104.088692 105.855262)
		(width 0.1143)
		(layer "In2.Cu")
		(net "85_10INCH_IN1_DP")
	)
	(segment
		(start 104.088692 105.855262)
		(end 99.73691 106.622596)
		(width 0.1143)
		(layer "In2.Cu")
		(net "85_10INCH_IN1_DP")
	)
	(segment
		(start 103.250492 53.819298)
		(end 99.825302 54.422802)
		(width 0.1143)
		(layer "In2.Cu")
		(net "85_10INCH_IN1_DP")
	)
	(segment
		(start 104.595676 100.085144)
		(end 104.9401 99.593654)
		(width 0.1143)
		(layer "In2.Cu")
		(net "85_10INCH_IN1_DP")
	)
	(segment
		(start 103.700834 84.186268)
		(end 104.045766 83.694016)
		(width 0.1143)
		(layer "In2.Cu")
		(net "85_10INCH_IN1_DP")
	)
	(segment
		(start 99.876356 38.357556)
		(end 99.611942 38.172136)
		(width 0.1143)
		(layer "In2.Cu")
		(net "85_10INCH_IN1_DP")
	)
	(segment
		(start 99.464114 86.36762)
		(end 99.25812 85.201506)
		(width 0.1143)
		(layer "In2.Cu")
		(net "85_10INCH_IN1_DP")
	)
	(segment
		(start 104.600248 104.098598)
		(end 104.944672 103.607108)
		(width 0.1143)
		(layer "In2.Cu")
		(net "85_10INCH_IN1_DP")
	)
	(segment
		(start 103.511096 76.191872)
		(end 103.855266 75.699112)
		(width 0.1143)
		(layer "In2.Cu")
		(net "85_10INCH_IN1_DP")
	)
	(segment
		(start 104.690418 102.16642)
		(end 104.196896 101.82225)
		(width 0.1143)
		(layer "In2.Cu")
		(net "85_10INCH_IN1_DP")
	)
	(segment
		(start 99.497134 64.856868)
		(end 103.56342 64.139572)
		(width 0.1143)
		(layer "In2.Cu")
		(net "85_10INCH_IN1_DP")
	)
	(segment
		(start 99.517962 102.415086)
		(end 99.32162 101.303074)
		(width 0.1143)
		(layer "In2.Cu")
		(net "85_10INCH_IN1_DP")
	)
	(segment
		(start 103.232712 41.779698)
		(end 99.801934 42.384726)
		(width 0.1143)
		(layer "In2.Cu")
		(net "85_10INCH_IN1_DP")
	)
	(segment
		(start 99.564698 44.774612)
		(end 103.634286 44.056554)
		(width 0.1143)
		(layer "In2.Cu")
		(net "85_10INCH_IN1_DP")
	)
	(segment
		(start 99.515422 70.301866)
		(end 99.309682 69.135752)
		(width 0.1143)
		(layer "In2.Cu")
		(net "85_10INCH_IN1_DP")
	)
	(segment
		(start 99.502214 56.827928)
		(end 103.65232 56.095646)
		(width 0.1143)
		(layer "In2.Cu")
		(net "85_10INCH_IN1_DP")
	)
	(segment
		(start 99.382072 96.990662)
		(end 104.556306 96.078294)
		(width 0.1143)
		(layer "In2.Cu")
		(net "85_10INCH_IN1_DP")
	)
	(segment
		(start 104.571546 112.131602)
		(end 104.91597 111.640366)
		(width 0.1143)
		(layer "In2.Cu")
		(net "85_10INCH_IN1_DP")
	)
	(segment
		(start 104.944672 103.607108)
		(end 104.690418 102.16642)
		(width 0.1143)
		(layer "In2.Cu")
		(net "85_10INCH_IN1_DP")
	)
	(segment
		(start 99.835208 74.49185)
		(end 99.570794 74.30643)
		(width 0.1143)
		(layer "In2.Cu")
		(net "85_10INCH_IN1_DP")
	)
	(segment
		(start 99.360736 77.15504)
		(end 99.546156 76.890626)
		(width 0.1143)
		(layer "In2.Cu")
		(net "85_10INCH_IN1_DP")
	)
	(segment
		(start 103.209852 77.910944)
		(end 99.831398 78.506574)
		(width 0.1143)
		(layer "In2.Cu")
		(net "85_10INCH_IN1_DP")
	)
	(segment
		(start 99.552506 48.79086)
		(end 103.638604 48.070262)
		(width 0.1143)
		(layer "In2.Cu")
		(net "85_10INCH_IN1_DP")
	)
	(segment
		(start 99.55149 100.974906)
		(end 104.595676 100.085144)
		(width 0.1143)
		(layer "In2.Cu")
		(net "85_10INCH_IN1_DP")
	)
	(segment
		(start 103.983536 47.57801)
		(end 103.729282 46.137576)
		(width 0.1143)
		(layer "In2.Cu")
		(net "85_10INCH_IN1_DP")
	)
	(segment
		(start 103.978964 43.564556)
		(end 103.72471 42.124376)
		(width 0.1143)
		(layer "In2.Cu")
		(net "85_10INCH_IN1_DP")
	)
	(segment
		(start 99.605084 110.66018)
		(end 99.34067 110.47476)
		(width 0.1143)
		(layer "In2.Cu")
		(net "85_10INCH_IN1_DP")
	)
	(segment
		(start 99.495102 68.871592)
		(end 103.602536 68.147184)
		(width 0.1143)
		(layer "In2.Cu")
		(net "85_10INCH_IN1_DP")
	)
	(segment
		(start 99.35464 53.071776)
		(end 99.354894 53.071522)
		(width 0.1143)
		(layer "In2.Cu")
		(net "85_10INCH_IN1_DP")
	)
	(segment
		(start 99.844098 90.546936)
		(end 99.579684 90.361516)
		(width 0.1143)
		(layer "In2.Cu")
		(net "85_10INCH_IN1_DP")
	)
	(segment
		(start 103.626666 38.127432)
		(end 103.134414 37.783008)
		(width 0.1143)
		(layer "In2.Cu")
		(net "85_10INCH_IN1_DP")
	)
	(segment
		(start 103.638604 48.070262)
		(end 103.983536 47.57801)
		(width 0.1143)
		(layer "In2.Cu")
		(net "85_10INCH_IN1_DP")
	)
	(segment
		(start 104.901238 95.586042)
		(end 104.646984 94.145608)
		(width 0.1143)
		(layer "In2.Cu")
		(net "85_10INCH_IN1_DP")
	)
	(segment
		(start 101.44506 34.389822)
		(end 101.44506 31.016194)
		(width 0.1143)
		(layer "In2.Cu")
		(net "85_10INCH_IN1_DP")
	)
	(segment
		(start 103.26624 57.830212)
		(end 99.786694 58.443876)
		(width 0.1143)
		(layer "In2.Cu")
		(net "85_10INCH_IN1_DP")
	)
	(segment
		(start 101.699568 117.908578)
		(end 101.435408 117.644418)
		(width 0.1143)
		(layer "In2.Cu")
		(net "85_10INCH_IN1_DP")
	)
	(segment
		(start 99.367086 49.055528)
		(end 99.552506 48.79086)
		(width 0.1143)
		(layer "In2.Cu")
		(net "85_10INCH_IN1_DP")
	)
	(segment
		(start 99.472496 106.437176)
		(end 99.266502 105.271062)
		(width 0.1143)
		(layer "In2.Cu")
		(net "85_10INCH_IN1_DP")
	)
	(segment
		(start 99.379024 45.039534)
		(end 99.379278 45.03928)
		(width 0.1143)
		(layer "In2.Cu")
		(net "85_10INCH_IN1_DP")
	)
	(segment
		(start 103.237284 45.792898)
		(end 99.849432 46.39056)
		(width 0.1143)
		(layer "In2.Cu")
		(net "85_10INCH_IN1_DP")
	)
	(segment
		(start 99.52228 58.258456)
		(end 99.316032 57.09285)
		(width 0.1143)
		(layer "In2.Cu")
		(net "85_10INCH_IN1_DP")
	)
	(segment
		(start 99.540314 52.807108)
		(end 103.690166 52.07508)
		(width 0.1143)
		(layer "In2.Cu")
		(net "85_10INCH_IN1_DP")
	)
	(segment
		(start 99.534218 94.383606)
		(end 99.314762 93.141038)
		(width 0.1143)
		(layer "In2.Cu")
		(net "85_10INCH_IN1_DP")
	)
	(segment
		(start 99.379278 45.03928)
		(end 99.564698 44.774612)
		(width 0.1143)
		(layer "In2.Cu")
		(net "85_10INCH_IN1_DP")
	)
	(segment
		(start 99.314762 93.141038)
		(end 99.43719 92.96654)
		(width 0.1143)
		(layer "In2.Cu")
		(net "85_10INCH_IN1_DP")
	)
	(segment
		(start 103.109014 73.914508)
		(end 99.835208 74.49185)
		(width 0.1143)
		(layer "In2.Cu")
		(net "85_10INCH_IN1_DP")
	)
	(segment
		(start 99.58705 62.261242)
		(end 99.380548 61.09208)
		(width 0.1143)
		(layer "In2.Cu")
		(net "85_10INCH_IN1_DP")
	)
	(segment
		(start 99.73691 106.622596)
		(end 99.472496 106.437176)
		(width 0.1143)
		(layer "In2.Cu")
		(net "85_10INCH_IN1_DP")
	)
	(segment
		(start 99.43719 92.96654)
		(end 104.050846 92.152724)
		(width 0.1143)
		(layer "In2.Cu")
		(net "85_10INCH_IN1_DP")
	)
	(segment
		(start 99.585018 46.20514)
		(end 99.379024 45.039534)
		(width 0.1143)
		(layer "In2.Cu")
		(net "85_10INCH_IN1_DP")
	)
	(segment
		(start 99.591622 36.741862)
		(end 100.487734 36.583112)
		(width 0.1143)
		(layer "In2.Cu")
		(net "85_10INCH_IN1_DP")
	)
	(segment
		(start 103.690166 52.07508)
		(end 104.034844 51.583336)
		(width 0.1143)
		(layer "In2.Cu")
		(net "85_10INCH_IN1_DP")
	)
	(segment
		(start 99.826064 82.521806)
		(end 99.56165 82.336386)
		(width 0.1143)
		(layer "In2.Cu")
		(net "85_10INCH_IN1_DP")
	)
	(segment
		(start 104.646984 94.145608)
		(end 104.153462 93.801184)
		(width 0.1143)
		(layer "In2.Cu")
		(net "85_10INCH_IN1_DP")
	)
	(segment
		(start 99.801934 42.384726)
		(end 99.53752 42.199306)
		(width 0.1143)
		(layer "In2.Cu")
		(net "85_10INCH_IN1_DP")
	)
	(segment
		(start 99.32035 109.044232)
		(end 104.491536 108.132372)
		(width 0.1143)
		(layer "In2.Cu")
		(net "85_10INCH_IN1_DP")
	)
	(segment
		(start 99.354894 53.071776)
		(end 99.540314 52.807108)
		(width 0.1143)
		(layer "In2.Cu")
		(net "85_10INCH_IN1_DP")
	)
	(segment
		(start 104.012746 59.61507)
		(end 103.758492 58.174636)
		(width 0.1143)
		(layer "In2.Cu")
		(net "85_10INCH_IN1_DP")
	)
	(segment
		(start 103.634286 44.056554)
		(end 103.978964 43.564556)
		(width 0.1143)
		(layer "In2.Cu")
		(net "85_10INCH_IN1_DP")
	)
	(segment
		(start 104.556306 96.078294)
		(end 104.901238 95.586042)
		(width 0.1143)
		(layer "In2.Cu")
		(net "85_10INCH_IN1_DP")
	)
	(segment
		(start 104.685846 98.153474)
		(end 104.192832 97.808542)
		(width 0.1143)
		(layer "In2.Cu")
		(net "85_10INCH_IN1_DP")
	)
	(segment
		(start 99.53752 42.199306)
		(end 99.331526 41.033446)
		(width 0.1143)
		(layer "In2.Cu")
		(net "85_10INCH_IN1_DP")
	)
	(segment
		(start 99.443794 84.937092)
		(end 103.700834 84.186268)
		(width 0.1143)
		(layer "In2.Cu")
		(net "85_10INCH_IN1_DP")
	)
	(segment
		(start 99.563682 60.830968)
		(end 103.667814 60.107322)
		(width 0.1143)
		(layer "In2.Cu")
		(net "85_10INCH_IN1_DP")
	)
	(segment
		(start 99.355402 81.170272)
		(end 99.541076 80.905858)
		(width 0.1143)
		(layer "In2.Cu")
		(net "85_10INCH_IN1_DP")
	)
	(segment
		(start 101.86162 112.610138)
		(end 104.571546 112.131602)
		(width 0.1143)
		(layer "In2.Cu")
		(net "85_10INCH_IN1_DP")
	)
	(segment
		(start 103.90759 63.647828)
		(end 103.65359 62.207648)
		(width 0.1143)
		(layer "In2.Cu")
		(net "85_10INCH_IN1_DP")
	)
	(segment
		(start 103.56342 64.139572)
		(end 103.90759 63.647828)
		(width 0.1143)
		(layer "In2.Cu")
		(net "85_10INCH_IN1_DP")
	)
	(segment
		(start 99.309682 69.135752)
		(end 99.495102 68.871592)
		(width 0.1143)
		(layer "In2.Cu")
		(net "85_10INCH_IN1_DP")
	)
	(segment
		(start 103.780844 50.142648)
		(end 103.288084 49.798478)
		(width 0.1143)
		(layer "In2.Cu")
		(net "85_10INCH_IN1_DP")
	)
	(segment
		(start 103.585518 72.164194)
		(end 103.930196 71.672196)
		(width 0.1143)
		(layer "In2.Cu")
		(net "85_10INCH_IN1_DP")
	)
	(segment
		(start 99.831398 78.506574)
		(end 99.566476 78.321154)
		(width 0.1143)
		(layer "In2.Cu")
		(net "85_10INCH_IN1_DP")
	)
	(segment
		(start 99.266502 105.271062)
		(end 99.451922 105.006648)
		(width 0.1143)
		(layer "In2.Cu")
		(net "85_10INCH_IN1_DP")
	)
	(segment
		(start 99.546156 76.890626)
		(end 103.511096 76.191872)
		(width 0.1143)
		(layer "In2.Cu")
		(net "85_10INCH_IN1_DP")
	)
	(segment
		(start 104.195372 86.19744)
		(end 103.702358 85.852508)
		(width 0.1143)
		(layer "In2.Cu")
		(net "85_10INCH_IN1_DP")
	)
	(segment
		(start 103.161084 61.86297)
		(end 99.851464 62.446662)
		(width 0.1143)
		(layer "In2.Cu")
		(net "85_10INCH_IN1_DP")
	)
	(segment
		(start 99.354894 53.071522)
		(end 99.354894 53.071776)
		(width 0.1143)
		(layer "In2.Cu")
		(net "85_10INCH_IN1_DP")
	)
	(segment
		(start 100.487734 36.583112)
		(end 101.180646 35.8902)
		(width 0.1143)
		(layer "In2.Cu")
		(net "85_10INCH_IN1_DP")
	)
	(segment
		(start 104.491536 108.132372)
		(end 104.836468 107.64012)
		(width 0.1143)
		(layer "In2.Cu")
		(net "85_10INCH_IN1_DP")
	)
	(segment
		(start 99.311714 65.121282)
		(end 99.497134 64.856868)
		(width 0.1143)
		(layer "In2.Cu")
		(net "85_10INCH_IN1_DP")
	)
	(segment
		(start 103.791512 82.253582)
		(end 103.299768 81.908904)
		(width 0.1143)
		(layer "In2.Cu")
		(net "85_10INCH_IN1_DP")
	)
	(segment
		(start 103.65359 62.207648)
		(end 103.161084 61.86297)
		(width 0.1143)
		(layer "In2.Cu")
		(net "85_10INCH_IN1_DP")
	)
	(segment
		(start 103.134414 37.783008)
		(end 99.876356 38.357556)
		(width 0.1143)
		(layer "In2.Cu")
		(net "85_10INCH_IN1_DP")
	)
	(segment
		(start 103.855266 75.699112)
		(end 103.601266 74.258932)
		(width 0.1143)
		(layer "In2.Cu")
		(net "85_10INCH_IN1_DP")
	)
	(segment
		(start 103.72471 42.124376)
		(end 103.232712 41.779698)
		(width 0.1143)
		(layer "In2.Cu")
		(net "85_10INCH_IN1_DP")
	)
	(segment
		(start 103.88092 39.567612)
		(end 103.626666 38.127432)
		(width 0.1143)
		(layer "In2.Cu")
		(net "85_10INCH_IN1_DP")
	)
	(segment
		(start 101.435408 113.03635)
		(end 101.86162 112.610138)
		(width 0.1143)
		(layer "In2.Cu")
		(net "85_10INCH_IN1_DP")
	)
	(segment
		(start 104.836468 107.64012)
		(end 104.582214 106.199686)
		(width 0.1143)
		(layer "In2.Cu")
		(net "85_10INCH_IN1_DP")
	)
	(segment
		(start 99.579684 90.361516)
		(end 99.37369 89.195402)
		(width 0.1143)
		(layer "In2.Cu")
		(net "85_10INCH_IN1_DP")
	)
	(segment
		(start 99.782376 102.600506)
		(end 99.517962 102.415086)
		(width 0.1143)
		(layer "In2.Cu")
		(net "85_10INCH_IN1_DP")
	)
	(segment
		(start 99.566476 78.321154)
		(end 99.360736 77.15504)
		(width 0.1143)
		(layer "In2.Cu")
		(net "85_10INCH_IN1_DP")
	)
	(segment
		(start 103.758492 58.174636)
		(end 103.26624 57.830212)
		(width 0.1143)
		(layer "In2.Cu")
		(net "85_10INCH_IN1_DP")
	)
	(segment
		(start 101.44506 31.016194)
		(end 101.72192 30.739334)
		(width 0.1143)
		(layer "In2.Cu")
		(net "85_10INCH_IN1_DP")
	)
	(segment
		(start 99.134676 109.308646)
		(end 99.32035 109.044232)
		(width 0.1143)
		(layer "In2.Cu")
		(net "85_10INCH_IN1_DP")
	)
	(segment
		(start 103.702358 85.852508)
		(end 99.728528 86.55304)
		(width 0.1143)
		(layer "In2.Cu")
		(net "85_10INCH_IN1_DP")
	)
	(segment
		(start 99.570794 74.30643)
		(end 99.364546 73.140316)
		(width 0.1143)
		(layer "In2.Cu")
		(net "85_10INCH_IN1_DP")
	)
	(segment
		(start 99.825302 54.422802)
		(end 99.560634 54.237636)
		(width 0.1143)
		(layer "In2.Cu")
		(net "85_10INCH_IN1_DP")
	)
	(segment
		(start 99.34067 110.47476)
		(end 99.134676 109.308646)
		(width 0.1143)
		(layer "In2.Cu")
		(net "85_10INCH_IN1_DP")
	)
	(segment
		(start 103.675942 70.232016)
		(end 103.183436 69.887338)
		(width 0.1143)
		(layer "In2.Cu")
		(net "85_10INCH_IN1_DP")
	)
	(via
		(at 100.835968 117.908578)
		(size 0.508)
		(drill 0.254)
		(layers "F.Cu" "B.Cu")
		(net "85_10INCH_IN1_DN")
	)
	(via
		(at 100.85832 30.739334)
		(size 0.508)
		(drill 0.254)
		(layers "F.Cu" "B.Cu")
		(net "85_10INCH_IN1_DN")
	)
	(segment
		(start 101.040184 30.087062)
		(end 100.85832 30.739334)
		(width 0.12954)
		(layer "B.Cu")
		(net "85_10INCH_IN1_DN")
	)
	(segment
		(start 101.017832 118.56085)
		(end 100.835968 117.908578)
		(width 0.12954)
		(layer "B.Cu")
		(net "85_10INCH_IN1_DN")
	)
	(segment
		(start 103.452422 58.369708)
		(end 103.187754 58.184542)
		(width 0.1143)
		(layer "In2.Cu")
		(net "85_10INCH_IN1_DN")
	)
	(segment
		(start 103.834946 90.416126)
		(end 103.569008 90.230706)
		(width 0.1143)
		(layer "In2.Cu")
		(net "85_10INCH_IN1_DN")
	)
	(segment
		(start 104.095042 87.55888)
		(end 103.889302 86.392512)
		(width 0.1143)
		(layer "In2.Cu")
		(net "85_10INCH_IN1_DN")
	)
	(segment
		(start 103.030528 74.268838)
		(end 99.756468 74.846434)
		(width 0.1143)
		(layer "In2.Cu")
		(net "85_10INCH_IN1_DN")
	)
	(segment
		(start 99.364038 88.624664)
		(end 103.91013 87.822532)
		(width 0.1143)
		(layer "In2.Cu")
		(net "85_10INCH_IN1_DN")
	)
	(segment
		(start 101.10978 30.990794)
		(end 100.85832 30.739334)
		(width 0.1143)
		(layer "In2.Cu")
		(net "85_10INCH_IN1_DN")
	)
	(segment
		(start 100.868734 35.727894)
		(end 101.10978 34.360358)
		(width 0.1143)
		(layer "In2.Cu")
		(net "85_10INCH_IN1_DN")
	)
	(segment
		(start 103.390446 71.85787)
		(end 103.575612 71.59371)
		(width 0.1143)
		(layer "In2.Cu")
		(net "85_10INCH_IN1_DN")
	)
	(segment
		(start 103.187754 58.184542)
		(end 99.707954 58.79846)
		(width 0.1143)
		(layer "In2.Cu")
		(net "85_10INCH_IN1_DN")
	)
	(segment
		(start 103.082598 62.2173)
		(end 99.772724 62.801246)
		(width 0.1143)
		(layer "In2.Cu")
		(net "85_10INCH_IN1_DN")
	)
	(segment
		(start 99.369626 44.468288)
		(end 103.439214 43.750484)
		(width 0.1143)
		(layer "In2.Cu")
		(net "85_10INCH_IN1_DN")
	)
	(segment
		(start 99.051618 36.927536)
		(end 99.39655 36.435792)
		(width 0.1143)
		(layer "In2.Cu")
		(net "85_10INCH_IN1_DN")
	)
	(segment
		(start 104.040686 91.582748)
		(end 103.834946 90.416126)
		(width 0.1143)
		(layer "In2.Cu")
		(net "85_10INCH_IN1_DN")
	)
	(segment
		(start 99.39655 36.435792)
		(end 100.325174 36.2712)
		(width 0.1143)
		(layer "In2.Cu")
		(net "85_10INCH_IN1_DN")
	)
	(segment
		(start 99.765358 90.90152)
		(end 99.27336 90.556588)
		(width 0.1143)
		(layer "In2.Cu")
		(net "85_10INCH_IN1_DN")
	)
	(segment
		(start 100.835968 117.908578)
		(end 101.100128 117.644418)
		(width 0.1143)
		(layer "In2.Cu")
		(net "85_10INCH_IN1_DN")
	)
	(segment
		(start 99.227894 94.578678)
		(end 98.960178 93.062298)
		(width 0.1143)
		(layer "In2.Cu")
		(net "85_10INCH_IN1_DN")
	)
	(segment
		(start 103.320596 38.322504)
		(end 103.055928 38.137338)
		(width 0.1143)
		(layer "In2.Cu")
		(net "85_10INCH_IN1_DN")
	)
	(segment
		(start 99.707954 58.79846)
		(end 99.215956 58.453528)
		(width 0.1143)
		(layer "In2.Cu")
		(net "85_10INCH_IN1_DN")
	)
	(segment
		(start 103.387144 66.409824)
		(end 103.122222 66.224658)
		(width 0.1143)
		(layer "In2.Cu")
		(net "85_10INCH_IN1_DN")
	)
	(segment
		(start 104.296464 107.826048)
		(end 104.481884 107.56138)
		(width 0.1143)
		(layer "In2.Cu")
		(net "85_10INCH_IN1_DN")
	)
	(segment
		(start 99.280726 62.456314)
		(end 99.025964 61.01334)
		(width 0.1143)
		(layer "In2.Cu")
		(net "85_10INCH_IN1_DN")
	)
	(segment
		(start 98.911918 105.192322)
		(end 99.25685 104.700324)
		(width 0.1143)
		(layer "In2.Cu")
		(net "85_10INCH_IN1_DN")
	)
	(segment
		(start 103.10495 70.241668)
		(end 99.701858 70.841616)
		(width 0.1143)
		(layer "In2.Cu")
		(net "85_10INCH_IN1_DN")
	)
	(segment
		(start 99.345242 52.500784)
		(end 103.495094 51.768756)
		(width 0.1143)
		(layer "In2.Cu")
		(net "85_10INCH_IN1_DN")
	)
	(segment
		(start 99.307396 56.521604)
		(end 103.457248 55.789576)
		(width 0.1143)
		(layer "In2.Cu")
		(net "85_10INCH_IN1_DN")
	)
	(segment
		(start 103.41864 42.319448)
		(end 103.154226 42.134282)
		(width 0.1143)
		(layer "In2.Cu")
		(net "85_10INCH_IN1_DN")
	)
	(segment
		(start 99.65817 106.97718)
		(end 99.166172 106.632248)
		(width 0.1143)
		(layer "In2.Cu")
		(net "85_10INCH_IN1_DN")
	)
	(segment
		(start 103.658162 59.53633)
		(end 103.452422 58.369708)
		(width 0.1143)
		(layer "In2.Cu")
		(net "85_10INCH_IN1_DN")
	)
	(segment
		(start 103.485188 82.448654)
		(end 103.221028 82.263488)
		(width 0.1143)
		(layer "In2.Cu")
		(net "85_10INCH_IN1_DN")
	)
	(segment
		(start 103.68026 51.504596)
		(end 103.47452 50.337974)
		(width 0.1143)
		(layer "In2.Cu")
		(net "85_10INCH_IN1_DN")
	)
	(segment
		(start 104.276144 106.395012)
		(end 104.01046 106.209592)
		(width 0.1143)
		(layer "In2.Cu")
		(net "85_10INCH_IN1_DN")
	)
	(segment
		(start 99.000818 81.091532)
		(end 99.346004 80.599534)
		(width 0.1143)
		(layer "In2.Cu")
		(net "85_10INCH_IN1_DN")
	)
	(segment
		(start 99.797616 38.71214)
		(end 99.305872 38.366954)
		(width 0.1143)
		(layer "In2.Cu")
		(net "85_10INCH_IN1_DN")
	)
	(segment
		(start 98.903536 85.122766)
		(end 99.248976 84.630768)
		(width 0.1143)
		(layer "In2.Cu")
		(net "85_10INCH_IN1_DN")
	)
	(segment
		(start 103.423212 46.332648)
		(end 103.158798 46.147482)
		(width 0.1143)
		(layer "In2.Cu")
		(net "85_10INCH_IN1_DN")
	)
	(segment
		(start 104.118664 102.17658)
		(end 99.703636 102.95509)
		(width 0.1143)
		(layer "In2.Cu")
		(net "85_10INCH_IN1_DN")
	)
	(segment
		(start 99.125532 108.737908)
		(end 104.296464 107.826048)
		(width 0.1143)
		(layer "In2.Cu")
		(net "85_10INCH_IN1_DN")
	)
	(segment
		(start 103.416608 79.88173)
		(end 103.602028 79.617316)
		(width 0.1143)
		(layer "In2.Cu")
		(net "85_10INCH_IN1_DN")
	)
	(segment
		(start 103.436166 54.359048)
		(end 103.171752 54.173628)
		(width 0.1143)
		(layer "In2.Cu")
		(net "85_10INCH_IN1_DN")
	)
	(segment
		(start 99.7585 50.761392)
		(end 99.266756 50.41646)
		(width 0.1143)
		(layer "In2.Cu")
		(net "85_10INCH_IN1_DN")
	)
	(segment
		(start 99.747324 82.87639)
		(end 99.255326 82.531458)
		(width 0.1143)
		(layer "In2.Cu")
		(net "85_10INCH_IN1_DN")
	)
	(segment
		(start 99.27336 90.556588)
		(end 99.019106 89.116662)
		(width 0.1143)
		(layer "In2.Cu")
		(net "85_10INCH_IN1_DN")
	)
	(segment
		(start 104.07523 94.155514)
		(end 99.719892 94.92361)
		(width 0.1143)
		(layer "In2.Cu")
		(net "85_10INCH_IN1_DN")
	)
	(segment
		(start 99.355402 72.569578)
		(end 103.390446 71.85787)
		(width 0.1143)
		(layer "In2.Cu")
		(net "85_10INCH_IN1_DN")
	)
	(segment
		(start 99.211384 66.482468)
		(end 98.95713 65.042542)
		(width 0.1143)
		(layer "In2.Cu")
		(net "85_10INCH_IN1_DN")
	)
	(segment
		(start 99.166172 106.632248)
		(end 98.911918 105.192322)
		(width 0.1143)
		(layer "In2.Cu")
		(net "85_10INCH_IN1_DN")
	)
	(segment
		(start 103.602028 79.617316)
		(end 103.396288 78.450694)
		(width 0.1143)
		(layer "In2.Cu")
		(net "85_10INCH_IN1_DN")
	)
	(segment
		(start 99.019106 89.116662)
		(end 99.364038 88.624664)
		(width 0.1143)
		(layer "In2.Cu")
		(net "85_10INCH_IN1_DN")
	)
	(segment
		(start 104.379776 98.348546)
		(end 104.114346 98.162872)
		(width 0.1143)
		(layer "In2.Cu")
		(net "85_10INCH_IN1_DN")
	)
	(segment
		(start 104.400604 99.77882)
		(end 104.585516 99.514914)
		(width 0.1143)
		(layer "In2.Cu")
		(net "85_10INCH_IN1_DN")
	)
	(segment
		(start 100.325174 36.2712)
		(end 100.868734 35.727894)
		(width 0.1143)
		(layer "In2.Cu")
		(net "85_10INCH_IN1_DN")
	)
	(segment
		(start 103.691182 83.615276)
		(end 103.485188 82.448654)
		(width 0.1143)
		(layer "In2.Cu")
		(net "85_10INCH_IN1_DN")
	)
	(segment
		(start 99.752912 78.860904)
		(end 99.260406 78.516226)
		(width 0.1143)
		(layer "In2.Cu")
		(net "85_10INCH_IN1_DN")
	)
	(segment
		(start 99.302062 64.550544)
		(end 103.368348 63.833502)
		(width 0.1143)
		(layer "In2.Cu")
		(net "85_10INCH_IN1_DN")
	)
	(segment
		(start 99.260406 78.516226)
		(end 99.006152 77.0763)
		(width 0.1143)
		(layer "In2.Cu")
		(net "85_10INCH_IN1_DN")
	)
	(segment
		(start 104.561386 111.561626)
		(end 104.355392 110.395512)
		(width 0.1143)
		(layer "In2.Cu")
		(net "85_10INCH_IN1_DN")
	)
	(segment
		(start 99.242118 92.660216)
		(end 103.855774 91.8464)
		(width 0.1143)
		(layer "In2.Cu")
		(net "85_10INCH_IN1_DN")
	)
	(segment
		(start 98.976942 40.954706)
		(end 99.321874 40.462454)
		(width 0.1143)
		(layer "In2.Cu")
		(net "85_10INCH_IN1_DN")
	)
	(segment
		(start 103.158798 46.147482)
		(end 99.770692 46.745144)
		(width 0.1143)
		(layer "In2.Cu")
		(net "85_10INCH_IN1_DN")
	)
	(segment
		(start 104.590088 103.528368)
		(end 104.384348 102.361746)
		(width 0.1143)
		(layer "In2.Cu")
		(net "85_10INCH_IN1_DN")
	)
	(segment
		(start 101.10978 34.360358)
		(end 101.10978 30.990794)
		(width 0.1143)
		(layer "In2.Cu")
		(net "85_10INCH_IN1_DN")
	)
	(segment
		(start 104.355392 110.395512)
		(end 104.09047 110.210092)
		(width 0.1143)
		(layer "In2.Cu")
		(net "85_10INCH_IN1_DN")
	)
	(segment
		(start 103.294942 74.454004)
		(end 103.030528 74.268838)
		(width 0.1143)
		(layer "In2.Cu")
		(net "85_10INCH_IN1_DN")
	)
	(segment
		(start 98.841814 97.176336)
		(end 99.187254 96.684338)
		(width 0.1143)
		(layer "In2.Cu")
		(net "85_10INCH_IN1_DN")
	)
	(segment
		(start 99.772724 62.801246)
		(end 99.280726 62.456314)
		(width 0.1143)
		(layer "In2.Cu")
		(net "85_10INCH_IN1_DN")
	)
	(segment
		(start 99.70389 66.827146)
		(end 99.211384 66.482468)
		(width 0.1143)
		(layer "In2.Cu")
		(net "85_10INCH_IN1_DN")
	)
	(segment
		(start 103.171752 54.173628)
		(end 99.746562 54.777386)
		(width 0.1143)
		(layer "In2.Cu")
		(net "85_10INCH_IN1_DN")
	)
	(segment
		(start 103.439214 43.750484)
		(end 103.62438 43.48607)
		(width 0.1143)
		(layer "In2.Cu")
		(net "85_10INCH_IN1_DN")
	)
	(segment
		(start 104.01046 106.209592)
		(end 99.65817 106.97718)
		(width 0.1143)
		(layer "In2.Cu")
		(net "85_10INCH_IN1_DN")
	)
	(segment
		(start 103.55326 63.569342)
		(end 103.34752 62.40272)
		(width 0.1143)
		(layer "In2.Cu")
		(net "85_10INCH_IN1_DN")
	)
	(segment
		(start 99.025964 61.01334)
		(end 99.36861 60.524644)
		(width 0.1143)
		(layer "In2.Cu")
		(net "85_10INCH_IN1_DN")
	)
	(segment
		(start 103.91013 87.822532)
		(end 104.095042 87.55888)
		(width 0.1143)
		(layer "In2.Cu")
		(net "85_10INCH_IN1_DN")
	)
	(segment
		(start 98.960178 93.062298)
		(end 99.242118 92.660216)
		(width 0.1143)
		(layer "In2.Cu")
		(net "85_10INCH_IN1_DN")
	)
	(segment
		(start 99.357434 48.484536)
		(end 103.443532 47.763938)
		(width 0.1143)
		(layer "In2.Cu")
		(net "85_10INCH_IN1_DN")
	)
	(segment
		(start 103.623872 86.206838)
		(end 99.649788 86.907624)
		(width 0.1143)
		(layer "In2.Cu")
		(net "85_10INCH_IN1_DN")
	)
	(segment
		(start 99.649788 86.907624)
		(end 99.15779 86.562692)
		(width 0.1143)
		(layer "In2.Cu")
		(net "85_10INCH_IN1_DN")
	)
	(segment
		(start 104.361234 95.77197)
		(end 104.546654 95.507302)
		(width 0.1143)
		(layer "In2.Cu")
		(net "85_10INCH_IN1_DN")
	)
	(segment
		(start 104.114346 98.162872)
		(end 99.588066 98.961194)
		(width 0.1143)
		(layer "In2.Cu")
		(net "85_10INCH_IN1_DN")
	)
	(segment
		(start 103.34117 39.75354)
		(end 103.526336 39.489126)
		(width 0.1143)
		(layer "In2.Cu")
		(net "85_10INCH_IN1_DN")
	)
	(segment
		(start 99.26447 74.501502)
		(end 99.009962 73.061576)
		(width 0.1143)
		(layer "In2.Cu")
		(net "85_10INCH_IN1_DN")
	)
	(segment
		(start 103.443532 47.763938)
		(end 103.628952 47.49927)
		(width 0.1143)
		(layer "In2.Cu")
		(net "85_10INCH_IN1_DN")
	)
	(segment
		(start 99.723194 42.73931)
		(end 99.231196 42.394378)
		(width 0.1143)
		(layer "In2.Cu")
		(net "85_10INCH_IN1_DN")
	)
	(segment
		(start 103.855774 91.8464)
		(end 104.040686 91.582748)
		(width 0.1143)
		(layer "In2.Cu")
		(net "85_10INCH_IN1_DN")
	)
	(segment
		(start 103.495094 51.768756)
		(end 103.68026 51.504596)
		(width 0.1143)
		(layer "In2.Cu")
		(net "85_10INCH_IN1_DN")
	)
	(segment
		(start 99.187254 96.684338)
		(end 104.361234 95.77197)
		(width 0.1143)
		(layer "In2.Cu")
		(net "85_10INCH_IN1_DN")
	)
	(segment
		(start 103.31577 75.885548)
		(end 103.500936 75.620626)
		(width 0.1143)
		(layer "In2.Cu")
		(net "85_10INCH_IN1_DN")
	)
	(segment
		(start 99.305872 38.366954)
		(end 99.051618 36.927536)
		(width 0.1143)
		(layer "In2.Cu")
		(net "85_10INCH_IN1_DN")
	)
	(segment
		(start 103.055928 38.137338)
		(end 99.797616 38.71214)
		(width 0.1143)
		(layer "In2.Cu")
		(net "85_10INCH_IN1_DN")
	)
	(segment
		(start 103.209598 50.152808)
		(end 99.7585 50.761392)
		(width 0.1143)
		(layer "In2.Cu")
		(net "85_10INCH_IN1_DN")
	)
	(segment
		(start 103.122222 66.224658)
		(end 99.70389 66.827146)
		(width 0.1143)
		(layer "In2.Cu")
		(net "85_10INCH_IN1_DN")
	)
	(segment
		(start 103.500682 75.620626)
		(end 103.294942 74.454004)
		(width 0.1143)
		(layer "In2.Cu")
		(net "85_10INCH_IN1_DN")
	)
	(segment
		(start 103.368348 63.833502)
		(end 103.55326 63.569342)
		(width 0.1143)
		(layer "In2.Cu")
		(net "85_10INCH_IN1_DN")
	)
	(segment
		(start 104.384348 102.361746)
		(end 104.118664 102.17658)
		(width 0.1143)
		(layer "In2.Cu")
		(net "85_10INCH_IN1_DN")
	)
	(segment
		(start 99.266756 50.41646)
		(end 99.012502 48.976788)
		(width 0.1143)
		(layer "In2.Cu")
		(net "85_10INCH_IN1_DN")
	)
	(segment
		(start 98.780092 109.229652)
		(end 99.125532 108.737908)
		(width 0.1143)
		(layer "In2.Cu")
		(net "85_10INCH_IN1_DN")
	)
	(segment
		(start 103.628952 47.49927)
		(end 103.423212 46.332648)
		(width 0.1143)
		(layer "In2.Cu")
		(net "85_10INCH_IN1_DN")
	)
	(segment
		(start 99.756468 74.846434)
		(end 99.26447 74.501502)
		(width 0.1143)
		(layer "In2.Cu")
		(net "85_10INCH_IN1_DN")
	)
	(segment
		(start 99.211638 102.610158)
		(end 98.967036 101.224588)
		(width 0.1143)
		(layer "In2.Cu")
		(net "85_10INCH_IN1_DN")
	)
	(segment
		(start 103.369872 70.427088)
		(end 103.10495 70.241668)
		(width 0.1143)
		(layer "In2.Cu")
		(net "85_10INCH_IN1_DN")
	)
	(segment
		(start 103.407464 67.84086)
		(end 103.592884 67.576446)
		(width 0.1143)
		(layer "In2.Cu")
		(net "85_10INCH_IN1_DN")
	)
	(segment
		(start 99.096068 98.616262)
		(end 98.841814 97.176336)
		(width 0.1143)
		(layer "In2.Cu")
		(net "85_10INCH_IN1_DN")
	)
	(segment
		(start 103.505762 83.879944)
		(end 103.691182 83.615276)
		(width 0.1143)
		(layer "In2.Cu")
		(net "85_10INCH_IN1_DN")
	)
	(segment
		(start 99.254564 54.432708)
		(end 99.00031 52.993036)
		(width 0.1143)
		(layer "In2.Cu")
		(net "85_10INCH_IN1_DN")
	)
	(segment
		(start 99.321874 40.462454)
		(end 103.34117 39.75354)
		(width 0.1143)
		(layer "In2.Cu")
		(net "85_10INCH_IN1_DN")
	)
	(segment
		(start 99.770692 46.745144)
		(end 99.278948 46.399958)
		(width 0.1143)
		(layer "In2.Cu")
		(net "85_10INCH_IN1_DN")
	)
	(segment
		(start 99.248976 84.630768)
		(end 103.505762 83.879944)
		(width 0.1143)
		(layer "In2.Cu")
		(net "85_10INCH_IN1_DN")
	)
	(segment
		(start 98.967036 101.224588)
		(end 99.356418 100.668836)
		(width 0.1143)
		(layer "In2.Cu")
		(net "85_10INCH_IN1_DN")
	)
	(segment
		(start 99.25685 104.700324)
		(end 104.405176 103.792274)
		(width 0.1143)
		(layer "In2.Cu")
		(net "85_10INCH_IN1_DN")
	)
	(segment
		(start 101.699314 112.298226)
		(end 104.376474 111.825278)
		(width 0.1143)
		(layer "In2.Cu")
		(net "85_10INCH_IN1_DN")
	)
	(segment
		(start 104.09047 110.210092)
		(end 99.526344 111.014764)
		(width 0.1143)
		(layer "In2.Cu")
		(net "85_10INCH_IN1_DN")
	)
	(segment
		(start 103.34752 62.40272)
		(end 103.082598 62.2173)
		(width 0.1143)
		(layer "In2.Cu")
		(net "85_10INCH_IN1_DN")
	)
	(segment
		(start 104.481884 107.56138)
		(end 104.276144 106.395012)
		(width 0.1143)
		(layer "In2.Cu")
		(net "85_10INCH_IN1_DN")
	)
	(segment
		(start 104.340914 94.340934)
		(end 104.07523 94.155514)
		(width 0.1143)
		(layer "In2.Cu")
		(net "85_10INCH_IN1_DN")
	)
	(segment
		(start 99.15779 86.562692)
		(end 98.903536 85.122766)
		(width 0.1143)
		(layer "In2.Cu")
		(net "85_10INCH_IN1_DN")
	)
	(segment
		(start 99.356418 100.668836)
		(end 104.400604 99.77882)
		(width 0.1143)
		(layer "In2.Cu")
		(net "85_10INCH_IN1_DN")
	)
	(segment
		(start 101.100128 112.897412)
		(end 101.699314 112.298226)
		(width 0.1143)
		(layer "In2.Cu")
		(net "85_10INCH_IN1_DN")
	)
	(segment
		(start 99.346004 80.599534)
		(end 103.416608 79.88173)
		(width 0.1143)
		(layer "In2.Cu")
		(net "85_10INCH_IN1_DN")
	)
	(segment
		(start 99.300284 68.565268)
		(end 103.407464 67.84086)
		(width 0.1143)
		(layer "In2.Cu")
		(net "85_10INCH_IN1_DN")
	)
	(segment
		(start 99.746562 54.777386)
		(end 99.254564 54.432708)
		(width 0.1143)
		(layer "In2.Cu")
		(net "85_10INCH_IN1_DN")
	)
	(segment
		(start 98.955098 69.057012)
		(end 99.300284 68.565268)
		(width 0.1143)
		(layer "In2.Cu")
		(net "85_10INCH_IN1_DN")
	)
	(segment
		(start 103.569008 90.230706)
		(end 99.765358 90.90152)
		(width 0.1143)
		(layer "In2.Cu")
		(net "85_10INCH_IN1_DN")
	)
	(segment
		(start 104.585516 99.514914)
		(end 104.379776 98.348546)
		(width 0.1143)
		(layer "In2.Cu")
		(net "85_10INCH_IN1_DN")
	)
	(segment
		(start 99.024694 44.96054)
		(end 99.369626 44.468288)
		(width 0.1143)
		(layer "In2.Cu")
		(net "85_10INCH_IN1_DN")
	)
	(segment
		(start 99.701858 70.841616)
		(end 99.209352 70.496938)
		(width 0.1143)
		(layer "In2.Cu")
		(net "85_10INCH_IN1_DN")
	)
	(segment
		(start 99.36861 60.524644)
		(end 103.472742 59.800998)
		(width 0.1143)
		(layer "In2.Cu")
		(net "85_10INCH_IN1_DN")
	)
	(segment
		(start 103.575612 71.59371)
		(end 103.369872 70.427088)
		(width 0.1143)
		(layer "In2.Cu")
		(net "85_10INCH_IN1_DN")
	)
	(segment
		(start 103.47452 50.337974)
		(end 103.209598 50.152808)
		(width 0.1143)
		(layer "In2.Cu")
		(net "85_10INCH_IN1_DN")
	)
	(segment
		(start 103.64216 55.525416)
		(end 103.436166 54.359048)
		(width 0.1143)
		(layer "In2.Cu")
		(net "85_10INCH_IN1_DN")
	)
	(segment
		(start 103.457248 55.789576)
		(end 103.64216 55.525416)
		(width 0.1143)
		(layer "In2.Cu")
		(net "85_10INCH_IN1_DN")
	)
	(segment
		(start 104.546654 95.507302)
		(end 104.340914 94.340934)
		(width 0.1143)
		(layer "In2.Cu")
		(net "85_10INCH_IN1_DN")
	)
	(segment
		(start 103.131366 78.265274)
		(end 99.752912 78.860904)
		(width 0.1143)
		(layer "In2.Cu")
		(net "85_10INCH_IN1_DN")
	)
	(segment
		(start 99.209352 70.496938)
		(end 98.955098 69.057012)
		(width 0.1143)
		(layer "In2.Cu")
		(net "85_10INCH_IN1_DN")
	)
	(segment
		(start 99.255326 82.531458)
		(end 99.000818 81.091532)
		(width 0.1143)
		(layer "In2.Cu")
		(net "85_10INCH_IN1_DN")
	)
	(segment
		(start 99.215956 58.453528)
		(end 98.961448 57.01411)
		(width 0.1143)
		(layer "In2.Cu")
		(net "85_10INCH_IN1_DN")
	)
	(segment
		(start 103.592884 67.576446)
		(end 103.387144 66.409824)
		(width 0.1143)
		(layer "In2.Cu")
		(net "85_10INCH_IN1_DN")
	)
	(segment
		(start 103.500936 75.620626)
		(end 103.500682 75.620626)
		(width 0.1143)
		(layer "In2.Cu")
		(net "85_10INCH_IN1_DN")
	)
	(segment
		(start 99.231196 42.394378)
		(end 98.976942 40.954706)
		(width 0.1143)
		(layer "In2.Cu")
		(net "85_10INCH_IN1_DN")
	)
	(segment
		(start 104.405176 103.792274)
		(end 104.590088 103.528368)
		(width 0.1143)
		(layer "In2.Cu")
		(net "85_10INCH_IN1_DN")
	)
	(segment
		(start 99.012502 48.976788)
		(end 99.357434 48.484536)
		(width 0.1143)
		(layer "In2.Cu")
		(net "85_10INCH_IN1_DN")
	)
	(segment
		(start 99.351084 76.584302)
		(end 103.31577 75.885548)
		(width 0.1143)
		(layer "In2.Cu")
		(net "85_10INCH_IN1_DN")
	)
	(segment
		(start 99.526344 111.014764)
		(end 99.034346 110.669832)
		(width 0.1143)
		(layer "In2.Cu")
		(net "85_10INCH_IN1_DN")
	)
	(segment
		(start 103.154226 42.134282)
		(end 99.723194 42.73931)
		(width 0.1143)
		(layer "In2.Cu")
		(net "85_10INCH_IN1_DN")
	)
	(segment
		(start 103.472742 59.800998)
		(end 103.658162 59.53633)
		(width 0.1143)
		(layer "In2.Cu")
		(net "85_10INCH_IN1_DN")
	)
	(segment
		(start 99.719892 94.92361)
		(end 99.227894 94.578678)
		(width 0.1143)
		(layer "In2.Cu")
		(net "85_10INCH_IN1_DN")
	)
	(segment
		(start 103.889302 86.392512)
		(end 103.623872 86.206838)
		(width 0.1143)
		(layer "In2.Cu")
		(net "85_10INCH_IN1_DN")
	)
	(segment
		(start 103.526336 39.489126)
		(end 103.320596 38.322504)
		(width 0.1143)
		(layer "In2.Cu")
		(net "85_10INCH_IN1_DN")
	)
	(segment
		(start 101.100128 117.644418)
		(end 101.100128 112.897412)
		(width 0.1143)
		(layer "In2.Cu")
		(net "85_10INCH_IN1_DN")
	)
	(segment
		(start 99.703636 102.95509)
		(end 99.211638 102.610158)
		(width 0.1143)
		(layer "In2.Cu")
		(net "85_10INCH_IN1_DN")
	)
	(segment
		(start 104.376474 111.825278)
		(end 104.561386 111.561626)
		(width 0.1143)
		(layer "In2.Cu")
		(net "85_10INCH_IN1_DN")
	)
	(segment
		(start 99.009962 73.061576)
		(end 99.355402 72.569578)
		(width 0.1143)
		(layer "In2.Cu")
		(net "85_10INCH_IN1_DN")
	)
	(segment
		(start 103.221028 82.263488)
		(end 99.747324 82.87639)
		(width 0.1143)
		(layer "In2.Cu")
		(net "85_10INCH_IN1_DN")
	)
	(segment
		(start 103.62438 43.48607)
		(end 103.41864 42.319448)
		(width 0.1143)
		(layer "In2.Cu")
		(net "85_10INCH_IN1_DN")
	)
	(segment
		(start 98.95713 65.042542)
		(end 99.302062 64.550544)
		(width 0.1143)
		(layer "In2.Cu")
		(net "85_10INCH_IN1_DN")
	)
	(segment
		(start 99.006152 77.0763)
		(end 99.351084 76.584302)
		(width 0.1143)
		(layer "In2.Cu")
		(net "85_10INCH_IN1_DN")
	)
	(segment
		(start 98.961448 57.01411)
		(end 99.307396 56.521604)
		(width 0.1143)
		(layer "In2.Cu")
		(net "85_10INCH_IN1_DN")
	)
	(segment
		(start 99.034346 110.669832)
		(end 98.780092 109.229652)
		(width 0.1143)
		(layer "In2.Cu")
		(net "85_10INCH_IN1_DN")
	)
	(segment
		(start 99.278948 46.399958)
		(end 99.024694 44.96054)
		(width 0.1143)
		(layer "In2.Cu")
		(net "85_10INCH_IN1_DN")
	)
	(segment
		(start 103.396288 78.450694)
		(end 103.131366 78.265274)
		(width 0.1143)
		(layer "In2.Cu")
		(net "85_10INCH_IN1_DN")
	)
	(segment
		(start 99.00031 52.993036)
		(end 99.345242 52.500784)
		(width 0.1143)
		(layer "In2.Cu")
		(net "85_10INCH_IN1_DN")
	)
	(segment
		(start 99.588066 98.961194)
		(end 99.096068 98.616262)
		(width 0.1143)
		(layer "In2.Cu")
		(net "85_10INCH_IN1_DN")
	)
	(segment
		(start 104.709976 -3.669538)
		(end 104.479344 -3.339846)
		(width 0.14224)
		(layer "B.Cu")
		(net "85_10INCH_BOT_DP")
	)
	(segment
		(start 98.748342 -5.651246)
		(end 98.96602 -4.416298)
		(width 0.14224)
		(layer "B.Cu")
		(net "85_10INCH_BOT_DP")
	)
	(segment
		(start 98.246946 -38.2397)
		(end 104.114346 -39.274242)
		(width 0.14224)
		(layer "B.Cu")
		(net "85_10INCH_BOT_DP")
	)
	(segment
		(start 104.256586 -18.615914)
		(end 99.126802 -17.71142)
		(width 0.14224)
		(layer "B.Cu")
		(net "85_10INCH_BOT_DP")
	)
	(segment
		(start 99.15779 1.426464)
		(end 98.751898 2.005584)
		(width 0.14224)
		(layer "B.Cu")
		(net "85_10INCH_BOT_DP")
	)
	(segment
		(start 104.54513 -4.603242)
		(end 104.709976 -3.669538)
		(width 0.14224)
		(layer "B.Cu")
		(net "85_10INCH_BOT_DP")
	)
	(segment
		(start 98.979482 10.896092)
		(end 99.55911 11.30173)
		(width 0.14224)
		(layer "B.Cu")
		(net "85_10INCH_BOT_DP")
	)
	(segment
		(start 97.703386 -23.337012)
		(end 98.28276 -22.931374)
		(width 0.14224)
		(layer "B.Cu")
		(net "85_10INCH_BOT_DP")
	)
	(segment
		(start 104.186482 -23.972266)
		(end 104.51592 -23.74138)
		(width 0.14224)
		(layer "B.Cu")
		(net "85_10INCH_BOT_DP")
	)
	(segment
		(start 99.164394 -21.54682)
		(end 98.758502 -20.9677)
		(width 0.14224)
		(layer "B.Cu")
		(net "85_10INCH_BOT_DP")
	)
	(segment
		(start 98.725482 5.838952)
		(end 98.751898 5.98932)
		(width 0.14224)
		(layer "B.Cu")
		(net "85_10INCH_BOT_DP")
	)
	(segment
		(start 99.549204 3.64617)
		(end 104.242108 2.818638)
		(width 0.14224)
		(layer "B.Cu")
		(net "85_10INCH_BOT_DP")
	)
	(segment
		(start 99.126802 -17.71142)
		(end 98.72091 -17.1323)
		(width 0.14224)
		(layer "B.Cu")
		(net "85_10INCH_BOT_DP")
	)
	(segment
		(start 101.032564 17.018508)
		(end 101.032564 17.175988)
		(width 0.14224)
		(layer "B.Cu")
		(net "85_10INCH_BOT_DP")
	)
	(segment
		(start 104.114346 -39.274242)
		(end 104.443784 -39.043356)
		(width 0.14224)
		(layer "B.Cu")
		(net "85_10INCH_BOT_DP")
	)
	(segment
		(start 104.38765 6.910832)
		(end 104.552496 7.844282)
		(width 0.14224)
		(layer "B.Cu")
		(net "85_10INCH_BOT_DP")
	)
	(segment
		(start 98.752152 5.98932)
		(end 98.94316 7.0739)
		(width 0.14224)
		(layer "B.Cu")
		(net "85_10INCH_BOT_DP")
	)
	(segment
		(start 104.468422 0.49022)
		(end 99.15779 1.426464)
		(width 0.14224)
		(layer "B.Cu")
		(net "85_10INCH_BOT_DP")
	)
	(segment
		(start 104.144064 -31.621984)
		(end 104.473502 -31.391098)
		(width 0.14224)
		(layer "B.Cu")
		(net "85_10INCH_BOT_DP")
	)
	(segment
		(start 103.922576 -16.268446)
		(end 104.252014 -16.03756)
		(width 0.14224)
		(layer "B.Cu")
		(net "85_10INCH_BOT_DP")
	)
	(segment
		(start 102.993444 10.696194)
		(end 103.322882 10.92708)
		(width 0.14224)
		(layer "B.Cu")
		(net "85_10INCH_BOT_DP")
	)
	(segment
		(start 101.720396 12.460732)
		(end 101.09835 13.082778)
		(width 0.14224)
		(layer "B.Cu")
		(net "85_10INCH_BOT_DP")
	)
	(segment
		(start 104.407716 -30.128464)
		(end 97.82683 -28.968192)
		(width 0.14224)
		(layer "B.Cu")
		(net "85_10INCH_BOT_DP")
	)
	(segment
		(start 104.41686 -15.10411)
		(end 104.186228 -14.774926)
		(width 0.14224)
		(layer "B.Cu")
		(net "85_10INCH_BOT_DP")
	)
	(segment
		(start 104.377998 -37.780722)
		(end 97.973896 -36.651438)
		(width 0.14224)
		(layer "B.Cu")
		(net "85_10INCH_BOT_DP")
	)
	(segment
		(start 104.508554 -42.883328)
		(end 104.6734 -41.949878)
		(width 0.14224)
		(layer "B.Cu")
		(net "85_10INCH_BOT_DP")
	)
	(segment
		(start 99.55911 11.30173)
		(end 102.993444 10.696194)
		(width 0.14224)
		(layer "B.Cu")
		(net "85_10INCH_BOT_DP")
	)
	(segment
		(start 97.82683 -28.968192)
		(end 97.421192 -28.389326)
		(width 0.14224)
		(layer "B.Cu")
		(net "85_10INCH_BOT_DP")
	)
	(segment
		(start 104.186228 -14.774926)
		(end 99.165156 -13.889482)
		(width 0.14224)
		(layer "B.Cu")
		(net "85_10INCH_BOT_DP")
	)
	(segment
		(start 104.699054 0.161036)
		(end 104.468422 0.49022)
		(width 0.14224)
		(layer "B.Cu")
		(net "85_10INCH_BOT_DP")
	)
	(segment
		(start 99.55657 -11.669776)
		(end 103.890572 -12.434062)
		(width 0.14224)
		(layer "B.Cu")
		(net "85_10INCH_BOT_DP")
	)
	(segment
		(start 98.218498 -26.74874)
		(end 104.20858 -27.804872)
		(width 0.14224)
		(layer "B.Cu")
		(net "85_10INCH_BOT_DP")
	)
	(segment
		(start 101.025198 -48.675544)
		(end 97.939352 -48.131476)
		(width 0.14224)
		(layer "B.Cu")
		(net "85_10INCH_BOT_DP")
	)
	(segment
		(start 98.751898 5.98932)
		(end 98.752152 5.98932)
		(width 0.14224)
		(layer "B.Cu")
		(net "85_10INCH_BOT_DP")
	)
	(segment
		(start 104.321864 8.173466)
		(end 99.167188 9.082278)
		(width 0.14224)
		(layer "B.Cu")
		(net "85_10INCH_BOT_DP")
	)
	(segment
		(start 103.257096 12.189714)
		(end 101.720396 12.460732)
		(width 0.14224)
		(layer "B.Cu")
		(net "85_10INCH_BOT_DP")
	)
	(segment
		(start 104.242108 2.818638)
		(end 104.571546 3.049524)
		(width 0.14224)
		(layer "B.Cu")
		(net "85_10INCH_BOT_DP")
	)
	(segment
		(start 104.179116 -43.114214)
		(end 104.508554 -42.883328)
		(width 0.14224)
		(layer "B.Cu")
		(net "85_10INCH_BOT_DP")
	)
	(segment
		(start 104.552496 7.844282)
		(end 104.321864 8.173466)
		(width 0.14224)
		(layer "B.Cu")
		(net "85_10INCH_BOT_DP")
	)
	(segment
		(start 104.6734 -41.949878)
		(end 104.442768 -41.620694)
		(width 0.14224)
		(layer "B.Cu")
		(net "85_10INCH_BOT_DP")
	)
	(segment
		(start 104.571546 3.049524)
		(end 104.736392 3.982974)
		(width 0.14224)
		(layer "B.Cu")
		(net "85_10INCH_BOT_DP")
	)
	(segment
		(start 99.167188 9.082278)
		(end 98.76155 9.661144)
		(width 0.14224)
		(layer "B.Cu")
		(net "85_10INCH_BOT_DP")
	)
	(segment
		(start 104.20858 -27.804872)
		(end 104.538018 -27.573986)
		(width 0.14224)
		(layer "B.Cu")
		(net "85_10INCH_BOT_DP")
	)
	(segment
		(start 101.25583 -49.004728)
		(end 101.025198 -48.675544)
		(width 0.14224)
		(layer "B.Cu")
		(net "85_10INCH_BOT_DP")
	)
	(segment
		(start 104.173782 -8.365998)
		(end 104.338628 -7.432548)
		(width 0.14224)
		(layer "B.Cu")
		(net "85_10INCH_BOT_DP")
	)
	(segment
		(start 104.472232 -26.311352)
		(end 97.891346 -25.15108)
		(width 0.14224)
		(layer "B.Cu")
		(net "85_10INCH_BOT_DP")
	)
	(segment
		(start 104.107996 -7.103364)
		(end 99.15398 -6.230112)
		(width 0.14224)
		(layer "B.Cu")
		(net "85_10INCH_BOT_DP")
	)
	(segment
		(start 103.890572 -12.434062)
		(end 104.22001 -12.203176)
		(width 0.14224)
		(layer "B.Cu")
		(net "85_10INCH_BOT_DP")
	)
	(segment
		(start 97.421192 -28.389326)
		(end 97.639124 -27.154378)
		(width 0.14224)
		(layer "B.Cu")
		(net "85_10INCH_BOT_DP")
	)
	(segment
		(start 97.53346 -47.552356)
		(end 97.751392 -46.317408)
		(width 0.14224)
		(layer "B.Cu")
		(net "85_10INCH_BOT_DP")
	)
	(segment
		(start 104.470454 -33.967674)
		(end 97.93986 -32.817054)
		(width 0.14224)
		(layer "B.Cu")
		(net "85_10INCH_BOT_DP")
	)
	(segment
		(start 97.713546 -42.482262)
		(end 98.29292 -42.07637)
		(width 0.14224)
		(layer "B.Cu")
		(net "85_10INCH_BOT_DP")
	)
	(segment
		(start 104.53624 -35.23107)
		(end 104.701086 -34.297366)
		(width 0.14224)
		(layer "B.Cu")
		(net "85_10INCH_BOT_DP")
	)
	(segment
		(start 101.032564 -53.420772)
		(end 101.09835 -53.354986)
		(width 0.14224)
		(layer "B.Cu")
		(net "85_10INCH_BOT_DP")
	)
	(segment
		(start 97.639124 -27.154378)
		(end 98.218498 -26.74874)
		(width 0.14224)
		(layer "B.Cu")
		(net "85_10INCH_BOT_DP")
	)
	(segment
		(start 97.533968 -32.23768)
		(end 97.7519 -31.002732)
		(width 0.14224)
		(layer "B.Cu")
		(net "85_10INCH_BOT_DP")
	)
	(segment
		(start 97.495614 -43.716956)
		(end 97.713546 -42.482262)
		(width 0.14224)
		(layer "B.Cu")
		(net "85_10INCH_BOT_DP")
	)
	(segment
		(start 99.518216 -15.491714)
		(end 103.922576 -16.268446)
		(width 0.14224)
		(layer "B.Cu")
		(net "85_10INCH_BOT_DP")
	)
	(segment
		(start 104.60863 -38.109906)
		(end 104.377998 -37.780722)
		(width 0.14224)
		(layer "B.Cu")
		(net "85_10INCH_BOT_DP")
	)
	(segment
		(start 99.131374 5.260086)
		(end 98.725482 5.838952)
		(width 0.14224)
		(layer "B.Cu")
		(net "85_10INCH_BOT_DP")
	)
	(segment
		(start 104.487218 -18.945098)
		(end 104.256586 -18.615914)
		(width 0.14224)
		(layer "B.Cu")
		(net "85_10INCH_BOT_DP")
	)
	(segment
		(start 98.976434 -19.732752)
		(end 99.555808 -19.327114)
		(width 0.14224)
		(layer "B.Cu")
		(net "85_10INCH_BOT_DP")
	)
	(segment
		(start 104.442768 -41.620694)
		(end 97.855532 -40.459152)
		(width 0.14224)
		(layer "B.Cu")
		(net "85_10INCH_BOT_DP")
	)
	(segment
		(start 104.736392 3.982974)
		(end 104.50576 4.312412)
		(width 0.14224)
		(layer "B.Cu")
		(net "85_10INCH_BOT_DP")
	)
	(segment
		(start 104.148128 -46.937422)
		(end 104.477566 -46.706536)
		(width 0.14224)
		(layer "B.Cu")
		(net "85_10INCH_BOT_DP")
	)
	(segment
		(start 104.51592 -23.74138)
		(end 104.680766 -22.80793)
		(width 0.14224)
		(layer "B.Cu")
		(net "85_10INCH_BOT_DP")
	)
	(segment
		(start 99.545648 -4.01066)
		(end 104.215692 -4.834128)
		(width 0.14224)
		(layer "B.Cu")
		(net "85_10INCH_BOT_DP")
	)
	(segment
		(start 98.331274 -30.597094)
		(end 104.144064 -31.621984)
		(width 0.14224)
		(layer "B.Cu")
		(net "85_10INCH_BOT_DP")
	)
	(segment
		(start 98.330766 -45.91177)
		(end 104.148128 -46.937422)
		(width 0.14224)
		(layer "B.Cu")
		(net "85_10INCH_BOT_DP")
	)
	(segment
		(start 97.7519 -31.002732)
		(end 98.331274 -30.597094)
		(width 0.14224)
		(layer "B.Cu")
		(net "85_10INCH_BOT_DP")
	)
	(segment
		(start 104.384856 -11.269726)
		(end 104.154224 -10.940542)
		(width 0.14224)
		(layer "B.Cu")
		(net "85_10INCH_BOT_DP")
	)
	(segment
		(start 97.785936 -34.837624)
		(end 98.36531 -34.431986)
		(width 0.14224)
		(layer "B.Cu")
		(net "85_10INCH_BOT_DP")
	)
	(segment
		(start 98.72091 -17.1323)
		(end 98.938842 -15.897352)
		(width 0.14224)
		(layer "B.Cu")
		(net "85_10INCH_BOT_DP")
	)
	(segment
		(start 98.751898 2.005584)
		(end 98.969576 3.240532)
		(width 0.14224)
		(layer "B.Cu")
		(net "85_10INCH_BOT_DP")
	)
	(segment
		(start 99.13366 -8.274304)
		(end 99.713288 -7.868666)
		(width 0.14224)
		(layer "B.Cu")
		(net "85_10INCH_BOT_DP")
	)
	(segment
		(start 99.713288 -7.868666)
		(end 103.844344 -8.596884)
		(width 0.14224)
		(layer "B.Cu")
		(net "85_10INCH_BOT_DP")
	)
	(segment
		(start 104.154224 -10.940542)
		(end 99.321874 -10.088372)
		(width 0.14224)
		(layer "B.Cu")
		(net "85_10INCH_BOT_DP")
	)
	(segment
		(start 101.09835 -53.354986)
		(end 101.09835 -49.896268)
		(width 0.14224)
		(layer "B.Cu")
		(net "85_10INCH_BOT_DP")
	)
	(segment
		(start 104.215692 -4.834128)
		(end 104.54513 -4.603242)
		(width 0.14224)
		(layer "B.Cu")
		(net "85_10INCH_BOT_DP")
	)
	(segment
		(start 97.667572 -38.645592)
		(end 98.246946 -38.2397)
		(width 0.14224)
		(layer "B.Cu")
		(net "85_10INCH_BOT_DP")
	)
	(segment
		(start 104.479344 -3.339846)
		(end 99.151694 -2.401062)
		(width 0.14224)
		(layer "B.Cu")
		(net "85_10INCH_BOT_DP")
	)
	(segment
		(start 103.992934 -20.109434)
		(end 104.322372 -19.878548)
		(width 0.14224)
		(layer "B.Cu")
		(net "85_10INCH_BOT_DP")
	)
	(segment
		(start 104.22001 -12.203176)
		(end 104.384856 -11.269726)
		(width 0.14224)
		(layer "B.Cu")
		(net "85_10INCH_BOT_DP")
	)
	(segment
		(start 97.751392 -46.317408)
		(end 98.330766 -45.91177)
		(width 0.14224)
		(layer "B.Cu")
		(net "85_10INCH_BOT_DP")
	)
	(segment
		(start 98.915982 -9.509252)
		(end 99.13366 -8.274304)
		(width 0.14224)
		(layer "B.Cu")
		(net "85_10INCH_BOT_DP")
	)
	(segment
		(start 104.477566 -46.706536)
		(end 104.642412 -45.773086)
		(width 0.14224)
		(layer "B.Cu")
		(net "85_10INCH_BOT_DP")
	)
	(segment
		(start 97.901506 -44.296076)
		(end 97.495614 -43.716956)
		(width 0.14224)
		(layer "B.Cu")
		(net "85_10INCH_BOT_DP")
	)
	(segment
		(start 98.759264 -13.310362)
		(end 98.977196 -12.075414)
		(width 0.14224)
		(layer "B.Cu")
		(net "85_10INCH_BOT_DP")
	)
	(segment
		(start 104.20477 -1.0033)
		(end 104.534208 -0.772414)
		(width 0.14224)
		(layer "B.Cu")
		(net "85_10INCH_BOT_DP")
	)
	(segment
		(start 104.206802 -35.461956)
		(end 104.53624 -35.23107)
		(width 0.14224)
		(layer "B.Cu")
		(net "85_10INCH_BOT_DP")
	)
	(segment
		(start 97.44964 -39.88054)
		(end 97.667572 -38.645592)
		(width 0.14224)
		(layer "B.Cu")
		(net "85_10INCH_BOT_DP")
	)
	(segment
		(start 99.543108 -0.181356)
		(end 104.20477 -1.0033)
		(width 0.14224)
		(layer "B.Cu")
		(net "85_10INCH_BOT_DP")
	)
	(segment
		(start 98.745802 -1.821942)
		(end 98.96348 -0.586994)
		(width 0.14224)
		(layer "B.Cu")
		(net "85_10INCH_BOT_DP")
	)
	(segment
		(start 104.638348 -30.457648)
		(end 104.407716 -30.128464)
		(width 0.14224)
		(layer "B.Cu")
		(net "85_10INCH_BOT_DP")
	)
	(segment
		(start 101.09835 -49.896268)
		(end 101.25583 -49.004728)
		(width 0.14224)
		(layer "B.Cu")
		(net "85_10INCH_BOT_DP")
	)
	(segment
		(start 103.487728 11.86053)
		(end 103.257096 12.189714)
		(width 0.14224)
		(layer "B.Cu")
		(net "85_10INCH_BOT_DP")
	)
	(segment
		(start 98.969576 3.240532)
		(end 99.549204 3.64617)
		(width 0.14224)
		(layer "B.Cu")
		(net "85_10INCH_BOT_DP")
	)
	(segment
		(start 104.058212 6.679946)
		(end 104.38765 6.910832)
		(width 0.14224)
		(layer "B.Cu")
		(net "85_10INCH_BOT_DP")
	)
	(segment
		(start 97.485454 -24.57196)
		(end 97.703386 -23.337012)
		(width 0.14224)
		(layer "B.Cu")
		(net "85_10INCH_BOT_DP")
	)
	(segment
		(start 103.844344 -8.596884)
		(end 104.173782 -8.365998)
		(width 0.14224)
		(layer "B.Cu")
		(net "85_10INCH_BOT_DP")
	)
	(segment
		(start 98.758502 -20.9677)
		(end 98.976434 -19.732752)
		(width 0.14224)
		(layer "B.Cu")
		(net "85_10INCH_BOT_DP")
	)
	(segment
		(start 98.29292 -42.07637)
		(end 104.179116 -43.114214)
		(width 0.14224)
		(layer "B.Cu")
		(net "85_10INCH_BOT_DP")
	)
	(segment
		(start 104.680766 -22.80793)
		(end 104.450134 -22.478746)
		(width 0.14224)
		(layer "B.Cu")
		(net "85_10INCH_BOT_DP")
	)
	(segment
		(start 98.977196 -12.075414)
		(end 99.55657 -11.669776)
		(width 0.14224)
		(layer "B.Cu")
		(net "85_10INCH_BOT_DP")
	)
	(segment
		(start 104.50576 4.312412)
		(end 99.131374 5.260086)
		(width 0.14224)
		(layer "B.Cu")
		(net "85_10INCH_BOT_DP")
	)
	(segment
		(start 97.93986 -32.817054)
		(end 97.533968 -32.23768)
		(width 0.14224)
		(layer "B.Cu")
		(net "85_10INCH_BOT_DP")
	)
	(segment
		(start 98.28276 -22.931374)
		(end 104.186482 -23.972266)
		(width 0.14224)
		(layer "B.Cu")
		(net "85_10INCH_BOT_DP")
	)
	(segment
		(start 97.891346 -25.15108)
		(end 97.485454 -24.57196)
		(width 0.14224)
		(layer "B.Cu")
		(net "85_10INCH_BOT_DP")
	)
	(segment
		(start 98.938842 -15.897352)
		(end 99.518216 -15.491714)
		(width 0.14224)
		(layer "B.Cu")
		(net "85_10INCH_BOT_DP")
	)
	(segment
		(start 99.555808 -19.327114)
		(end 103.992934 -20.109434)
		(width 0.14224)
		(layer "B.Cu")
		(net "85_10INCH_BOT_DP")
	)
	(segment
		(start 97.973896 -36.651438)
		(end 97.568004 -36.072826)
		(width 0.14224)
		(layer "B.Cu")
		(net "85_10INCH_BOT_DP")
	)
	(segment
		(start 104.642412 -45.773086)
		(end 104.41178 -45.443902)
		(width 0.14224)
		(layer "B.Cu")
		(net "85_10INCH_BOT_DP")
	)
	(segment
		(start 104.443784 -39.043356)
		(end 104.60863 -38.109906)
		(width 0.14224)
		(layer "B.Cu")
		(net "85_10INCH_BOT_DP")
	)
	(segment
		(start 104.252014 -16.03756)
		(end 104.41686 -15.10411)
		(width 0.14224)
		(layer "B.Cu")
		(net "85_10INCH_BOT_DP")
	)
	(segment
		(start 98.76155 9.661144)
		(end 98.979482 10.896092)
		(width 0.14224)
		(layer "B.Cu")
		(net "85_10INCH_BOT_DP")
	)
	(segment
		(start 103.322882 10.92708)
		(end 103.487728 11.86053)
		(width 0.14224)
		(layer "B.Cu")
		(net "85_10INCH_BOT_DP")
	)
	(segment
		(start 101.09835 13.082778)
		(end 101.09835 16.952722)
		(width 0.14224)
		(layer "B.Cu")
		(net "85_10INCH_BOT_DP")
	)
	(segment
		(start 99.321874 -10.088372)
		(end 98.915982 -9.509252)
		(width 0.14224)
		(layer "B.Cu")
		(net "85_10INCH_BOT_DP")
	)
	(segment
		(start 99.151694 -2.401062)
		(end 98.745802 -1.821942)
		(width 0.14224)
		(layer "B.Cu")
		(net "85_10INCH_BOT_DP")
	)
	(segment
		(start 104.702864 -26.640536)
		(end 104.472232 -26.311352)
		(width 0.14224)
		(layer "B.Cu")
		(net "85_10INCH_BOT_DP")
	)
	(segment
		(start 99.165156 -13.889482)
		(end 98.759264 -13.310362)
		(width 0.14224)
		(layer "B.Cu")
		(net "85_10INCH_BOT_DP")
	)
	(segment
		(start 104.538018 -27.573986)
		(end 104.702864 -26.640536)
		(width 0.14224)
		(layer "B.Cu")
		(net "85_10INCH_BOT_DP")
	)
	(segment
		(start 98.36531 -34.431986)
		(end 104.206802 -35.461956)
		(width 0.14224)
		(layer "B.Cu")
		(net "85_10INCH_BOT_DP")
	)
	(segment
		(start 104.701086 -34.297366)
		(end 104.470454 -33.967674)
		(width 0.14224)
		(layer "B.Cu")
		(net "85_10INCH_BOT_DP")
	)
	(segment
		(start 99.15398 -6.230112)
		(end 98.748342 -5.651246)
		(width 0.14224)
		(layer "B.Cu")
		(net "85_10INCH_BOT_DP")
	)
	(segment
		(start 104.338628 -7.432548)
		(end 104.107996 -7.103364)
		(width 0.14224)
		(layer "B.Cu")
		(net "85_10INCH_BOT_DP")
	)
	(segment
		(start 101.032564 -53.578252)
		(end 101.032564 -53.420772)
		(width 0.14224)
		(layer "B.Cu")
		(net "85_10INCH_BOT_DP")
	)
	(segment
		(start 104.534208 -0.772414)
		(end 104.699054 0.161036)
		(width 0.14224)
		(layer "B.Cu")
		(net "85_10INCH_BOT_DP")
	)
	(segment
		(start 98.96602 -4.416298)
		(end 99.545648 -4.01066)
		(width 0.14224)
		(layer "B.Cu")
		(net "85_10INCH_BOT_DP")
	)
	(segment
		(start 104.41178 -45.443902)
		(end 97.901506 -44.296076)
		(width 0.14224)
		(layer "B.Cu")
		(net "85_10INCH_BOT_DP")
	)
	(segment
		(start 104.450134 -22.478746)
		(end 99.164394 -21.54682)
		(width 0.14224)
		(layer "B.Cu")
		(net "85_10INCH_BOT_DP")
	)
	(segment
		(start 97.939352 -48.131476)
		(end 97.53346 -47.552356)
		(width 0.14224)
		(layer "B.Cu")
		(net "85_10INCH_BOT_DP")
	)
	(segment
		(start 104.322372 -19.878548)
		(end 104.487218 -18.945098)
		(width 0.14224)
		(layer "B.Cu")
		(net "85_10INCH_BOT_DP")
	)
	(segment
		(start 99.522788 7.479538)
		(end 104.058212 6.679946)
		(width 0.14224)
		(layer "B.Cu")
		(net "85_10INCH_BOT_DP")
	)
	(segment
		(start 98.94316 7.0739)
		(end 99.522788 7.479538)
		(width 0.14224)
		(layer "B.Cu")
		(net "85_10INCH_BOT_DP")
	)
	(segment
		(start 97.568004 -36.072826)
		(end 97.785936 -34.837624)
		(width 0.14224)
		(layer "B.Cu")
		(net "85_10INCH_BOT_DP")
	)
	(segment
		(start 97.855532 -40.459152)
		(end 97.44964 -39.88054)
		(width 0.14224)
		(layer "B.Cu")
		(net "85_10INCH_BOT_DP")
	)
	(segment
		(start 101.09835 16.952722)
		(end 101.032564 17.018508)
		(width 0.14224)
		(layer "B.Cu")
		(net "85_10INCH_BOT_DP")
	)
	(segment
		(start 98.96348 -0.586994)
		(end 99.543108 -0.181356)
		(width 0.14224)
		(layer "B.Cu")
		(net "85_10INCH_BOT_DP")
	)
	(segment
		(start 104.473502 -31.391098)
		(end 104.638348 -30.457648)
		(width 0.14224)
		(layer "B.Cu")
		(net "85_10INCH_BOT_DP")
	)
	(segment
		(start 99.38131 9.418574)
		(end 99.150932 9.747504)
		(width 0.14224)
		(layer "B.Cu")
		(net "85_10INCH_BOT_DN")
	)
	(segment
		(start 103.659178 10.712958)
		(end 103.87711 11.94689)
		(width 0.14224)
		(layer "B.Cu")
		(net "85_10INCH_BOT_DN")
	)
	(segment
		(start 104.079294 -20.498816)
		(end 104.658668 -20.09267)
		(width 0.14224)
		(layer "B.Cu")
		(net "85_10INCH_BOT_DN")
	)
	(segment
		(start 97.874836 -24.4856)
		(end 98.039682 -23.551388)
		(width 0.14224)
		(layer "B.Cu")
		(net "85_10INCH_BOT_DN")
	)
	(segment
		(start 103.079804 10.306812)
		(end 103.659178 10.712958)
		(width 0.14224)
		(layer "B.Cu")
		(net "85_10INCH_BOT_DN")
	)
	(segment
		(start 103.976932 -12.823444)
		(end 104.556306 -12.417298)
		(width 0.14224)
		(layer "B.Cu")
		(net "85_10INCH_BOT_DN")
	)
	(segment
		(start 104.682544 0.826516)
		(end 99.371912 1.76276)
		(width 0.14224)
		(layer "B.Cu")
		(net "85_10INCH_BOT_DN")
	)
	(segment
		(start 99.64293 -12.059158)
		(end 103.976932 -12.823444)
		(width 0.14224)
		(layer "B.Cu")
		(net "85_10INCH_BOT_DN")
	)
	(segment
		(start 101.532436 -53.420772)
		(end 101.46665 -53.354986)
		(width 0.14224)
		(layer "B.Cu")
		(net "85_10INCH_BOT_DN")
	)
	(segment
		(start 104.556306 -12.417298)
		(end 104.774238 -11.183366)
		(width 0.14224)
		(layer "B.Cu")
		(net "85_10INCH_BOT_DN")
	)
	(segment
		(start 99.604576 -15.881096)
		(end 104.008936 -16.657828)
		(width 0.14224)
		(layer "B.Cu")
		(net "85_10INCH_BOT_DN")
	)
	(segment
		(start 98.153474 -47.79518)
		(end 97.922842 -47.465996)
		(width 0.14224)
		(layer "B.Cu")
		(net "85_10INCH_BOT_DN")
	)
	(segment
		(start 104.907842 2.835402)
		(end 105.125774 4.069334)
		(width 0.14224)
		(layer "B.Cu")
		(net "85_10INCH_BOT_DN")
	)
	(segment
		(start 97.922842 -47.465996)
		(end 98.087688 -46.531784)
		(width 0.14224)
		(layer "B.Cu")
		(net "85_10INCH_BOT_DN")
	)
	(segment
		(start 98.003868 -38.859714)
		(end 98.333306 -38.629082)
		(width 0.14224)
		(layer "B.Cu")
		(net "85_10INCH_BOT_DN")
	)
	(segment
		(start 98.088196 -31.217108)
		(end 98.417634 -30.986476)
		(width 0.14224)
		(layer "B.Cu")
		(net "85_10INCH_BOT_DN")
	)
	(segment
		(start 104.265476 -43.503596)
		(end 104.84485 -43.09745)
		(width 0.14224)
		(layer "B.Cu")
		(net "85_10INCH_BOT_DN")
	)
	(segment
		(start 104.774238 -11.183366)
		(end 104.368346 -10.604246)
		(width 0.14224)
		(layer "B.Cu")
		(net "85_10INCH_BOT_DN")
	)
	(segment
		(start 97.884996 -43.630596)
		(end 98.049842 -42.696384)
		(width 0.14224)
		(layer "B.Cu")
		(net "85_10INCH_BOT_DN")
	)
	(segment
		(start 104.322118 -6.767068)
		(end 99.368102 -5.893816)
		(width 0.14224)
		(layer "B.Cu")
		(net "85_10INCH_BOT_DN")
	)
	(segment
		(start 104.470708 -18.279618)
		(end 99.340924 -17.375124)
		(width 0.14224)
		(layer "B.Cu")
		(net "85_10INCH_BOT_DN")
	)
	(segment
		(start 99.306126 3.026156)
		(end 99.635564 3.256788)
		(width 0.14224)
		(layer "B.Cu")
		(net "85_10INCH_BOT_DN")
	)
	(segment
		(start 99.31273 -19.947128)
		(end 99.642168 -19.716496)
		(width 0.14224)
		(layer "B.Cu")
		(net "85_10INCH_BOT_DN")
	)
	(segment
		(start 104.998012 -38.023546)
		(end 104.59212 -37.444426)
		(width 0.14224)
		(layer "B.Cu")
		(net "85_10INCH_BOT_DN")
	)
	(segment
		(start 104.234488 -47.326804)
		(end 104.813862 -46.920658)
		(width 0.14224)
		(layer "B.Cu")
		(net "85_10INCH_BOT_DN")
	)
	(segment
		(start 104.686354 -25.975056)
		(end 98.105468 -24.814784)
		(width 0.14224)
		(layer "B.Cu")
		(net "85_10INCH_BOT_DN")
	)
	(segment
		(start 104.230424 -32.011366)
		(end 104.809798 -31.60522)
		(width 0.14224)
		(layer "B.Cu")
		(net "85_10INCH_BOT_DN")
	)
	(segment
		(start 99.345496 5.596382)
		(end 99.114864 5.925312)
		(width 0.14224)
		(layer "B.Cu")
		(net "85_10INCH_BOT_DN")
	)
	(segment
		(start 104.58831 -16.251682)
		(end 104.806242 -15.01775)
		(width 0.14224)
		(layer "B.Cu")
		(net "85_10INCH_BOT_DN")
	)
	(segment
		(start 104.59212 -37.444426)
		(end 98.188018 -36.315142)
		(width 0.14224)
		(layer "B.Cu")
		(net "85_10INCH_BOT_DN")
	)
	(segment
		(start 104.200706 -39.663624)
		(end 104.78008 -39.257478)
		(width 0.14224)
		(layer "B.Cu")
		(net "85_10INCH_BOT_DN")
	)
	(segment
		(start 104.368346 -10.604246)
		(end 99.535996 -9.752076)
		(width 0.14224)
		(layer "B.Cu")
		(net "85_10INCH_BOT_DN")
	)
	(segment
		(start 104.535986 8.509762)
		(end 99.38131 9.418574)
		(width 0.14224)
		(layer "B.Cu")
		(net "85_10INCH_BOT_DN")
	)
	(segment
		(start 98.188018 -36.315142)
		(end 97.957386 -35.986212)
		(width 0.14224)
		(layer "B.Cu")
		(net "85_10INCH_BOT_DN")
	)
	(segment
		(start 99.147884 -20.88134)
		(end 99.31273 -19.947128)
		(width 0.14224)
		(layer "B.Cu")
		(net "85_10INCH_BOT_DN")
	)
	(segment
		(start 98.122232 -35.052)
		(end 98.45167 -34.821368)
		(width 0.14224)
		(layer "B.Cu")
		(net "85_10INCH_BOT_DN")
	)
	(segment
		(start 105.02773 -30.371288)
		(end 104.621838 -29.792168)
		(width 0.14224)
		(layer "B.Cu")
		(net "85_10INCH_BOT_DN")
	)
	(segment
		(start 104.68483 -33.631378)
		(end 98.153982 -32.480758)
		(width 0.14224)
		(layer "B.Cu")
		(net "85_10INCH_BOT_DN")
	)
	(segment
		(start 104.72801 -7.346188)
		(end 104.322118 -6.767068)
		(width 0.14224)
		(layer "B.Cu")
		(net "85_10INCH_BOT_DN")
	)
	(segment
		(start 98.039682 -23.551388)
		(end 98.36912 -23.320756)
		(width 0.14224)
		(layer "B.Cu")
		(net "85_10INCH_BOT_DN")
	)
	(segment
		(start 104.510078 -8.580374)
		(end 104.72801 -7.346188)
		(width 0.14224)
		(layer "B.Cu")
		(net "85_10INCH_BOT_DN")
	)
	(segment
		(start 99.368102 -5.893816)
		(end 99.137724 -5.564886)
		(width 0.14224)
		(layer "B.Cu")
		(net "85_10INCH_BOT_DN")
	)
	(segment
		(start 99.275138 -16.111728)
		(end 99.604576 -15.881096)
		(width 0.14224)
		(layer "B.Cu")
		(net "85_10INCH_BOT_DN")
	)
	(segment
		(start 98.36912 -23.320756)
		(end 104.272842 -24.361648)
		(width 0.14224)
		(layer "B.Cu")
		(net "85_10INCH_BOT_DN")
	)
	(segment
		(start 104.723946 6.69671)
		(end 104.941878 7.930642)
		(width 0.14224)
		(layer "B.Cu")
		(net "85_10INCH_BOT_DN")
	)
	(segment
		(start 99.30003 -0.80137)
		(end 99.629468 -0.570738)
		(width 0.14224)
		(layer "B.Cu")
		(net "85_10INCH_BOT_DN")
	)
	(segment
		(start 98.115628 -43.95978)
		(end 97.884996 -43.630596)
		(width 0.14224)
		(layer "B.Cu")
		(net "85_10INCH_BOT_DN")
	)
	(segment
		(start 104.8766 -18.858738)
		(end 104.470708 -18.279618)
		(width 0.14224)
		(layer "B.Cu")
		(net "85_10INCH_BOT_DN")
	)
	(segment
		(start 104.852216 -23.955502)
		(end 105.070148 -22.72157)
		(width 0.14224)
		(layer "B.Cu")
		(net "85_10INCH_BOT_DN")
	)
	(segment
		(start 104.69372 -3.00355)
		(end 99.365816 -2.064766)
		(width 0.14224)
		(layer "B.Cu")
		(net "85_10INCH_BOT_DN")
	)
	(segment
		(start 104.881426 -4.817364)
		(end 105.099358 -3.583432)
		(width 0.14224)
		(layer "B.Cu")
		(net "85_10INCH_BOT_DN")
	)
	(segment
		(start 99.379278 -13.553186)
		(end 99.148646 -13.224002)
		(width 0.14224)
		(layer "B.Cu")
		(net "85_10INCH_BOT_DN")
	)
	(segment
		(start 105.070148 -22.72157)
		(end 104.664256 -22.14245)
		(width 0.14224)
		(layer "B.Cu")
		(net "85_10INCH_BOT_DN")
	)
	(segment
		(start 98.417634 -30.986476)
		(end 104.230424 -32.011366)
		(width 0.14224)
		(layer "B.Cu")
		(net "85_10INCH_BOT_DN")
	)
	(segment
		(start 99.642168 -19.716496)
		(end 104.079294 -20.498816)
		(width 0.14224)
		(layer "B.Cu")
		(net "85_10INCH_BOT_DN")
	)
	(segment
		(start 99.315778 10.681716)
		(end 99.64547 10.912348)
		(width 0.14224)
		(layer "B.Cu")
		(net "85_10INCH_BOT_DN")
	)
	(segment
		(start 104.658668 -20.09267)
		(end 104.8766 -18.858738)
		(width 0.14224)
		(layer "B.Cu")
		(net "85_10INCH_BOT_DN")
	)
	(segment
		(start 104.806242 -15.01775)
		(end 104.40035 -14.43863)
		(width 0.14224)
		(layer "B.Cu")
		(net "85_10INCH_BOT_DN")
	)
	(segment
		(start 104.40035 -14.43863)
		(end 99.379278 -13.553186)
		(width 0.14224)
		(layer "B.Cu")
		(net "85_10INCH_BOT_DN")
	)
	(segment
		(start 105.090468 -34.21126)
		(end 104.68483 -33.631378)
		(width 0.14224)
		(layer "B.Cu")
		(net "85_10INCH_BOT_DN")
	)
	(segment
		(start 97.839022 -39.793926)
		(end 98.003868 -38.859714)
		(width 0.14224)
		(layer "B.Cu")
		(net "85_10INCH_BOT_DN")
	)
	(segment
		(start 105.031794 -45.686726)
		(end 104.625902 -45.107606)
		(width 0.14224)
		(layer "B.Cu")
		(net "85_10INCH_BOT_DN")
	)
	(segment
		(start 101.645212 -48.918368)
		(end 101.23932 -48.339248)
		(width 0.14224)
		(layer "B.Cu")
		(net "85_10INCH_BOT_DN")
	)
	(segment
		(start 98.333306 -38.629082)
		(end 104.200706 -39.663624)
		(width 0.14224)
		(layer "B.Cu")
		(net "85_10INCH_BOT_DN")
	)
	(segment
		(start 99.340924 -17.375124)
		(end 99.110292 -17.04594)
		(width 0.14224)
		(layer "B.Cu")
		(net "85_10INCH_BOT_DN")
	)
	(segment
		(start 97.97542 -27.368754)
		(end 98.304858 -27.138122)
		(width 0.14224)
		(layer "B.Cu")
		(net "85_10INCH_BOT_DN")
	)
	(segment
		(start 99.47021 -8.48868)
		(end 99.799648 -8.258048)
		(width 0.14224)
		(layer "B.Cu")
		(net "85_10INCH_BOT_DN")
	)
	(segment
		(start 104.29113 -1.392682)
		(end 104.870504 -0.986536)
		(width 0.14224)
		(layer "B.Cu")
		(net "85_10INCH_BOT_DN")
	)
	(segment
		(start 105.088436 0.247396)
		(end 104.682544 0.826516)
		(width 0.14224)
		(layer "B.Cu")
		(net "85_10INCH_BOT_DN")
	)
	(segment
		(start 98.304858 -27.138122)
		(end 104.29494 -28.194254)
		(width 0.14224)
		(layer "B.Cu")
		(net "85_10INCH_BOT_DN")
	)
	(segment
		(start 99.135184 -1.735582)
		(end 99.30003 -0.80137)
		(width 0.14224)
		(layer "B.Cu")
		(net "85_10INCH_BOT_DN")
	)
	(segment
		(start 104.874314 -27.788108)
		(end 105.092246 -26.554176)
		(width 0.14224)
		(layer "B.Cu")
		(net "85_10INCH_BOT_DN")
	)
	(segment
		(start 104.872536 -35.445192)
		(end 105.090468 -34.21126)
		(width 0.14224)
		(layer "B.Cu")
		(net "85_10INCH_BOT_DN")
	)
	(segment
		(start 104.664256 -22.14245)
		(end 99.378516 -21.210524)
		(width 0.14224)
		(layer "B.Cu")
		(net "85_10INCH_BOT_DN")
	)
	(segment
		(start 104.84485 -43.09745)
		(end 105.062782 -41.863518)
		(width 0.14224)
		(layer "B.Cu")
		(net "85_10INCH_BOT_DN")
	)
	(segment
		(start 104.65689 -41.284398)
		(end 98.069654 -40.122856)
		(width 0.14224)
		(layer "B.Cu")
		(net "85_10INCH_BOT_DN")
	)
	(segment
		(start 104.008936 -16.657828)
		(end 104.58831 -16.251682)
		(width 0.14224)
		(layer "B.Cu")
		(net "85_10INCH_BOT_DN")
	)
	(segment
		(start 99.635564 3.256788)
		(end 104.328468 2.429256)
		(width 0.14224)
		(layer "B.Cu")
		(net "85_10INCH_BOT_DN")
	)
	(segment
		(start 99.378516 -21.210524)
		(end 99.147884 -20.88134)
		(width 0.14224)
		(layer "B.Cu")
		(net "85_10INCH_BOT_DN")
	)
	(segment
		(start 103.930704 -8.986266)
		(end 104.510078 -8.580374)
		(width 0.14224)
		(layer "B.Cu")
		(net "85_10INCH_BOT_DN")
	)
	(segment
		(start 98.040952 -28.631896)
		(end 97.810574 -28.302966)
		(width 0.14224)
		(layer "B.Cu")
		(net "85_10INCH_BOT_DN")
	)
	(segment
		(start 99.114864 5.925312)
		(end 99.27971 6.859524)
		(width 0.14224)
		(layer "B.Cu")
		(net "85_10INCH_BOT_DN")
	)
	(segment
		(start 99.30257 -4.630674)
		(end 99.632008 -4.400042)
		(width 0.14224)
		(layer "B.Cu")
		(net "85_10INCH_BOT_DN")
	)
	(segment
		(start 104.941878 7.930642)
		(end 104.535986 8.509762)
		(width 0.14224)
		(layer "B.Cu")
		(net "85_10INCH_BOT_DN")
	)
	(segment
		(start 98.37928 -42.465752)
		(end 104.265476 -43.503596)
		(width 0.14224)
		(layer "B.Cu")
		(net "85_10INCH_BOT_DN")
	)
	(segment
		(start 99.150932 9.747504)
		(end 99.315778 10.681716)
		(width 0.14224)
		(layer "B.Cu")
		(net "85_10INCH_BOT_DN")
	)
	(segment
		(start 99.535996 -9.752076)
		(end 99.305364 -9.422892)
		(width 0.14224)
		(layer "B.Cu")
		(net "85_10INCH_BOT_DN")
	)
	(segment
		(start 99.609148 7.090156)
		(end 104.144572 6.290564)
		(width 0.14224)
		(layer "B.Cu")
		(net "85_10INCH_BOT_DN")
	)
	(segment
		(start 97.810574 -28.302966)
		(end 97.97542 -27.368754)
		(width 0.14224)
		(layer "B.Cu")
		(net "85_10INCH_BOT_DN")
	)
	(segment
		(start 101.46665 -49.92878)
		(end 101.645212 -48.918368)
		(width 0.14224)
		(layer "B.Cu")
		(net "85_10INCH_BOT_DN")
	)
	(segment
		(start 101.898704 12.803378)
		(end 101.46665 13.235432)
		(width 0.14224)
		(layer "B.Cu")
		(net "85_10INCH_BOT_DN")
	)
	(segment
		(start 99.799648 -8.258048)
		(end 103.930704 -8.986266)
		(width 0.14224)
		(layer "B.Cu")
		(net "85_10INCH_BOT_DN")
	)
	(segment
		(start 99.110292 -17.04594)
		(end 99.275138 -16.111728)
		(width 0.14224)
		(layer "B.Cu")
		(net "85_10INCH_BOT_DN")
	)
	(segment
		(start 97.92335 -32.15132)
		(end 98.088196 -31.217108)
		(width 0.14224)
		(layer "B.Cu")
		(net "85_10INCH_BOT_DN")
	)
	(segment
		(start 97.957386 -35.986212)
		(end 98.122232 -35.052)
		(width 0.14224)
		(layer "B.Cu")
		(net "85_10INCH_BOT_DN")
	)
	(segment
		(start 104.809798 -31.60522)
		(end 105.02773 -30.371288)
		(width 0.14224)
		(layer "B.Cu")
		(net "85_10INCH_BOT_DN")
	)
	(segment
		(start 99.632008 -4.400042)
		(end 104.302052 -5.22351)
		(width 0.14224)
		(layer "B.Cu")
		(net "85_10INCH_BOT_DN")
	)
	(segment
		(start 98.153982 -32.480758)
		(end 97.92335 -32.15132)
		(width 0.14224)
		(layer "B.Cu")
		(net "85_10INCH_BOT_DN")
	)
	(segment
		(start 105.125774 4.069334)
		(end 104.720136 4.648962)
		(width 0.14224)
		(layer "B.Cu")
		(net "85_10INCH_BOT_DN")
	)
	(segment
		(start 98.417126 -46.301152)
		(end 104.234488 -47.326804)
		(width 0.14224)
		(layer "B.Cu")
		(net "85_10INCH_BOT_DN")
	)
	(segment
		(start 101.532436 -53.578252)
		(end 101.532436 -53.420772)
		(width 0.14224)
		(layer "B.Cu")
		(net "85_10INCH_BOT_DN")
	)
	(segment
		(start 99.305364 -9.422892)
		(end 99.47021 -8.48868)
		(width 0.14224)
		(layer "B.Cu")
		(net "85_10INCH_BOT_DN")
	)
	(segment
		(start 99.148646 -13.224002)
		(end 99.313492 -12.28979)
		(width 0.14224)
		(layer "B.Cu")
		(net "85_10INCH_BOT_DN")
	)
	(segment
		(start 105.099358 -3.583432)
		(end 104.69372 -3.00355)
		(width 0.14224)
		(layer "B.Cu")
		(net "85_10INCH_BOT_DN")
	)
	(segment
		(start 101.23932 -48.339248)
		(end 98.153474 -47.79518)
		(width 0.14224)
		(layer "B.Cu")
		(net "85_10INCH_BOT_DN")
	)
	(segment
		(start 98.069654 -40.122856)
		(end 97.839022 -39.793926)
		(width 0.14224)
		(layer "B.Cu")
		(net "85_10INCH_BOT_DN")
	)
	(segment
		(start 104.29494 -28.194254)
		(end 104.874314 -27.788108)
		(width 0.14224)
		(layer "B.Cu")
		(net "85_10INCH_BOT_DN")
	)
	(segment
		(start 101.46665 13.235432)
		(end 101.46665 16.952722)
		(width 0.14224)
		(layer "B.Cu")
		(net "85_10INCH_BOT_DN")
	)
	(segment
		(start 105.062782 -41.863518)
		(end 104.65689 -41.284398)
		(width 0.14224)
		(layer "B.Cu")
		(net "85_10INCH_BOT_DN")
	)
	(segment
		(start 99.371912 1.76276)
		(end 99.14128 2.091944)
		(width 0.14224)
		(layer "B.Cu")
		(net "85_10INCH_BOT_DN")
	)
	(segment
		(start 99.629468 -0.570738)
		(end 104.29113 -1.392682)
		(width 0.14224)
		(layer "B.Cu")
		(net "85_10INCH_BOT_DN")
	)
	(segment
		(start 99.27971 6.859524)
		(end 99.609148 7.090156)
		(width 0.14224)
		(layer "B.Cu")
		(net "85_10INCH_BOT_DN")
	)
	(segment
		(start 98.049842 -42.696384)
		(end 98.37928 -42.465752)
		(width 0.14224)
		(layer "B.Cu")
		(net "85_10INCH_BOT_DN")
	)
	(segment
		(start 104.720136 4.648962)
		(end 99.345496 5.596382)
		(width 0.14224)
		(layer "B.Cu")
		(net "85_10INCH_BOT_DN")
	)
	(segment
		(start 104.78008 -39.257478)
		(end 104.998012 -38.023546)
		(width 0.14224)
		(layer "B.Cu")
		(net "85_10INCH_BOT_DN")
	)
	(segment
		(start 101.532436 17.018508)
		(end 101.532436 17.175988)
		(width 0.14224)
		(layer "B.Cu")
		(net "85_10INCH_BOT_DN")
	)
	(segment
		(start 101.46665 16.952722)
		(end 101.532436 17.018508)
		(width 0.14224)
		(layer "B.Cu")
		(net "85_10INCH_BOT_DN")
	)
	(segment
		(start 104.272842 -24.361648)
		(end 104.852216 -23.955502)
		(width 0.14224)
		(layer "B.Cu")
		(net "85_10INCH_BOT_DN")
	)
	(segment
		(start 104.302052 -5.22351)
		(end 104.881426 -4.817364)
		(width 0.14224)
		(layer "B.Cu")
		(net "85_10INCH_BOT_DN")
	)
	(segment
		(start 103.87711 11.94689)
		(end 103.471218 12.52601)
		(width 0.14224)
		(layer "B.Cu")
		(net "85_10INCH_BOT_DN")
	)
	(segment
		(start 99.313492 -12.28979)
		(end 99.64293 -12.059158)
		(width 0.14224)
		(layer "B.Cu")
		(net "85_10INCH_BOT_DN")
	)
	(segment
		(start 104.328468 2.429256)
		(end 104.907842 2.835402)
		(width 0.14224)
		(layer "B.Cu")
		(net "85_10INCH_BOT_DN")
	)
	(segment
		(start 104.813862 -46.920658)
		(end 105.031794 -45.686726)
		(width 0.14224)
		(layer "B.Cu")
		(net "85_10INCH_BOT_DN")
	)
	(segment
		(start 101.46665 -53.354986)
		(end 101.46665 -49.92878)
		(width 0.14224)
		(layer "B.Cu")
		(net "85_10INCH_BOT_DN")
	)
	(segment
		(start 98.087688 -46.531784)
		(end 98.417126 -46.301152)
		(width 0.14224)
		(layer "B.Cu")
		(net "85_10INCH_BOT_DN")
	)
	(segment
		(start 104.870504 -0.986536)
		(end 105.088436 0.247396)
		(width 0.14224)
		(layer "B.Cu")
		(net "85_10INCH_BOT_DN")
	)
	(segment
		(start 104.144572 6.290564)
		(end 104.723946 6.69671)
		(width 0.14224)
		(layer "B.Cu")
		(net "85_10INCH_BOT_DN")
	)
	(segment
		(start 105.092246 -26.554176)
		(end 104.686354 -25.975056)
		(width 0.14224)
		(layer "B.Cu")
		(net "85_10INCH_BOT_DN")
	)
	(segment
		(start 104.621838 -29.792168)
		(end 98.040952 -28.631896)
		(width 0.14224)
		(layer "B.Cu")
		(net "85_10INCH_BOT_DN")
	)
	(segment
		(start 98.45167 -34.821368)
		(end 104.293162 -35.851338)
		(width 0.14224)
		(layer "B.Cu")
		(net "85_10INCH_BOT_DN")
	)
	(segment
		(start 104.625902 -45.107606)
		(end 98.115628 -43.95978)
		(width 0.14224)
		(layer "B.Cu")
		(net "85_10INCH_BOT_DN")
	)
	(segment
		(start 103.471218 12.52601)
		(end 101.898704 12.803378)
		(width 0.14224)
		(layer "B.Cu")
		(net "85_10INCH_BOT_DN")
	)
	(segment
		(start 98.105468 -24.814784)
		(end 97.874836 -24.4856)
		(width 0.14224)
		(layer "B.Cu")
		(net "85_10INCH_BOT_DN")
	)
	(segment
		(start 99.14128 2.091944)
		(end 99.306126 3.026156)
		(width 0.14224)
		(layer "B.Cu")
		(net "85_10INCH_BOT_DN")
	)
	(segment
		(start 99.64547 10.912348)
		(end 103.079804 10.306812)
		(width 0.14224)
		(layer "B.Cu")
		(net "85_10INCH_BOT_DN")
	)
	(segment
		(start 99.137724 -5.564886)
		(end 99.30257 -4.630674)
		(width 0.14224)
		(layer "B.Cu")
		(net "85_10INCH_BOT_DN")
	)
	(segment
		(start 99.365816 -2.064766)
		(end 99.135184 -1.735582)
		(width 0.14224)
		(layer "B.Cu")
		(net "85_10INCH_BOT_DN")
	)
	(segment
		(start 104.293162 -35.851338)
		(end 104.872536 -35.445192)
		(width 0.14224)
		(layer "B.Cu")
		(net "85_10INCH_BOT_DN")
	)
	(via
		(at 15.125446 -16.002)
		(size 0.6604)
		(drill 0.3302)
		(layers "F.Cu" "B.Cu")
		(net "PWR_LED_BUF_N_R")
	)
	(segment
		(start 15.125446 -16.266414)
		(end 15.400528 -16.541496)
		(width 0.11684)
		(layer "B.Cu")
		(net "PWR_LED_BUF_N_R")
	)
	(segment
		(start 15.629128 -9.43102)
		(end 15.629128 -13.857478)
		(width 0.11684)
		(layer "B.Cu")
		(net "PWR_LED_BUF_N_R")
	)
	(segment
		(start 15.548356 -16.898112)
		(end 15.548356 -18.169636)
		(width 0.11684)
		(layer "B.Cu")
		(net "PWR_LED_BUF_N_R")
	)
	(segment
		(start 15.829534 -20.447)
		(end 15.429484 -20.84705)
		(width 0.11684)
		(layer "B.Cu")
		(net "PWR_LED_BUF_N_R")
	)
	(segment
		(start 15.429484 -20.84705)
		(end 15.113 -20.84705)
		(width 0.11684)
		(layer "B.Cu")
		(net "PWR_LED_BUF_N_R")
	)
	(segment
		(start 18.770092 -6.290056)
		(end 15.629128 -9.43102)
		(width 0.11684)
		(layer "B.Cu")
		(net "PWR_LED_BUF_N_R")
	)
	(segment
		(start 15.125446 -16.002)
		(end 15.125446 -16.266414)
		(width 0.11684)
		(layer "B.Cu")
		(net "PWR_LED_BUF_N_R")
	)
	(segment
		(start 15.548356 -18.169636)
		(end 15.829534 -18.450814)
		(width 0.11684)
		(layer "B.Cu")
		(net "PWR_LED_BUF_N_R")
	)
	(segment
		(start 15.829534 -18.450814)
		(end 15.829534 -20.447)
		(width 0.11684)
		(layer "B.Cu")
		(net "PWR_LED_BUF_N_R")
	)
	(segment
		(start 14.097 -20.84705)
		(end 14.097 -21.06295)
		(width 0.11684)
		(layer "B.Cu")
		(net "PWR_LED_BUF_N_R")
	)
	(segment
		(start 14.097 -21.06295)
		(end 14.87805 -21.844)
		(width 0.11684)
		(layer "B.Cu")
		(net "PWR_LED_BUF_N_R")
	)
	(segment
		(start 15.629128 -13.857478)
		(end 15.125446 -14.36116)
		(width 0.11684)
		(layer "B.Cu")
		(net "PWR_LED_BUF_N_R")
	)
	(segment
		(start 15.125446 -14.36116)
		(end 15.125446 -16.002)
		(width 0.11684)
		(layer "B.Cu")
		(net "PWR_LED_BUF_N_R")
	)
	(segment
		(start 15.400528 -16.541496)
		(end 15.548356 -16.898112)
		(width 0.11684)
		(layer "B.Cu")
		(net "PWR_LED_BUF_N_R")
	)
	(segment
		(start 15.113 -20.84705)
		(end 14.097 -20.84705)
		(width 0.11684)
		(layer "B.Cu")
		(net "PWR_LED_BUF_N_R")
	)
	(segment
		(start 12.930632 -15.471394)
		(end 11.952986 -16.44904)
		(width 0.11684)
		(layer "F.Cu")
		(net "PWR_LED_BUF_N")
	)
	(segment
		(start 14.130528 -15.471394)
		(end 12.930632 -15.471394)
		(width 0.11684)
		(layer "F.Cu")
		(net "PWR_LED_BUF_N")
	)
	(segment
		(start 13.335508 -20.568412)
		(end 15.702534 -20.568412)
		(width 0.11684)
		(layer "F.Cu")
		(net "PWR_LED_BUF_N")
	)
	(segment
		(start 15.829534 -20.441412)
		(end 15.829534 -17.5768)
		(width 0.11684)
		(layer "F.Cu")
		(net "PWR_LED_BUF_N")
	)
	(segment
		(start 15.829534 -17.5768)
		(end 15.829534 -17.1704)
		(width 0.11684)
		(layer "F.Cu")
		(net "PWR_LED_BUF_N")
	)
	(segment
		(start 15.702534 -20.568412)
		(end 15.829534 -20.441412)
		(width 0.11684)
		(layer "F.Cu")
		(net "PWR_LED_BUF_N")
	)
	(segment
		(start 15.829534 -17.1704)
		(end 14.130528 -15.471394)
		(width 0.11684)
		(layer "F.Cu")
		(net "PWR_LED_BUF_N")
	)
	(via
		(at 15.829534 -17.5768)
		(size 0.762)
		(drill 0.381)
		(layers "F.Cu" "B.Cu")
		(net "PWR_LED_BUF_N")
	)
	(via
		(at 13.335508 -20.568412)
		(size 0.508)
		(drill 0.254)
		(layers "F.Cu" "B.Cu")
		(net "PWR_LED_BUF_N")
	)
	(segment
		(start 13.335508 -21.101558)
		(end 14.07795 -21.844)
		(width 0.11684)
		(layer "B.Cu")
		(net "PWR_LED_BUF_N")
	)
	(segment
		(start 13.335508 -20.568412)
		(end 13.335508 -21.101558)
		(width 0.11684)
		(layer "B.Cu")
		(net "PWR_LED_BUF_N")
	)
	(segment
		(start 27.559 -9.88695)
		(end 28.575 -9.88695)
		(width 0.11684)
		(layer "F.Cu")
		(net "HDD_LED_BUF_R")
	)
	(segment
		(start 27.559254 -8.329422)
		(end 27.559254 -9.886696)
		(width 0.11684)
		(layer "F.Cu")
		(net "HDD_LED_BUF_R")
	)
	(segment
		(start 27.559254 -9.886696)
		(end 27.559 -9.88695)
		(width 0.11684)
		(layer "F.Cu")
		(net "HDD_LED_BUF_R")
	)
	(segment
		(start 25.519888 -6.290056)
		(end 27.559254 -8.329422)
		(width 0.11684)
		(layer "F.Cu")
		(net "HDD_LED_BUF_R")
	)
	(segment
		(start 28.575 -9.88695)
		(end 29.591 -9.88695)
		(width 0.11684)
		(layer "F.Cu")
		(net "HDD_LED_BUF_R")
	)
	(segment
		(start 27.559 -10.68705)
		(end 27.178 -11.06805)
		(width 0.11684)
		(layer "F.Cu")
		(net "HDD_LED_BUF")
	)
	(segment
		(start 9.6901 -15.325852)
		(end 9.521952 -15.494)
		(width 0.11684)
		(layer "F.Cu")
		(net "HDD_LED_BUF")
	)
	(segment
		(start 10.251694 -18.34896)
		(end 10.653014 -18.34896)
		(width 0.11684)
		(layer "F.Cu")
		(net "HDD_LED_BUF")
	)
	(segment
		(start 9.648952 -18.47596)
		(end 10.124694 -18.47596)
		(width 0.11684)
		(layer "F.Cu")
		(net "HDD_LED_BUF")
	)
	(segment
		(start 10.124694 -18.47596)
		(end 10.251694 -18.34896)
		(width 0.11684)
		(layer "F.Cu")
		(net "HDD_LED_BUF")
	)
	(segment
		(start 13.013944 -15.076932)
		(end 12.358624 -15.076932)
		(width 0.11684)
		(layer "F.Cu")
		(net "HDD_LED_BUF")
	)
	(segment
		(start 12.109704 -15.325852)
		(end 9.6901 -15.325852)
		(width 0.11684)
		(layer "F.Cu")
		(net "HDD_LED_BUF")
	)
	(segment
		(start 9.521952 -18.34896)
		(end 9.648952 -18.47596)
		(width 0.11684)
		(layer "F.Cu")
		(net "HDD_LED_BUF")
	)
	(segment
		(start 12.358624 -15.076932)
		(end 12.109704 -15.325852)
		(width 0.11684)
		(layer "F.Cu")
		(net "HDD_LED_BUF")
	)
	(segment
		(start 13.6144 -11.2014)
		(end 13.3604 -11.4554)
		(width 0.11684)
		(layer "F.Cu")
		(net "HDD_LED_BUF")
	)
	(segment
		(start 13.3604 -11.4554)
		(end 13.3604 -14.730476)
		(width 0.11684)
		(layer "F.Cu")
		(net "HDD_LED_BUF")
	)
	(segment
		(start 27.178 -11.06805)
		(end 27.178 -11.303)
		(width 0.11684)
		(layer "F.Cu")
		(net "HDD_LED_BUF")
	)
	(segment
		(start 9.521952 -15.494)
		(end 9.521952 -18.34896)
		(width 0.11684)
		(layer "F.Cu")
		(net "HDD_LED_BUF")
	)
	(segment
		(start 13.3604 -14.730476)
		(end 13.013944 -15.076932)
		(width 0.11684)
		(layer "F.Cu")
		(net "HDD_LED_BUF")
	)
	(via
		(at 13.6144 -11.2014)
		(size 0.508)
		(drill 0.254)
		(layers "F.Cu" "B.Cu")
		(net "HDD_LED_BUF")
	)
	(via
		(at 27.178 -11.303)
		(size 0.508)
		(drill 0.254)
		(layers "F.Cu" "B.Cu")
		(net "HDD_LED_BUF")
	)
	(segment
		(start 26.6192 -11.8618)
		(end 14.2748 -11.8618)
		(width 0.08382)
		(layer "In2.Cu")
		(net "HDD_LED_BUF")
	)
	(segment
		(start 27.178 -11.303)
		(end 26.6192 -11.8618)
		(width 0.08382)
		(layer "In2.Cu")
		(net "HDD_LED_BUF")
	)
	(segment
		(start 14.2748 -11.8618)
		(end 13.6144 -11.2014)
		(width 0.08382)
		(layer "In2.Cu")
		(net "HDD_LED_BUF")
	)
	(segment
		(start 84.89315 -18.796)
		(end 84.89315 -17.78)
		(width 0.11684)
		(layer "F.Cu")
		(net "REAR_ID_RST_BTN_N")
	)
	(segment
		(start 82.55508 -17.907)
		(end 83.388454 -17.907)
		(width 0.11684)
		(layer "F.Cu")
		(net "REAR_ID_RST_BTN_N")
	)
	(segment
		(start 86.614 -15.5702)
		(end 85.395054 -15.5702)
		(width 0.11684)
		(layer "F.Cu")
		(net "REAR_ID_RST_BTN_N")
	)
	(segment
		(start 88.265 -8.2804)
		(end 86.97468 -6.99008)
		(width 0.11684)
		(layer "F.Cu")
		(net "REAR_ID_RST_BTN_N")
	)
	(segment
		(start 84.89315 -17.78)
		(end 84.89315 -16.764)
		(width 0.11684)
		(layer "F.Cu")
		(net "REAR_ID_RST_BTN_N")
	)
	(segment
		(start 86.614 -15.5702)
		(end 88.265 -13.9192)
		(width 0.11684)
		(layer "F.Cu")
		(net "REAR_ID_RST_BTN_N")
	)
	(segment
		(start 85.395054 -15.5702)
		(end 84.89315 -16.072104)
		(width 0.11684)
		(layer "F.Cu")
		(net "REAR_ID_RST_BTN_N")
	)
	(segment
		(start 88.265 -13.9192)
		(end 88.265 -8.2804)
		(width 0.11684)
		(layer "F.Cu")
		(net "REAR_ID_RST_BTN_N")
	)
	(segment
		(start 86.97468 -6.99008)
		(end 84.250022 -6.99008)
		(width 0.11684)
		(layer "F.Cu")
		(net "REAR_ID_RST_BTN_N")
	)
	(segment
		(start 84.277454 -18.796)
		(end 84.89315 -18.796)
		(width 0.11684)
		(layer "F.Cu")
		(net "REAR_ID_RST_BTN_N")
	)
	(segment
		(start 84.89315 -16.072104)
		(end 84.89315 -16.764)
		(width 0.11684)
		(layer "F.Cu")
		(net "REAR_ID_RST_BTN_N")
	)
	(segment
		(start 83.388454 -17.907)
		(end 84.277454 -18.796)
		(width 0.11684)
		(layer "F.Cu")
		(net "REAR_ID_RST_BTN_N")
	)
	(via
		(at 86.614 -15.5702)
		(size 0.762)
		(drill 0.381)
		(layers "F.Cu" "B.Cu")
		(net "REAR_ID_RST_BTN_N")
	)
	(segment
		(start 15.494 -84.09305)
		(end 15.494 -84.149946)
		(width 0.11684)
		(layer "F.Cu")
		(net "PU_FPGA_NSTATUS")
	)
	(segment
		(start 16.4592 -85.115146)
		(end 16.4592 -85.979)
		(width 0.11684)
		(layer "F.Cu")
		(net "PU_FPGA_NSTATUS")
	)
	(segment
		(start 17.859502 -87.379302)
		(end 17.859502 -87.587074)
		(width 0.11684)
		(layer "F.Cu")
		(net "PU_FPGA_NSTATUS")
	)
	(segment
		(start 15.494 -84.149946)
		(end 16.4592 -85.115146)
		(width 0.11684)
		(layer "F.Cu")
		(net "PU_FPGA_NSTATUS")
	)
	(segment
		(start 16.4592 -85.979)
		(end 17.859502 -87.379302)
		(width 0.11684)
		(layer "F.Cu")
		(net "PU_FPGA_NSTATUS")
	)
	(segment
		(start 29.682948 -90.555572)
		(end 29.682948 -89.449402)
		(width 0.11684)
		(layer "F.Cu")
		(net "PU_FPGA_NCONFIG")
	)
	(segment
		(start 30.179518 -88.999568)
		(end 30.15615 -88.9762)
		(width 0.11684)
		(layer "F.Cu")
		(net "PU_FPGA_NCONFIG")
	)
	(segment
		(start 30.179518 -89.943432)
		(end 30.179518 -88.999568)
		(width 0.11684)
		(layer "F.Cu")
		(net "PU_FPGA_NCONFIG")
	)
	(segment
		(start 19.864324 -96.782382)
		(end 20.259548 -96.387158)
		(width 0.11684)
		(layer "F.Cu")
		(net "PU_FPGA_NCONFIG")
	)
	(segment
		(start 29.35732 -90.8812)
		(end 29.682948 -90.555572)
		(width 0.11684)
		(layer "F.Cu")
		(net "PU_FPGA_NCONFIG")
	)
	(segment
		(start 30.1752 -89.94775)
		(end 30.179518 -89.943432)
		(width 0.11684)
		(layer "F.Cu")
		(net "PU_FPGA_NCONFIG")
	)
	(segment
		(start 28.27782 -90.8812)
		(end 29.35732 -90.8812)
		(width 0.11684)
		(layer "F.Cu")
		(net "PU_FPGA_NCONFIG")
	)
	(segment
		(start 29.682948 -89.449402)
		(end 30.15615 -88.9762)
		(width 0.11684)
		(layer "F.Cu")
		(net "PU_FPGA_NCONFIG")
	)
	(via
		(at 28.27782 -90.8812)
		(size 0.508)
		(drill 0.254)
		(layers "F.Cu" "B.Cu")
		(net "PU_FPGA_NCONFIG")
	)
	(via
		(at 19.864324 -96.782382)
		(size 0.4572)
		(drill 0.254)
		(layers "F.Cu" "B.Cu")
		(net "PU_FPGA_NCONFIG")
	)
	(segment
		(start 20.247864 -97.165922)
		(end 19.864324 -96.782382)
		(width 0.10668)
		(layer "In4.Cu")
		(net "PU_FPGA_NCONFIG")
	)
	(segment
		(start 24.9428 -93.55074)
		(end 24.9428 -96.26092)
		(width 0.10668)
		(layer "In4.Cu")
		(net "PU_FPGA_NCONFIG")
	)
	(segment
		(start 23.544784 -96.3676)
		(end 23.438104 -96.47428)
		(width 0.10668)
		(layer "In4.Cu")
		(net "PU_FPGA_NCONFIG")
	)
	(segment
		(start 24.9428 -96.26092)
		(end 24.83612 -96.3676)
		(width 0.10668)
		(layer "In4.Cu")
		(net "PU_FPGA_NCONFIG")
	)
	(segment
		(start 28.27782 -90.8812)
		(end 27.61234 -90.8812)
		(width 0.10668)
		(layer "In4.Cu")
		(net "PU_FPGA_NCONFIG")
	)
	(segment
		(start 23.213568 -97.165922)
		(end 20.247864 -97.165922)
		(width 0.10668)
		(layer "In4.Cu")
		(net "PU_FPGA_NCONFIG")
	)
	(segment
		(start 23.438104 -96.47428)
		(end 23.438104 -96.941386)
		(width 0.10668)
		(layer "In4.Cu")
		(net "PU_FPGA_NCONFIG")
	)
	(segment
		(start 24.83612 -96.3676)
		(end 23.544784 -96.3676)
		(width 0.10668)
		(layer "In4.Cu")
		(net "PU_FPGA_NCONFIG")
	)
	(segment
		(start 27.61234 -90.8812)
		(end 24.9428 -93.55074)
		(width 0.10668)
		(layer "In4.Cu")
		(net "PU_FPGA_NCONFIG")
	)
	(segment
		(start 23.438104 -96.941386)
		(end 23.213568 -97.165922)
		(width 0.10668)
		(layer "In4.Cu")
		(net "PU_FPGA_NCONFIG")
	)
	(segment
		(start 17.464278 -88.791796)
		(end 17.859502 -89.18702)
		(width 0.11684)
		(layer "F.Cu")
		(net "PU_FPGA_CONFIG_DONE")
	)
	(via
		(at 16.6116 -87.4268)
		(size 0.6604)
		(drill 0.3302)
		(layers "F.Cu" "B.Cu")
		(net "PU_FPGA_CONFIG_DONE")
	)
	(via
		(at 17.464278 -88.791796)
		(size 0.4572)
		(drill 0.254)
		(layers "F.Cu" "B.Cu")
		(net "PU_FPGA_CONFIG_DONE")
	)
	(segment
		(start 17.464278 -88.541606)
		(end 16.6116 -87.688928)
		(width 0.11684)
		(layer "B.Cu")
		(net "PU_FPGA_CONFIG_DONE")
	)
	(segment
		(start 16.6116 -87.688928)
		(end 16.6116 -87.4268)
		(width 0.11684)
		(layer "B.Cu")
		(net "PU_FPGA_CONFIG_DONE")
	)
	(segment
		(start 15.7734 -85.115654)
		(end 15.7734 -86.2838)
		(width 0.11684)
		(layer "B.Cu")
		(net "PU_FPGA_CONFIG_DONE")
	)
	(segment
		(start 14.2494 -84.09305)
		(end 14.81455 -84.6582)
		(width 0.11684)
		(layer "B.Cu")
		(net "PU_FPGA_CONFIG_DONE")
	)
	(segment
		(start 16.6116 -87.122)
		(end 16.6116 -87.4268)
		(width 0.11684)
		(layer "B.Cu")
		(net "PU_FPGA_CONFIG_DONE")
	)
	(segment
		(start 15.315946 -84.6582)
		(end 15.7734 -85.115654)
		(width 0.11684)
		(layer "B.Cu")
		(net "PU_FPGA_CONFIG_DONE")
	)
	(segment
		(start 17.464278 -88.791796)
		(end 17.464278 -88.541606)
		(width 0.11684)
		(layer "B.Cu")
		(net "PU_FPGA_CONFIG_DONE")
	)
	(segment
		(start 14.81455 -84.6582)
		(end 15.315946 -84.6582)
		(width 0.11684)
		(layer "B.Cu")
		(net "PU_FPGA_CONFIG_DONE")
	)
	(segment
		(start 15.7734 -86.2838)
		(end 16.6116 -87.122)
		(width 0.11684)
		(layer "B.Cu")
		(net "PU_FPGA_CONFIG_DONE")
	)
	(segment
		(start 19.324066 -78.75905)
		(end 19.751294 -78.331822)
		(width 0.11684)
		(layer "B.Cu")
		(net "PU_25M_FPGA_CLK_EN")
	)
	(segment
		(start 18.2626 -78.75905)
		(end 19.324066 -78.75905)
		(width 0.11684)
		(layer "B.Cu")
		(net "PU_25M_FPGA_CLK_EN")
	)
	(via
		(at 22.5298 -80.8482)
		(size 0.6604)
		(drill 0.3302)
		(layers "F.Cu" "B.Cu")
		(net "CLK_25M_OSC_FPGA_R")
	)
	(segment
		(start 22.7838 -78.867)
		(end 22.7838 -77.614272)
		(width 0.11684)
		(layer "B.Cu")
		(net "CLK_25M_OSC_FPGA_R")
	)
	(segment
		(start 22.7838 -77.614272)
		(end 21.851366 -76.681838)
		(width 0.11684)
		(layer "B.Cu")
		(net "CLK_25M_OSC_FPGA_R")
	)
	(segment
		(start 22.5298 -79.121)
		(end 22.7838 -78.867)
		(width 0.11684)
		(layer "B.Cu")
		(net "CLK_25M_OSC_FPGA_R")
	)
	(segment
		(start 22.5298 -80.8482)
		(end 22.5298 -79.121)
		(width 0.11684)
		(layer "B.Cu")
		(net "CLK_25M_OSC_FPGA_R")
	)
	(segment
		(start 22.5298 -83.29295)
		(end 22.5298 -80.8482)
		(width 0.11684)
		(layer "B.Cu")
		(net "CLK_25M_OSC_FPGA_R")
	)
	(segment
		(start 21.859494 -89.18702)
		(end 22.254718 -88.791796)
		(width 0.11684)
		(layer "F.Cu")
		(net "CLK_25M_OSC_FPGA")
	)
	(via
		(at 22.5298 -85.629242)
		(size 0.6604)
		(drill 0.3302)
		(layers "F.Cu" "B.Cu")
		(net "CLK_25M_OSC_FPGA")
	)
	(via
		(at 22.254718 -88.791796)
		(size 0.4572)
		(drill 0.254)
		(layers "F.Cu" "B.Cu")
		(net "CLK_25M_OSC_FPGA")
	)
	(segment
		(start 22.5298 -86.703408)
		(end 22.254718 -86.97849)
		(width 0.11684)
		(layer "B.Cu")
		(net "CLK_25M_OSC_FPGA")
	)
	(segment
		(start 22.5298 -85.629242)
		(end 22.5298 -86.703408)
		(width 0.11684)
		(layer "B.Cu")
		(net "CLK_25M_OSC_FPGA")
	)
	(segment
		(start 22.254718 -86.97849)
		(end 22.254718 -88.791796)
		(width 0.11684)
		(layer "B.Cu")
		(net "CLK_25M_OSC_FPGA")
	)
	(segment
		(start 22.5298 -84.09305)
		(end 22.5298 -85.629242)
		(width 0.11684)
		(layer "B.Cu")
		(net "CLK_25M_OSC_FPGA")
	)
	(segment
		(start 62.95771 -35.494976)
		(end 62.95771 -35.728402)
		(width 0.14224)
		(layer "F.Cu")
		(net "USB_HOST_BMC_B_R_DP")
	)
	(segment
		(start 62.399164 -37.077142)
		(end 62.253368 -37.428932)
		(width 0.14224)
		(layer "F.Cu")
		(net "USB_HOST_BMC_B_R_DP")
	)
	(segment
		(start 62.289182 -36.811458)
		(end 62.399164 -37.077142)
		(width 0.14224)
		(layer "F.Cu")
		(net "USB_HOST_BMC_B_R_DP")
	)
	(segment
		(start 61.21527 -38.466776)
		(end 61.033152 -38.648894)
		(width 0.14224)
		(layer "F.Cu")
		(net "USB_HOST_BMC_B_R_DP")
	)
	(segment
		(start 62.700662 -36.349432)
		(end 62.434978 -36.459414)
		(width 0.14224)
		(layer "F.Cu")
		(net "USB_HOST_BMC_B_R_DP")
	)
	(segment
		(start 62.53607 -35.270948)
		(end 62.733682 -35.270948)
		(width 0.14224)
		(layer "F.Cu")
		(net "USB_HOST_BMC_B_R_DP")
	)
	(segment
		(start 61.21527 -38.179502)
		(end 61.21527 -38.466776)
		(width 0.14224)
		(layer "F.Cu")
		(net "USB_HOST_BMC_B_R_DP")
	)
	(segment
		(start 62.95771 -35.728402)
		(end 62.700662 -36.349432)
		(width 0.14224)
		(layer "F.Cu")
		(net "USB_HOST_BMC_B_R_DP")
	)
	(segment
		(start 62.253368 -37.428932)
		(end 61.790326 -37.891974)
		(width 0.14224)
		(layer "F.Cu")
		(net "USB_HOST_BMC_B_R_DP")
	)
	(segment
		(start 61.033152 -38.649148)
		(end 60.927996 -38.754304)
		(width 0.14224)
		(layer "F.Cu")
		(net "USB_HOST_BMC_B_R_DP")
	)
	(segment
		(start 61.033152 -38.648894)
		(end 61.033152 -38.649148)
		(width 0.14224)
		(layer "F.Cu")
		(net "USB_HOST_BMC_B_R_DP")
	)
	(segment
		(start 61.502798 -37.891974)
		(end 61.21527 -38.179502)
		(width 0.14224)
		(layer "F.Cu")
		(net "USB_HOST_BMC_B_R_DP")
	)
	(segment
		(start 62.733682 -35.270948)
		(end 62.95771 -35.494976)
		(width 0.14224)
		(layer "F.Cu")
		(net "USB_HOST_BMC_B_R_DP")
	)
	(segment
		(start 60.927996 -38.754304)
		(end 60.927996 -39.33825)
		(width 0.14224)
		(layer "F.Cu")
		(net "USB_HOST_BMC_B_R_DP")
	)
	(segment
		(start 62.434978 -36.459414)
		(end 62.289182 -36.811458)
		(width 0.14224)
		(layer "F.Cu")
		(net "USB_HOST_BMC_B_R_DP")
	)
	(segment
		(start 61.790326 -37.891974)
		(end 61.502798 -37.891974)
		(width 0.14224)
		(layer "F.Cu")
		(net "USB_HOST_BMC_B_R_DP")
	)
	(segment
		(start 60.927996 -39.33825)
		(end 60.894976 -39.37127)
		(width 0.14224)
		(layer "F.Cu")
		(net "USB_HOST_BMC_B_R_DP")
	)
	(segment
		(start 61.09843 -39.967916)
		(end 60.894976 -40.17137)
		(width 0.13716)
		(layer "F.Cu")
		(net "USB_HOST_BMC_B_R_DN")
	)
	(segment
		(start 63.32601 -35.801808)
		(end 62.565788 -37.63772)
		(width 0.14224)
		(layer "F.Cu")
		(net "USB_HOST_BMC_B_R_DN")
	)
	(segment
		(start 63.32601 -35.498786)
		(end 63.32601 -35.801808)
		(width 0.14224)
		(layer "F.Cu")
		(net "USB_HOST_BMC_B_R_DN")
	)
	(segment
		(start 62.565788 -37.63772)
		(end 61.293756 -38.909498)
		(width 0.14224)
		(layer "F.Cu")
		(net "USB_HOST_BMC_B_R_DN")
	)
	(segment
		(start 61.293756 -38.909498)
		(end 61.293756 -39.496238)
		(width 0.13716)
		(layer "F.Cu")
		(net "USB_HOST_BMC_B_R_DN")
	)
	(segment
		(start 63.553848 -35.270948)
		(end 63.32601 -35.498786)
		(width 0.14224)
		(layer "F.Cu")
		(net "USB_HOST_BMC_B_R_DN")
	)
	(segment
		(start 61.293756 -39.496238)
		(end 61.09843 -39.967916)
		(width 0.13716)
		(layer "F.Cu")
		(net "USB_HOST_BMC_B_R_DN")
	)
	(segment
		(start 63.4238 -30.754574)
		(end 62.860936 -33.584388)
		(width 0.14224)
		(layer "F.Cu")
		(net "USB_HOST_BMC_B_DP")
	)
	(segment
		(start 62.868302 -27.131518)
		(end 62.868302 -28.048966)
		(width 0.14224)
		(layer "F.Cu")
		(net "USB_HOST_BMC_B_DP")
	)
	(segment
		(start 26.22931 -114.735356)
		(end 24.986742 -113.492788)
		(width 0.14224)
		(layer "F.Cu")
		(net "USB_HOST_BMC_B_DP")
	)
	(segment
		(start 62.860936 -33.584388)
		(end 62.860936 -34.145982)
		(width 0.14224)
		(layer "F.Cu")
		(net "USB_HOST_BMC_B_DP")
	)
	(segment
		(start 63.4238 -29.390086)
		(end 63.4238 -30.754574)
		(width 0.14224)
		(layer "F.Cu")
		(net "USB_HOST_BMC_B_DP")
	)
	(segment
		(start 24.986742 -113.40592)
		(end 25.23998 -113.152682)
		(width 0.14224)
		(layer "F.Cu")
		(net "USB_HOST_BMC_B_DP")
	)
	(segment
		(start 62.860936 -34.145982)
		(end 62.53607 -34.470848)
		(width 0.14224)
		(layer "F.Cu")
		(net "USB_HOST_BMC_B_DP")
	)
	(segment
		(start 26.345134 -118.25986)
		(end 26.345134 -117.531388)
		(width 0.14224)
		(layer "F.Cu")
		(net "USB_HOST_BMC_B_DP")
	)
	(segment
		(start 26.345134 -117.531388)
		(end 26.22931 -117.415564)
		(width 0.14224)
		(layer "F.Cu")
		(net "USB_HOST_BMC_B_DP")
	)
	(segment
		(start 62.607952 -26.871168)
		(end 62.868302 -27.131518)
		(width 0.14224)
		(layer "F.Cu")
		(net "USB_HOST_BMC_B_DP")
	)
	(segment
		(start 24.986742 -113.492788)
		(end 24.986742 -113.40592)
		(width 0.14224)
		(layer "F.Cu")
		(net "USB_HOST_BMC_B_DP")
	)
	(segment
		(start 62.868302 -28.048966)
		(end 63.4238 -29.390086)
		(width 0.14224)
		(layer "F.Cu")
		(net "USB_HOST_BMC_B_DP")
	)
	(segment
		(start 26.22931 -117.415564)
		(end 26.22931 -114.735356)
		(width 0.14224)
		(layer "F.Cu")
		(net "USB_HOST_BMC_B_DP")
	)
	(via
		(at 25.23998 -113.152682)
		(size 0.508)
		(drill 0.254)
		(layers "F.Cu" "B.Cu")
		(net "USB_HOST_BMC_B_DP")
	)
	(via
		(at 62.607952 -26.871168)
		(size 0.508)
		(drill 0.254)
		(layers "F.Cu" "B.Cu")
		(net "USB_HOST_BMC_B_DP")
	)
	(segment
		(start 5.26288 -80.760062)
		(end 5.26288 -85.08746)
		(width 0.1143)
		(layer "In9.Cu")
		(net "USB_HOST_BMC_B_DP")
	)
	(segment
		(start 2.84988 -93.5355)
		(end 2.84988 -93.983302)
		(width 0.1143)
		(layer "In9.Cu")
		(net "USB_HOST_BMC_B_DP")
	)
	(segment
		(start 56.579516 -15.275306)
		(end 56.3372 -15.03299)
		(width 0.1143)
		(layer "In9.Cu")
		(net "USB_HOST_BMC_B_DP")
	)
	(segment
		(start 4.152392 -109.080046)
		(end 10.454894 -111.69015)
		(width 0.1143)
		(layer "In9.Cu")
		(net "USB_HOST_BMC_B_DP")
	)
	(segment
		(start 7.64921 -27.75077)
		(end 7.343648 -27.75077)
		(width 0.1143)
		(layer "In9.Cu")
		(net "USB_HOST_BMC_B_DP")
	)
	(segment
		(start 24.96312 -112.875822)
		(end 25.23998 -113.152682)
		(width 0.1143)
		(layer "In9.Cu")
		(net "USB_HOST_BMC_B_DP")
	)
	(segment
		(start 54.99862 -13.999972)
		(end 54.99862 -13.69441)
		(width 0.1143)
		(layer "In9.Cu")
		(net "USB_HOST_BMC_B_DP")
	)
	(segment
		(start 2.84988 -89.0778)
		(end 2.84988 -92.7989)
		(width 0.1143)
		(layer "In9.Cu")
		(net "USB_HOST_BMC_B_DP")
	)
	(segment
		(start 3.05308 -93.0021)
		(end 3.05308 -93.3323)
		(width 0.1143)
		(layer "In9.Cu")
		(net "USB_HOST_BMC_B_DP")
	)
	(segment
		(start 3.06578 -94.199202)
		(end 3.06578 -94.542102)
		(width 0.1143)
		(layer "In9.Cu")
		(net "USB_HOST_BMC_B_DP")
	)
	(segment
		(start 7.891526 -27.508454)
		(end 7.64921 -27.75077)
		(width 0.1143)
		(layer "In9.Cu")
		(net "USB_HOST_BMC_B_DP")
	)
	(segment
		(start 55.789068 -14.484858)
		(end 55.546752 -14.242542)
		(width 0.1143)
		(layer "In9.Cu")
		(net "USB_HOST_BMC_B_DP")
	)
	(segment
		(start 2.84988 -93.983302)
		(end 3.06578 -94.199202)
		(width 0.1143)
		(layer "In9.Cu")
		(net "USB_HOST_BMC_B_DP")
	)
	(segment
		(start 62.422532 -24.059388)
		(end 62.166754 -23.95347)
		(width 0.1143)
		(layer "In9.Cu")
		(net "USB_HOST_BMC_B_DP")
	)
	(segment
		(start 11.63447 -9.799574)
		(end 11.079226 -10.354818)
		(width 0.1143)
		(layer "In9.Cu")
		(net "USB_HOST_BMC_B_DP")
	)
	(segment
		(start 55.789068 -14.79042)
		(end 55.789068 -14.484858)
		(width 0.1143)
		(layer "In9.Cu")
		(net "USB_HOST_BMC_B_DP")
	)
	(segment
		(start 57.127648 -15.823438)
		(end 56.822086 -15.823438)
		(width 0.1143)
		(layer "In9.Cu")
		(net "USB_HOST_BMC_B_DP")
	)
	(segment
		(start 10.454894 -111.69015)
		(end 18.826988 -111.69015)
		(width 0.1143)
		(layer "In9.Cu")
		(net "USB_HOST_BMC_B_DP")
	)
	(segment
		(start 18.826988 -111.69015)
		(end 19.204178 -111.53394)
		(width 0.1143)
		(layer "In9.Cu")
		(net "USB_HOST_BMC_B_DP")
	)
	(segment
		(start 2.84988 -92.7989)
		(end 3.05308 -93.0021)
		(width 0.1143)
		(layer "In9.Cu")
		(net "USB_HOST_BMC_B_DP")
	)
	(segment
		(start 11.079226 -10.354818)
		(end 10.6934 -11.28649)
		(width 0.1143)
		(layer "In9.Cu")
		(net "USB_HOST_BMC_B_DP")
	)
	(segment
		(start 62.884812 -26.594308)
		(end 62.884812 -25.175718)
		(width 0.1143)
		(layer "In9.Cu")
		(net "USB_HOST_BMC_B_DP")
	)
	(segment
		(start 3.008122 -32.086296)
		(end 3.008122 -78.505304)
		(width 0.1143)
		(layer "In9.Cu")
		(net "USB_HOST_BMC_B_DP")
	)
	(segment
		(start 3.06578 -94.542102)
		(end 2.84988 -94.758002)
		(width 0.1143)
		(layer "In9.Cu")
		(net "USB_HOST_BMC_B_DP")
	)
	(segment
		(start 62.141354 -23.380954)
		(end 61.77153 -22.487382)
		(width 0.1143)
		(layer "In9.Cu")
		(net "USB_HOST_BMC_B_DP")
	)
	(segment
		(start 50.575718 -9.271508)
		(end 47.830994 -8.725662)
		(width 0.1143)
		(layer "In9.Cu")
		(net "USB_HOST_BMC_B_DP")
	)
	(segment
		(start 24.480266 -111.72952)
		(end 24.96312 -112.212374)
		(width 0.1143)
		(layer "In9.Cu")
		(net "USB_HOST_BMC_B_DP")
	)
	(segment
		(start 60.995814 -21.711666)
		(end 60.690252 -21.711666)
		(width 0.1143)
		(layer "In9.Cu")
		(net "USB_HOST_BMC_B_DP")
	)
	(segment
		(start 4.785614 -86.239604)
		(end 3.488182 -87.537036)
		(width 0.1143)
		(layer "In9.Cu")
		(net "USB_HOST_BMC_B_DP")
	)
	(segment
		(start 7.343648 -27.75077)
		(end 3.008122 -32.086296)
		(width 0.1143)
		(layer "In9.Cu")
		(net "USB_HOST_BMC_B_DP")
	)
	(segment
		(start 56.822086 -15.823438)
		(end 56.579516 -15.580868)
		(width 0.1143)
		(layer "In9.Cu")
		(net "USB_HOST_BMC_B_DP")
	)
	(segment
		(start 10.6934 -23.33498)
		(end 9.939528 -25.15489)
		(width 0.1143)
		(layer "In9.Cu")
		(net "USB_HOST_BMC_B_DP")
	)
	(segment
		(start 62.607952 -26.871168)
		(end 62.884812 -26.594308)
		(width 0.1143)
		(layer "In9.Cu")
		(net "USB_HOST_BMC_B_DP")
	)
	(segment
		(start 3.008122 -78.505304)
		(end 5.26288 -80.760062)
		(width 0.1143)
		(layer "In9.Cu")
		(net "USB_HOST_BMC_B_DP")
	)
	(segment
		(start 22.095206 -111.53394)
		(end 22.567392 -111.72952)
		(width 0.1143)
		(layer "In9.Cu")
		(net "USB_HOST_BMC_B_DP")
	)
	(segment
		(start 60.447682 -21.163534)
		(end 58.80227 -19.518122)
		(width 0.1143)
		(layer "In9.Cu")
		(net "USB_HOST_BMC_B_DP")
	)
	(segment
		(start 3.488182 -87.537036)
		(end 2.84988 -89.0778)
		(width 0.1143)
		(layer "In9.Cu")
		(net "USB_HOST_BMC_B_DP")
	)
	(segment
		(start 47.830994 -8.725662)
		(end 14.227302 -8.725662)
		(width 0.1143)
		(layer "In9.Cu")
		(net "USB_HOST_BMC_B_DP")
	)
	(segment
		(start 61.77153 -22.487382)
		(end 60.995814 -21.711666)
		(width 0.1143)
		(layer "In9.Cu")
		(net "USB_HOST_BMC_B_DP")
	)
	(segment
		(start 24.96312 -112.212374)
		(end 24.96312 -112.875822)
		(width 0.1143)
		(layer "In9.Cu")
		(net "USB_HOST_BMC_B_DP")
	)
	(segment
		(start 58.80227 -19.518122)
		(end 57.373774 -16.069564)
		(width 0.1143)
		(layer "In9.Cu")
		(net "USB_HOST_BMC_B_DP")
	)
	(segment
		(start 10.6934 -11.28649)
		(end 10.6934 -23.33498)
		(width 0.1143)
		(layer "In9.Cu")
		(net "USB_HOST_BMC_B_DP")
	)
	(segment
		(start 56.3372 -15.03299)
		(end 56.031638 -15.03299)
		(width 0.1143)
		(layer "In9.Cu")
		(net "USB_HOST_BMC_B_DP")
	)
	(segment
		(start 54.99862 -13.69441)
		(end 50.575718 -9.271508)
		(width 0.1143)
		(layer "In9.Cu")
		(net "USB_HOST_BMC_B_DP")
	)
	(segment
		(start 56.579516 -15.580868)
		(end 56.579516 -15.275306)
		(width 0.1143)
		(layer "In9.Cu")
		(net "USB_HOST_BMC_B_DP")
	)
	(segment
		(start 7.891526 -27.202892)
		(end 7.891526 -27.508454)
		(width 0.1143)
		(layer "In9.Cu")
		(net "USB_HOST_BMC_B_DP")
	)
	(segment
		(start 62.884812 -25.175718)
		(end 62.422532 -24.059388)
		(width 0.1143)
		(layer "In9.Cu")
		(net "USB_HOST_BMC_B_DP")
	)
	(segment
		(start 3.214116 -108.14177)
		(end 4.152392 -109.080046)
		(width 0.1143)
		(layer "In9.Cu")
		(net "USB_HOST_BMC_B_DP")
	)
	(segment
		(start 2.84988 -107.262422)
		(end 3.214116 -108.14177)
		(width 0.1143)
		(layer "In9.Cu")
		(net "USB_HOST_BMC_B_DP")
	)
	(segment
		(start 56.031638 -15.03299)
		(end 55.789068 -14.79042)
		(width 0.1143)
		(layer "In9.Cu")
		(net "USB_HOST_BMC_B_DP")
	)
	(segment
		(start 55.546752 -14.242542)
		(end 55.24119 -14.242542)
		(width 0.1143)
		(layer "In9.Cu")
		(net "USB_HOST_BMC_B_DP")
	)
	(segment
		(start 55.24119 -14.242542)
		(end 54.99862 -13.999972)
		(width 0.1143)
		(layer "In9.Cu")
		(net "USB_HOST_BMC_B_DP")
	)
	(segment
		(start 19.204178 -111.53394)
		(end 22.095206 -111.53394)
		(width 0.1143)
		(layer "In9.Cu")
		(net "USB_HOST_BMC_B_DP")
	)
	(segment
		(start 57.373774 -16.069564)
		(end 57.127648 -15.823438)
		(width 0.1143)
		(layer "In9.Cu")
		(net "USB_HOST_BMC_B_DP")
	)
	(segment
		(start 62.03569 -23.636478)
		(end 62.141354 -23.380954)
		(width 0.1143)
		(layer "In9.Cu")
		(net "USB_HOST_BMC_B_DP")
	)
	(segment
		(start 60.690252 -21.711666)
		(end 60.447682 -21.469096)
		(width 0.1143)
		(layer "In9.Cu")
		(net "USB_HOST_BMC_B_DP")
	)
	(segment
		(start 2.84988 -94.758002)
		(end 2.84988 -107.262422)
		(width 0.1143)
		(layer "In9.Cu")
		(net "USB_HOST_BMC_B_DP")
	)
	(segment
		(start 14.227302 -8.725662)
		(end 11.63447 -9.799574)
		(width 0.1143)
		(layer "In9.Cu")
		(net "USB_HOST_BMC_B_DP")
	)
	(segment
		(start 5.26288 -85.08746)
		(end 4.785614 -86.239604)
		(width 0.1143)
		(layer "In9.Cu")
		(net "USB_HOST_BMC_B_DP")
	)
	(segment
		(start 3.05308 -93.3323)
		(end 2.84988 -93.5355)
		(width 0.1143)
		(layer "In9.Cu")
		(net "USB_HOST_BMC_B_DP")
	)
	(segment
		(start 22.567392 -111.72952)
		(end 24.480266 -111.72952)
		(width 0.1143)
		(layer "In9.Cu")
		(net "USB_HOST_BMC_B_DP")
	)
	(segment
		(start 60.447682 -21.469096)
		(end 60.447682 -21.163534)
		(width 0.1143)
		(layer "In9.Cu")
		(net "USB_HOST_BMC_B_DP")
	)
	(segment
		(start 9.939528 -25.15489)
		(end 7.891526 -27.202892)
		(width 0.1143)
		(layer "In9.Cu")
		(net "USB_HOST_BMC_B_DP")
	)
	(segment
		(start 62.166754 -23.95347)
		(end 62.03569 -23.636478)
		(width 0.1143)
		(layer "In9.Cu")
		(net "USB_HOST_BMC_B_DP")
	)
	(segment
		(start 63.7921 -29.31668)
		(end 63.7921 -30.790896)
		(width 0.14224)
		(layer "F.Cu")
		(net "USB_HOST_BMC_B_DN")
	)
	(segment
		(start 24.618442 -113.645442)
		(end 25.86101 -114.88801)
		(width 0.14224)
		(layer "F.Cu")
		(net "USB_HOST_BMC_B_DN")
	)
	(segment
		(start 63.236602 -27.97556)
		(end 63.7921 -29.31668)
		(width 0.14224)
		(layer "F.Cu")
		(net "USB_HOST_BMC_B_DN")
	)
	(segment
		(start 24.618442 -113.420144)
		(end 24.618442 -113.645442)
		(width 0.14224)
		(layer "F.Cu")
		(net "USB_HOST_BMC_B_DN")
	)
	(segment
		(start 24.35098 -113.152682)
		(end 24.618442 -113.420144)
		(width 0.14224)
		(layer "F.Cu")
		(net "USB_HOST_BMC_B_DN")
	)
	(segment
		(start 25.744932 -117.536722)
		(end 25.744932 -118.25986)
		(width 0.14224)
		(layer "F.Cu")
		(net "USB_HOST_BMC_B_DN")
	)
	(segment
		(start 63.7921 -30.790896)
		(end 63.229236 -33.62071)
		(width 0.14224)
		(layer "F.Cu")
		(net "USB_HOST_BMC_B_DN")
	)
	(segment
		(start 63.229236 -34.146236)
		(end 63.553848 -34.470848)
		(width 0.14224)
		(layer "F.Cu")
		(net "USB_HOST_BMC_B_DN")
	)
	(segment
		(start 63.236602 -27.131518)
		(end 63.236602 -27.97556)
		(width 0.14224)
		(layer "F.Cu")
		(net "USB_HOST_BMC_B_DN")
	)
	(segment
		(start 25.86101 -114.88801)
		(end 25.86101 -117.420644)
		(width 0.14224)
		(layer "F.Cu")
		(net "USB_HOST_BMC_B_DN")
	)
	(segment
		(start 63.229236 -33.62071)
		(end 63.229236 -34.146236)
		(width 0.14224)
		(layer "F.Cu")
		(net "USB_HOST_BMC_B_DN")
	)
	(segment
		(start 63.496952 -26.871168)
		(end 63.236602 -27.131518)
		(width 0.14224)
		(layer "F.Cu")
		(net "USB_HOST_BMC_B_DN")
	)
	(segment
		(start 25.86101 -117.420644)
		(end 25.744932 -117.536722)
		(width 0.14224)
		(layer "F.Cu")
		(net "USB_HOST_BMC_B_DN")
	)
	(via
		(at 24.35098 -113.152682)
		(size 0.508)
		(drill 0.254)
		(layers "F.Cu" "B.Cu")
		(net "USB_HOST_BMC_B_DN")
	)
	(via
		(at 63.496952 -26.871168)
		(size 0.508)
		(drill 0.254)
		(layers "F.Cu" "B.Cu")
		(net "USB_HOST_BMC_B_DN")
	)
	(segment
		(start 4.9276 -80.899)
		(end 4.9276 -85.020658)
		(width 0.1143)
		(layer "In9.Cu")
		(net "USB_HOST_BMC_B_DN")
	)
	(segment
		(start 47.864014 -8.390382)
		(end 14.1605 -8.390382)
		(width 0.1143)
		(layer "In9.Cu")
		(net "USB_HOST_BMC_B_DN")
	)
	(segment
		(start 4.501388 -86.049612)
		(end 3.203956 -87.347044)
		(width 0.1143)
		(layer "In9.Cu")
		(net "USB_HOST_BMC_B_DN")
	)
	(segment
		(start 2.672842 -78.644242)
		(end 4.9276 -80.899)
		(width 0.1143)
		(layer "In9.Cu")
		(net "USB_HOST_BMC_B_DN")
	)
	(segment
		(start 4.9276 -85.020658)
		(end 4.501388 -86.049612)
		(width 0.1143)
		(layer "In9.Cu")
		(net "USB_HOST_BMC_B_DN")
	)
	(segment
		(start 19.27098 -111.86922)
		(end 22.028404 -111.86922)
		(width 0.1143)
		(layer "In9.Cu")
		(net "USB_HOST_BMC_B_DN")
	)
	(segment
		(start 24.341328 -112.0648)
		(end 24.62784 -112.351312)
		(width 0.1143)
		(layer "In9.Cu")
		(net "USB_HOST_BMC_B_DN")
	)
	(segment
		(start 10.35812 -23.268178)
		(end 9.655302 -24.964644)
		(width 0.1143)
		(layer "In9.Cu")
		(net "USB_HOST_BMC_B_DN")
	)
	(segment
		(start 24.62784 -112.875822)
		(end 24.35098 -113.152682)
		(width 0.1143)
		(layer "In9.Cu")
		(net "USB_HOST_BMC_B_DN")
	)
	(segment
		(start 62.055756 -22.29739)
		(end 59.086496 -19.32813)
		(width 0.1143)
		(layer "In9.Cu")
		(net "USB_HOST_BMC_B_DN")
	)
	(segment
		(start 57.658 -15.879572)
		(end 50.740818 -8.96239)
		(width 0.1143)
		(layer "In9.Cu")
		(net "USB_HOST_BMC_B_DN")
	)
	(segment
		(start 2.672842 -32.019494)
		(end 2.672842 -78.644242)
		(width 0.1143)
		(layer "In9.Cu")
		(net "USB_HOST_BMC_B_DN")
	)
	(segment
		(start 10.388092 -112.02543)
		(end 18.89379 -112.02543)
		(width 0.1143)
		(layer "In9.Cu")
		(net "USB_HOST_BMC_B_DN")
	)
	(segment
		(start 10.795 -10.164826)
		(end 10.35812 -11.219688)
		(width 0.1143)
		(layer "In9.Cu")
		(net "USB_HOST_BMC_B_DN")
	)
	(segment
		(start 3.9624 -109.364272)
		(end 10.388092 -112.02543)
		(width 0.1143)
		(layer "In9.Cu")
		(net "USB_HOST_BMC_B_DN")
	)
	(segment
		(start 11.444478 -9.515348)
		(end 10.795 -10.164826)
		(width 0.1143)
		(layer "In9.Cu")
		(net "USB_HOST_BMC_B_DN")
	)
	(segment
		(start 18.89379 -112.02543)
		(end 19.27098 -111.86922)
		(width 0.1143)
		(layer "In9.Cu")
		(net "USB_HOST_BMC_B_DN")
	)
	(segment
		(start 10.35812 -11.219688)
		(end 10.35812 -23.268178)
		(width 0.1143)
		(layer "In9.Cu")
		(net "USB_HOST_BMC_B_DN")
	)
	(segment
		(start 2.92989 -108.331762)
		(end 3.9624 -109.364272)
		(width 0.1143)
		(layer "In9.Cu")
		(net "USB_HOST_BMC_B_DN")
	)
	(segment
		(start 3.203956 -87.347044)
		(end 2.5146 -89.010998)
		(width 0.1143)
		(layer "In9.Cu")
		(net "USB_HOST_BMC_B_DN")
	)
	(segment
		(start 50.740818 -8.96239)
		(end 47.864014 -8.390382)
		(width 0.1143)
		(layer "In9.Cu")
		(net "USB_HOST_BMC_B_DN")
	)
	(segment
		(start 24.62784 -112.351312)
		(end 24.62784 -112.875822)
		(width 0.1143)
		(layer "In9.Cu")
		(net "USB_HOST_BMC_B_DN")
	)
	(segment
		(start 22.50059 -112.0648)
		(end 24.341328 -112.0648)
		(width 0.1143)
		(layer "In9.Cu")
		(net "USB_HOST_BMC_B_DN")
	)
	(segment
		(start 2.5146 -89.010998)
		(end 2.5146 -107.329224)
		(width 0.1143)
		(layer "In9.Cu")
		(net "USB_HOST_BMC_B_DN")
	)
	(segment
		(start 63.496952 -26.871168)
		(end 63.220092 -26.594308)
		(width 0.1143)
		(layer "In9.Cu")
		(net "USB_HOST_BMC_B_DN")
	)
	(segment
		(start 63.220092 -25.108916)
		(end 62.055756 -22.29739)
		(width 0.1143)
		(layer "In9.Cu")
		(net "USB_HOST_BMC_B_DN")
	)
	(segment
		(start 14.1605 -8.390382)
		(end 11.444478 -9.515348)
		(width 0.1143)
		(layer "In9.Cu")
		(net "USB_HOST_BMC_B_DN")
	)
	(segment
		(start 9.655302 -24.964898)
		(end 2.723896 -31.896304)
		(width 0.1143)
		(layer "In9.Cu")
		(net "USB_HOST_BMC_B_DN")
	)
	(segment
		(start 22.028404 -111.86922)
		(end 22.50059 -112.0648)
		(width 0.1143)
		(layer "In9.Cu")
		(net "USB_HOST_BMC_B_DN")
	)
	(segment
		(start 2.5146 -107.329224)
		(end 2.92989 -108.331762)
		(width 0.1143)
		(layer "In9.Cu")
		(net "USB_HOST_BMC_B_DN")
	)
	(segment
		(start 63.220092 -26.594308)
		(end 63.220092 -25.108916)
		(width 0.1143)
		(layer "In9.Cu")
		(net "USB_HOST_BMC_B_DN")
	)
	(segment
		(start 2.723896 -31.896304)
		(end 2.672842 -32.019494)
		(width 0.1143)
		(layer "In9.Cu")
		(net "USB_HOST_BMC_B_DN")
	)
	(segment
		(start 9.655302 -24.964644)
		(end 9.655302 -24.964898)
		(width 0.1143)
		(layer "In9.Cu")
		(net "USB_HOST_BMC_B_DN")
	)
	(segment
		(start 59.086496 -19.32813)
		(end 57.658 -15.879572)
		(width 0.1143)
		(layer "In9.Cu")
		(net "USB_HOST_BMC_B_DN")
	)
	(segment
		(start 24.429212 -117.418612)
		(end 24.545036 -117.534436)
		(width 0.14224)
		(layer "F.Cu")
		(net "USB_HOST_BMC_A_DP")
	)
	(segment
		(start 24.1935 -115.276376)
		(end 24.1935 -115.969034)
		(width 0.14224)
		(layer "F.Cu")
		(net "USB_HOST_BMC_A_DP")
	)
	(segment
		(start 24.460454 -115.009422)
		(end 24.1935 -115.276376)
		(width 0.14224)
		(layer "F.Cu")
		(net "USB_HOST_BMC_A_DP")
	)
	(segment
		(start 65.1002 -27.73045)
		(end 65.1002 -27.225244)
		(width 0.14224)
		(layer "F.Cu")
		(net "USB_HOST_BMC_A_DP")
	)
	(segment
		(start 64.81445 -28.0162)
		(end 65.1002 -27.73045)
		(width 0.14224)
		(layer "F.Cu")
		(net "USB_HOST_BMC_A_DP")
	)
	(segment
		(start 64.97193 -28.17368)
		(end 64.97193 -28.825952)
		(width 0.14224)
		(layer "F.Cu")
		(net "USB_HOST_BMC_A_DP")
	)
	(segment
		(start 24.429212 -116.538248)
		(end 24.429212 -117.418612)
		(width 0.14224)
		(layer "F.Cu")
		(net "USB_HOST_BMC_A_DP")
	)
	(segment
		(start 64.97193 -28.825952)
		(end 64.8208 -28.977082)
		(width 0.14224)
		(layer "F.Cu")
		(net "USB_HOST_BMC_A_DP")
	)
	(segment
		(start 64.81445 -28.0162)
		(end 64.97193 -28.17368)
		(width 0.14224)
		(layer "F.Cu")
		(net "USB_HOST_BMC_A_DP")
	)
	(segment
		(start 64.8208 -28.977082)
		(end 64.600328 -28.977082)
		(width 0.14224)
		(layer "F.Cu")
		(net "USB_HOST_BMC_A_DP")
	)
	(segment
		(start 24.545036 -117.534436)
		(end 24.545036 -118.25986)
		(width 0.14224)
		(layer "F.Cu")
		(net "USB_HOST_BMC_A_DP")
	)
	(segment
		(start 24.1935 -115.969034)
		(end 24.429212 -116.538248)
		(width 0.14224)
		(layer "F.Cu")
		(net "USB_HOST_BMC_A_DP")
	)
	(segment
		(start 65.1002 -27.225244)
		(end 64.824102 -26.949146)
		(width 0.14224)
		(layer "F.Cu")
		(net "USB_HOST_BMC_A_DP")
	)
	(via
		(at 24.460454 -115.009422)
		(size 0.508)
		(drill 0.254)
		(layers "F.Cu" "B.Cu")
		(net "USB_HOST_BMC_A_DP")
	)
	(via
		(at 64.824102 -26.949146)
		(size 0.508)
		(drill 0.254)
		(layers "F.Cu" "B.Cu")
		(net "USB_HOST_BMC_A_DP")
	)
	(segment
		(start 2.284984 -31.615634)
		(end 9.230106 -24.670512)
		(width 0.1143)
		(layer "In9.Cu")
		(net "USB_HOST_BMC_A_DP")
	)
	(segment
		(start 50.797714 -8.422894)
		(end 51.891184 -9.007602)
		(width 0.1143)
		(layer "In9.Cu")
		(net "USB_HOST_BMC_A_DP")
	)
	(segment
		(start 19.389598 -112.54232)
		(end 10.269982 -112.54232)
		(width 0.1143)
		(layer "In9.Cu")
		(net "USB_HOST_BMC_A_DP")
	)
	(segment
		(start 53.996844 -10.83818)
		(end 54.272434 -11.042396)
		(width 0.1143)
		(layer "In9.Cu")
		(net "USB_HOST_BMC_A_DP")
	)
	(segment
		(start 59.442096 -15.216378)
		(end 60.097162 -18.509234)
		(width 0.1143)
		(layer "In9.Cu")
		(net "USB_HOST_BMC_A_DP")
	)
	(segment
		(start 64.27216 -22.684232)
		(end 64.27216 -22.972014)
		(width 0.1143)
		(layer "In9.Cu")
		(net "USB_HOST_BMC_A_DP")
	)
	(segment
		(start 24.1808 -114.271298)
		(end 24.027384 -113.900966)
		(width 0.1143)
		(layer "In9.Cu")
		(net "USB_HOST_BMC_A_DP")
	)
	(segment
		(start 63.751206 -22.450806)
		(end 64.038734 -22.450806)
		(width 0.1143)
		(layer "In9.Cu")
		(net "USB_HOST_BMC_A_DP")
	)
	(segment
		(start 19.818858 -112.36452)
		(end 19.389598 -112.54232)
		(width 0.1143)
		(layer "In9.Cu")
		(net "USB_HOST_BMC_A_DP")
	)
	(segment
		(start 64.897762 -24.5745)
		(end 65.100962 -24.7777)
		(width 0.1143)
		(layer "In9.Cu")
		(net "USB_HOST_BMC_A_DP")
	)
	(segment
		(start 2.797302 -87.034116)
		(end 4.077462 -85.753956)
		(width 0.1143)
		(layer "In9.Cu")
		(net "USB_HOST_BMC_A_DP")
	)
	(segment
		(start 64.038734 -22.450806)
		(end 64.27216 -22.684232)
		(width 0.1143)
		(layer "In9.Cu")
		(net "USB_HOST_BMC_A_DP")
	)
	(segment
		(start 3.700018 -109.82071)
		(end 2.497836 -108.618528)
		(width 0.1143)
		(layer "In9.Cu")
		(net "USB_HOST_BMC_A_DP")
	)
	(segment
		(start 4.42468 -84.915756)
		(end 4.42468 -81.115662)
		(width 0.1143)
		(layer "In9.Cu")
		(net "USB_HOST_BMC_A_DP")
	)
	(segment
		(start 4.077462 -85.753956)
		(end 4.42468 -84.915756)
		(width 0.1143)
		(layer "In9.Cu")
		(net "USB_HOST_BMC_A_DP")
	)
	(segment
		(start 1.96088 -107.321858)
		(end 1.96088 -89.053416)
		(width 0.1143)
		(layer "In9.Cu")
		(net "USB_HOST_BMC_A_DP")
	)
	(segment
		(start 58.869834 -14.183106)
		(end 59.177428 -14.57706)
		(width 0.1143)
		(layer "In9.Cu")
		(net "USB_HOST_BMC_A_DP")
	)
	(segment
		(start 64.793368 -23.20544)
		(end 65.100962 -23.513034)
		(width 0.1143)
		(layer "In9.Cu")
		(net "USB_HOST_BMC_A_DP")
	)
	(segment
		(start 9.779 -11.28014)
		(end 10.349738 -9.90219)
		(width 0.1143)
		(layer "In9.Cu")
		(net "USB_HOST_BMC_A_DP")
	)
	(segment
		(start 22.945344 -112.81918)
		(end 21.84781 -112.36452)
		(width 0.1143)
		(layer "In9.Cu")
		(net "USB_HOST_BMC_A_DP")
	)
	(segment
		(start 64.897762 -24.2443)
		(end 64.897762 -24.5745)
		(width 0.1143)
		(layer "In9.Cu")
		(net "USB_HOST_BMC_A_DP")
	)
	(segment
		(start 65.100962 -24.7777)
		(end 65.100962 -25.1079)
		(width 0.1143)
		(layer "In9.Cu")
		(net "USB_HOST_BMC_A_DP")
	)
	(segment
		(start 54.272434 -11.042396)
		(end 54.57444 -10.997692)
		(width 0.1143)
		(layer "In9.Cu")
		(net "USB_HOST_BMC_A_DP")
	)
	(segment
		(start 54.57444 -10.997692)
		(end 58.869834 -14.183106)
		(width 0.1143)
		(layer "In9.Cu")
		(net "USB_HOST_BMC_A_DP")
	)
	(segment
		(start 10.349738 -9.90219)
		(end 11.185398 -9.06653)
		(width 0.1143)
		(layer "In9.Cu")
		(net "USB_HOST_BMC_A_DP")
	)
	(segment
		(start 2.177542 -78.868524)
		(end 2.177542 -31.874968)
		(width 0.1143)
		(layer "In9.Cu")
		(net "USB_HOST_BMC_A_DP")
	)
	(segment
		(start 60.097162 -18.509234)
		(end 62.72276 -21.134832)
		(width 0.1143)
		(layer "In9.Cu")
		(net "USB_HOST_BMC_A_DP")
	)
	(segment
		(start 48.126904 -7.891526)
		(end 50.797714 -8.422894)
		(width 0.1143)
		(layer "In9.Cu")
		(net "USB_HOST_BMC_A_DP")
	)
	(segment
		(start 9.779 -23.345394)
		(end 9.779 -11.28014)
		(width 0.1143)
		(layer "In9.Cu")
		(net "USB_HOST_BMC_A_DP")
	)
	(segment
		(start 2.177542 -31.874968)
		(end 2.284984 -31.615634)
		(width 0.1143)
		(layer "In9.Cu")
		(net "USB_HOST_BMC_A_DP")
	)
	(segment
		(start 63.51778 -22.21738)
		(end 63.751206 -22.450806)
		(width 0.1143)
		(layer "In9.Cu")
		(net "USB_HOST_BMC_A_DP")
	)
	(segment
		(start 64.27216 -22.972014)
		(end 64.505586 -23.20544)
		(width 0.1143)
		(layer "In9.Cu")
		(net "USB_HOST_BMC_A_DP")
	)
	(segment
		(start 51.891184 -9.007602)
		(end 53.951886 -10.53592)
		(width 0.1143)
		(layer "In9.Cu")
		(net "USB_HOST_BMC_A_DP")
	)
	(segment
		(start 9.230106 -24.670512)
		(end 9.779 -23.345394)
		(width 0.1143)
		(layer "In9.Cu")
		(net "USB_HOST_BMC_A_DP")
	)
	(segment
		(start 62.72276 -21.422614)
		(end 62.956186 -21.65604)
		(width 0.1143)
		(layer "In9.Cu")
		(net "USB_HOST_BMC_A_DP")
	)
	(segment
		(start 65.100962 -26.672286)
		(end 64.824102 -26.949146)
		(width 0.1143)
		(layer "In9.Cu")
		(net "USB_HOST_BMC_A_DP")
	)
	(segment
		(start 65.100962 -25.8445)
		(end 65.100962 -26.672286)
		(width 0.1143)
		(layer "In9.Cu")
		(net "USB_HOST_BMC_A_DP")
	)
	(segment
		(start 63.51778 -21.929852)
		(end 63.51778 -22.21738)
		(width 0.1143)
		(layer "In9.Cu")
		(net "USB_HOST_BMC_A_DP")
	)
	(segment
		(start 63.243968 -21.65604)
		(end 63.51778 -21.929852)
		(width 0.1143)
		(layer "In9.Cu")
		(net "USB_HOST_BMC_A_DP")
	)
	(segment
		(start 11.185398 -9.06653)
		(end 14.022324 -7.891526)
		(width 0.1143)
		(layer "In9.Cu")
		(net "USB_HOST_BMC_A_DP")
	)
	(segment
		(start 65.100962 -24.0411)
		(end 64.897762 -24.2443)
		(width 0.1143)
		(layer "In9.Cu")
		(net "USB_HOST_BMC_A_DP")
	)
	(segment
		(start 64.505586 -23.20544)
		(end 64.793368 -23.20544)
		(width 0.1143)
		(layer "In9.Cu")
		(net "USB_HOST_BMC_A_DP")
	)
	(segment
		(start 10.269982 -112.54232)
		(end 3.700018 -109.82071)
		(width 0.1143)
		(layer "In9.Cu")
		(net "USB_HOST_BMC_A_DP")
	)
	(segment
		(start 65.100962 -23.513034)
		(end 65.100962 -24.0411)
		(width 0.1143)
		(layer "In9.Cu")
		(net "USB_HOST_BMC_A_DP")
	)
	(segment
		(start 62.72276 -21.134832)
		(end 62.72276 -21.422614)
		(width 0.1143)
		(layer "In9.Cu")
		(net "USB_HOST_BMC_A_DP")
	)
	(segment
		(start 53.951886 -10.53592)
		(end 53.996844 -10.83818)
		(width 0.1143)
		(layer "In9.Cu")
		(net "USB_HOST_BMC_A_DP")
	)
	(segment
		(start 24.1808 -114.729768)
		(end 24.1808 -114.271298)
		(width 0.1143)
		(layer "In9.Cu")
		(net "USB_HOST_BMC_A_DP")
	)
	(segment
		(start 64.897762 -25.3111)
		(end 64.897762 -25.6413)
		(width 0.1143)
		(layer "In9.Cu")
		(net "USB_HOST_BMC_A_DP")
	)
	(segment
		(start 14.022324 -7.891526)
		(end 48.126904 -7.891526)
		(width 0.1143)
		(layer "In9.Cu")
		(net "USB_HOST_BMC_A_DP")
	)
	(segment
		(start 62.956186 -21.65604)
		(end 63.243968 -21.65604)
		(width 0.1143)
		(layer "In9.Cu")
		(net "USB_HOST_BMC_A_DP")
	)
	(segment
		(start 21.84781 -112.36452)
		(end 19.818858 -112.36452)
		(width 0.1143)
		(layer "In9.Cu")
		(net "USB_HOST_BMC_A_DP")
	)
	(segment
		(start 65.100962 -25.1079)
		(end 64.897762 -25.3111)
		(width 0.1143)
		(layer "In9.Cu")
		(net "USB_HOST_BMC_A_DP")
	)
	(segment
		(start 64.897762 -25.6413)
		(end 65.100962 -25.8445)
		(width 0.1143)
		(layer "In9.Cu")
		(net "USB_HOST_BMC_A_DP")
	)
	(segment
		(start 24.027384 -113.900966)
		(end 22.945344 -112.81918)
		(width 0.1143)
		(layer "In9.Cu")
		(net "USB_HOST_BMC_A_DP")
	)
	(segment
		(start 4.42468 -81.115662)
		(end 2.177542 -78.868524)
		(width 0.1143)
		(layer "In9.Cu")
		(net "USB_HOST_BMC_A_DP")
	)
	(segment
		(start 2.497836 -108.618528)
		(end 1.96088 -107.321858)
		(width 0.1143)
		(layer "In9.Cu")
		(net "USB_HOST_BMC_A_DP")
	)
	(segment
		(start 24.460454 -115.009422)
		(end 24.1808 -114.729768)
		(width 0.1143)
		(layer "In9.Cu")
		(net "USB_HOST_BMC_A_DP")
	)
	(segment
		(start 1.96088 -89.053416)
		(end 2.797302 -87.034116)
		(width 0.1143)
		(layer "In9.Cu")
		(net "USB_HOST_BMC_A_DP")
	)
	(segment
		(start 59.177428 -14.57706)
		(end 59.442096 -15.216378)
		(width 0.1143)
		(layer "In9.Cu")
		(net "USB_HOST_BMC_A_DP")
	)
	(segment
		(start 65.34023 -28.44292)
		(end 65.76695 -28.0162)
		(width 0.14224)
		(layer "F.Cu")
		(net "USB_HOST_BMC_A_DN")
	)
	(segment
		(start 24.060912 -116.611654)
		(end 24.060912 -117.417088)
		(width 0.14224)
		(layer "F.Cu")
		(net "USB_HOST_BMC_A_DN")
	)
	(segment
		(start 65.76695 -28.0162)
		(end 65.4685 -27.71775)
		(width 0.14224)
		(layer "F.Cu")
		(net "USB_HOST_BMC_A_DN")
	)
	(segment
		(start 65.4685 -27.71775)
		(end 65.4685 -27.193748)
		(width 0.14224)
		(layer "F.Cu")
		(net "USB_HOST_BMC_A_DN")
	)
	(segment
		(start 65.4685 -27.193748)
		(end 65.713102 -26.949146)
		(width 0.14224)
		(layer "F.Cu")
		(net "USB_HOST_BMC_A_DN")
	)
	(segment
		(start 23.945088 -117.532912)
		(end 23.945088 -118.25986)
		(width 0.14224)
		(layer "F.Cu")
		(net "USB_HOST_BMC_A_DN")
	)
	(segment
		(start 65.34023 -28.699206)
		(end 65.34023 -28.44292)
		(width 0.14224)
		(layer "F.Cu")
		(net "USB_HOST_BMC_A_DN")
	)
	(segment
		(start 23.8252 -116.04244)
		(end 24.060912 -116.611654)
		(width 0.14224)
		(layer "F.Cu")
		(net "USB_HOST_BMC_A_DN")
	)
	(segment
		(start 24.060912 -117.417088)
		(end 23.945088 -117.532912)
		(width 0.14224)
		(layer "F.Cu")
		(net "USB_HOST_BMC_A_DN")
	)
	(segment
		(start 23.8252 -115.263168)
		(end 23.8252 -116.04244)
		(width 0.14224)
		(layer "F.Cu")
		(net "USB_HOST_BMC_A_DN")
	)
	(segment
		(start 65.618106 -28.977082)
		(end 65.34023 -28.699206)
		(width 0.14224)
		(layer "F.Cu")
		(net "USB_HOST_BMC_A_DN")
	)
	(segment
		(start 23.571454 -115.009422)
		(end 23.8252 -115.263168)
		(width 0.14224)
		(layer "F.Cu")
		(net "USB_HOST_BMC_A_DN")
	)
	(via
		(at 65.713102 -26.949146)
		(size 0.508)
		(drill 0.254)
		(layers "F.Cu" "B.Cu")
		(net "USB_HOST_BMC_A_DN")
	)
	(via
		(at 23.571454 -115.009422)
		(size 0.508)
		(drill 0.254)
		(layers "F.Cu" "B.Cu")
		(net "USB_HOST_BMC_A_DN")
	)
	(segment
		(start 4.0894 -84.848954)
		(end 4.0894 -81.2546)
		(width 0.1143)
		(layer "In9.Cu")
		(net "USB_HOST_BMC_A_DN")
	)
	(segment
		(start 22.755352 -113.103406)
		(end 21.781008 -112.6998)
		(width 0.1143)
		(layer "In9.Cu")
		(net "USB_HOST_BMC_A_DN")
	)
	(segment
		(start 10.065512 -9.712198)
		(end 10.995406 -8.782304)
		(width 0.1143)
		(layer "In9.Cu")
		(net "USB_HOST_BMC_A_DN")
	)
	(segment
		(start 59.106308 -13.94079)
		(end 59.469782 -14.406626)
		(width 0.1143)
		(layer "In9.Cu")
		(net "USB_HOST_BMC_A_DN")
	)
	(segment
		(start 60.40628 -18.344134)
		(end 65.436242 -23.374096)
		(width 0.1143)
		(layer "In9.Cu")
		(net "USB_HOST_BMC_A_DN")
	)
	(segment
		(start 2.513076 -86.844124)
		(end 3.793236 -85.563964)
		(width 0.1143)
		(layer "In9.Cu")
		(net "USB_HOST_BMC_A_DN")
	)
	(segment
		(start 13.955522 -7.556246)
		(end 48.160178 -7.556246)
		(width 0.1143)
		(layer "In9.Cu")
		(net "USB_HOST_BMC_A_DN")
	)
	(segment
		(start 10.995406 -8.782304)
		(end 13.955522 -7.556246)
		(width 0.1143)
		(layer "In9.Cu")
		(net "USB_HOST_BMC_A_DN")
	)
	(segment
		(start 2.21361 -108.80852)
		(end 1.6256 -107.38866)
		(width 0.1143)
		(layer "In9.Cu")
		(net "USB_HOST_BMC_A_DN")
	)
	(segment
		(start 59.469782 -14.406626)
		(end 59.764676 -15.118588)
		(width 0.1143)
		(layer "In9.Cu")
		(net "USB_HOST_BMC_A_DN")
	)
	(segment
		(start 3.793236 -85.563964)
		(end 4.0894 -84.848954)
		(width 0.1143)
		(layer "In9.Cu")
		(net "USB_HOST_BMC_A_DN")
	)
	(segment
		(start 23.571454 -115.009422)
		(end 23.84552 -114.735356)
		(width 0.1143)
		(layer "In9.Cu")
		(net "USB_HOST_BMC_A_DN")
	)
	(segment
		(start 48.160178 -7.556246)
		(end 50.912014 -8.103616)
		(width 0.1143)
		(layer "In9.Cu")
		(net "USB_HOST_BMC_A_DN")
	)
	(segment
		(start 65.436242 -26.672286)
		(end 65.713102 -26.949146)
		(width 0.1143)
		(layer "In9.Cu")
		(net "USB_HOST_BMC_A_DN")
	)
	(segment
		(start 50.912014 -8.103616)
		(end 52.07127 -8.723376)
		(width 0.1143)
		(layer "In9.Cu")
		(net "USB_HOST_BMC_A_DN")
	)
	(segment
		(start 19.4564 -112.8776)
		(end 10.20318 -112.8776)
		(width 0.1143)
		(layer "In9.Cu")
		(net "USB_HOST_BMC_A_DN")
	)
	(segment
		(start 3.510026 -110.104936)
		(end 2.21361 -108.80852)
		(width 0.1143)
		(layer "In9.Cu")
		(net "USB_HOST_BMC_A_DN")
	)
	(segment
		(start 1.842262 -79.007462)
		(end 1.842262 -31.808166)
		(width 0.1143)
		(layer "In9.Cu")
		(net "USB_HOST_BMC_A_DN")
	)
	(segment
		(start 9.44372 -11.213338)
		(end 10.065512 -9.712198)
		(width 0.1143)
		(layer "In9.Cu")
		(net "USB_HOST_BMC_A_DN")
	)
	(segment
		(start 23.84552 -114.3381)
		(end 23.743158 -114.090958)
		(width 0.1143)
		(layer "In9.Cu")
		(net "USB_HOST_BMC_A_DN")
	)
	(segment
		(start 10.20318 -112.8776)
		(end 3.510026 -110.104936)
		(width 0.1143)
		(layer "In9.Cu")
		(net "USB_HOST_BMC_A_DN")
	)
	(segment
		(start 4.0894 -81.2546)
		(end 1.842262 -79.007462)
		(width 0.1143)
		(layer "In9.Cu")
		(net "USB_HOST_BMC_A_DN")
	)
	(segment
		(start 65.436242 -23.374096)
		(end 65.436242 -26.672286)
		(width 0.1143)
		(layer "In9.Cu")
		(net "USB_HOST_BMC_A_DN")
	)
	(segment
		(start 2.000758 -31.425642)
		(end 8.94588 -24.48052)
		(width 0.1143)
		(layer "In9.Cu")
		(net "USB_HOST_BMC_A_DN")
	)
	(segment
		(start 52.07127 -8.723376)
		(end 59.106308 -13.94079)
		(width 0.1143)
		(layer "In9.Cu")
		(net "USB_HOST_BMC_A_DN")
	)
	(segment
		(start 1.842262 -31.808166)
		(end 2.000758 -31.425642)
		(width 0.1143)
		(layer "In9.Cu")
		(net "USB_HOST_BMC_A_DN")
	)
	(segment
		(start 8.94588 -24.48052)
		(end 9.44372 -23.278592)
		(width 0.1143)
		(layer "In9.Cu")
		(net "USB_HOST_BMC_A_DN")
	)
	(segment
		(start 23.84552 -114.735356)
		(end 23.84552 -114.3381)
		(width 0.1143)
		(layer "In9.Cu")
		(net "USB_HOST_BMC_A_DN")
	)
	(segment
		(start 9.44372 -23.278592)
		(end 9.44372 -11.213338)
		(width 0.1143)
		(layer "In9.Cu")
		(net "USB_HOST_BMC_A_DN")
	)
	(segment
		(start 21.781008 -112.6998)
		(end 19.88566 -112.6998)
		(width 0.1143)
		(layer "In9.Cu")
		(net "USB_HOST_BMC_A_DN")
	)
	(segment
		(start 59.764676 -15.118588)
		(end 60.40628 -18.344134)
		(width 0.1143)
		(layer "In9.Cu")
		(net "USB_HOST_BMC_A_DN")
	)
	(segment
		(start 23.743158 -114.090958)
		(end 22.755352 -113.103406)
		(width 0.1143)
		(layer "In9.Cu")
		(net "USB_HOST_BMC_A_DN")
	)
	(segment
		(start 1.6256 -107.38866)
		(end 1.6256 -88.986614)
		(width 0.1143)
		(layer "In9.Cu")
		(net "USB_HOST_BMC_A_DN")
	)
	(segment
		(start 19.88566 -112.6998)
		(end 19.4564 -112.8776)
		(width 0.1143)
		(layer "In9.Cu")
		(net "USB_HOST_BMC_A_DN")
	)
	(segment
		(start 1.6256 -88.986614)
		(end 2.513076 -86.844124)
		(width 0.1143)
		(layer "In9.Cu")
		(net "USB_HOST_BMC_A_DN")
	)
	(segment
		(start 29.7434 -62.88024)
		(end 29.7434 -64.121538)
		(width 0.11684)
		(layer "F.Cu")
		(net "UART_BMC_5_TXD_R")
	)
	(segment
		(start 29.62656 -62.7634)
		(end 29.7434 -62.88024)
		(width 0.11684)
		(layer "F.Cu")
		(net "UART_BMC_5_TXD_R")
	)
	(segment
		(start 29.7434 -64.121538)
		(end 30.148022 -65.098422)
		(width 0.11684)
		(layer "F.Cu")
		(net "UART_BMC_5_TXD_R")
	)
	(segment
		(start 28.001214 -61.48324)
		(end 28.001214 -62.418214)
		(width 0.11684)
		(layer "F.Cu")
		(net "UART_BMC_5_TXD_R")
	)
	(segment
		(start 28.001214 -62.418214)
		(end 28.3464 -62.7634)
		(width 0.11684)
		(layer "F.Cu")
		(net "UART_BMC_5_TXD_R")
	)
	(segment
		(start 28.3464 -62.7634)
		(end 29.62656 -62.7634)
		(width 0.11684)
		(layer "F.Cu")
		(net "UART_BMC_5_TXD_R")
	)
	(segment
		(start 30.148022 -65.098422)
		(end 30.861 -65.8114)
		(width 0.11684)
		(layer "F.Cu")
		(net "UART_BMC_5_TXD_R")
	)
	(segment
		(start 30.861 -65.8114)
		(end 32.258 -65.8114)
		(width 0.11684)
		(layer "F.Cu")
		(net "UART_BMC_5_TXD_R")
	)
	(segment
		(start 32.258 -65.8114)
		(end 32.4104 -65.9638)
		(width 0.11684)
		(layer "F.Cu")
		(net "UART_BMC_5_TXD_R")
	)
	(via
		(at 66.138552 -31.750254)
		(size 0.508)
		(drill 0.254)
		(layers "F.Cu" "B.Cu")
		(net "UART_BMC_5_TXD_R")
	)
	(via
		(at 65.385188 -32.97936)
		(size 0.6604)
		(drill 0.3302)
		(layers "F.Cu" "B.Cu")
		(net "UART_BMC_5_TXD_R")
	)
	(via
		(at 73.044812 -21.359368)
		(size 0.508)
		(drill 0.254)
		(layers "F.Cu" "B.Cu")
		(net "UART_BMC_5_TXD_R")
	)
	(via
		(at 48.50511 -88.41486)
		(size 0.508)
		(drill 0.254)
		(layers "F.Cu" "B.Cu")
		(net "UART_BMC_5_TXD_R")
	)
	(via
		(at 32.4104 -65.9638)
		(size 0.508)
		(drill 0.254)
		(layers "F.Cu" "B.Cu")
		(net "UART_BMC_5_TXD_R")
	)
	(via
		(at 87.757 -87.04326)
		(size 0.508)
		(drill 0.254)
		(layers "F.Cu" "B.Cu")
		(net "UART_BMC_5_TXD_R")
	)
	(segment
		(start 48.054006 -88.41486)
		(end 47.55388 -87.914734)
		(width 0.11684)
		(layer "B.Cu")
		(net "UART_BMC_5_TXD_R")
	)
	(segment
		(start 45.6057 -85.6488)
		(end 45.212 -86.0425)
		(width 0.11684)
		(layer "B.Cu")
		(net "UART_BMC_5_TXD_R")
	)
	(segment
		(start 65.385188 -32.97936)
		(end 65.2018 -33.422082)
		(width 0.11684)
		(layer "B.Cu")
		(net "UART_BMC_5_TXD_R")
	)
	(segment
		(start 66.138552 -31.750254)
		(end 66.138552 -32.225996)
		(width 0.11684)
		(layer "B.Cu")
		(net "UART_BMC_5_TXD_R")
	)
	(segment
		(start 66.138552 -32.225996)
		(end 65.385188 -32.97936)
		(width 0.11684)
		(layer "B.Cu")
		(net "UART_BMC_5_TXD_R")
	)
	(segment
		(start 65.2018 -33.422082)
		(end 65.2018 -34.237676)
		(width 0.11684)
		(layer "B.Cu")
		(net "UART_BMC_5_TXD_R")
	)
	(segment
		(start 47.55388 -87.05596)
		(end 46.14672 -85.6488)
		(width 0.11684)
		(layer "B.Cu")
		(net "UART_BMC_5_TXD_R")
	)
	(segment
		(start 45.212 -86.0425)
		(end 44.62526 -85.45576)
		(width 0.11684)
		(layer "B.Cu")
		(net "UART_BMC_5_TXD_R")
	)
	(segment
		(start 48.50511 -88.41486)
		(end 48.054006 -88.41486)
		(width 0.11684)
		(layer "B.Cu")
		(net "UART_BMC_5_TXD_R")
	)
	(segment
		(start 47.55388 -87.914734)
		(end 47.55388 -87.86495)
		(width 0.11684)
		(layer "B.Cu")
		(net "UART_BMC_5_TXD_R")
	)
	(segment
		(start 47.55388 -87.86495)
		(end 47.55388 -87.05596)
		(width 0.11684)
		(layer "B.Cu")
		(net "UART_BMC_5_TXD_R")
	)
	(segment
		(start 44.62526 -85.45576)
		(end 43.199558 -85.45576)
		(width 0.11684)
		(layer "B.Cu")
		(net "UART_BMC_5_TXD_R")
	)
	(segment
		(start 46.14672 -85.6488)
		(end 45.6057 -85.6488)
		(width 0.11684)
		(layer "B.Cu")
		(net "UART_BMC_5_TXD_R")
	)
	(segment
		(start 72.82688 -91.8337)
		(end 72.15378 -92.5068)
		(width 0.08382)
		(layer "In2.Cu")
		(net "UART_BMC_5_TXD_R")
	)
	(segment
		(start 67.68338 -30.53842)
		(end 67.68338 -31.74492)
		(width 0.08382)
		(layer "In2.Cu")
		(net "UART_BMC_5_TXD_R")
	)
	(segment
		(start 71.171054 -29.6418)
		(end 68.58 -29.6418)
		(width 0.08382)
		(layer "In2.Cu")
		(net "UART_BMC_5_TXD_R")
	)
	(segment
		(start 68.58 -29.6418)
		(end 67.68338 -30.53842)
		(width 0.08382)
		(layer "In2.Cu")
		(net "UART_BMC_5_TXD_R")
	)
	(segment
		(start 72.15378 -92.5068)
		(end 68.834 -92.5068)
		(width 0.08382)
		(layer "In2.Cu")
		(net "UART_BMC_5_TXD_R")
	)
	(segment
		(start 77.195934 -90.0176)
		(end 75.379834 -91.8337)
		(width 0.08382)
		(layer "In2.Cu")
		(net "UART_BMC_5_TXD_R")
	)
	(segment
		(start 58.4454 -91.8718)
		(end 57.5564 -90.9828)
		(width 0.08382)
		(layer "In2.Cu")
		(net "UART_BMC_5_TXD_R")
	)
	(segment
		(start 73.044812 -21.359368)
		(end 73.052432 -21.359368)
		(width 0.08382)
		(layer "In2.Cu")
		(net "UART_BMC_5_TXD_R")
	)
	(segment
		(start 67.68338 -31.74492)
		(end 67.44462 -31.98368)
		(width 0.08382)
		(layer "In2.Cu")
		(net "UART_BMC_5_TXD_R")
	)
	(segment
		(start 87.60714 -87.60206)
		(end 85.4964 -89.7128)
		(width 0.08382)
		(layer "In2.Cu")
		(net "UART_BMC_5_TXD_R")
	)
	(segment
		(start 84.65947 -89.710006)
		(end 81.689194 -89.710006)
		(width 0.08382)
		(layer "In2.Cu")
		(net "UART_BMC_5_TXD_R")
	)
	(segment
		(start 66.81978 -31.98368)
		(end 66.586354 -31.750254)
		(width 0.08382)
		(layer "In2.Cu")
		(net "UART_BMC_5_TXD_R")
	)
	(segment
		(start 57.5564 -90.9828)
		(end 53.7464 -90.9828)
		(width 0.08382)
		(layer "In2.Cu")
		(net "UART_BMC_5_TXD_R")
	)
	(segment
		(start 87.757 -87.04326)
		(end 87.60714 -87.19312)
		(width 0.08382)
		(layer "In2.Cu")
		(net "UART_BMC_5_TXD_R")
	)
	(segment
		(start 59.5884 -91.8718)
		(end 58.4454 -91.8718)
		(width 0.08382)
		(layer "In2.Cu")
		(net "UART_BMC_5_TXD_R")
	)
	(segment
		(start 75.379834 -91.8337)
		(end 72.82688 -91.8337)
		(width 0.08382)
		(layer "In2.Cu")
		(net "UART_BMC_5_TXD_R")
	)
	(segment
		(start 60.44438 -91.01582)
		(end 59.5884 -91.8718)
		(width 0.08382)
		(layer "In2.Cu")
		(net "UART_BMC_5_TXD_R")
	)
	(segment
		(start 52.25669 -89.49309)
		(end 49.675034 -89.49309)
		(width 0.08382)
		(layer "In2.Cu")
		(net "UART_BMC_5_TXD_R")
	)
	(segment
		(start 87.60714 -87.19312)
		(end 87.60714 -87.60206)
		(width 0.08382)
		(layer "In2.Cu")
		(net "UART_BMC_5_TXD_R")
	)
	(segment
		(start 73.00722 -27.805634)
		(end 71.171054 -29.6418)
		(width 0.08382)
		(layer "In2.Cu")
		(net "UART_BMC_5_TXD_R")
	)
	(segment
		(start 81.3816 -90.0176)
		(end 77.195934 -90.0176)
		(width 0.08382)
		(layer "In2.Cu")
		(net "UART_BMC_5_TXD_R")
	)
	(segment
		(start 67.34302 -91.01582)
		(end 60.44438 -91.01582)
		(width 0.08382)
		(layer "In2.Cu")
		(net "UART_BMC_5_TXD_R")
	)
	(segment
		(start 66.586354 -31.750254)
		(end 66.138552 -31.750254)
		(width 0.08382)
		(layer "In2.Cu")
		(net "UART_BMC_5_TXD_R")
	)
	(segment
		(start 84.662264 -89.7128)
		(end 84.65947 -89.710006)
		(width 0.08382)
		(layer "In2.Cu")
		(net "UART_BMC_5_TXD_R")
	)
	(segment
		(start 73.00722 -21.40458)
		(end 73.00722 -27.805634)
		(width 0.08382)
		(layer "In2.Cu")
		(net "UART_BMC_5_TXD_R")
	)
	(segment
		(start 73.052432 -21.359368)
		(end 73.00722 -21.40458)
		(width 0.08382)
		(layer "In2.Cu")
		(net "UART_BMC_5_TXD_R")
	)
	(segment
		(start 68.834 -92.5068)
		(end 67.34302 -91.01582)
		(width 0.08382)
		(layer "In2.Cu")
		(net "UART_BMC_5_TXD_R")
	)
	(segment
		(start 81.689194 -89.710006)
		(end 81.3816 -90.0176)
		(width 0.08382)
		(layer "In2.Cu")
		(net "UART_BMC_5_TXD_R")
	)
	(segment
		(start 53.7464 -90.9828)
		(end 52.25669 -89.49309)
		(width 0.08382)
		(layer "In2.Cu")
		(net "UART_BMC_5_TXD_R")
	)
	(segment
		(start 49.675034 -89.49309)
		(end 48.596804 -88.41486)
		(width 0.08382)
		(layer "In2.Cu")
		(net "UART_BMC_5_TXD_R")
	)
	(segment
		(start 48.596804 -88.41486)
		(end 48.50511 -88.41486)
		(width 0.08382)
		(layer "In2.Cu")
		(net "UART_BMC_5_TXD_R")
	)
	(segment
		(start 85.4964 -89.7128)
		(end 84.662264 -89.7128)
		(width 0.08382)
		(layer "In2.Cu")
		(net "UART_BMC_5_TXD_R")
	)
	(segment
		(start 67.44462 -31.98368)
		(end 66.81978 -31.98368)
		(width 0.08382)
		(layer "In2.Cu")
		(net "UART_BMC_5_TXD_R")
	)
	(segment
		(start 86.833964 -86.915244)
		(end 85.449664 -85.530944)
		(width 0.10668)
		(layer "In4.Cu")
		(net "UART_BMC_5_TXD_R")
	)
	(segment
		(start 80.4926 -23.4188)
		(end 79.7052 -22.6314)
		(width 0.10668)
		(layer "In4.Cu")
		(net "UART_BMC_5_TXD_R")
	)
	(segment
		(start 85.5726 -28.1178)
		(end 85.3948 -27.94)
		(width 0.10668)
		(layer "In4.Cu")
		(net "UART_BMC_5_TXD_R")
	)
	(segment
		(start 79.7052 -22.6314)
		(end 74.316844 -22.6314)
		(width 0.10668)
		(layer "In4.Cu")
		(net "UART_BMC_5_TXD_R")
	)
	(segment
		(start 88.082882 -29.154882)
		(end 87.0458 -28.1178)
		(width 0.10668)
		(layer "In4.Cu")
		(net "UART_BMC_5_TXD_R")
	)
	(segment
		(start 87.757 -87.04326)
		(end 87.628984 -86.915244)
		(width 0.10668)
		(layer "In4.Cu")
		(net "UART_BMC_5_TXD_R")
	)
	(segment
		(start 85.3948 -27.94)
		(end 85.3948 -26.543)
		(width 0.10668)
		(layer "In4.Cu")
		(net "UART_BMC_5_TXD_R")
	)
	(segment
		(start 80.4926 -23.876)
		(end 80.4926 -23.4188)
		(width 0.10668)
		(layer "In4.Cu")
		(net "UART_BMC_5_TXD_R")
	)
	(segment
		(start 87.0458 -28.1178)
		(end 85.5726 -28.1178)
		(width 0.10668)
		(layer "In4.Cu")
		(net "UART_BMC_5_TXD_R")
	)
	(segment
		(start 74.316844 -22.6314)
		(end 73.044812 -21.359368)
		(width 0.10668)
		(layer "In4.Cu")
		(net "UART_BMC_5_TXD_R")
	)
	(segment
		(start 84.9122 -26.0604)
		(end 82.677 -26.0604)
		(width 0.10668)
		(layer "In4.Cu")
		(net "UART_BMC_5_TXD_R")
	)
	(segment
		(start 85.449664 -80.703674)
		(end 88.082882 -78.070456)
		(width 0.10668)
		(layer "In4.Cu")
		(net "UART_BMC_5_TXD_R")
	)
	(segment
		(start 85.449664 -85.530944)
		(end 85.449664 -80.703674)
		(width 0.10668)
		(layer "In4.Cu")
		(net "UART_BMC_5_TXD_R")
	)
	(segment
		(start 87.628984 -86.915244)
		(end 86.833964 -86.915244)
		(width 0.10668)
		(layer "In4.Cu")
		(net "UART_BMC_5_TXD_R")
	)
	(segment
		(start 88.082882 -78.070456)
		(end 88.082882 -29.154882)
		(width 0.10668)
		(layer "In4.Cu")
		(net "UART_BMC_5_TXD_R")
	)
	(segment
		(start 82.677 -26.0604)
		(end 80.4926 -23.876)
		(width 0.10668)
		(layer "In4.Cu")
		(net "UART_BMC_5_TXD_R")
	)
	(segment
		(start 85.3948 -26.543)
		(end 84.9122 -26.0604)
		(width 0.10668)
		(layer "In4.Cu")
		(net "UART_BMC_5_TXD_R")
	)
	(segment
		(start 34.14776 -74.804016)
		(end 34.14776 -72.924416)
		(width 0.10668)
		(layer "In7.Cu")
		(net "UART_BMC_5_TXD_R")
	)
	(segment
		(start 38.107366 -79.340202)
		(end 36.521644 -77.75448)
		(width 0.10668)
		(layer "In7.Cu")
		(net "UART_BMC_5_TXD_R")
	)
	(segment
		(start 32.7406 -70.134734)
		(end 33.16478 -69.710554)
		(width 0.10668)
		(layer "In7.Cu")
		(net "UART_BMC_5_TXD_R")
	)
	(segment
		(start 33.16478 -69.265292)
		(end 33.6804 -68.749672)
		(width 0.10668)
		(layer "In7.Cu")
		(net "UART_BMC_5_TXD_R")
	)
	(segment
		(start 47.60468 -87.51443)
		(end 47.60468 -86.846664)
		(width 0.10668)
		(layer "In7.Cu")
		(net "UART_BMC_5_TXD_R")
	)
	(segment
		(start 33.6804 -68.749672)
		(end 33.6804 -66.844418)
		(width 0.10668)
		(layer "In7.Cu")
		(net "UART_BMC_5_TXD_R")
	)
	(segment
		(start 35.89528 -77.75448)
		(end 34.40938 -76.26858)
		(width 0.10668)
		(layer "In7.Cu")
		(net "UART_BMC_5_TXD_R")
	)
	(segment
		(start 43.943016 -83.185)
		(end 42.600372 -83.185)
		(width 0.10668)
		(layer "In7.Cu")
		(net "UART_BMC_5_TXD_R")
	)
	(segment
		(start 42.600372 -83.185)
		(end 38.755574 -79.340202)
		(width 0.10668)
		(layer "In7.Cu")
		(net "UART_BMC_5_TXD_R")
	)
	(segment
		(start 47.60468 -86.846664)
		(end 43.943016 -83.185)
		(width 0.10668)
		(layer "In7.Cu")
		(net "UART_BMC_5_TXD_R")
	)
	(segment
		(start 48.50511 -88.41486)
		(end 47.60468 -87.51443)
		(width 0.10668)
		(layer "In7.Cu")
		(net "UART_BMC_5_TXD_R")
	)
	(segment
		(start 38.755574 -79.340202)
		(end 38.107366 -79.340202)
		(width 0.10668)
		(layer "In7.Cu")
		(net "UART_BMC_5_TXD_R")
	)
	(segment
		(start 33.99028 -72.766682)
		(end 32.7406 -71.517002)
		(width 0.10668)
		(layer "In7.Cu")
		(net "UART_BMC_5_TXD_R")
	)
	(segment
		(start 34.14776 -72.924416)
		(end 33.99028 -72.766936)
		(width 0.10668)
		(layer "In7.Cu")
		(net "UART_BMC_5_TXD_R")
	)
	(segment
		(start 32.799782 -65.9638)
		(end 32.4104 -65.9638)
		(width 0.10668)
		(layer "In7.Cu")
		(net "UART_BMC_5_TXD_R")
	)
	(segment
		(start 33.16478 -69.710554)
		(end 33.16478 -69.265292)
		(width 0.10668)
		(layer "In7.Cu")
		(net "UART_BMC_5_TXD_R")
	)
	(segment
		(start 34.40938 -75.065636)
		(end 34.14776 -74.804016)
		(width 0.10668)
		(layer "In7.Cu")
		(net "UART_BMC_5_TXD_R")
	)
	(segment
		(start 36.521644 -77.75448)
		(end 35.89528 -77.75448)
		(width 0.10668)
		(layer "In7.Cu")
		(net "UART_BMC_5_TXD_R")
	)
	(segment
		(start 33.6804 -66.844418)
		(end 32.799782 -65.9638)
		(width 0.10668)
		(layer "In7.Cu")
		(net "UART_BMC_5_TXD_R")
	)
	(segment
		(start 34.40938 -76.26858)
		(end 34.40938 -75.065636)
		(width 0.10668)
		(layer "In7.Cu")
		(net "UART_BMC_5_TXD_R")
	)
	(segment
		(start 33.99028 -72.766936)
		(end 33.99028 -72.766682)
		(width 0.10668)
		(layer "In7.Cu")
		(net "UART_BMC_5_TXD_R")
	)
	(segment
		(start 32.7406 -71.517002)
		(end 32.7406 -70.134734)
		(width 0.10668)
		(layer "In7.Cu")
		(net "UART_BMC_5_TXD_R")
	)
	(segment
		(start 59.29503 -40.971216)
		(end 59.690254 -40.575992)
		(width 0.11684)
		(layer "F.Cu")
		(net "UART_BMC_5_TXD")
	)
	(via
		(at 64.156844 -36.163504)
		(size 0.6604)
		(drill 0.3302)
		(layers "F.Cu" "B.Cu")
		(net "UART_BMC_5_TXD")
	)
	(via
		(at 59.690254 -40.575992)
		(size 0.4572)
		(drill 0.254)
		(layers "F.Cu" "B.Cu")
		(net "UART_BMC_5_TXD")
	)
	(segment
		(start 60.325254 -40.1828)
		(end 60.6552 -40.1828)
		(width 0.11684)
		(layer "B.Cu")
		(net "UART_BMC_5_TXD")
	)
	(segment
		(start 61.354716 -39.483284)
		(end 61.354716 -39.013892)
		(width 0.11684)
		(layer "B.Cu")
		(net "UART_BMC_5_TXD")
	)
	(segment
		(start 64.156844 -36.366704)
		(end 64.156844 -36.163504)
		(width 0.11684)
		(layer "B.Cu")
		(net "UART_BMC_5_TXD")
	)
	(segment
		(start 62.852808 -37.5158)
		(end 63.007748 -37.5158)
		(width 0.11684)
		(layer "B.Cu")
		(net "UART_BMC_5_TXD")
	)
	(segment
		(start 61.354716 -39.013892)
		(end 62.852808 -37.5158)
		(width 0.11684)
		(layer "B.Cu")
		(net "UART_BMC_5_TXD")
	)
	(segment
		(start 60.6552 -40.1828)
		(end 61.354716 -39.483284)
		(width 0.11684)
		(layer "B.Cu")
		(net "UART_BMC_5_TXD")
	)
	(segment
		(start 59.690254 -40.575992)
		(end 60.103258 -40.404796)
		(width 0.11684)
		(layer "B.Cu")
		(net "UART_BMC_5_TXD")
	)
	(segment
		(start 64.217296 -36.163504)
		(end 65.2018 -35.179)
		(width 0.11684)
		(layer "B.Cu")
		(net "UART_BMC_5_TXD")
	)
	(segment
		(start 65.2018 -35.179)
		(end 65.2018 -35.037776)
		(width 0.11684)
		(layer "B.Cu")
		(net "UART_BMC_5_TXD")
	)
	(segment
		(start 60.103258 -40.404796)
		(end 60.325254 -40.1828)
		(width 0.11684)
		(layer "B.Cu")
		(net "UART_BMC_5_TXD")
	)
	(segment
		(start 64.156844 -36.163504)
		(end 64.217296 -36.163504)
		(width 0.11684)
		(layer "B.Cu")
		(net "UART_BMC_5_TXD")
	)
	(segment
		(start 63.007748 -37.5158)
		(end 64.156844 -36.366704)
		(width 0.11684)
		(layer "B.Cu")
		(net "UART_BMC_5_TXD")
	)
	(segment
		(start 32.201104 -66.5226)
		(end 32.92475 -66.5226)
		(width 0.11684)
		(layer "F.Cu")
		(net "UART_BMC_5_RXD_R")
	)
	(segment
		(start 35.2806 -64.5414)
		(end 34.1376 -65.6844)
		(width 0.11684)
		(layer "F.Cu")
		(net "UART_BMC_5_RXD_R")
	)
	(segment
		(start 34.1376 -65.6844)
		(end 33.76295 -65.6844)
		(width 0.11684)
		(layer "F.Cu")
		(net "UART_BMC_5_RXD_R")
	)
	(segment
		(start 31.623 -67.100704)
		(end 32.201104 -66.5226)
		(width 0.11684)
		(layer "F.Cu")
		(net "UART_BMC_5_RXD_R")
	)
	(segment
		(start 31.623 -67.12585)
		(end 31.623 -67.100704)
		(width 0.11684)
		(layer "F.Cu")
		(net "UART_BMC_5_RXD_R")
	)
	(segment
		(start 35.052 -62.1284)
		(end 35.2806 -62.357)
		(width 0.11684)
		(layer "F.Cu")
		(net "UART_BMC_5_RXD_R")
	)
	(segment
		(start 35.2806 -62.357)
		(end 35.2806 -64.5414)
		(width 0.11684)
		(layer "F.Cu")
		(net "UART_BMC_5_RXD_R")
	)
	(segment
		(start 33.76295 -65.6844)
		(end 32.92475 -66.5226)
		(width 0.11684)
		(layer "F.Cu")
		(net "UART_BMC_5_RXD_R")
	)
	(via
		(at 27.50058 -35.21202)
		(size 0.508)
		(drill 0.254)
		(layers "F.Cu" "B.Cu")
		(net "UART_BMC_5_RXD_R")
	)
	(via
		(at 66.0908 -33.62833)
		(size 0.508)
		(drill 0.254)
		(layers "F.Cu" "B.Cu")
		(net "UART_BMC_5_RXD_R")
	)
	(via
		(at 40.194484 -20.033488)
		(size 0.508)
		(drill 0.254)
		(layers "F.Cu" "B.Cu")
		(net "UART_BMC_5_RXD_R")
	)
	(via
		(at 35.052 -62.1284)
		(size 0.508)
		(drill 0.254)
		(layers "F.Cu" "B.Cu")
		(net "UART_BMC_5_RXD_R")
	)
	(segment
		(start 66.0908 -33.62833)
		(end 66.0908 -34.23793)
		(width 0.11684)
		(layer "B.Cu")
		(net "UART_BMC_5_RXD_R")
	)
	(segment
		(start 29.46654 -60.04306)
		(end 29.869892 -59.639708)
		(width 0.11684)
		(layer "B.Cu")
		(net "UART_BMC_5_RXD_R")
	)
	(segment
		(start 31.8262 -54.0004)
		(end 31.218378 -53.392578)
		(width 0.11684)
		(layer "B.Cu")
		(net "UART_BMC_5_RXD_R")
	)
	(segment
		(start 30.230318 -61.98362)
		(end 29.738574 -61.98362)
		(width 0.11684)
		(layer "B.Cu")
		(net "UART_BMC_5_RXD_R")
	)
	(segment
		(start 29.869892 -59.639708)
		(end 30.442662 -58.257186)
		(width 0.11684)
		(layer "B.Cu")
		(net "UART_BMC_5_RXD_R")
	)
	(segment
		(start 30.8102 -45.698918)
		(end 27.50058 -42.389298)
		(width 0.11684)
		(layer "B.Cu")
		(net "UART_BMC_5_RXD_R")
	)
	(segment
		(start 30.442662 -58.257186)
		(end 30.442662 -57.926224)
		(width 0.11684)
		(layer "B.Cu")
		(net "UART_BMC_5_RXD_R")
	)
	(segment
		(start 31.84271 -62.3316)
		(end 31.40329 -62.77102)
		(width 0.11684)
		(layer "B.Cu")
		(net "UART_BMC_5_RXD_R")
	)
	(segment
		(start 29.46654 -61.711586)
		(end 29.46654 -60.04306)
		(width 0.11684)
		(layer "B.Cu")
		(net "UART_BMC_5_RXD_R")
	)
	(segment
		(start 31.218378 -53.392578)
		(end 30.8102 -52.407058)
		(width 0.11684)
		(layer "B.Cu")
		(net "UART_BMC_5_RXD_R")
	)
	(segment
		(start 30.442662 -57.926224)
		(end 31.8262 -54.586124)
		(width 0.11684)
		(layer "B.Cu")
		(net "UART_BMC_5_RXD_R")
	)
	(segment
		(start 35.052 -62.1284)
		(end 34.561526 -62.3316)
		(width 0.11684)
		(layer "B.Cu")
		(net "UART_BMC_5_RXD_R")
	)
	(segment
		(start 31.40329 -62.77102)
		(end 31.017718 -62.77102)
		(width 0.11684)
		(layer "B.Cu")
		(net "UART_BMC_5_RXD_R")
	)
	(segment
		(start 31.8262 -54.586124)
		(end 31.8262 -54.0004)
		(width 0.11684)
		(layer "B.Cu")
		(net "UART_BMC_5_RXD_R")
	)
	(segment
		(start 34.561526 -62.3316)
		(end 31.84271 -62.3316)
		(width 0.11684)
		(layer "B.Cu")
		(net "UART_BMC_5_RXD_R")
	)
	(segment
		(start 31.017718 -62.77102)
		(end 30.230318 -61.98362)
		(width 0.11684)
		(layer "B.Cu")
		(net "UART_BMC_5_RXD_R")
	)
	(segment
		(start 30.8102 -52.407058)
		(end 30.8102 -45.698918)
		(width 0.11684)
		(layer "B.Cu")
		(net "UART_BMC_5_RXD_R")
	)
	(segment
		(start 29.738574 -61.98362)
		(end 29.46654 -61.711586)
		(width 0.11684)
		(layer "B.Cu")
		(net "UART_BMC_5_RXD_R")
	)
	(segment
		(start 27.50058 -42.389298)
		(end 27.50058 -35.21202)
		(width 0.11684)
		(layer "B.Cu")
		(net "UART_BMC_5_RXD_R")
	)
	(segment
		(start 46.716696 -16.937736)
		(end 48.19904 -18.42008)
		(width 0.10668)
		(layer "In4.Cu")
		(net "UART_BMC_5_RXD_R")
	)
	(segment
		(start 68.09867 -27.341322)
		(end 66.031618 -29.408374)
		(width 0.10668)
		(layer "In4.Cu")
		(net "UART_BMC_5_RXD_R")
	)
	(segment
		(start 49.58588 -18.42008)
		(end 51.609498 -19.25828)
		(width 0.10668)
		(layer "In4.Cu")
		(net "UART_BMC_5_RXD_R")
	)
	(segment
		(start 40.767 -19.460972)
		(end 40.767 -18.275808)
		(width 0.10668)
		(layer "In4.Cu")
		(net "UART_BMC_5_RXD_R")
	)
	(segment
		(start 66.587878 -21.644356)
		(end 67.31 -22.366478)
		(width 0.10668)
		(layer "In4.Cu")
		(net "UART_BMC_5_RXD_R")
	)
	(segment
		(start 53.513482 -19.25828)
		(end 54.414674 -20.159472)
		(width 0.10668)
		(layer "In4.Cu")
		(net "UART_BMC_5_RXD_R")
	)
	(segment
		(start 51.609498 -19.25828)
		(end 53.513482 -19.25828)
		(width 0.10668)
		(layer "In4.Cu")
		(net "UART_BMC_5_RXD_R")
	)
	(segment
		(start 54.414674 -20.159472)
		(end 59.270392 -20.159472)
		(width 0.10668)
		(layer "In4.Cu")
		(net "UART_BMC_5_RXD_R")
	)
	(segment
		(start 68.09867 -24.920448)
		(end 68.09867 -27.341322)
		(width 0.10668)
		(layer "In4.Cu")
		(net "UART_BMC_5_RXD_R")
	)
	(segment
		(start 66.031618 -29.408374)
		(end 66.031618 -30.667706)
		(width 0.10668)
		(layer "In4.Cu")
		(net "UART_BMC_5_RXD_R")
	)
	(segment
		(start 60.755276 -21.644356)
		(end 66.587878 -21.644356)
		(width 0.10668)
		(layer "In4.Cu")
		(net "UART_BMC_5_RXD_R")
	)
	(segment
		(start 42.105072 -16.937736)
		(end 46.716696 -16.937736)
		(width 0.10668)
		(layer "In4.Cu")
		(net "UART_BMC_5_RXD_R")
	)
	(segment
		(start 67.31 -24.131778)
		(end 68.09867 -24.920448)
		(width 0.10668)
		(layer "In4.Cu")
		(net "UART_BMC_5_RXD_R")
	)
	(segment
		(start 67.31 -22.366478)
		(end 67.31 -24.131778)
		(width 0.10668)
		(layer "In4.Cu")
		(net "UART_BMC_5_RXD_R")
	)
	(segment
		(start 48.19904 -18.42008)
		(end 49.58588 -18.42008)
		(width 0.10668)
		(layer "In4.Cu")
		(net "UART_BMC_5_RXD_R")
	)
	(segment
		(start 65.321688 -31.377636)
		(end 65.321688 -32.093916)
		(width 0.10668)
		(layer "In4.Cu")
		(net "UART_BMC_5_RXD_R")
	)
	(segment
		(start 65.321688 -32.093916)
		(end 66.0908 -32.863028)
		(width 0.10668)
		(layer "In4.Cu")
		(net "UART_BMC_5_RXD_R")
	)
	(segment
		(start 59.270392 -20.159472)
		(end 60.755276 -21.644356)
		(width 0.10668)
		(layer "In4.Cu")
		(net "UART_BMC_5_RXD_R")
	)
	(segment
		(start 40.194484 -20.033488)
		(end 40.767 -19.460972)
		(width 0.10668)
		(layer "In4.Cu")
		(net "UART_BMC_5_RXD_R")
	)
	(segment
		(start 66.031618 -30.667706)
		(end 65.321688 -31.377636)
		(width 0.10668)
		(layer "In4.Cu")
		(net "UART_BMC_5_RXD_R")
	)
	(segment
		(start 66.0908 -32.863028)
		(end 66.0908 -33.62833)
		(width 0.10668)
		(layer "In4.Cu")
		(net "UART_BMC_5_RXD_R")
	)
	(segment
		(start 40.767 -18.275808)
		(end 42.105072 -16.937736)
		(width 0.10668)
		(layer "In4.Cu")
		(net "UART_BMC_5_RXD_R")
	)
	(segment
		(start 36.314126 -20.82546)
		(end 34.22904 -20.82546)
		(width 0.10668)
		(layer "In7.Cu")
		(net "UART_BMC_5_RXD_R")
	)
	(segment
		(start 31.62046 -19.807174)
		(end 31.239206 -19.807174)
		(width 0.10668)
		(layer "In7.Cu")
		(net "UART_BMC_5_RXD_R")
	)
	(segment
		(start 28.75661 -30.39999)
		(end 27.27706 -31.87954)
		(width 0.10668)
		(layer "In7.Cu")
		(net "UART_BMC_5_RXD_R")
	)
	(segment
		(start 30.988 -22.098)
		(end 30.988 -24.18461)
		(width 0.10668)
		(layer "In7.Cu")
		(net "UART_BMC_5_RXD_R")
	)
	(segment
		(start 28.75788 -28.080462)
		(end 28.75788 -30.288738)
		(width 0.10668)
		(layer "In7.Cu")
		(net "UART_BMC_5_RXD_R")
	)
	(segment
		(start 33.57118 -20.1676)
		(end 31.980886 -20.1676)
		(width 0.10668)
		(layer "In7.Cu")
		(net "UART_BMC_5_RXD_R")
	)
	(segment
		(start 40.194484 -20.033488)
		(end 39.300912 -20.92706)
		(width 0.10668)
		(layer "In7.Cu")
		(net "UART_BMC_5_RXD_R")
	)
	(segment
		(start 27.27706 -31.87954)
		(end 27.27706 -32.8295)
		(width 0.10668)
		(layer "In7.Cu")
		(net "UART_BMC_5_RXD_R")
	)
	(segment
		(start 28.75661 -30.290008)
		(end 28.75661 -30.39999)
		(width 0.10668)
		(layer "In7.Cu")
		(net "UART_BMC_5_RXD_R")
	)
	(segment
		(start 39.300912 -20.92706)
		(end 36.415726 -20.92706)
		(width 0.10668)
		(layer "In7.Cu")
		(net "UART_BMC_5_RXD_R")
	)
	(segment
		(start 30.9626 -22.0726)
		(end 30.988 -22.098)
		(width 0.10668)
		(layer "In7.Cu")
		(net "UART_BMC_5_RXD_R")
	)
	(segment
		(start 28.75788 -30.288738)
		(end 28.75661 -30.290008)
		(width 0.10668)
		(layer "In7.Cu")
		(net "UART_BMC_5_RXD_R")
	)
	(segment
		(start 27.27706 -32.8295)
		(end 27.3558 -32.90824)
		(width 0.10668)
		(layer "In7.Cu")
		(net "UART_BMC_5_RXD_R")
	)
	(segment
		(start 30.988 -24.18461)
		(end 28.75661 -26.416)
		(width 0.10668)
		(layer "In7.Cu")
		(net "UART_BMC_5_RXD_R")
	)
	(segment
		(start 27.3558 -32.90824)
		(end 27.3558 -35.06724)
		(width 0.10668)
		(layer "In7.Cu")
		(net "UART_BMC_5_RXD_R")
	)
	(segment
		(start 34.22904 -20.82546)
		(end 33.57118 -20.1676)
		(width 0.10668)
		(layer "In7.Cu")
		(net "UART_BMC_5_RXD_R")
	)
	(segment
		(start 31.239206 -19.807174)
		(end 30.9626 -20.08378)
		(width 0.10668)
		(layer "In7.Cu")
		(net "UART_BMC_5_RXD_R")
	)
	(segment
		(start 30.9626 -20.08378)
		(end 30.9626 -22.0726)
		(width 0.10668)
		(layer "In7.Cu")
		(net "UART_BMC_5_RXD_R")
	)
	(segment
		(start 27.3558 -35.06724)
		(end 27.50058 -35.21202)
		(width 0.10668)
		(layer "In7.Cu")
		(net "UART_BMC_5_RXD_R")
	)
	(segment
		(start 28.75661 -28.079192)
		(end 28.75788 -28.080462)
		(width 0.10668)
		(layer "In7.Cu")
		(net "UART_BMC_5_RXD_R")
	)
	(segment
		(start 31.980886 -20.1676)
		(end 31.62046 -19.807174)
		(width 0.10668)
		(layer "In7.Cu")
		(net "UART_BMC_5_RXD_R")
	)
	(segment
		(start 36.415726 -20.92706)
		(end 36.314126 -20.82546)
		(width 0.10668)
		(layer "In7.Cu")
		(net "UART_BMC_5_RXD_R")
	)
	(segment
		(start 28.75661 -26.416)
		(end 28.75661 -28.079192)
		(width 0.10668)
		(layer "In7.Cu")
		(net "UART_BMC_5_RXD_R")
	)
	(segment
		(start 59.29503 -41.771316)
		(end 59.690254 -41.376092)
		(width 0.11684)
		(layer "F.Cu")
		(net "UART_BMC_5_RXD")
	)
	(via
		(at 59.690254 -41.376092)
		(size 0.4572)
		(drill 0.254)
		(layers "F.Cu" "B.Cu")
		(net "UART_BMC_5_RXD")
	)
	(via
		(at 62.1919 -38.9509)
		(size 0.6604)
		(drill 0.3302)
		(layers "F.Cu" "B.Cu")
		(net "UART_BMC_5_RXD")
	)
	(segment
		(start 64.6176 -36.455604)
		(end 66.035174 -35.03803)
		(width 0.11684)
		(layer "B.Cu")
		(net "UART_BMC_5_RXD")
	)
	(segment
		(start 62.1919 -39.087044)
		(end 62.1919 -38.9509)
		(width 0.11684)
		(layer "B.Cu")
		(net "UART_BMC_5_RXD")
	)
	(segment
		(start 60.8838 -40.741346)
		(end 60.8838 -40.395144)
		(width 0.11684)
		(layer "B.Cu")
		(net "UART_BMC_5_RXD")
	)
	(segment
		(start 60.8838 -40.395144)
		(end 62.1919 -39.087044)
		(width 0.11684)
		(layer "B.Cu")
		(net "UART_BMC_5_RXD")
	)
	(segment
		(start 60.641484 -40.983662)
		(end 60.8838 -40.741346)
		(width 0.11684)
		(layer "B.Cu")
		(net "UART_BMC_5_RXD")
	)
	(segment
		(start 60.082684 -40.983662)
		(end 60.641484 -40.983662)
		(width 0.11684)
		(layer "B.Cu")
		(net "UART_BMC_5_RXD")
	)
	(segment
		(start 62.1919 -38.9509)
		(end 64.6176 -36.5252)
		(width 0.11684)
		(layer "B.Cu")
		(net "UART_BMC_5_RXD")
	)
	(segment
		(start 66.035174 -35.03803)
		(end 66.0908 -35.03803)
		(width 0.11684)
		(layer "B.Cu")
		(net "UART_BMC_5_RXD")
	)
	(segment
		(start 59.690254 -41.376092)
		(end 60.082684 -40.983662)
		(width 0.11684)
		(layer "B.Cu")
		(net "UART_BMC_5_RXD")
	)
	(segment
		(start 64.6176 -36.5252)
		(end 64.6176 -36.455604)
		(width 0.11684)
		(layer "B.Cu")
		(net "UART_BMC_5_RXD")
	)
	(segment
		(start 19.655536 -62.538864)
		(end 19.655536 -60.98159)
		(width 0.11684)
		(layer "F.Cu")
		(net "UART_BMC_1_RXD_R")
	)
	(segment
		(start 19.3548 -62.8396)
		(end 19.655536 -62.538864)
		(width 0.11684)
		(layer "F.Cu")
		(net "UART_BMC_1_RXD_R")
	)
	(via
		(at 19.3548 -62.8396)
		(size 0.508)
		(drill 0.254)
		(layers "F.Cu" "B.Cu")
		(net "UART_BMC_1_RXD_R")
	)
	(via
		(at 18.6817 -42.33672)
		(size 0.508)
		(drill 0.254)
		(layers "F.Cu" "B.Cu")
		(net "UART_BMC_1_RXD_R")
	)
	(via
		(at 60.87364 -23.34768)
		(size 0.508)
		(drill 0.254)
		(layers "F.Cu" "B.Cu")
		(net "UART_BMC_1_RXD_R")
	)
	(via
		(at 60.9346 -29.8577)
		(size 0.508)
		(drill 0.254)
		(layers "F.Cu" "B.Cu")
		(net "UART_BMC_1_RXD_R")
	)
	(segment
		(start 60.8838 -30.439614)
		(end 60.85586 -30.467554)
		(width 0.11684)
		(layer "B.Cu")
		(net "UART_BMC_1_RXD_R")
	)
	(segment
		(start 60.9346 -29.8831)
		(end 60.8838 -29.9339)
		(width 0.11684)
		(layer "B.Cu")
		(net "UART_BMC_1_RXD_R")
	)
	(segment
		(start 60.8838 -29.9339)
		(end 60.8838 -30.439614)
		(width 0.11684)
		(layer "B.Cu")
		(net "UART_BMC_1_RXD_R")
	)
	(segment
		(start 60.9346 -29.8577)
		(end 60.9346 -29.8831)
		(width 0.11684)
		(layer "B.Cu")
		(net "UART_BMC_1_RXD_R")
	)
	(segment
		(start 40.193976 -26.74366)
		(end 41.37406 -26.74366)
		(width 0.08382)
		(layer "In2.Cu")
		(net "UART_BMC_1_RXD_R")
	)
	(segment
		(start 20.025868 -41.92778)
		(end 20.807172 -41.92778)
		(width 0.08382)
		(layer "In2.Cu")
		(net "UART_BMC_1_RXD_R")
	)
	(segment
		(start 18.8976 -40.132)
		(end 18.8976 -40.799512)
		(width 0.08382)
		(layer "In2.Cu")
		(net "UART_BMC_1_RXD_R")
	)
	(segment
		(start 59.480704 -23.34768)
		(end 60.87364 -23.34768)
		(width 0.08382)
		(layer "In2.Cu")
		(net "UART_BMC_1_RXD_R")
	)
	(segment
		(start 50.956972 -24.29129)
		(end 53.983382 -24.29129)
		(width 0.08382)
		(layer "In2.Cu")
		(net "UART_BMC_1_RXD_R")
	)
	(segment
		(start 22.210268 -36.146486)
		(end 22.201886 -36.136326)
		(width 0.08382)
		(layer "In2.Cu")
		(net "UART_BMC_1_RXD_R")
	)
	(segment
		(start 41.88714 -27.25674)
		(end 49.29124 -27.25674)
		(width 0.08382)
		(layer "In2.Cu")
		(net "UART_BMC_1_RXD_R")
	)
	(segment
		(start 22.199854 -36.119054)
		(end 22.1996 -36.116514)
		(width 0.08382)
		(layer "In2.Cu")
		(net "UART_BMC_1_RXD_R")
	)
	(segment
		(start 26.2382 -23.266146)
		(end 26.618946 -22.8854)
		(width 0.08382)
		(layer "In2.Cu")
		(net "UART_BMC_1_RXD_R")
	)
	(segment
		(start 22.208998 -34.102802)
		(end 22.597618 -33.714182)
		(width 0.08382)
		(layer "In2.Cu")
		(net "UART_BMC_1_RXD_R")
	)
	(segment
		(start 34.2138 -22.7838)
		(end 35.5346 -21.463)
		(width 0.08382)
		(layer "In2.Cu")
		(net "UART_BMC_1_RXD_R")
	)
	(segment
		(start 18.160492 -39.39667)
		(end 18.170398 -39.404798)
		(width 0.08382)
		(layer "In2.Cu")
		(net "UART_BMC_1_RXD_R")
	)
	(segment
		(start 18.6817 -42.33672)
		(end 18.360136 -42.015156)
		(width 0.08382)
		(layer "In2.Cu")
		(net "UART_BMC_1_RXD_R")
	)
	(segment
		(start 22.1996 -36.116514)
		(end 22.1996 -34.12363)
		(width 0.08382)
		(layer "In2.Cu")
		(net "UART_BMC_1_RXD_R")
	)
	(segment
		(start 26.2382 -30.48)
		(end 26.2382 -23.266146)
		(width 0.08382)
		(layer "In2.Cu")
		(net "UART_BMC_1_RXD_R")
	)
	(segment
		(start 49.53 -27.01798)
		(end 49.53 -25.718262)
		(width 0.08382)
		(layer "In2.Cu")
		(net "UART_BMC_1_RXD_R")
	)
	(segment
		(start 36.259008 -21.463)
		(end 37.342064 -21.911564)
		(width 0.08382)
		(layer "In2.Cu")
		(net "UART_BMC_1_RXD_R")
	)
	(segment
		(start 23.749 -33.7058)
		(end 25.1587 -32.2961)
		(width 0.08382)
		(layer "In2.Cu")
		(net "UART_BMC_1_RXD_R")
	)
	(segment
		(start 18.170398 -39.404798)
		(end 18.8976 -40.132)
		(width 0.08382)
		(layer "In2.Cu")
		(net "UART_BMC_1_RXD_R")
	)
	(segment
		(start 35.5346 -21.463)
		(end 36.259008 -21.463)
		(width 0.08382)
		(layer "In2.Cu")
		(net "UART_BMC_1_RXD_R")
	)
	(segment
		(start 22.31771 -40.417242)
		(end 22.31771 -36.253928)
		(width 0.08382)
		(layer "In2.Cu")
		(net "UART_BMC_1_RXD_R")
	)
	(segment
		(start 49.53 -25.718262)
		(end 50.956972 -24.29129)
		(width 0.08382)
		(layer "In2.Cu")
		(net "UART_BMC_1_RXD_R")
	)
	(segment
		(start 16.992346 -39.3954)
		(end 18.14957 -39.3954)
		(width 0.08382)
		(layer "In2.Cu")
		(net "UART_BMC_1_RXD_R")
	)
	(segment
		(start 27.914346 -22.8854)
		(end 28.845256 -23.81631)
		(width 0.08382)
		(layer "In2.Cu")
		(net "UART_BMC_1_RXD_R")
	)
	(segment
		(start 31.505144 -23.81631)
		(end 32.537654 -22.7838)
		(width 0.08382)
		(layer "In2.Cu")
		(net "UART_BMC_1_RXD_R")
	)
	(segment
		(start 25.1587 -32.2961)
		(end 25.1587 -31.5595)
		(width 0.08382)
		(layer "In2.Cu")
		(net "UART_BMC_1_RXD_R")
	)
	(segment
		(start 18.360136 -42.015156)
		(end 17.300956 -42.015156)
		(width 0.08382)
		(layer "In2.Cu")
		(net "UART_BMC_1_RXD_R")
	)
	(segment
		(start 38.33876 -24.888444)
		(end 40.193976 -26.74366)
		(width 0.08382)
		(layer "In2.Cu")
		(net "UART_BMC_1_RXD_R")
	)
	(segment
		(start 41.37406 -26.74366)
		(end 41.88714 -27.25674)
		(width 0.08382)
		(layer "In2.Cu")
		(net "UART_BMC_1_RXD_R")
	)
	(segment
		(start 25.1587 -31.5595)
		(end 26.2382 -30.48)
		(width 0.08382)
		(layer "In2.Cu")
		(net "UART_BMC_1_RXD_R")
	)
	(segment
		(start 18.8976 -40.799512)
		(end 20.025868 -41.92778)
		(width 0.08382)
		(layer "In2.Cu")
		(net "UART_BMC_1_RXD_R")
	)
	(segment
		(start 22.20087 -36.12007)
		(end 22.199854 -36.119054)
		(width 0.08382)
		(layer "In2.Cu")
		(net "UART_BMC_1_RXD_R")
	)
	(segment
		(start 22.20087 -34.112708)
		(end 22.208998 -34.102802)
		(width 0.08382)
		(layer "In2.Cu")
		(net "UART_BMC_1_RXD_R")
	)
	(segment
		(start 16.74749 -41.46169)
		(end 16.74749 -39.640256)
		(width 0.08382)
		(layer "In2.Cu")
		(net "UART_BMC_1_RXD_R")
	)
	(segment
		(start 22.1996 -34.12363)
		(end 22.20087 -34.112708)
		(width 0.08382)
		(layer "In2.Cu")
		(net "UART_BMC_1_RXD_R")
	)
	(segment
		(start 22.597618 -33.714182)
		(end 22.606508 -33.70707)
		(width 0.08382)
		(layer "In2.Cu")
		(net "UART_BMC_1_RXD_R")
	)
	(segment
		(start 18.14957 -39.3954)
		(end 18.160492 -39.39667)
		(width 0.08382)
		(layer "In2.Cu")
		(net "UART_BMC_1_RXD_R")
	)
	(segment
		(start 22.61743 -33.7058)
		(end 23.749 -33.7058)
		(width 0.08382)
		(layer "In2.Cu")
		(net "UART_BMC_1_RXD_R")
	)
	(segment
		(start 53.983382 -24.29129)
		(end 54.430676 -23.843996)
		(width 0.08382)
		(layer "In2.Cu")
		(net "UART_BMC_1_RXD_R")
	)
	(segment
		(start 22.20087 -36.132008)
		(end 22.20087 -36.12007)
		(width 0.08382)
		(layer "In2.Cu")
		(net "UART_BMC_1_RXD_R")
	)
	(segment
		(start 22.201124 -36.134548)
		(end 22.20087 -36.132008)
		(width 0.08382)
		(layer "In2.Cu")
		(net "UART_BMC_1_RXD_R")
	)
	(segment
		(start 17.300956 -42.015156)
		(end 16.74749 -41.46169)
		(width 0.08382)
		(layer "In2.Cu")
		(net "UART_BMC_1_RXD_R")
	)
	(segment
		(start 37.342064 -21.911564)
		(end 38.33876 -22.90826)
		(width 0.08382)
		(layer "In2.Cu")
		(net "UART_BMC_1_RXD_R")
	)
	(segment
		(start 20.807172 -41.92778)
		(end 22.31771 -40.417242)
		(width 0.08382)
		(layer "In2.Cu")
		(net "UART_BMC_1_RXD_R")
	)
	(segment
		(start 32.537654 -22.7838)
		(end 34.2138 -22.7838)
		(width 0.08382)
		(layer "In2.Cu")
		(net "UART_BMC_1_RXD_R")
	)
	(segment
		(start 28.845256 -23.81631)
		(end 31.505144 -23.81631)
		(width 0.08382)
		(layer "In2.Cu")
		(net "UART_BMC_1_RXD_R")
	)
	(segment
		(start 26.618946 -22.8854)
		(end 27.914346 -22.8854)
		(width 0.08382)
		(layer "In2.Cu")
		(net "UART_BMC_1_RXD_R")
	)
	(segment
		(start 49.29124 -27.25674)
		(end 49.53 -27.01798)
		(width 0.08382)
		(layer "In2.Cu")
		(net "UART_BMC_1_RXD_R")
	)
	(segment
		(start 16.74749 -39.640256)
		(end 16.992346 -39.3954)
		(width 0.08382)
		(layer "In2.Cu")
		(net "UART_BMC_1_RXD_R")
	)
	(segment
		(start 58.984388 -23.843996)
		(end 59.480704 -23.34768)
		(width 0.08382)
		(layer "In2.Cu")
		(net "UART_BMC_1_RXD_R")
	)
	(segment
		(start 22.606508 -33.70707)
		(end 22.61743 -33.7058)
		(width 0.08382)
		(layer "In2.Cu")
		(net "UART_BMC_1_RXD_R")
	)
	(segment
		(start 38.33876 -22.90826)
		(end 38.33876 -24.888444)
		(width 0.08382)
		(layer "In2.Cu")
		(net "UART_BMC_1_RXD_R")
	)
	(segment
		(start 22.31771 -36.253928)
		(end 22.210268 -36.146486)
		(width 0.08382)
		(layer "In2.Cu")
		(net "UART_BMC_1_RXD_R")
	)
	(segment
		(start 54.430676 -23.843996)
		(end 58.984388 -23.843996)
		(width 0.08382)
		(layer "In2.Cu")
		(net "UART_BMC_1_RXD_R")
	)
	(segment
		(start 22.201886 -36.136326)
		(end 22.201124 -36.134548)
		(width 0.08382)
		(layer "In2.Cu")
		(net "UART_BMC_1_RXD_R")
	)
	(segment
		(start 61.334904 -29.191204)
		(end 61.334904 -28.575762)
		(width 0.10668)
		(layer "In7.Cu")
		(net "UART_BMC_1_RXD_R")
	)
	(segment
		(start 61.59754 -26.791412)
		(end 61.330078 -26.52395)
		(width 0.10668)
		(layer "In7.Cu")
		(net "UART_BMC_1_RXD_R")
	)
	(segment
		(start 61.330078 -26.52395)
		(end 61.330078 -25.876504)
		(width 0.10668)
		(layer "In7.Cu")
		(net "UART_BMC_1_RXD_R")
	)
	(segment
		(start 60.9346 -29.591508)
		(end 61.334904 -29.191204)
		(width 0.10668)
		(layer "In7.Cu")
		(net "UART_BMC_1_RXD_R")
	)
	(segment
		(start 60.9346 -29.8577)
		(end 60.9346 -29.591508)
		(width 0.10668)
		(layer "In7.Cu")
		(net "UART_BMC_1_RXD_R")
	)
	(segment
		(start 61.59754 -28.313126)
		(end 61.59754 -26.791412)
		(width 0.10668)
		(layer "In7.Cu")
		(net "UART_BMC_1_RXD_R")
	)
	(segment
		(start 61.330078 -25.876504)
		(end 61.685424 -25.521158)
		(width 0.10668)
		(layer "In7.Cu")
		(net "UART_BMC_1_RXD_R")
	)
	(segment
		(start 60.87364 -24.34336)
		(end 60.87364 -23.34768)
		(width 0.10668)
		(layer "In7.Cu")
		(net "UART_BMC_1_RXD_R")
	)
	(segment
		(start 61.334904 -28.575762)
		(end 61.59754 -28.313126)
		(width 0.10668)
		(layer "In7.Cu")
		(net "UART_BMC_1_RXD_R")
	)
	(segment
		(start 61.685424 -25.521158)
		(end 61.685424 -25.155144)
		(width 0.10668)
		(layer "In7.Cu")
		(net "UART_BMC_1_RXD_R")
	)
	(segment
		(start 61.685424 -25.155144)
		(end 60.87364 -24.34336)
		(width 0.10668)
		(layer "In7.Cu")
		(net "UART_BMC_1_RXD_R")
	)
	(segment
		(start 16.87703 -51.30165)
		(end 16.87703 -50.67427)
		(width 0.08382)
		(layer "In9.Cu")
		(net "UART_BMC_1_RXD_R")
	)
	(segment
		(start 17.993868 -43.333416)
		(end 18.6817 -42.645584)
		(width 0.08382)
		(layer "In9.Cu")
		(net "UART_BMC_1_RXD_R")
	)
	(segment
		(start 15.825724 -47.37608)
		(end 16.761714 -46.44009)
		(width 0.08382)
		(layer "In9.Cu")
		(net "UART_BMC_1_RXD_R")
	)
	(segment
		(start 17.948148 -61.91504)
		(end 16.98752 -60.954412)
		(width 0.08382)
		(layer "In9.Cu")
		(net "UART_BMC_1_RXD_R")
	)
	(segment
		(start 16.98752 -59.775344)
		(end 16.19885 -58.986674)
		(width 0.08382)
		(layer "In9.Cu")
		(net "UART_BMC_1_RXD_R")
	)
	(segment
		(start 19.3548 -62.8396)
		(end 19.3548 -62.5348)
		(width 0.08382)
		(layer "In9.Cu")
		(net "UART_BMC_1_RXD_R")
	)
	(segment
		(start 16.98752 -60.954412)
		(end 16.98752 -59.775344)
		(width 0.08382)
		(layer "In9.Cu")
		(net "UART_BMC_1_RXD_R")
	)
	(segment
		(start 16.761714 -44.121832)
		(end 17.55013 -43.333416)
		(width 0.08382)
		(layer "In9.Cu")
		(net "UART_BMC_1_RXD_R")
	)
	(segment
		(start 19.3548 -62.5348)
		(end 18.73504 -61.91504)
		(width 0.08382)
		(layer "In9.Cu")
		(net "UART_BMC_1_RXD_R")
	)
	(segment
		(start 17.55013 -43.333416)
		(end 17.993868 -43.333416)
		(width 0.08382)
		(layer "In9.Cu")
		(net "UART_BMC_1_RXD_R")
	)
	(segment
		(start 16.11376 -48.629316)
		(end 15.825724 -48.34128)
		(width 0.08382)
		(layer "In9.Cu")
		(net "UART_BMC_1_RXD_R")
	)
	(segment
		(start 16.19885 -57.512458)
		(end 16.35125 -57.360058)
		(width 0.08382)
		(layer "In9.Cu")
		(net "UART_BMC_1_RXD_R")
	)
	(segment
		(start 16.35125 -51.82743)
		(end 16.87703 -51.30165)
		(width 0.08382)
		(layer "In9.Cu")
		(net "UART_BMC_1_RXD_R")
	)
	(segment
		(start 18.6817 -42.645584)
		(end 18.6817 -42.33672)
		(width 0.08382)
		(layer "In9.Cu")
		(net "UART_BMC_1_RXD_R")
	)
	(segment
		(start 15.825724 -48.34128)
		(end 15.825724 -47.37608)
		(width 0.08382)
		(layer "In9.Cu")
		(net "UART_BMC_1_RXD_R")
	)
	(segment
		(start 16.87703 -50.67427)
		(end 16.11376 -49.911)
		(width 0.08382)
		(layer "In9.Cu")
		(net "UART_BMC_1_RXD_R")
	)
	(segment
		(start 16.11376 -49.911)
		(end 16.11376 -48.629316)
		(width 0.08382)
		(layer "In9.Cu")
		(net "UART_BMC_1_RXD_R")
	)
	(segment
		(start 16.19885 -58.986674)
		(end 16.19885 -57.512458)
		(width 0.08382)
		(layer "In9.Cu")
		(net "UART_BMC_1_RXD_R")
	)
	(segment
		(start 18.73504 -61.91504)
		(end 17.948148 -61.91504)
		(width 0.08382)
		(layer "In9.Cu")
		(net "UART_BMC_1_RXD_R")
	)
	(segment
		(start 16.761714 -46.44009)
		(end 16.761714 -44.121832)
		(width 0.08382)
		(layer "In9.Cu")
		(net "UART_BMC_1_RXD_R")
	)
	(segment
		(start 16.35125 -57.360058)
		(end 16.35125 -51.82743)
		(width 0.08382)
		(layer "In9.Cu")
		(net "UART_BMC_1_RXD_R")
	)
	(segment
		(start 55.295038 -41.771316)
		(end 55.690262 -41.376092)
		(width 0.11684)
		(layer "F.Cu")
		(net "UART_BMC_1_RXD")
	)
	(via
		(at 60.102242 -32.714438)
		(size 0.6604)
		(drill 0.3302)
		(layers "F.Cu" "B.Cu")
		(net "UART_BMC_1_RXD")
	)
	(via
		(at 55.690262 -41.376092)
		(size 0.4572)
		(drill 0.254)
		(layers "F.Cu" "B.Cu")
		(net "UART_BMC_1_RXD")
	)
	(segment
		(start 55.2704 -40.705786)
		(end 55.2704 -39.646352)
		(width 0.11684)
		(layer "B.Cu")
		(net "UART_BMC_1_RXD")
	)
	(segment
		(start 60.102242 -32.714438)
		(end 60.102242 -32.328358)
		(width 0.11684)
		(layer "B.Cu")
		(net "UART_BMC_1_RXD")
	)
	(segment
		(start 58.318908 -36.7157)
		(end 59.379866 -36.276788)
		(width 0.11684)
		(layer "B.Cu")
		(net "UART_BMC_1_RXD")
	)
	(segment
		(start 60.85586 -31.57474)
		(end 60.85586 -31.267654)
		(width 0.11684)
		(layer "B.Cu")
		(net "UART_BMC_1_RXD")
	)
	(segment
		(start 55.529226 -39.387526)
		(end 55.646828 -39.387526)
		(width 0.11684)
		(layer "B.Cu")
		(net "UART_BMC_1_RXD")
	)
	(segment
		(start 60.198 -32.810196)
		(end 60.102242 -32.714438)
		(width 0.11684)
		(layer "B.Cu")
		(net "UART_BMC_1_RXD")
	)
	(segment
		(start 55.690262 -41.125648)
		(end 55.2704 -40.705786)
		(width 0.11684)
		(layer "B.Cu")
		(net "UART_BMC_1_RXD")
	)
	(segment
		(start 59.379866 -36.276788)
		(end 60.198 -35.458654)
		(width 0.11684)
		(layer "B.Cu")
		(net "UART_BMC_1_RXD")
	)
	(segment
		(start 60.102242 -32.328358)
		(end 60.85586 -31.57474)
		(width 0.11684)
		(layer "B.Cu")
		(net "UART_BMC_1_RXD")
	)
	(segment
		(start 55.646828 -39.387526)
		(end 58.318908 -36.7157)
		(width 0.11684)
		(layer "B.Cu")
		(net "UART_BMC_1_RXD")
	)
	(segment
		(start 55.2704 -39.646352)
		(end 55.529226 -39.387526)
		(width 0.11684)
		(layer "B.Cu")
		(net "UART_BMC_1_RXD")
	)
	(segment
		(start 55.690262 -41.376092)
		(end 55.690262 -41.125648)
		(width 0.11684)
		(layer "B.Cu")
		(net "UART_BMC_1_RXD")
	)
	(segment
		(start 60.198 -35.458654)
		(end 60.198 -32.810196)
		(width 0.11684)
		(layer "B.Cu")
		(net "UART_BMC_1_RXD")
	)
	(segment
		(start 48.499776 -42.976038)
		(end 48.895 -42.580814)
		(width 0.11684)
		(layer "F.Cu")
		(net "UART_6_BMC_R_TXD")
	)
	(segment
		(start 48.895 -42.580814)
		(end 48.895 -42.571162)
		(width 0.11684)
		(layer "F.Cu")
		(net "UART_6_BMC_R_TXD")
	)
	(via
		(at 48.499776 -42.976038)
		(size 0.4572)
		(drill 0.254)
		(layers "F.Cu" "B.Cu")
		(net "UART_6_BMC_R_TXD")
	)
	(segment
		(start 44.7548 -38.5064)
		(end 44.173394 -38.5064)
		(width 0.11684)
		(layer "B.Cu")
		(net "UART_6_BMC_R_TXD")
	)
	(segment
		(start 48.499776 -42.976038)
		(end 48.1076 -42.583862)
		(width 0.11684)
		(layer "B.Cu")
		(net "UART_6_BMC_R_TXD")
	)
	(segment
		(start 40.235632 -33.481772)
		(end 40.235632 -31.773622)
		(width 0.11684)
		(layer "B.Cu")
		(net "UART_6_BMC_R_TXD")
	)
	(segment
		(start 46.503336 -40.415718)
		(end 46.273974 -40.186356)
		(width 0.11684)
		(layer "B.Cu")
		(net "UART_6_BMC_R_TXD")
	)
	(segment
		(start 40.8432 -31.166054)
		(end 40.8432 -30.453076)
		(width 0.11684)
		(layer "B.Cu")
		(net "UART_6_BMC_R_TXD")
	)
	(segment
		(start 47.30369 -41.160954)
		(end 47.118016 -40.97528)
		(width 0.11684)
		(layer "B.Cu")
		(net "UART_6_BMC_R_TXD")
	)
	(segment
		(start 47.30369 -41.537382)
		(end 47.30369 -41.160954)
		(width 0.11684)
		(layer "B.Cu")
		(net "UART_6_BMC_R_TXD")
	)
	(segment
		(start 46.503336 -40.737028)
		(end 46.503336 -40.415718)
		(width 0.11684)
		(layer "B.Cu")
		(net "UART_6_BMC_R_TXD")
	)
	(segment
		(start 40.235632 -31.773622)
		(end 40.8432 -31.166054)
		(width 0.11684)
		(layer "B.Cu")
		(net "UART_6_BMC_R_TXD")
	)
	(segment
		(start 48.1076 -42.583862)
		(end 48.1076 -42.01668)
		(width 0.11684)
		(layer "B.Cu")
		(net "UART_6_BMC_R_TXD")
	)
	(segment
		(start 41.0972 -35.430206)
		(end 41.0972 -34.34334)
		(width 0.11684)
		(layer "B.Cu")
		(net "UART_6_BMC_R_TXD")
	)
	(segment
		(start 45.4152 -39.1668)
		(end 44.7548 -38.5064)
		(width 0.11684)
		(layer "B.Cu")
		(net "UART_6_BMC_R_TXD")
	)
	(segment
		(start 45.6946 -40.0304)
		(end 45.6946 -39.5732)
		(width 0.11684)
		(layer "B.Cu")
		(net "UART_6_BMC_R_TXD")
	)
	(segment
		(start 41.0972 -34.34334)
		(end 40.235632 -33.481772)
		(width 0.11684)
		(layer "B.Cu")
		(net "UART_6_BMC_R_TXD")
	)
	(segment
		(start 48.1076 -42.01668)
		(end 47.858426 -41.767506)
		(width 0.11684)
		(layer "B.Cu")
		(net "UART_6_BMC_R_TXD")
	)
	(segment
		(start 47.118016 -40.97528)
		(end 46.741588 -40.97528)
		(width 0.11684)
		(layer "B.Cu")
		(net "UART_6_BMC_R_TXD")
	)
	(segment
		(start 45.4152 -39.2938)
		(end 45.4152 -39.1668)
		(width 0.11684)
		(layer "B.Cu")
		(net "UART_6_BMC_R_TXD")
	)
	(segment
		(start 47.533814 -41.767506)
		(end 47.30369 -41.537382)
		(width 0.11684)
		(layer "B.Cu")
		(net "UART_6_BMC_R_TXD")
	)
	(segment
		(start 40.8432 -30.453076)
		(end 40.666924 -30.2768)
		(width 0.11684)
		(layer "B.Cu")
		(net "UART_6_BMC_R_TXD")
	)
	(segment
		(start 46.273974 -40.186356)
		(end 45.850556 -40.186356)
		(width 0.11684)
		(layer "B.Cu")
		(net "UART_6_BMC_R_TXD")
	)
	(segment
		(start 46.741588 -40.97528)
		(end 46.503336 -40.737028)
		(width 0.11684)
		(layer "B.Cu")
		(net "UART_6_BMC_R_TXD")
	)
	(segment
		(start 44.173394 -38.5064)
		(end 41.0972 -35.430206)
		(width 0.11684)
		(layer "B.Cu")
		(net "UART_6_BMC_R_TXD")
	)
	(segment
		(start 45.850556 -40.186356)
		(end 45.6946 -40.0304)
		(width 0.11684)
		(layer "B.Cu")
		(net "UART_6_BMC_R_TXD")
	)
	(segment
		(start 45.6946 -39.5732)
		(end 45.4152 -39.2938)
		(width 0.11684)
		(layer "B.Cu")
		(net "UART_6_BMC_R_TXD")
	)
	(segment
		(start 40.666924 -30.2768)
		(end 40.25265 -30.2768)
		(width 0.11684)
		(layer "B.Cu")
		(net "UART_6_BMC_R_TXD")
	)
	(segment
		(start 47.858426 -41.767506)
		(end 47.533814 -41.767506)
		(width 0.11684)
		(layer "B.Cu")
		(net "UART_6_BMC_R_TXD")
	)
	(segment
		(start 48.0949 -40.17137)
		(end 47.699676 -39.776146)
		(width 0.11684)
		(layer "F.Cu")
		(net "UART_6_BMC_R_RXD")
	)
	(segment
		(start 44.704 -35.02025)
		(end 44.704 -35.687)
		(width 0.11684)
		(layer "F.Cu")
		(net "UART_6_BMC_R_RXD")
	)
	(via
		(at 47.699676 -39.776146)
		(size 0.4572)
		(drill 0.254)
		(layers "F.Cu" "B.Cu")
		(net "UART_6_BMC_R_RXD")
	)
	(via
		(at 44.704 -35.687)
		(size 0.508)
		(drill 0.254)
		(layers "F.Cu" "B.Cu")
		(net "UART_6_BMC_R_RXD")
	)
	(segment
		(start 43.25366 -37.3507)
		(end 43.25366 -36.9697)
		(width 0.10668)
		(layer "In7.Cu")
		(net "UART_6_BMC_R_RXD")
	)
	(segment
		(start 47.699676 -39.776146)
		(end 48.1076 -39.368222)
		(width 0.10668)
		(layer "In7.Cu")
		(net "UART_6_BMC_R_RXD")
	)
	(segment
		(start 43.59656 -37.6936)
		(end 43.25366 -37.3507)
		(width 0.10668)
		(layer "In7.Cu")
		(net "UART_6_BMC_R_RXD")
	)
	(segment
		(start 47.4218 -37.6936)
		(end 43.59656 -37.6936)
		(width 0.10668)
		(layer "In7.Cu")
		(net "UART_6_BMC_R_RXD")
	)
	(segment
		(start 48.1076 -39.368222)
		(end 48.1076 -38.3794)
		(width 0.10668)
		(layer "In7.Cu")
		(net "UART_6_BMC_R_RXD")
	)
	(segment
		(start 44.53636 -35.687)
		(end 44.704 -35.687)
		(width 0.10668)
		(layer "In7.Cu")
		(net "UART_6_BMC_R_RXD")
	)
	(segment
		(start 43.25366 -36.9697)
		(end 44.53636 -35.687)
		(width 0.10668)
		(layer "In7.Cu")
		(net "UART_6_BMC_R_RXD")
	)
	(segment
		(start 48.1076 -38.3794)
		(end 47.4218 -37.6936)
		(width 0.10668)
		(layer "In7.Cu")
		(net "UART_6_BMC_R_RXD")
	)
	(segment
		(start 42.379138 -38.71341)
		(end 42.4942 -39.292022)
		(width 0.11684)
		(layer "F.Cu")
		(net "FM_BMC_CRASHLOG_TRIG_R1_N")
	)
	(segment
		(start 44.603162 -42.571162)
		(end 44.895008 -42.571162)
		(width 0.11684)
		(layer "F.Cu")
		(net "FM_BMC_CRASHLOG_TRIG_R1_N")
	)
	(segment
		(start 43.082972 -41.367456)
		(end 44.06265 -42.347134)
		(width 0.11684)
		(layer "F.Cu")
		(net "FM_BMC_CRASHLOG_TRIG_R1_N")
	)
	(segment
		(start 42.388282 -40.004238)
		(end 42.408602 -40.106854)
		(width 0.11684)
		(layer "F.Cu")
		(net "FM_BMC_CRASHLOG_TRIG_R1_N")
	)
	(segment
		(start 44.06265 -42.347134)
		(end 44.603162 -42.571162)
		(width 0.11684)
		(layer "F.Cu")
		(net "FM_BMC_CRASHLOG_TRIG_R1_N")
	)
	(segment
		(start 42.4942 -39.292022)
		(end 42.4942 -39.470838)
		(width 0.11684)
		(layer "F.Cu")
		(net "FM_BMC_CRASHLOG_TRIG_R1_N")
	)
	(segment
		(start 42.08526 -38.003988)
		(end 42.379138 -38.71341)
		(width 0.11684)
		(layer "F.Cu")
		(net "FM_BMC_CRASHLOG_TRIG_R1_N")
	)
	(segment
		(start 42.4942 -39.470838)
		(end 42.388282 -40.004238)
		(width 0.11684)
		(layer "F.Cu")
		(net "FM_BMC_CRASHLOG_TRIG_R1_N")
	)
	(segment
		(start 42.408602 -40.106854)
		(end 43.082972 -41.367456)
		(width 0.11684)
		(layer "F.Cu")
		(net "FM_BMC_CRASHLOG_TRIG_R1_N")
	)
	(via
		(at 42.08526 -38.003988)
		(size 0.508)
		(drill 0.254)
		(layers "F.Cu" "B.Cu")
		(net "FM_BMC_CRASHLOG_TRIG_R1_N")
	)
	(segment
		(start 41.59885 -37.517578)
		(end 41.59885 -37.338)
		(width 0.11684)
		(layer "B.Cu")
		(net "FM_BMC_CRASHLOG_TRIG_R1_N")
	)
	(segment
		(start 42.08526 -38.003988)
		(end 41.59885 -37.517578)
		(width 0.11684)
		(layer "B.Cu")
		(net "FM_BMC_CRASHLOG_TRIG_R1_N")
	)
	(segment
		(start 45.299884 -42.976038)
		(end 44.735496 -42.976038)
		(width 0.11684)
		(layer "F.Cu")
		(net "FM_BIC_DEBUG_SW_N_R")
	)
	(segment
		(start 45.695108 -43.371262)
		(end 45.299884 -42.976038)
		(width 0.11684)
		(layer "F.Cu")
		(net "FM_BIC_DEBUG_SW_N_R")
	)
	(segment
		(start 43.683174 -42.540174)
		(end 42.0624 -40.9194)
		(width 0.11684)
		(layer "F.Cu")
		(net "FM_BIC_DEBUG_SW_N_R")
	)
	(segment
		(start 42.0624 -40.9194)
		(end 41.2242 -40.9194)
		(width 0.11684)
		(layer "F.Cu")
		(net "FM_BIC_DEBUG_SW_N_R")
	)
	(segment
		(start 44.735496 -42.976038)
		(end 43.683174 -42.540174)
		(width 0.11684)
		(layer "F.Cu")
		(net "FM_BIC_DEBUG_SW_N_R")
	)
	(segment
		(start 40.513 -40.2082)
		(end 40.37965 -40.2082)
		(width 0.11684)
		(layer "F.Cu")
		(net "FM_BIC_DEBUG_SW_N_R")
	)
	(segment
		(start 41.2242 -40.9194)
		(end 40.513 -40.2082)
		(width 0.11684)
		(layer "F.Cu")
		(net "FM_BIC_DEBUG_SW_N_R")
	)
	(segment
		(start 35.66795 -44.5008)
		(end 35.052254 -44.5008)
		(width 0.11684)
		(layer "F.Cu")
		(net "U43_CT")
	)
	(segment
		(start 33.86455 -43.9674)
		(end 33.782 -44.04995)
		(width 0.11684)
		(layer "F.Cu")
		(net "U43_CT")
	)
	(segment
		(start 35.329876 -44.219876)
		(end 34.93516 -43.82516)
		(width 0.11684)
		(layer "F.Cu")
		(net "U43_CT")
	)
	(segment
		(start 35.387026 -44.219876)
		(end 35.329876 -44.219876)
		(width 0.11684)
		(layer "F.Cu")
		(net "U43_CT")
	)
	(segment
		(start 34.93516 -41.63441)
		(end 34.85896 -41.55821)
		(width 0.11684)
		(layer "F.Cu")
		(net "U43_CT")
	)
	(segment
		(start 34.93516 -43.053)
		(end 34.93516 -41.63441)
		(width 0.11684)
		(layer "F.Cu")
		(net "U43_CT")
	)
	(segment
		(start 34.518854 -43.9674)
		(end 33.86455 -43.9674)
		(width 0.11684)
		(layer "F.Cu")
		(net "U43_CT")
	)
	(segment
		(start 34.93516 -43.82516)
		(end 34.93516 -43.053)
		(width 0.11684)
		(layer "F.Cu")
		(net "U43_CT")
	)
	(segment
		(start 35.052254 -44.5008)
		(end 34.518854 -43.9674)
		(width 0.11684)
		(layer "F.Cu")
		(net "U43_CT")
	)
	(segment
		(start 35.66795 -44.5008)
		(end 35.387026 -44.219876)
		(width 0.11684)
		(layer "F.Cu")
		(net "U43_CT")
	)
	(via
		(at 34.93516 -43.053)
		(size 0.762)
		(drill 0.381)
		(layers "F.Cu" "B.Cu")
		(net "U43_CT")
	)
	(segment
		(start 73.8378 -104.248712)
		(end 73.6473 -104.058212)
		(width 0.11684)
		(layer "F.Cu")
		(net "SPI_TPM_CS_R_N")
	)
	(segment
		(start 69.951346 -100.1776)
		(end 68.9864 -100.1776)
		(width 0.11684)
		(layer "F.Cu")
		(net "SPI_TPM_CS_R_N")
	)
	(segment
		(start 73.6473 -103.407972)
		(end 73.8378 -103.217472)
		(width 0.11684)
		(layer "F.Cu")
		(net "SPI_TPM_CS_R_N")
	)
	(segment
		(start 69.0626 -107.62615)
		(end 70.5104 -106.17835)
		(width 0.11684)
		(layer "F.Cu")
		(net "SPI_TPM_CS_R_N")
	)
	(segment
		(start 71.23684 -101.463094)
		(end 69.951346 -100.1776)
		(width 0.11684)
		(layer "F.Cu")
		(net "SPI_TPM_CS_R_N")
	)
	(segment
		(start 68.9864 -100.1776)
		(end 68.72478 -99.91598)
		(width 0.11684)
		(layer "F.Cu")
		(net "SPI_TPM_CS_R_N")
	)
	(segment
		(start 71.42734 -104.058212)
		(end 71.23684 -103.867712)
		(width 0.11684)
		(layer "F.Cu")
		(net "SPI_TPM_CS_R_N")
	)
	(segment
		(start 73.6473 -102.757732)
		(end 71.42734 -102.757732)
		(width 0.11684)
		(layer "F.Cu")
		(net "SPI_TPM_CS_R_N")
	)
	(segment
		(start 70.5104 -106.17835)
		(end 70.5104 -105.6386)
		(width 0.11684)
		(layer "F.Cu")
		(net "SPI_TPM_CS_R_N")
	)
	(segment
		(start 69.324474 -97.877122)
		(end 68.589144 -97.877122)
		(width 0.11684)
		(layer "F.Cu")
		(net "SPI_TPM_CS_R_N")
	)
	(segment
		(start 71.440548 -104.708452)
		(end 73.6473 -104.708452)
		(width 0.11684)
		(layer "F.Cu")
		(net "SPI_TPM_CS_R_N")
	)
	(segment
		(start 71.42734 -102.757732)
		(end 71.23684 -102.567232)
		(width 0.11684)
		(layer "F.Cu")
		(net "SPI_TPM_CS_R_N")
	)
	(segment
		(start 73.6473 -104.708452)
		(end 73.8378 -104.517952)
		(width 0.11684)
		(layer "F.Cu")
		(net "SPI_TPM_CS_R_N")
	)
	(segment
		(start 71.23684 -103.867712)
		(end 71.23684 -103.598472)
		(width 0.11684)
		(layer "F.Cu")
		(net "SPI_TPM_CS_R_N")
	)
	(segment
		(start 71.23684 -102.567232)
		(end 71.23684 -101.463094)
		(width 0.11684)
		(layer "F.Cu")
		(net "SPI_TPM_CS_R_N")
	)
	(segment
		(start 68.72478 -99.91598)
		(end 68.72478 -99.466908)
		(width 0.11684)
		(layer "F.Cu")
		(net "SPI_TPM_CS_R_N")
	)
	(segment
		(start 73.8378 -102.948232)
		(end 73.6473 -102.757732)
		(width 0.11684)
		(layer "F.Cu")
		(net "SPI_TPM_CS_R_N")
	)
	(segment
		(start 68.72478 -99.466908)
		(end 69.81952 -98.372168)
		(width 0.11684)
		(layer "F.Cu")
		(net "SPI_TPM_CS_R_N")
	)
	(segment
		(start 73.8378 -104.517952)
		(end 73.8378 -104.248712)
		(width 0.11684)
		(layer "F.Cu")
		(net "SPI_TPM_CS_R_N")
	)
	(segment
		(start 71.42734 -103.407972)
		(end 73.6473 -103.407972)
		(width 0.11684)
		(layer "F.Cu")
		(net "SPI_TPM_CS_R_N")
	)
	(segment
		(start 71.23684 -103.598472)
		(end 71.42734 -103.407972)
		(width 0.11684)
		(layer "F.Cu")
		(net "SPI_TPM_CS_R_N")
	)
	(segment
		(start 73.8378 -103.217472)
		(end 73.8378 -102.948232)
		(width 0.11684)
		(layer "F.Cu")
		(net "SPI_TPM_CS_R_N")
	)
	(segment
		(start 73.6473 -104.058212)
		(end 71.42734 -104.058212)
		(width 0.11684)
		(layer "F.Cu")
		(net "SPI_TPM_CS_R_N")
	)
	(segment
		(start 69.81952 -98.372168)
		(end 69.324474 -97.877122)
		(width 0.11684)
		(layer "F.Cu")
		(net "SPI_TPM_CS_R_N")
	)
	(segment
		(start 70.5104 -105.6386)
		(end 71.440548 -104.708452)
		(width 0.11684)
		(layer "F.Cu")
		(net "SPI_TPM_CS_R_N")
	)
	(via
		(at 69.81952 -98.372168)
		(size 0.762)
		(drill 0.381)
		(layers "F.Cu" "B.Cu")
		(net "SPI_TPM_CS_R_N")
	)
	(segment
		(start 69.0626 -108.42625)
		(end 68.58 -108.90885)
		(width 0.11684)
		(layer "F.Cu")
		(net "SPI_TPM_CS_N")
	)
	(segment
		(start 70.358 -112.776)
		(end 68.58 -110.998)
		(width 0.11684)
		(layer "F.Cu")
		(net "SPI_TPM_CS_N")
	)
	(segment
		(start 68.58 -110.998)
		(end 68.58 -109.6264)
		(width 0.11684)
		(layer "F.Cu")
		(net "SPI_TPM_CS_N")
	)
	(segment
		(start 68.58 -108.90885)
		(end 68.58 -109.6264)
		(width 0.11684)
		(layer "F.Cu")
		(net "SPI_TPM_CS_N")
	)
	(segment
		(start 70.358 -115.243356)
		(end 70.358 -112.776)
		(width 0.11684)
		(layer "F.Cu")
		(net "SPI_TPM_CS_N")
	)
	(segment
		(start 69.342 -116.259356)
		(end 70.358 -115.243356)
		(width 0.11684)
		(layer "F.Cu")
		(net "SPI_TPM_CS_N")
	)
	(segment
		(start 69.06006 -118.25986)
		(end 69.06006 -117.339872)
		(width 0.11684)
		(layer "F.Cu")
		(net "SPI_TPM_CS_N")
	)
	(segment
		(start 69.06006 -117.339872)
		(end 69.342 -117.057932)
		(width 0.11684)
		(layer "F.Cu")
		(net "SPI_TPM_CS_N")
	)
	(segment
		(start 69.342 -117.057932)
		(end 69.342 -116.259356)
		(width 0.11684)
		(layer "F.Cu")
		(net "SPI_TPM_CS_N")
	)
	(via
		(at 68.58 -109.6264)
		(size 0.762)
		(drill 0.381)
		(layers "F.Cu" "B.Cu")
		(net "SPI_TPM_CS_N")
	)
	(segment
		(start 55.5752 -116.36502)
		(end 55.5752 -116.603526)
		(width 0.11684)
		(layer "F.Cu")
		(net "SPI_SYS_WP_R_IO2")
	)
	(segment
		(start 55.1688 -118.155974)
		(end 55.064914 -118.25986)
		(width 0.11684)
		(layer "F.Cu")
		(net "SPI_SYS_WP_R_IO2")
	)
	(segment
		(start 53.04282 -107.219496)
		(end 53.04282 -107.823)
		(width 0.11684)
		(layer "F.Cu")
		(net "SPI_SYS_WP_R_IO2")
	)
	(segment
		(start 55.1688 -117.398292)
		(end 55.1688 -118.155974)
		(width 0.11684)
		(layer "F.Cu")
		(net "SPI_SYS_WP_R_IO2")
	)
	(segment
		(start 53.31206 -113.354866)
		(end 53.358542 -113.424462)
		(width 0.11684)
		(layer "F.Cu")
		(net "SPI_SYS_WP_R_IO2")
	)
	(segment
		(start 55.5752 -116.603526)
		(end 55.353966 -117.137688)
		(width 0.11684)
		(layer "F.Cu")
		(net "SPI_SYS_WP_R_IO2")
	)
	(segment
		(start 53.358542 -113.424462)
		(end 53.38191 -113.45291)
		(width 0.11684)
		(layer "F.Cu")
		(net "SPI_SYS_WP_R_IO2")
	)
	(segment
		(start 55.442104 -116.043456)
		(end 55.5752 -116.36502)
		(width 0.11684)
		(layer "F.Cu")
		(net "SPI_SYS_WP_R_IO2")
	)
	(segment
		(start 53.26888 -113.25098)
		(end 53.31206 -113.354866)
		(width 0.11684)
		(layer "F.Cu")
		(net "SPI_SYS_WP_R_IO2")
	)
	(segment
		(start 53.38191 -113.45291)
		(end 54.774846 -114.989864)
		(width 0.11684)
		(layer "F.Cu")
		(net "SPI_SYS_WP_R_IO2")
	)
	(segment
		(start 54.774846 -114.989864)
		(end 55.442104 -116.043456)
		(width 0.11684)
		(layer "F.Cu")
		(net "SPI_SYS_WP_R_IO2")
	)
	(segment
		(start 53.30825 -106.5784)
		(end 53.04282 -107.219496)
		(width 0.11684)
		(layer "F.Cu")
		(net "SPI_SYS_WP_R_IO2")
	)
	(segment
		(start 55.22214 -117.269514)
		(end 55.1688 -117.398292)
		(width 0.11684)
		(layer "F.Cu")
		(net "SPI_SYS_WP_R_IO2")
	)
	(segment
		(start 53.2384 -111.805212)
		(end 53.2384 -113.097564)
		(width 0.11684)
		(layer "F.Cu")
		(net "SPI_SYS_WP_R_IO2")
	)
	(segment
		(start 53.04282 -107.823)
		(end 53.2384 -111.805212)
		(width 0.11684)
		(layer "F.Cu")
		(net "SPI_SYS_WP_R_IO2")
	)
	(segment
		(start 53.2384 -113.097564)
		(end 53.26888 -113.25098)
		(width 0.11684)
		(layer "F.Cu")
		(net "SPI_SYS_WP_R_IO2")
	)
	(segment
		(start 55.353966 -117.137688)
		(end 55.22214 -117.269514)
		(width 0.11684)
		(layer "F.Cu")
		(net "SPI_SYS_WP_R_IO2")
	)
	(via
		(at 53.04282 -107.823)
		(size 0.762)
		(drill 0.381)
		(layers "F.Cu" "B.Cu")
		(net "SPI_SYS_WP_R_IO2")
	)
	(segment
		(start 54.7878 -109.79785)
		(end 55.1434 -110.15345)
		(width 0.11684)
		(layer "F.Cu")
		(net "SPI_SYS_R_MOSI")
	)
	(segment
		(start 56.06796 -114.665506)
		(end 56.32577 -114.923316)
		(width 0.11684)
		(layer "F.Cu")
		(net "SPI_SYS_R_MOSI")
	)
	(segment
		(start 56.3626 -118.362476)
		(end 56.265064 -118.460012)
		(width 0.11684)
		(layer "F.Cu")
		(net "SPI_SYS_R_MOSI")
	)
	(segment
		(start 56.06796 -113.78184)
		(end 56.06796 -114.665506)
		(width 0.11684)
		(layer "F.Cu")
		(net "SPI_SYS_R_MOSI")
	)
	(segment
		(start 56.9214 -116.7638)
		(end 56.3626 -117.3226)
		(width 0.11684)
		(layer "F.Cu")
		(net "SPI_SYS_R_MOSI")
	)
	(segment
		(start 56.32577 -114.923316)
		(end 56.9214 -116.361464)
		(width 0.11684)
		(layer "F.Cu")
		(net "SPI_SYS_R_MOSI")
	)
	(segment
		(start 56.067198 -111.693198)
		(end 56.35244 -112.381538)
		(width 0.11684)
		(layer "F.Cu")
		(net "SPI_SYS_R_MOSI")
	)
	(segment
		(start 56.35244 -113.49736)
		(end 56.06796 -113.78184)
		(width 0.11684)
		(layer "F.Cu")
		(net "SPI_SYS_R_MOSI")
	)
	(segment
		(start 56.3626 -117.3226)
		(end 56.3626 -118.362476)
		(width 0.11684)
		(layer "F.Cu")
		(net "SPI_SYS_R_MOSI")
	)
	(segment
		(start 55.1434 -110.7694)
		(end 56.067198 -111.693198)
		(width 0.11684)
		(layer "F.Cu")
		(net "SPI_SYS_R_MOSI")
	)
	(segment
		(start 70.2056 -94.0816)
		(end 69.75094 -93.62694)
		(width 0.11684)
		(layer "F.Cu")
		(net "SPI_SYS_R_MOSI")
	)
	(segment
		(start 56.35244 -112.381538)
		(end 56.35244 -113.49736)
		(width 0.11684)
		(layer "F.Cu")
		(net "SPI_SYS_R_MOSI")
	)
	(segment
		(start 55.1434 -110.15345)
		(end 55.1434 -110.7694)
		(width 0.11684)
		(layer "F.Cu")
		(net "SPI_SYS_R_MOSI")
	)
	(segment
		(start 69.75094 -93.62694)
		(end 68.589144 -93.62694)
		(width 0.11684)
		(layer "F.Cu")
		(net "SPI_SYS_R_MOSI")
	)
	(segment
		(start 56.9214 -116.361464)
		(end 56.9214 -116.7638)
		(width 0.11684)
		(layer "F.Cu")
		(net "SPI_SYS_R_MOSI")
	)
	(via
		(at 56.74868 -93.23832)
		(size 0.508)
		(drill 0.254)
		(layers "F.Cu" "B.Cu")
		(net "SPI_SYS_R_MOSI")
	)
	(via
		(at 70.2056 -94.0816)
		(size 0.762)
		(drill 0.254)
		(layers "F.Cu" "B.Cu")
		(net "SPI_SYS_R_MOSI")
	)
	(via
		(at 55.1434 -110.7694)
		(size 0.508)
		(drill 0.254)
		(layers "F.Cu" "B.Cu")
		(net "SPI_SYS_R_MOSI")
	)
	(segment
		(start 65.813686 -91.97848)
		(end 60.843414 -91.97848)
		(width 0.08382)
		(layer "In2.Cu")
		(net "SPI_SYS_R_MOSI")
	)
	(segment
		(start 59.821064 -93.00083)
		(end 58.981086 -93.00083)
		(width 0.08382)
		(layer "In2.Cu")
		(net "SPI_SYS_R_MOSI")
	)
	(segment
		(start 69.9897 -93.8657)
		(end 67.700906 -93.8657)
		(width 0.08382)
		(layer "In2.Cu")
		(net "SPI_SYS_R_MOSI")
	)
	(segment
		(start 70.2056 -94.0816)
		(end 69.9897 -93.8657)
		(width 0.08382)
		(layer "In2.Cu")
		(net "SPI_SYS_R_MOSI")
	)
	(segment
		(start 67.700906 -93.8657)
		(end 65.813686 -91.97848)
		(width 0.08382)
		(layer "In2.Cu")
		(net "SPI_SYS_R_MOSI")
	)
	(segment
		(start 60.843414 -91.97848)
		(end 59.821064 -93.00083)
		(width 0.08382)
		(layer "In2.Cu")
		(net "SPI_SYS_R_MOSI")
	)
	(segment
		(start 58.981086 -93.00083)
		(end 58.4073 -93.23832)
		(width 0.08382)
		(layer "In2.Cu")
		(net "SPI_SYS_R_MOSI")
	)
	(segment
		(start 58.4073 -93.23832)
		(end 56.74868 -93.23832)
		(width 0.08382)
		(layer "In2.Cu")
		(net "SPI_SYS_R_MOSI")
	)
	(segment
		(start 54.41696 -102.405942)
		(end 54.41696 -108.20273)
		(width 0.08382)
		(layer "In9.Cu")
		(net "SPI_SYS_R_MOSI")
	)
	(segment
		(start 55.3466 -98.103182)
		(end 55.3466 -100.16109)
		(width 0.08382)
		(layer "In9.Cu")
		(net "SPI_SYS_R_MOSI")
	)
	(segment
		(start 55.1434 -109.9566)
		(end 55.1434 -110.7694)
		(width 0.08382)
		(layer "In9.Cu")
		(net "SPI_SYS_R_MOSI")
	)
	(segment
		(start 56.74868 -93.23832)
		(end 55.91302 -95.256096)
		(width 0.08382)
		(layer "In9.Cu")
		(net "SPI_SYS_R_MOSI")
	)
	(segment
		(start 55.91302 -95.256096)
		(end 55.3466 -98.103182)
		(width 0.08382)
		(layer "In9.Cu")
		(net "SPI_SYS_R_MOSI")
	)
	(segment
		(start 55.3466 -100.16109)
		(end 54.41696 -102.405942)
		(width 0.08382)
		(layer "In9.Cu")
		(net "SPI_SYS_R_MOSI")
	)
	(segment
		(start 54.41696 -108.20273)
		(end 55.1434 -109.9566)
		(width 0.08382)
		(layer "In9.Cu")
		(net "SPI_SYS_R_MOSI")
	)
	(segment
		(start 55.64378 -114.77498)
		(end 55.9562 -115.0874)
		(width 0.11684)
		(layer "F.Cu")
		(net "SPI_SYS_R_MISO")
	)
	(segment
		(start 55.9562 -115.0874)
		(end 55.9562 -117.1194)
		(width 0.11684)
		(layer "F.Cu")
		(net "SPI_SYS_R_MISO")
	)
	(segment
		(start 55.209186 -111.6838)
		(end 55.9816 -112.456214)
		(width 0.11684)
		(layer "F.Cu")
		(net "SPI_SYS_R_MISO")
	)
	(segment
		(start 55.7784 -117.2972)
		(end 55.7784 -118.146576)
		(width 0.11684)
		(layer "F.Cu")
		(net "SPI_SYS_R_MISO")
	)
	(segment
		(start 68.986654 -96.901)
		(end 69.3674 -96.901)
		(width 0.11684)
		(layer "F.Cu")
		(net "SPI_SYS_R_MISO")
	)
	(segment
		(start 68.589144 -96.79305)
		(end 68.878704 -96.79305)
		(width 0.11684)
		(layer "F.Cu")
		(net "SPI_SYS_R_MISO")
	)
	(segment
		(start 55.7784 -118.146576)
		(end 55.665116 -118.25986)
		(width 0.11684)
		(layer "F.Cu")
		(net "SPI_SYS_R_MISO")
	)
	(segment
		(start 55.9816 -113.3348)
		(end 55.64378 -113.67262)
		(width 0.11684)
		(layer "F.Cu")
		(net "SPI_SYS_R_MISO")
	)
	(segment
		(start 68.878704 -96.79305)
		(end 68.986654 -96.901)
		(width 0.11684)
		(layer "F.Cu")
		(net "SPI_SYS_R_MISO")
	)
	(segment
		(start 54.5846 -110.998)
		(end 54.5846 -111.56696)
		(width 0.11684)
		(layer "F.Cu")
		(net "SPI_SYS_R_MISO")
	)
	(segment
		(start 53.7718 -110.1852)
		(end 54.3306 -110.744)
		(width 0.11684)
		(layer "F.Cu")
		(net "SPI_SYS_R_MISO")
	)
	(segment
		(start 55.9562 -117.1194)
		(end 55.7784 -117.2972)
		(width 0.11684)
		(layer "F.Cu")
		(net "SPI_SYS_R_MISO")
	)
	(segment
		(start 55.64378 -113.67262)
		(end 55.64378 -114.77498)
		(width 0.11684)
		(layer "F.Cu")
		(net "SPI_SYS_R_MISO")
	)
	(segment
		(start 54.5846 -111.56696)
		(end 54.70144 -111.6838)
		(width 0.11684)
		(layer "F.Cu")
		(net "SPI_SYS_R_MISO")
	)
	(segment
		(start 53.7718 -109.79785)
		(end 53.7718 -110.1852)
		(width 0.11684)
		(layer "F.Cu")
		(net "SPI_SYS_R_MISO")
	)
	(segment
		(start 55.9816 -112.456214)
		(end 55.9816 -113.3348)
		(width 0.11684)
		(layer "F.Cu")
		(net "SPI_SYS_R_MISO")
	)
	(segment
		(start 54.70144 -111.6838)
		(end 55.209186 -111.6838)
		(width 0.11684)
		(layer "F.Cu")
		(net "SPI_SYS_R_MISO")
	)
	(segment
		(start 54.3306 -110.744)
		(end 54.5846 -110.998)
		(width 0.11684)
		(layer "F.Cu")
		(net "SPI_SYS_R_MISO")
	)
	(via
		(at 69.3674 -96.901)
		(size 0.508)
		(drill 0.254)
		(layers "F.Cu" "B.Cu")
		(net "SPI_SYS_R_MISO")
	)
	(via
		(at 56.53405 -98.45675)
		(size 0.508)
		(drill 0.254)
		(layers "F.Cu" "B.Cu")
		(net "SPI_SYS_R_MISO")
	)
	(via
		(at 54.3306 -110.744)
		(size 0.508)
		(drill 0.254)
		(layers "F.Cu" "B.Cu")
		(net "SPI_SYS_R_MISO")
	)
	(segment
		(start 59.03722 -98.15576)
		(end 56.79059 -98.15576)
		(width 0.08382)
		(layer "In2.Cu")
		(net "SPI_SYS_R_MISO")
	)
	(segment
		(start 65.665604 -96.10598)
		(end 65.497964 -95.93834)
		(width 0.08382)
		(layer "In2.Cu")
		(net "SPI_SYS_R_MISO")
	)
	(segment
		(start 64.906144 -96.901)
		(end 64.59728 -96.901)
		(width 0.08382)
		(layer "In2.Cu")
		(net "SPI_SYS_R_MISO")
	)
	(segment
		(start 65.073784 -96.73336)
		(end 64.906144 -96.901)
		(width 0.08382)
		(layer "In2.Cu")
		(net "SPI_SYS_R_MISO")
	)
	(segment
		(start 69.3674 -96.901)
		(end 65.833244 -96.901)
		(width 0.08382)
		(layer "In2.Cu")
		(net "SPI_SYS_R_MISO")
	)
	(segment
		(start 56.79059 -98.15576)
		(end 56.53405 -98.412554)
		(width 0.08382)
		(layer "In2.Cu")
		(net "SPI_SYS_R_MISO")
	)
	(segment
		(start 61.595 -96.1644)
		(end 61.214 -96.5454)
		(width 0.08382)
		(layer "In2.Cu")
		(net "SPI_SYS_R_MISO")
	)
	(segment
		(start 65.665604 -96.73336)
		(end 65.665604 -96.10598)
		(width 0.08382)
		(layer "In2.Cu")
		(net "SPI_SYS_R_MISO")
	)
	(segment
		(start 59.90336 -98.28784)
		(end 59.1693 -98.28784)
		(width 0.08382)
		(layer "In2.Cu")
		(net "SPI_SYS_R_MISO")
	)
	(segment
		(start 64.59728 -96.901)
		(end 63.86068 -96.1644)
		(width 0.08382)
		(layer "In2.Cu")
		(net "SPI_SYS_R_MISO")
	)
	(segment
		(start 65.833244 -96.901)
		(end 65.665604 -96.73336)
		(width 0.08382)
		(layer "In2.Cu")
		(net "SPI_SYS_R_MISO")
	)
	(segment
		(start 59.1693 -98.28784)
		(end 59.03722 -98.15576)
		(width 0.08382)
		(layer "In2.Cu")
		(net "SPI_SYS_R_MISO")
	)
	(segment
		(start 65.073784 -96.10598)
		(end 65.073784 -96.73336)
		(width 0.08382)
		(layer "In2.Cu")
		(net "SPI_SYS_R_MISO")
	)
	(segment
		(start 65.497964 -95.93834)
		(end 65.241424 -95.93834)
		(width 0.08382)
		(layer "In2.Cu")
		(net "SPI_SYS_R_MISO")
	)
	(segment
		(start 63.86068 -96.1644)
		(end 61.595 -96.1644)
		(width 0.08382)
		(layer "In2.Cu")
		(net "SPI_SYS_R_MISO")
	)
	(segment
		(start 56.53405 -98.412554)
		(end 56.53405 -98.45675)
		(width 0.08382)
		(layer "In2.Cu")
		(net "SPI_SYS_R_MISO")
	)
	(segment
		(start 65.241424 -95.93834)
		(end 65.073784 -96.10598)
		(width 0.08382)
		(layer "In2.Cu")
		(net "SPI_SYS_R_MISO")
	)
	(segment
		(start 61.214 -96.9772)
		(end 59.90336 -98.28784)
		(width 0.08382)
		(layer "In2.Cu")
		(net "SPI_SYS_R_MISO")
	)
	(segment
		(start 61.214 -96.5454)
		(end 61.214 -96.9772)
		(width 0.08382)
		(layer "In2.Cu")
		(net "SPI_SYS_R_MISO")
	)
	(segment
		(start 54.3306 -110.744)
		(end 54.3306 -102.0064)
		(width 0.10668)
		(layer "In4.Cu")
		(net "SPI_SYS_R_MISO")
	)
	(segment
		(start 55.245 -101.092)
		(end 55.245 -99.7458)
		(width 0.10668)
		(layer "In4.Cu")
		(net "SPI_SYS_R_MISO")
	)
	(segment
		(start 54.3306 -102.0064)
		(end 55.245 -101.092)
		(width 0.10668)
		(layer "In4.Cu")
		(net "SPI_SYS_R_MISO")
	)
	(segment
		(start 55.245 -99.7458)
		(end 56.53405 -98.45675)
		(width 0.10668)
		(layer "In4.Cu")
		(net "SPI_SYS_R_MISO")
	)
	(segment
		(start 56.22544 -108.625386)
		(end 56.22544 -110.390178)
		(width 0.11684)
		(layer "F.Cu")
		(net "SPI_SYS_R_CLK")
	)
	(segment
		(start 56.842152 -105.21696)
		(end 55.48884 -105.21696)
		(width 0.11684)
		(layer "F.Cu")
		(net "SPI_SYS_R_CLK")
	)
	(segment
		(start 55.32755 -105.37825)
		(end 55.32755 -105.664)
		(width 0.11684)
		(layer "F.Cu")
		(net "SPI_SYS_R_CLK")
	)
	(segment
		(start 55.48884 -105.21696)
		(end 55.32755 -105.37825)
		(width 0.11684)
		(layer "F.Cu")
		(net "SPI_SYS_R_CLK")
	)
	(segment
		(start 56.22544 -110.390178)
		(end 56.225948 -110.391194)
		(width 0.11684)
		(layer "F.Cu")
		(net "SPI_SYS_R_CLK")
	)
	(segment
		(start 55.433722 -107.84332)
		(end 55.443374 -107.84332)
		(width 0.11684)
		(layer "F.Cu")
		(net "SPI_SYS_R_CLK")
	)
	(segment
		(start 57.512712 -103.364538)
		(end 57.512712 -104.5464)
		(width 0.11684)
		(layer "F.Cu")
		(net "SPI_SYS_R_CLK")
	)
	(segment
		(start 56.787288 -110.952534)
		(end 57.4802 -112.626648)
		(width 0.11684)
		(layer "F.Cu")
		(net "SPI_SYS_R_CLK")
	)
	(segment
		(start 55.091076 -105.900474)
		(end 55.0164 -106.080814)
		(width 0.11684)
		(layer "F.Cu")
		(net "SPI_SYS_R_CLK")
	)
	(segment
		(start 55.0164 -107.27182)
		(end 55.07228 -107.406948)
		(width 0.11684)
		(layer "F.Cu")
		(net "SPI_SYS_R_CLK")
	)
	(segment
		(start 55.32755 -105.664)
		(end 55.091076 -105.900474)
		(width 0.11684)
		(layer "F.Cu")
		(net "SPI_SYS_R_CLK")
	)
	(segment
		(start 55.0164 -106.080814)
		(end 55.0164 -107.27182)
		(width 0.11684)
		(layer "F.Cu")
		(net "SPI_SYS_R_CLK")
	)
	(segment
		(start 57.4802 -112.626648)
		(end 57.4802 -118.24462)
		(width 0.11684)
		(layer "F.Cu")
		(net "SPI_SYS_R_CLK")
	)
	(segment
		(start 57.4802 -118.24462)
		(end 57.46496 -118.25986)
		(width 0.11684)
		(layer "F.Cu")
		(net "SPI_SYS_R_CLK")
	)
	(segment
		(start 55.124858 -107.534456)
		(end 55.433722 -107.84332)
		(width 0.11684)
		(layer "F.Cu")
		(net "SPI_SYS_R_CLK")
	)
	(segment
		(start 56.225948 -110.391194)
		(end 56.787288 -110.952534)
		(width 0.11684)
		(layer "F.Cu")
		(net "SPI_SYS_R_CLK")
	)
	(segment
		(start 57.531 -103.34625)
		(end 57.512712 -103.364538)
		(width 0.11684)
		(layer "F.Cu")
		(net "SPI_SYS_R_CLK")
	)
	(segment
		(start 55.443374 -107.84332)
		(end 56.22544 -108.625386)
		(width 0.11684)
		(layer "F.Cu")
		(net "SPI_SYS_R_CLK")
	)
	(segment
		(start 55.07228 -107.406948)
		(end 55.124858 -107.534456)
		(width 0.11684)
		(layer "F.Cu")
		(net "SPI_SYS_R_CLK")
	)
	(segment
		(start 57.512712 -104.5464)
		(end 56.842152 -105.21696)
		(width 0.11684)
		(layer "F.Cu")
		(net "SPI_SYS_R_CLK")
	)
	(via
		(at 57.512712 -104.5464)
		(size 0.762)
		(drill 0.381)
		(layers "F.Cu" "B.Cu")
		(net "SPI_SYS_R_CLK")
	)
	(segment
		(start 66.238374 -94.356174)
		(end 66.7258 -94.8436)
		(width 0.11684)
		(layer "F.Cu")
		(net "SPI_SYS_R1_MOSI")
	)
	(segment
		(start 66.7258 -94.8436)
		(end 68.1228 -94.8436)
		(width 0.11684)
		(layer "F.Cu")
		(net "SPI_SYS_R1_MOSI")
	)
	(segment
		(start 68.1228 -93.960696)
		(end 68.1228 -94.8436)
		(width 0.11684)
		(layer "F.Cu")
		(net "SPI_SYS_R1_MOSI")
	)
	(segment
		(start 67.789044 -93.62694)
		(end 68.1228 -93.960696)
		(width 0.11684)
		(layer "F.Cu")
		(net "SPI_SYS_R1_MOSI")
	)
	(segment
		(start 64.81191 -94.356174)
		(end 66.238374 -94.356174)
		(width 0.11684)
		(layer "F.Cu")
		(net "SPI_SYS_R1_MOSI")
	)
	(via
		(at 68.1228 -94.8436)
		(size 0.762)
		(drill 0.381)
		(layers "F.Cu" "B.Cu")
		(net "SPI_SYS_R1_MOSI")
	)
	(segment
		(start 66.968878 -95.57512)
		(end 69.235574 -95.57512)
		(width 0.11684)
		(layer "F.Cu")
		(net "SPI_SYS_R1_MISO")
	)
	(segment
		(start 66.1924 -95.539052)
		(end 66.1924 -96.192086)
		(width 0.11684)
		(layer "F.Cu")
		(net "SPI_SYS_R1_MISO")
	)
	(segment
		(start 66.634106 -96.37522)
		(end 66.81724 -96.192086)
		(width 0.11684)
		(layer "F.Cu")
		(net "SPI_SYS_R1_MISO")
	)
	(segment
		(start 69.235574 -95.57512)
		(end 68.544694 -96.266)
		(width 0.11684)
		(layer "F.Cu")
		(net "SPI_SYS_R1_MISO")
	)
	(segment
		(start 66.375534 -96.37522)
		(end 66.634106 -96.37522)
		(width 0.11684)
		(layer "F.Cu")
		(net "SPI_SYS_R1_MISO")
	)
	(segment
		(start 68.097654 -96.266)
		(end 67.789044 -96.57461)
		(width 0.11684)
		(layer "F.Cu")
		(net "SPI_SYS_R1_MISO")
	)
	(segment
		(start 64.81191 -95.355918)
		(end 66.009266 -95.355918)
		(width 0.11684)
		(layer "F.Cu")
		(net "SPI_SYS_R1_MISO")
	)
	(segment
		(start 66.1924 -96.192086)
		(end 66.375534 -96.37522)
		(width 0.11684)
		(layer "F.Cu")
		(net "SPI_SYS_R1_MISO")
	)
	(segment
		(start 66.009266 -95.355918)
		(end 66.1924 -95.539052)
		(width 0.11684)
		(layer "F.Cu")
		(net "SPI_SYS_R1_MISO")
	)
	(segment
		(start 67.789044 -96.57461)
		(end 67.789044 -96.79305)
		(width 0.11684)
		(layer "F.Cu")
		(net "SPI_SYS_R1_MISO")
	)
	(segment
		(start 68.544694 -96.266)
		(end 68.097654 -96.266)
		(width 0.11684)
		(layer "F.Cu")
		(net "SPI_SYS_R1_MISO")
	)
	(segment
		(start 66.81724 -96.192086)
		(end 66.81724 -95.726758)
		(width 0.11684)
		(layer "F.Cu")
		(net "SPI_SYS_R1_MISO")
	)
	(segment
		(start 66.81724 -95.726758)
		(end 66.968878 -95.57512)
		(width 0.11684)
		(layer "F.Cu")
		(net "SPI_SYS_R1_MISO")
	)
	(via
		(at 69.235574 -95.57512)
		(size 0.762)
		(drill 0.381)
		(layers "F.Cu" "B.Cu")
		(net "SPI_SYS_R1_MISO")
	)
	(segment
		(start 55.0672 -93.2688)
		(end 55.8292 -92.5068)
		(width 0.11684)
		(layer "F.Cu")
		(net "SPI_SYS_R1_CLK")
	)
	(segment
		(start 57.5056 -100.2284)
		(end 55.9308 -100.2284)
		(width 0.11684)
		(layer "F.Cu")
		(net "SPI_SYS_R1_CLK")
	)
	(segment
		(start 56.12765 -105.664)
		(end 57.447688 -105.664)
		(width 0.11684)
		(layer "F.Cu")
		(net "SPI_SYS_R1_CLK")
	)
	(segment
		(start 58.11012 -90.9828)
		(end 56.4896 -90.9828)
		(width 0.11684)
		(layer "F.Cu")
		(net "SPI_SYS_R1_CLK")
	)
	(segment
		(start 59.09056 -91.96324)
		(end 58.11012 -90.9828)
		(width 0.11684)
		(layer "F.Cu")
		(net "SPI_SYS_R1_CLK")
	)
	(segment
		(start 62.618874 -92.539058)
		(end 62.43574 -92.355924)
		(width 0.11684)
		(layer "F.Cu")
		(net "SPI_SYS_R1_CLK")
	)
	(segment
		(start 58.42 -101.1428)
		(end 57.5056 -100.2284)
		(width 0.11684)
		(layer "F.Cu")
		(net "SPI_SYS_R1_CLK")
	)
	(segment
		(start 55.9308 -100.2284)
		(end 55.0672 -99.3648)
		(width 0.11684)
		(layer "F.Cu")
		(net "SPI_SYS_R1_CLK")
	)
	(segment
		(start 64.81191 -92.355924)
		(end 63.426848 -92.355924)
		(width 0.11684)
		(layer "F.Cu")
		(net "SPI_SYS_R1_CLK")
	)
	(segment
		(start 61.2648 -91.96324)
		(end 59.09056 -91.96324)
		(width 0.11684)
		(layer "F.Cu")
		(net "SPI_SYS_R1_CLK")
	)
	(segment
		(start 62.802008 -93.49486)
		(end 62.618874 -93.311726)
		(width 0.11684)
		(layer "F.Cu")
		(net "SPI_SYS_R1_CLK")
	)
	(segment
		(start 63.426848 -92.355924)
		(end 63.243714 -92.539058)
		(width 0.11684)
		(layer "F.Cu")
		(net "SPI_SYS_R1_CLK")
	)
	(segment
		(start 62.618874 -93.311726)
		(end 62.618874 -92.539058)
		(width 0.11684)
		(layer "F.Cu")
		(net "SPI_SYS_R1_CLK")
	)
	(segment
		(start 63.243714 -92.539058)
		(end 63.243714 -93.311726)
		(width 0.11684)
		(layer "F.Cu")
		(net "SPI_SYS_R1_CLK")
	)
	(segment
		(start 55.0672 -94.957392)
		(end 55.250334 -94.774258)
		(width 0.11684)
		(layer "F.Cu")
		(net "SPI_SYS_R1_CLK")
	)
	(segment
		(start 55.0672 -93.966284)
		(end 55.0672 -93.2688)
		(width 0.11684)
		(layer "F.Cu")
		(net "SPI_SYS_R1_CLK")
	)
	(segment
		(start 55.8292 -91.6432)
		(end 55.8292 -92.5068)
		(width 0.11684)
		(layer "F.Cu")
		(net "SPI_SYS_R1_CLK")
	)
	(segment
		(start 58.42 -104.691688)
		(end 58.42 -101.1428)
		(width 0.11684)
		(layer "F.Cu")
		(net "SPI_SYS_R1_CLK")
	)
	(segment
		(start 55.250334 -94.149418)
		(end 55.0672 -93.966284)
		(width 0.11684)
		(layer "F.Cu")
		(net "SPI_SYS_R1_CLK")
	)
	(segment
		(start 55.928006 -94.774258)
		(end 56.11114 -94.591124)
		(width 0.11684)
		(layer "F.Cu")
		(net "SPI_SYS_R1_CLK")
	)
	(segment
		(start 62.212982 -92.355924)
		(end 61.2648 -91.96324)
		(width 0.11684)
		(layer "F.Cu")
		(net "SPI_SYS_R1_CLK")
	)
	(segment
		(start 55.928006 -94.149418)
		(end 55.250334 -94.149418)
		(width 0.11684)
		(layer "F.Cu")
		(net "SPI_SYS_R1_CLK")
	)
	(segment
		(start 56.11114 -94.591124)
		(end 56.11114 -94.332552)
		(width 0.11684)
		(layer "F.Cu")
		(net "SPI_SYS_R1_CLK")
	)
	(segment
		(start 56.4896 -90.9828)
		(end 55.8292 -91.6432)
		(width 0.11684)
		(layer "F.Cu")
		(net "SPI_SYS_R1_CLK")
	)
	(segment
		(start 57.447688 -105.664)
		(end 58.42 -104.691688)
		(width 0.11684)
		(layer "F.Cu")
		(net "SPI_SYS_R1_CLK")
	)
	(segment
		(start 55.250334 -94.774258)
		(end 55.928006 -94.774258)
		(width 0.11684)
		(layer "F.Cu")
		(net "SPI_SYS_R1_CLK")
	)
	(segment
		(start 63.243714 -93.311726)
		(end 63.06058 -93.49486)
		(width 0.11684)
		(layer "F.Cu")
		(net "SPI_SYS_R1_CLK")
	)
	(segment
		(start 56.11114 -94.332552)
		(end 55.928006 -94.149418)
		(width 0.11684)
		(layer "F.Cu")
		(net "SPI_SYS_R1_CLK")
	)
	(segment
		(start 62.43574 -92.355924)
		(end 62.212982 -92.355924)
		(width 0.11684)
		(layer "F.Cu")
		(net "SPI_SYS_R1_CLK")
	)
	(segment
		(start 55.0672 -99.3648)
		(end 55.0672 -94.957392)
		(width 0.11684)
		(layer "F.Cu")
		(net "SPI_SYS_R1_CLK")
	)
	(segment
		(start 63.06058 -93.49486)
		(end 62.802008 -93.49486)
		(width 0.11684)
		(layer "F.Cu")
		(net "SPI_SYS_R1_CLK")
	)
	(via
		(at 55.8292 -92.5068)
		(size 0.762)
		(drill 0.381)
		(layers "F.Cu" "B.Cu")
		(net "SPI_SYS_R1_CLK")
	)
	(segment
		(start 54.5846 -117.3226)
		(end 54.5846 -118.340378)
		(width 0.11684)
		(layer "F.Cu")
		(net "SPI_SYS_HOLD_R_IO3")
	)
	(segment
		(start 55.11165 -116.214906)
		(end 55.17642 -116.371624)
		(width 0.11684)
		(layer "F.Cu")
		(net "SPI_SYS_HOLD_R_IO3")
	)
	(segment
		(start 52.6542 -109.79785)
		(end 52.68722 -109.83087)
		(width 0.11684)
		(layer "F.Cu")
		(net "SPI_SYS_HOLD_R_IO3")
	)
	(segment
		(start 55.17642 -116.371624)
		(end 55.17642 -116.597176)
		(width 0.11684)
		(layer "F.Cu")
		(net "SPI_SYS_HOLD_R_IO3")
	)
	(segment
		(start 54.720236 -115.629436)
		(end 55.11165 -116.214906)
		(width 0.11684)
		(layer "F.Cu")
		(net "SPI_SYS_HOLD_R_IO3")
	)
	(segment
		(start 54.5846 -118.340378)
		(end 54.464966 -118.460012)
		(width 0.11684)
		(layer "F.Cu")
		(net "SPI_SYS_HOLD_R_IO3")
	)
	(segment
		(start 52.68722 -113.59642)
		(end 54.720236 -115.629436)
		(width 0.11684)
		(layer "F.Cu")
		(net "SPI_SYS_HOLD_R_IO3")
	)
	(segment
		(start 52.68722 -109.83087)
		(end 52.68722 -113.59642)
		(width 0.11684)
		(layer "F.Cu")
		(net "SPI_SYS_HOLD_R_IO3")
	)
	(segment
		(start 55.17642 -116.597176)
		(end 55.081932 -116.825268)
		(width 0.11684)
		(layer "F.Cu")
		(net "SPI_SYS_HOLD_R_IO3")
	)
	(segment
		(start 55.081932 -116.825268)
		(end 54.5846 -117.3226)
		(width 0.11684)
		(layer "F.Cu")
		(net "SPI_SYS_HOLD_R_IO3")
	)
	(segment
		(start 56.866536 -118.258336)
		(end 56.866536 -117.352064)
		(width 0.11684)
		(layer "F.Cu")
		(net "SPI_SYS_CS0_N")
	)
	(segment
		(start 55.868316 -110.629954)
		(end 55.7784 -110.413038)
		(width 0.11684)
		(layer "F.Cu")
		(net "SPI_SYS_CS0_N")
	)
	(segment
		(start 56.865012 -118.25986)
		(end 56.866536 -118.258336)
		(width 0.11684)
		(layer "F.Cu")
		(net "SPI_SYS_CS0_N")
	)
	(segment
		(start 57.2008 -115.3922)
		(end 56.3372 -114.5286)
		(width 0.11684)
		(layer "F.Cu")
		(net "SPI_SYS_CS0_N")
	)
	(segment
		(start 56.3372 -113.919)
		(end 56.86044 -113.39576)
		(width 0.11684)
		(layer "F.Cu")
		(net "SPI_SYS_CS0_N")
	)
	(segment
		(start 55.7784 -110.413038)
		(end 55.7784 -109.79785)
		(width 0.11684)
		(layer "F.Cu")
		(net "SPI_SYS_CS0_N")
	)
	(segment
		(start 57.2008 -117.0178)
		(end 57.2008 -115.3922)
		(width 0.11684)
		(layer "F.Cu")
		(net "SPI_SYS_CS0_N")
	)
	(segment
		(start 56.86044 -113.39576)
		(end 56.86044 -112.231932)
		(width 0.11684)
		(layer "F.Cu")
		(net "SPI_SYS_CS0_N")
	)
	(segment
		(start 56.3372 -114.5286)
		(end 56.3372 -113.919)
		(width 0.11684)
		(layer "F.Cu")
		(net "SPI_SYS_CS0_N")
	)
	(segment
		(start 56.429402 -111.19104)
		(end 55.868316 -110.629954)
		(width 0.11684)
		(layer "F.Cu")
		(net "SPI_SYS_CS0_N")
	)
	(segment
		(start 56.86044 -112.231932)
		(end 56.429402 -111.19104)
		(width 0.11684)
		(layer "F.Cu")
		(net "SPI_SYS_CS0_N")
	)
	(segment
		(start 56.866536 -117.352064)
		(end 57.2008 -117.0178)
		(width 0.11684)
		(layer "F.Cu")
		(net "SPI_SYS_CS0_N")
	)
	(segment
		(start 55.295038 -55.371238)
		(end 55.690262 -55.766462)
		(width 0.11684)
		(layer "F.Cu")
		(net "SPI_BMC_BOOT_CS1_R1_N")
	)
	(via
		(at 55.690262 -55.766462)
		(size 0.4572)
		(drill 0.254)
		(layers "F.Cu" "B.Cu")
		(net "SPI_BMC_BOOT_CS1_R1_N")
	)
	(segment
		(start 56.890158 -57.15381)
		(end 56.890158 -58.807096)
		(width 0.11684)
		(layer "B.Cu")
		(net "SPI_BMC_BOOT_CS1_R1_N")
	)
	(segment
		(start 56.093614 -56.824372)
		(end 56.237124 -56.967882)
		(width 0.11684)
		(layer "B.Cu")
		(net "SPI_BMC_BOOT_CS1_R1_N")
	)
	(segment
		(start 57.2135 -59.130438)
		(end 57.2135 -59.4995)
		(width 0.11684)
		(layer "B.Cu")
		(net "SPI_BMC_BOOT_CS1_R1_N")
	)
	(segment
		(start 57.687464 -63.048388)
		(end 57.687464 -63.461646)
		(width 0.11684)
		(layer "B.Cu")
		(net "SPI_BMC_BOOT_CS1_R1_N")
	)
	(segment
		(start 56.70423 -56.967882)
		(end 56.890158 -57.15381)
		(width 0.11684)
		(layer "B.Cu")
		(net "SPI_BMC_BOOT_CS1_R1_N")
	)
	(segment
		(start 57.692798 -63.043054)
		(end 57.687464 -63.048388)
		(width 0.11684)
		(layer "B.Cu")
		(net "SPI_BMC_BOOT_CS1_R1_N")
	)
	(segment
		(start 56.237124 -56.967882)
		(end 56.70423 -56.967882)
		(width 0.11684)
		(layer "B.Cu")
		(net "SPI_BMC_BOOT_CS1_R1_N")
	)
	(segment
		(start 57.531 -59.817)
		(end 57.531 -61.595)
		(width 0.11684)
		(layer "B.Cu")
		(net "SPI_BMC_BOOT_CS1_R1_N")
	)
	(segment
		(start 56.093614 -56.169814)
		(end 56.093614 -56.824372)
		(width 0.11684)
		(layer "B.Cu")
		(net "SPI_BMC_BOOT_CS1_R1_N")
	)
	(segment
		(start 57.531 -61.595)
		(end 57.692798 -61.756798)
		(width 0.11684)
		(layer "B.Cu")
		(net "SPI_BMC_BOOT_CS1_R1_N")
	)
	(segment
		(start 56.890158 -58.807096)
		(end 57.2135 -59.130438)
		(width 0.11684)
		(layer "B.Cu")
		(net "SPI_BMC_BOOT_CS1_R1_N")
	)
	(segment
		(start 55.690262 -55.766462)
		(end 56.093614 -56.169814)
		(width 0.11684)
		(layer "B.Cu")
		(net "SPI_BMC_BOOT_CS1_R1_N")
	)
	(segment
		(start 57.2135 -59.4995)
		(end 57.531 -59.817)
		(width 0.11684)
		(layer "B.Cu")
		(net "SPI_BMC_BOOT_CS1_R1_N")
	)
	(segment
		(start 57.692798 -61.756798)
		(end 57.692798 -63.043054)
		(width 0.11684)
		(layer "B.Cu")
		(net "SPI_BMC_BOOT_CS1_R1_N")
	)
	(segment
		(start 54.494938 -56.171338)
		(end 54.890162 -55.776114)
		(width 0.11684)
		(layer "F.Cu")
		(net "SPI_BMC_BOOT_CS0_R1_N")
	)
	(via
		(at 54.890162 -55.776114)
		(size 0.4572)
		(drill 0.254)
		(layers "F.Cu" "B.Cu")
		(net "SPI_BMC_BOOT_CS0_R1_N")
	)
	(segment
		(start 56.710326 -60.40755)
		(end 56.710326 -59.986926)
		(width 0.11684)
		(layer "B.Cu")
		(net "SPI_BMC_BOOT_CS0_R1_N")
	)
	(segment
		(start 56.123332 -59.399932)
		(end 56.123332 -58.782712)
		(width 0.11684)
		(layer "B.Cu")
		(net "SPI_BMC_BOOT_CS0_R1_N")
	)
	(segment
		(start 55.2958 -58.34761)
		(end 55.2958 -56.181752)
		(width 0.11684)
		(layer "B.Cu")
		(net "SPI_BMC_BOOT_CS0_R1_N")
	)
	(segment
		(start 56.123332 -58.782712)
		(end 55.907686 -58.567066)
		(width 0.11684)
		(layer "B.Cu")
		(net "SPI_BMC_BOOT_CS0_R1_N")
	)
	(segment
		(start 55.907686 -58.567066)
		(end 55.515256 -58.567066)
		(width 0.11684)
		(layer "B.Cu")
		(net "SPI_BMC_BOOT_CS0_R1_N")
	)
	(segment
		(start 55.2958 -56.181752)
		(end 54.890162 -55.776114)
		(width 0.11684)
		(layer "B.Cu")
		(net "SPI_BMC_BOOT_CS0_R1_N")
	)
	(segment
		(start 56.710326 -59.986926)
		(end 56.123332 -59.399932)
		(width 0.11684)
		(layer "B.Cu")
		(net "SPI_BMC_BOOT_CS0_R1_N")
	)
	(segment
		(start 55.515256 -58.567066)
		(end 55.2958 -58.34761)
		(width 0.11684)
		(layer "B.Cu")
		(net "SPI_BMC_BOOT_CS0_R1_N")
	)
	(via
		(at 38.94582 -99.49434)
		(size 0.6604)
		(drill 0.3302)
		(layers "F.Cu" "B.Cu")
		(net "SPI_BMC_BIOS_SOURCE_CS0_N")
	)
	(segment
		(start 37.87521 -99.49434)
		(end 37.80155 -99.568)
		(width 0.11684)
		(layer "B.Cu")
		(net "SPI_BMC_BIOS_SOURCE_CS0_N")
	)
	(segment
		(start 38.94582 -99.49434)
		(end 37.87521 -99.49434)
		(width 0.11684)
		(layer "B.Cu")
		(net "SPI_BMC_BIOS_SOURCE_CS0_N")
	)
	(segment
		(start 39.529258 -100.077778)
		(end 38.94582 -99.49434)
		(width 0.11684)
		(layer "B.Cu")
		(net "SPI_BMC_BIOS_SOURCE_CS0_N")
	)
	(segment
		(start 40.969184 -100.077778)
		(end 39.529258 -100.077778)
		(width 0.11684)
		(layer "B.Cu")
		(net "SPI_BMC_BIOS_SOURCE_CS0_N")
	)
	(via
		(at 60.586874 -66.822574)
		(size 0.508)
		(drill 0.254)
		(layers "F.Cu" "B.Cu")
		(net "SPI_BMC_BIOS_ROM_R_IO3")
	)
	(via
		(at 58.849006 -85.063584)
		(size 0.508)
		(drill 0.254)
		(layers "F.Cu" "B.Cu")
		(net "SPI_BMC_BIOS_ROM_R_IO3")
	)
	(via
		(at 54.9275 -83.34502)
		(size 0.6604)
		(drill 0.3302)
		(layers "F.Cu" "B.Cu")
		(net "SPI_BMC_BIOS_ROM_R_IO3")
	)
	(segment
		(start 50.798984 -82.779616)
		(end 50.109628 -83.468972)
		(width 0.11684)
		(layer "B.Cu")
		(net "SPI_BMC_BIOS_ROM_R_IO3")
	)
	(segment
		(start 48.370236 -82.33664)
		(end 48.370236 -80.478884)
		(width 0.11684)
		(layer "B.Cu")
		(net "SPI_BMC_BIOS_ROM_R_IO3")
	)
	(segment
		(start 49.635664 -82.6516)
		(end 49.4284 -82.6516)
		(width 0.11684)
		(layer "B.Cu")
		(net "SPI_BMC_BIOS_ROM_R_IO3")
	)
	(segment
		(start 48.370236 -79.685388)
		(end 48.370236 -79.18704)
		(width 0.11684)
		(layer "B.Cu")
		(net "SPI_BMC_BIOS_ROM_R_IO3")
	)
	(segment
		(start 48.516794 -79.831946)
		(end 48.370236 -79.685388)
		(width 0.11684)
		(layer "B.Cu")
		(net "SPI_BMC_BIOS_ROM_R_IO3")
	)
	(segment
		(start 47.369476 -81.08188)
		(end 47.222918 -80.935322)
		(width 0.11684)
		(layer "B.Cu")
		(net "SPI_BMC_BIOS_ROM_R_IO3")
	)
	(segment
		(start 60.94222 -64.66967)
		(end 60.7314 -64.45885)
		(width 0.11684)
		(layer "B.Cu")
		(net "SPI_BMC_BIOS_ROM_R_IO3")
	)
	(segment
		(start 58.8518 -85.063584)
		(end 58.8518 -85.0646)
		(width 0.11684)
		(layer "B.Cu")
		(net "SPI_BMC_BIOS_ROM_R_IO3")
	)
	(segment
		(start 48.370236 -79.18704)
		(end 48.253396 -79.0702)
		(width 0.11684)
		(layer "B.Cu")
		(net "SPI_BMC_BIOS_ROM_R_IO3")
	)
	(segment
		(start 49.292256 -80.706722)
		(end 48.870616 -81.128362)
		(width 0.11684)
		(layer "B.Cu")
		(net "SPI_BMC_BIOS_ROM_R_IO3")
	)
	(segment
		(start 48.516794 -80.332326)
		(end 48.5902 -80.332326)
		(width 0.11684)
		(layer "B.Cu")
		(net "SPI_BMC_BIOS_ROM_R_IO3")
	)
	(segment
		(start 54.75732 -83.5152)
		(end 51.8668 -83.5152)
		(width 0.11684)
		(layer "B.Cu")
		(net "SPI_BMC_BIOS_ROM_R_IO3")
	)
	(segment
		(start 47.369476 -82.169)
		(end 47.369476 -81.08188)
		(width 0.11684)
		(layer "B.Cu")
		(net "SPI_BMC_BIOS_ROM_R_IO3")
	)
	(segment
		(start 58.3692 -85.0646)
		(end 56.64962 -83.34502)
		(width 0.11684)
		(layer "B.Cu")
		(net "SPI_BMC_BIOS_ROM_R_IO3")
	)
	(segment
		(start 50.83175 -81.92643)
		(end 50.71491 -81.80959)
		(width 0.11684)
		(layer "B.Cu")
		(net "SPI_BMC_BIOS_ROM_R_IO3")
	)
	(segment
		(start 48.870616 -82.33664)
		(end 48.753776 -82.45348)
		(width 0.11684)
		(layer "B.Cu")
		(net "SPI_BMC_BIOS_ROM_R_IO3")
	)
	(segment
		(start 50.71491 -81.80959)
		(end 50.477674 -81.80959)
		(width 0.11684)
		(layer "B.Cu")
		(net "SPI_BMC_BIOS_ROM_R_IO3")
	)
	(segment
		(start 48.5902 -79.831946)
		(end 48.516794 -79.831946)
		(width 0.11684)
		(layer "B.Cu")
		(net "SPI_BMC_BIOS_ROM_R_IO3")
	)
	(segment
		(start 51.131216 -82.779616)
		(end 50.798984 -82.779616)
		(width 0.11684)
		(layer "B.Cu")
		(net "SPI_BMC_BIOS_ROM_R_IO3")
	)
	(segment
		(start 58.8518 -85.0646)
		(end 58.3692 -85.0646)
		(width 0.11684)
		(layer "B.Cu")
		(net "SPI_BMC_BIOS_ROM_R_IO3")
	)
	(segment
		(start 49.82718 -83.352132)
		(end 49.82718 -83.168236)
		(width 0.11684)
		(layer "B.Cu")
		(net "SPI_BMC_BIOS_ROM_R_IO3")
	)
	(segment
		(start 48.370236 -80.478884)
		(end 48.516794 -80.332326)
		(width 0.11684)
		(layer "B.Cu")
		(net "SPI_BMC_BIOS_ROM_R_IO3")
	)
	(segment
		(start 47.986696 -79.0702)
		(end 47.869856 -79.18704)
		(width 0.11684)
		(layer "B.Cu")
		(net "SPI_BMC_BIOS_ROM_R_IO3")
	)
	(segment
		(start 48.5902 -80.332326)
		(end 48.7172 -80.205326)
		(width 0.11684)
		(layer "B.Cu")
		(net "SPI_BMC_BIOS_ROM_R_IO3")
	)
	(segment
		(start 47.723298 -79.948278)
		(end 47.263558 -79.948278)
		(width 0.11684)
		(layer "B.Cu")
		(net "SPI_BMC_BIOS_ROM_R_IO3")
	)
	(segment
		(start 48.870616 -81.128362)
		(end 48.870616 -82.33664)
		(width 0.11684)
		(layer "B.Cu")
		(net "SPI_BMC_BIOS_ROM_R_IO3")
	)
	(segment
		(start 47.0916 -80.120236)
		(end 47.0916 -80.321658)
		(width 0.11684)
		(layer "B.Cu")
		(net "SPI_BMC_BIOS_ROM_R_IO3")
	)
	(segment
		(start 50.090324 -81.281524)
		(end 49.515522 -80.706722)
		(width 0.11684)
		(layer "B.Cu")
		(net "SPI_BMC_BIOS_ROM_R_IO3")
	)
	(segment
		(start 54.9275 -83.34502)
		(end 54.75732 -83.5152)
		(width 0.11684)
		(layer "B.Cu")
		(net "SPI_BMC_BIOS_ROM_R_IO3")
	)
	(segment
		(start 49.4284 -82.6516)
		(end 49.281588 -82.504788)
		(width 0.11684)
		(layer "B.Cu")
		(net "SPI_BMC_BIOS_ROM_R_IO3")
	)
	(segment
		(start 49.515522 -80.706722)
		(end 49.292256 -80.706722)
		(width 0.11684)
		(layer "B.Cu")
		(net "SPI_BMC_BIOS_ROM_R_IO3")
	)
	(segment
		(start 50.109628 -83.468972)
		(end 49.94402 -83.468972)
		(width 0.11684)
		(layer "B.Cu")
		(net "SPI_BMC_BIOS_ROM_R_IO3")
	)
	(segment
		(start 47.222918 -80.935322)
		(end 46.019466 -80.935322)
		(width 0.11684)
		(layer "B.Cu")
		(net "SPI_BMC_BIOS_ROM_R_IO3")
	)
	(segment
		(start 49.94402 -83.468972)
		(end 49.82718 -83.352132)
		(width 0.11684)
		(layer "B.Cu")
		(net "SPI_BMC_BIOS_ROM_R_IO3")
	)
	(segment
		(start 49.82718 -83.168236)
		(end 50.83175 -82.163666)
		(width 0.11684)
		(layer "B.Cu")
		(net "SPI_BMC_BIOS_ROM_R_IO3")
	)
	(segment
		(start 48.253396 -79.0702)
		(end 47.986696 -79.0702)
		(width 0.11684)
		(layer "B.Cu")
		(net "SPI_BMC_BIOS_ROM_R_IO3")
	)
	(segment
		(start 60.586874 -66.822574)
		(end 60.94222 -66.467228)
		(width 0.11684)
		(layer "B.Cu")
		(net "SPI_BMC_BIOS_ROM_R_IO3")
	)
	(segment
		(start 47.697898 -82.296)
		(end 47.496476 -82.296)
		(width 0.11684)
		(layer "B.Cu")
		(net "SPI_BMC_BIOS_ROM_R_IO3")
	)
	(segment
		(start 51.8668 -83.5152)
		(end 51.131216 -82.779616)
		(width 0.11684)
		(layer "B.Cu")
		(net "SPI_BMC_BIOS_ROM_R_IO3")
	)
	(segment
		(start 49.281588 -82.297524)
		(end 50.090324 -81.488788)
		(width 0.11684)
		(layer "B.Cu")
		(net "SPI_BMC_BIOS_ROM_R_IO3")
	)
	(segment
		(start 50.477674 -81.80959)
		(end 49.635664 -82.6516)
		(width 0.11684)
		(layer "B.Cu")
		(net "SPI_BMC_BIOS_ROM_R_IO3")
	)
	(segment
		(start 48.487076 -82.45348)
		(end 48.370236 -82.33664)
		(width 0.11684)
		(layer "B.Cu")
		(net "SPI_BMC_BIOS_ROM_R_IO3")
	)
	(segment
		(start 47.0916 -80.321658)
		(end 47.2186 -80.448658)
		(width 0.11684)
		(layer "B.Cu")
		(net "SPI_BMC_BIOS_ROM_R_IO3")
	)
	(segment
		(start 47.869856 -79.18704)
		(end 47.869856 -79.80172)
		(width 0.11684)
		(layer "B.Cu")
		(net "SPI_BMC_BIOS_ROM_R_IO3")
	)
	(segment
		(start 47.723298 -80.448658)
		(end 47.869856 -80.595216)
		(width 0.11684)
		(layer "B.Cu")
		(net "SPI_BMC_BIOS_ROM_R_IO3")
	)
	(segment
		(start 47.869856 -79.80172)
		(end 47.723298 -79.948278)
		(width 0.11684)
		(layer "B.Cu")
		(net "SPI_BMC_BIOS_ROM_R_IO3")
	)
	(segment
		(start 47.869856 -80.595216)
		(end 47.869856 -82.124042)
		(width 0.11684)
		(layer "B.Cu")
		(net "SPI_BMC_BIOS_ROM_R_IO3")
	)
	(segment
		(start 47.869856 -82.124042)
		(end 47.697898 -82.296)
		(width 0.11684)
		(layer "B.Cu")
		(net "SPI_BMC_BIOS_ROM_R_IO3")
	)
	(segment
		(start 50.090324 -81.488788)
		(end 50.090324 -81.281524)
		(width 0.11684)
		(layer "B.Cu")
		(net "SPI_BMC_BIOS_ROM_R_IO3")
	)
	(segment
		(start 58.849006 -85.063584)
		(end 58.8518 -85.063584)
		(width 0.11684)
		(layer "B.Cu")
		(net "SPI_BMC_BIOS_ROM_R_IO3")
	)
	(segment
		(start 49.281588 -82.504788)
		(end 49.281588 -82.297524)
		(width 0.11684)
		(layer "B.Cu")
		(net "SPI_BMC_BIOS_ROM_R_IO3")
	)
	(segment
		(start 60.94222 -66.467228)
		(end 60.94222 -64.66967)
		(width 0.11684)
		(layer "B.Cu")
		(net "SPI_BMC_BIOS_ROM_R_IO3")
	)
	(segment
		(start 48.753776 -82.45348)
		(end 48.487076 -82.45348)
		(width 0.11684)
		(layer "B.Cu")
		(net "SPI_BMC_BIOS_ROM_R_IO3")
	)
	(segment
		(start 50.83175 -82.163666)
		(end 50.83175 -81.92643)
		(width 0.11684)
		(layer "B.Cu")
		(net "SPI_BMC_BIOS_ROM_R_IO3")
	)
	(segment
		(start 48.7172 -79.958946)
		(end 48.5902 -79.831946)
		(width 0.11684)
		(layer "B.Cu")
		(net "SPI_BMC_BIOS_ROM_R_IO3")
	)
	(segment
		(start 47.263558 -79.948278)
		(end 47.0916 -80.120236)
		(width 0.11684)
		(layer "B.Cu")
		(net "SPI_BMC_BIOS_ROM_R_IO3")
	)
	(segment
		(start 48.7172 -80.205326)
		(end 48.7172 -79.958946)
		(width 0.11684)
		(layer "B.Cu")
		(net "SPI_BMC_BIOS_ROM_R_IO3")
	)
	(segment
		(start 47.496476 -82.296)
		(end 47.369476 -82.169)
		(width 0.11684)
		(layer "B.Cu")
		(net "SPI_BMC_BIOS_ROM_R_IO3")
	)
	(segment
		(start 56.64962 -83.34502)
		(end 54.9275 -83.34502)
		(width 0.11684)
		(layer "B.Cu")
		(net "SPI_BMC_BIOS_ROM_R_IO3")
	)
	(segment
		(start 47.2186 -80.448658)
		(end 47.723298 -80.448658)
		(width 0.11684)
		(layer "B.Cu")
		(net "SPI_BMC_BIOS_ROM_R_IO3")
	)
	(segment
		(start 60.6298 -83.439)
		(end 60.6298 -82.758788)
		(width 0.08382)
		(layer "In9.Cu")
		(net "SPI_BMC_BIOS_ROM_R_IO3")
	)
	(segment
		(start 59.99988 -67.409568)
		(end 60.586874 -66.822574)
		(width 0.08382)
		(layer "In9.Cu")
		(net "SPI_BMC_BIOS_ROM_R_IO3")
	)
	(segment
		(start 60.08624 -72.139048)
		(end 59.62904 -72.139048)
		(width 0.08382)
		(layer "In9.Cu")
		(net "SPI_BMC_BIOS_ROM_R_IO3")
	)
	(segment
		(start 60.25388 -72.563228)
		(end 60.25388 -72.306688)
		(width 0.08382)
		(layer "In9.Cu")
		(net "SPI_BMC_BIOS_ROM_R_IO3")
	)
	(segment
		(start 58.849006 -85.063584)
		(end 58.8518 -85.06079)
		(width 0.08382)
		(layer "In9.Cu")
		(net "SPI_BMC_BIOS_ROM_R_IO3")
	)
	(segment
		(start 59.21375 -81.342738)
		(end 59.21375 -76.311506)
		(width 0.08382)
		(layer "In9.Cu")
		(net "SPI_BMC_BIOS_ROM_R_IO3")
	)
	(segment
		(start 59.4614 -71.2216)
		(end 59.99988 -70.68312)
		(width 0.08382)
		(layer "In9.Cu")
		(net "SPI_BMC_BIOS_ROM_R_IO3")
	)
	(segment
		(start 59.21375 -76.311506)
		(end 59.01309 -76.110846)
		(width 0.08382)
		(layer "In9.Cu")
		(net "SPI_BMC_BIOS_ROM_R_IO3")
	)
	(segment
		(start 61.20638 -89.17432)
		(end 61.3537 -89.027)
		(width 0.08382)
		(layer "In9.Cu")
		(net "SPI_BMC_BIOS_ROM_R_IO3")
	)
	(segment
		(start 60.6298 -82.758788)
		(end 59.21375 -81.342738)
		(width 0.08382)
		(layer "In9.Cu")
		(net "SPI_BMC_BIOS_ROM_R_IO3")
	)
	(segment
		(start 59.4614 -71.971408)
		(end 59.4614 -71.2216)
		(width 0.08382)
		(layer "In9.Cu")
		(net "SPI_BMC_BIOS_ROM_R_IO3")
	)
	(segment
		(start 60.25388 -72.306688)
		(end 60.08624 -72.139048)
		(width 0.08382)
		(layer "In9.Cu")
		(net "SPI_BMC_BIOS_ROM_R_IO3")
	)
	(segment
		(start 60.833 -89.17432)
		(end 61.20638 -89.17432)
		(width 0.08382)
		(layer "In9.Cu")
		(net "SPI_BMC_BIOS_ROM_R_IO3")
	)
	(segment
		(start 60.66917 -84.98713)
		(end 60.66917 -89.01049)
		(width 0.08382)
		(layer "In9.Cu")
		(net "SPI_BMC_BIOS_ROM_R_IO3")
	)
	(segment
		(start 58.8518 -84.7344)
		(end 59.0042 -84.582)
		(width 0.08382)
		(layer "In9.Cu")
		(net "SPI_BMC_BIOS_ROM_R_IO3")
	)
	(segment
		(start 60.41263 -83.893406)
		(end 60.41263 -83.65617)
		(width 0.08382)
		(layer "In9.Cu")
		(net "SPI_BMC_BIOS_ROM_R_IO3")
	)
	(segment
		(start 58.8518 -85.06079)
		(end 58.8518 -84.7344)
		(width 0.08382)
		(layer "In9.Cu")
		(net "SPI_BMC_BIOS_ROM_R_IO3")
	)
	(segment
		(start 61.3537 -84.834476)
		(end 60.41263 -83.893406)
		(width 0.08382)
		(layer "In9.Cu")
		(net "SPI_BMC_BIOS_ROM_R_IO3")
	)
	(segment
		(start 60.26404 -84.582)
		(end 60.66917 -84.98713)
		(width 0.08382)
		(layer "In9.Cu")
		(net "SPI_BMC_BIOS_ROM_R_IO3")
	)
	(segment
		(start 59.99988 -70.68312)
		(end 59.99988 -67.409568)
		(width 0.08382)
		(layer "In9.Cu")
		(net "SPI_BMC_BIOS_ROM_R_IO3")
	)
	(segment
		(start 60.41263 -83.65617)
		(end 60.6298 -83.439)
		(width 0.08382)
		(layer "In9.Cu")
		(net "SPI_BMC_BIOS_ROM_R_IO3")
	)
	(segment
		(start 60.66917 -89.01049)
		(end 60.833 -89.17432)
		(width 0.08382)
		(layer "In9.Cu")
		(net "SPI_BMC_BIOS_ROM_R_IO3")
	)
	(segment
		(start 59.01309 -73.804018)
		(end 60.25388 -72.563228)
		(width 0.08382)
		(layer "In9.Cu")
		(net "SPI_BMC_BIOS_ROM_R_IO3")
	)
	(segment
		(start 59.62904 -72.139048)
		(end 59.4614 -71.971408)
		(width 0.08382)
		(layer "In9.Cu")
		(net "SPI_BMC_BIOS_ROM_R_IO3")
	)
	(segment
		(start 61.3537 -89.027)
		(end 61.3537 -84.834476)
		(width 0.08382)
		(layer "In9.Cu")
		(net "SPI_BMC_BIOS_ROM_R_IO3")
	)
	(segment
		(start 59.01309 -76.110846)
		(end 59.01309 -73.804018)
		(width 0.08382)
		(layer "In9.Cu")
		(net "SPI_BMC_BIOS_ROM_R_IO3")
	)
	(segment
		(start 59.0042 -84.582)
		(end 60.26404 -84.582)
		(width 0.08382)
		(layer "In9.Cu")
		(net "SPI_BMC_BIOS_ROM_R_IO3")
	)
	(segment
		(start 59.69 -64.48425)
		(end 59.7154 -64.45885)
		(width 0.11684)
		(layer "F.Cu")
		(net "SPI_BMC_BIOS_ROM_R_IO2")
	)
	(segment
		(start 59.756802 -68.214748)
		(end 59.756802 -67.451986)
		(width 0.11684)
		(layer "F.Cu")
		(net "SPI_BMC_BIOS_ROM_R_IO2")
	)
	(segment
		(start 59.69 -66.952114)
		(end 59.69 -64.48425)
		(width 0.11684)
		(layer "F.Cu")
		(net "SPI_BMC_BIOS_ROM_R_IO2")
	)
	(segment
		(start 59.756802 -67.451986)
		(end 59.69 -67.385184)
		(width 0.11684)
		(layer "F.Cu")
		(net "SPI_BMC_BIOS_ROM_R_IO2")
	)
	(segment
		(start 61.490098 -68.942458)
		(end 60.484512 -68.942458)
		(width 0.11684)
		(layer "F.Cu")
		(net "SPI_BMC_BIOS_ROM_R_IO2")
	)
	(segment
		(start 59.69 -67.385184)
		(end 59.69 -66.952114)
		(width 0.11684)
		(layer "F.Cu")
		(net "SPI_BMC_BIOS_ROM_R_IO2")
	)
	(segment
		(start 60.484512 -68.942458)
		(end 59.756802 -68.214748)
		(width 0.11684)
		(layer "F.Cu")
		(net "SPI_BMC_BIOS_ROM_R_IO2")
	)
	(segment
		(start 59.69 -66.952114)
		(end 59.691524 -66.952114)
		(width 0.11684)
		(layer "F.Cu")
		(net "SPI_BMC_BIOS_ROM_R_IO2")
	)
	(via
		(at 61.490098 -68.942458)
		(size 0.508)
		(drill 0.254)
		(layers "F.Cu" "B.Cu")
		(net "SPI_BMC_BIOS_ROM_R_IO2")
	)
	(via
		(at 61.8998 -94.67342)
		(size 0.508)
		(drill 0.254)
		(layers "F.Cu" "B.Cu")
		(net "SPI_BMC_BIOS_ROM_R_IO2")
	)
	(via
		(at 59.691524 -66.952114)
		(size 0.762)
		(drill 0.381)
		(layers "F.Cu" "B.Cu")
		(net "SPI_BMC_BIOS_ROM_R_IO2")
	)
	(segment
		(start 52.1462 -101.7016)
		(end 53.9242 -99.9236)
		(width 0.11684)
		(layer "B.Cu")
		(net "SPI_BMC_BIOS_ROM_R_IO2")
	)
	(segment
		(start 62.58052 -100.8888)
		(end 62.58052 -97.396554)
		(width 0.11684)
		(layer "B.Cu")
		(net "SPI_BMC_BIOS_ROM_R_IO2")
	)
	(segment
		(start 49.379886 -103.188008)
		(end 50.1142 -102.453694)
		(width 0.11684)
		(layer "B.Cu")
		(net "SPI_BMC_BIOS_ROM_R_IO2")
	)
	(segment
		(start 55.403242 -99.9236)
		(end 59.021218 -101.4222)
		(width 0.11684)
		(layer "B.Cu")
		(net "SPI_BMC_BIOS_ROM_R_IO2")
	)
	(segment
		(start 50.1142 -102.108)
		(end 50.5206 -101.7016)
		(width 0.11684)
		(layer "B.Cu")
		(net "SPI_BMC_BIOS_ROM_R_IO2")
	)
	(segment
		(start 59.021218 -101.4222)
		(end 62.04712 -101.4222)
		(width 0.11684)
		(layer "B.Cu")
		(net "SPI_BMC_BIOS_ROM_R_IO2")
	)
	(segment
		(start 46.811184 -102.677976)
		(end 47.777654 -102.677976)
		(width 0.11684)
		(layer "B.Cu")
		(net "SPI_BMC_BIOS_ROM_R_IO2")
	)
	(segment
		(start 48.287686 -103.188008)
		(end 49.379886 -103.188008)
		(width 0.11684)
		(layer "B.Cu")
		(net "SPI_BMC_BIOS_ROM_R_IO2")
	)
	(segment
		(start 62.237366 -94.67342)
		(end 61.8998 -94.67342)
		(width 0.11684)
		(layer "B.Cu")
		(net "SPI_BMC_BIOS_ROM_R_IO2")
	)
	(segment
		(start 62.58052 -97.396554)
		(end 62.78372 -97.193354)
		(width 0.11684)
		(layer "B.Cu")
		(net "SPI_BMC_BIOS_ROM_R_IO2")
	)
	(segment
		(start 62.04712 -101.4222)
		(end 62.58052 -100.8888)
		(width 0.11684)
		(layer "B.Cu")
		(net "SPI_BMC_BIOS_ROM_R_IO2")
	)
	(segment
		(start 50.5206 -101.7016)
		(end 52.1462 -101.7016)
		(width 0.11684)
		(layer "B.Cu")
		(net "SPI_BMC_BIOS_ROM_R_IO2")
	)
	(segment
		(start 62.78372 -97.193354)
		(end 62.78372 -95.219774)
		(width 0.11684)
		(layer "B.Cu")
		(net "SPI_BMC_BIOS_ROM_R_IO2")
	)
	(segment
		(start 53.9242 -99.9236)
		(end 55.403242 -99.9236)
		(width 0.11684)
		(layer "B.Cu")
		(net "SPI_BMC_BIOS_ROM_R_IO2")
	)
	(segment
		(start 47.777654 -102.677976)
		(end 48.287686 -103.188008)
		(width 0.11684)
		(layer "B.Cu")
		(net "SPI_BMC_BIOS_ROM_R_IO2")
	)
	(segment
		(start 50.1142 -102.453694)
		(end 50.1142 -102.108)
		(width 0.11684)
		(layer "B.Cu")
		(net "SPI_BMC_BIOS_ROM_R_IO2")
	)
	(segment
		(start 62.78372 -95.219774)
		(end 62.237366 -94.67342)
		(width 0.11684)
		(layer "B.Cu")
		(net "SPI_BMC_BIOS_ROM_R_IO2")
	)
	(segment
		(start 62.6491 -94.2975)
		(end 62.27318 -94.67342)
		(width 0.08382)
		(layer "In9.Cu")
		(net "SPI_BMC_BIOS_ROM_R_IO2")
	)
	(segment
		(start 61.490098 -68.942458)
		(end 61.490098 -69.975984)
		(width 0.08382)
		(layer "In9.Cu")
		(net "SPI_BMC_BIOS_ROM_R_IO2")
	)
	(segment
		(start 63.0682 -71.554086)
		(end 63.0682 -73.507346)
		(width 0.08382)
		(layer "In9.Cu")
		(net "SPI_BMC_BIOS_ROM_R_IO2")
	)
	(segment
		(start 63.8556 -78.03642)
		(end 62.2046 -79.68742)
		(width 0.08382)
		(layer "In9.Cu")
		(net "SPI_BMC_BIOS_ROM_R_IO2")
	)
	(segment
		(start 62.6491 -82.936588)
		(end 62.6491 -94.2975)
		(width 0.08382)
		(layer "In9.Cu")
		(net "SPI_BMC_BIOS_ROM_R_IO2")
	)
	(segment
		(start 63.414656 -73.853802)
		(end 63.414656 -76.521056)
		(width 0.08382)
		(layer "In9.Cu")
		(net "SPI_BMC_BIOS_ROM_R_IO2")
	)
	(segment
		(start 62.27318 -94.67342)
		(end 61.8998 -94.67342)
		(width 0.08382)
		(layer "In9.Cu")
		(net "SPI_BMC_BIOS_ROM_R_IO2")
	)
	(segment
		(start 63.414656 -76.521056)
		(end 63.8556 -76.962)
		(width 0.08382)
		(layer "In9.Cu")
		(net "SPI_BMC_BIOS_ROM_R_IO2")
	)
	(segment
		(start 63.8556 -76.962)
		(end 63.8556 -78.03642)
		(width 0.08382)
		(layer "In9.Cu")
		(net "SPI_BMC_BIOS_ROM_R_IO2")
	)
	(segment
		(start 62.2046 -79.68742)
		(end 62.2046 -81.863692)
		(width 0.08382)
		(layer "In9.Cu")
		(net "SPI_BMC_BIOS_ROM_R_IO2")
	)
	(segment
		(start 61.490098 -69.975984)
		(end 63.0682 -71.554086)
		(width 0.08382)
		(layer "In9.Cu")
		(net "SPI_BMC_BIOS_ROM_R_IO2")
	)
	(segment
		(start 63.0682 -73.507346)
		(end 63.414656 -73.853802)
		(width 0.08382)
		(layer "In9.Cu")
		(net "SPI_BMC_BIOS_ROM_R_IO2")
	)
	(segment
		(start 62.2046 -81.863692)
		(end 62.6491 -82.936588)
		(width 0.08382)
		(layer "In9.Cu")
		(net "SPI_BMC_BIOS_ROM_R_IO2")
	)
	(segment
		(start 57.29986 -56.566562)
		(end 57.29986 -56.57088)
		(width 0.11684)
		(layer "F.Cu")
		(net "SPI_BMC_BIOS_ROM_IO3")
	)
	(segment
		(start 57.695084 -56.171338)
		(end 57.29986 -56.566562)
		(width 0.11684)
		(layer "F.Cu")
		(net "SPI_BMC_BIOS_ROM_IO3")
	)
	(via
		(at 59.70778 -60.195206)
		(size 0.6604)
		(drill 0.3302)
		(layers "F.Cu" "B.Cu")
		(net "SPI_BMC_BIOS_ROM_IO3")
	)
	(via
		(at 57.29986 -56.57088)
		(size 0.4572)
		(drill 0.254)
		(layers "F.Cu" "B.Cu")
		(net "SPI_BMC_BIOS_ROM_IO3")
	)
	(segment
		(start 59.86399 -57.767728)
		(end 59.456828 -57.767728)
		(width 0.11684)
		(layer "B.Cu")
		(net "SPI_BMC_BIOS_ROM_IO3")
	)
	(segment
		(start 59.70778 -58.914538)
		(end 60.109354 -58.512964)
		(width 0.11684)
		(layer "B.Cu")
		(net "SPI_BMC_BIOS_ROM_IO3")
	)
	(segment
		(start 60.109354 -58.512964)
		(end 60.109354 -58.013092)
		(width 0.11684)
		(layer "B.Cu")
		(net "SPI_BMC_BIOS_ROM_IO3")
	)
	(segment
		(start 59.29376 -57.215786)
		(end 59.051952 -56.973978)
		(width 0.11684)
		(layer "B.Cu")
		(net "SPI_BMC_BIOS_ROM_IO3")
	)
	(segment
		(start 57.553352 -56.57088)
		(end 57.29986 -56.57088)
		(width 0.11684)
		(layer "B.Cu")
		(net "SPI_BMC_BIOS_ROM_IO3")
	)
	(segment
		(start 59.456828 -57.767728)
		(end 59.30392 -57.61482)
		(width 0.11684)
		(layer "B.Cu")
		(net "SPI_BMC_BIOS_ROM_IO3")
	)
	(segment
		(start 60.109354 -58.013092)
		(end 59.86399 -57.767728)
		(width 0.11684)
		(layer "B.Cu")
		(net "SPI_BMC_BIOS_ROM_IO3")
	)
	(segment
		(start 59.707272 -63.187326)
		(end 59.707272 -60.680092)
		(width 0.11684)
		(layer "B.Cu")
		(net "SPI_BMC_BIOS_ROM_IO3")
	)
	(segment
		(start 59.70778 -60.195206)
		(end 59.70778 -58.914538)
		(width 0.11684)
		(layer "B.Cu")
		(net "SPI_BMC_BIOS_ROM_IO3")
	)
	(segment
		(start 60.178696 -63.65875)
		(end 59.707272 -63.187326)
		(width 0.11684)
		(layer "B.Cu")
		(net "SPI_BMC_BIOS_ROM_IO3")
	)
	(segment
		(start 57.95645 -56.973978)
		(end 57.553352 -56.57088)
		(width 0.11684)
		(layer "B.Cu")
		(net "SPI_BMC_BIOS_ROM_IO3")
	)
	(segment
		(start 60.7314 -63.65875)
		(end 60.178696 -63.65875)
		(width 0.11684)
		(layer "B.Cu")
		(net "SPI_BMC_BIOS_ROM_IO3")
	)
	(segment
		(start 59.051952 -56.973978)
		(end 57.95645 -56.973978)
		(width 0.11684)
		(layer "B.Cu")
		(net "SPI_BMC_BIOS_ROM_IO3")
	)
	(segment
		(start 59.707272 -60.680092)
		(end 59.70778 -60.195206)
		(width 0.11684)
		(layer "B.Cu")
		(net "SPI_BMC_BIOS_ROM_IO3")
	)
	(segment
		(start 59.30392 -57.61482)
		(end 59.29376 -57.61482)
		(width 0.11684)
		(layer "B.Cu")
		(net "SPI_BMC_BIOS_ROM_IO3")
	)
	(segment
		(start 59.29376 -57.61482)
		(end 59.29376 -57.215786)
		(width 0.11684)
		(layer "B.Cu")
		(net "SPI_BMC_BIOS_ROM_IO3")
	)
	(segment
		(start 59.772804 -62.349888)
		(end 59.7154 -62.407292)
		(width 0.11684)
		(layer "F.Cu")
		(net "SPI_BMC_BIOS_ROM_IO2")
	)
	(segment
		(start 58.82132 -60.952126)
		(end 58.82132 -59.69762)
		(width 0.11684)
		(layer "F.Cu")
		(net "SPI_BMC_BIOS_ROM_IO2")
	)
	(segment
		(start 58.82132 -59.69762)
		(end 58.49493 -59.37123)
		(width 0.11684)
		(layer "F.Cu")
		(net "SPI_BMC_BIOS_ROM_IO2")
	)
	(segment
		(start 59.772804 -62.349888)
		(end 59.772804 -61.90361)
		(width 0.11684)
		(layer "F.Cu")
		(net "SPI_BMC_BIOS_ROM_IO2")
	)
	(segment
		(start 59.772804 -61.90361)
		(end 58.82132 -60.952126)
		(width 0.11684)
		(layer "F.Cu")
		(net "SPI_BMC_BIOS_ROM_IO2")
	)
	(segment
		(start 59.7154 -62.407292)
		(end 59.7154 -63.65875)
		(width 0.11684)
		(layer "F.Cu")
		(net "SPI_BMC_BIOS_ROM_IO2")
	)
	(via
		(at 59.772804 -62.349888)
		(size 0.762)
		(drill 0.381)
		(layers "F.Cu" "B.Cu")
		(net "SPI_BMC_BIOS_ROM_IO2")
	)
	(segment
		(start 62.003432 -65.631314)
		(end 62.2808 -65.353946)
		(width 0.11684)
		(layer "F.Cu")
		(net "SPI_BMC_BIOS_CS0_R1_N")
	)
	(segment
		(start 62.0141 -63.73368)
		(end 62.0141 -62.021974)
		(width 0.11684)
		(layer "F.Cu")
		(net "SPI_BMC_BIOS_CS0_R1_N")
	)
	(segment
		(start 62.0141 -62.021974)
		(end 61.551566 -61.55944)
		(width 0.11684)
		(layer "F.Cu")
		(net "SPI_BMC_BIOS_CS0_R1_N")
	)
	(segment
		(start 59.690254 -60.587636)
		(end 59.690254 -58.966354)
		(width 0.11684)
		(layer "F.Cu")
		(net "SPI_BMC_BIOS_CS0_R1_N")
	)
	(segment
		(start 62.2808 -65.353946)
		(end 62.2808 -64.541146)
		(width 0.11684)
		(layer "F.Cu")
		(net "SPI_BMC_BIOS_CS0_R1_N")
	)
	(segment
		(start 60.662058 -61.55944)
		(end 59.690254 -60.587636)
		(width 0.11684)
		(layer "F.Cu")
		(net "SPI_BMC_BIOS_CS0_R1_N")
	)
	(segment
		(start 61.70676 -65.631314)
		(end 62.003432 -65.631314)
		(width 0.11684)
		(layer "F.Cu")
		(net "SPI_BMC_BIOS_CS0_R1_N")
	)
	(segment
		(start 62.0141 -64.274446)
		(end 62.0141 -63.73368)
		(width 0.11684)
		(layer "F.Cu")
		(net "SPI_BMC_BIOS_CS0_R1_N")
	)
	(segment
		(start 62.2808 -64.541146)
		(end 62.0141 -64.274446)
		(width 0.11684)
		(layer "F.Cu")
		(net "SPI_BMC_BIOS_CS0_R1_N")
	)
	(segment
		(start 61.551566 -61.55944)
		(end 60.662058 -61.55944)
		(width 0.11684)
		(layer "F.Cu")
		(net "SPI_BMC_BIOS_CS0_R1_N")
	)
	(segment
		(start 59.690254 -58.966354)
		(end 59.29503 -58.57113)
		(width 0.11684)
		(layer "F.Cu")
		(net "SPI_BMC_BIOS_CS0_R1_N")
	)
	(via
		(at 62.0141 -63.73368)
		(size 0.762)
		(drill 0.381)
		(layers "F.Cu" "B.Cu")
		(net "SPI_BMC_BIOS_CS0_R1_N")
	)
	(segment
		(start 25.4 -110.311946)
		(end 27.94 -112.851946)
		(width 0.11684)
		(layer "F.Cu")
		(net "QSPI_2_PLD_IO3")
	)
	(segment
		(start 51.605942 -74.687684)
		(end 53.213 -73.080626)
		(width 0.11684)
		(layer "F.Cu")
		(net "QSPI_2_PLD_IO3")
	)
	(segment
		(start 26.279094 -108.17225)
		(end 26.279094 -108.61294)
		(width 0.11684)
		(layer "F.Cu")
		(net "QSPI_2_PLD_IO3")
	)
	(segment
		(start 27.94 -115.062254)
		(end 27.54503 -115.457224)
		(width 0.11684)
		(layer "F.Cu")
		(net "QSPI_2_PLD_IO3")
	)
	(segment
		(start 49.901348 -74.687684)
		(end 51.605942 -74.687684)
		(width 0.11684)
		(layer "F.Cu")
		(net "QSPI_2_PLD_IO3")
	)
	(segment
		(start 53.213 -73.080626)
		(end 53.213 -70.12305)
		(width 0.11684)
		(layer "F.Cu")
		(net "QSPI_2_PLD_IO3")
	)
	(segment
		(start 27.94 -112.851946)
		(end 27.94 -115.062254)
		(width 0.11684)
		(layer "F.Cu")
		(net "QSPI_2_PLD_IO3")
	)
	(segment
		(start 25.4 -109.492034)
		(end 25.4 -110.311946)
		(width 0.11684)
		(layer "F.Cu")
		(net "QSPI_2_PLD_IO3")
	)
	(segment
		(start 27.54503 -115.457224)
		(end 27.54503 -118.25986)
		(width 0.11684)
		(layer "F.Cu")
		(net "QSPI_2_PLD_IO3")
	)
	(segment
		(start 49.896522 -74.69251)
		(end 49.901348 -74.687684)
		(width 0.11684)
		(layer "F.Cu")
		(net "QSPI_2_PLD_IO3")
	)
	(segment
		(start 26.279094 -108.61294)
		(end 25.4 -109.492034)
		(width 0.11684)
		(layer "F.Cu")
		(net "QSPI_2_PLD_IO3")
	)
	(via
		(at 49.896522 -74.69251)
		(size 0.508)
		(drill 0.254)
		(layers "F.Cu" "B.Cu")
		(net "QSPI_2_PLD_IO3")
	)
	(via
		(at 26.279094 -108.17225)
		(size 0.508)
		(drill 0.254)
		(layers "F.Cu" "B.Cu")
		(net "QSPI_2_PLD_IO3")
	)
	(segment
		(start 37.1094 -98.7044)
		(end 37.1094 -96.058228)
		(width 0.08382)
		(layer "In9.Cu")
		(net "QSPI_2_PLD_IO3")
	)
	(segment
		(start 33.576514 -106.453686)
		(end 36.091114 -106.453686)
		(width 0.08382)
		(layer "In9.Cu")
		(net "QSPI_2_PLD_IO3")
	)
	(segment
		(start 37.1094 -96.058228)
		(end 39.566596 -93.601032)
		(width 0.08382)
		(layer "In9.Cu")
		(net "QSPI_2_PLD_IO3")
	)
	(segment
		(start 43.165268 -83.02117)
		(end 43.165268 -82.765646)
		(width 0.08382)
		(layer "In9.Cu")
		(net "QSPI_2_PLD_IO3")
	)
	(segment
		(start 26.279094 -108.17225)
		(end 26.803096 -108.17225)
		(width 0.08382)
		(layer "In9.Cu")
		(net "QSPI_2_PLD_IO3")
	)
	(segment
		(start 43.948858 -84.422742)
		(end 44.12996 -84.24164)
		(width 0.08382)
		(layer "In9.Cu")
		(net "QSPI_2_PLD_IO3")
	)
	(segment
		(start 40.970708 -94.131892)
		(end 40.970708 -93.876368)
		(width 0.08382)
		(layer "In9.Cu")
		(net "QSPI_2_PLD_IO3")
	)
	(segment
		(start 40.956484 -91.020138)
		(end 39.67607 -89.739724)
		(width 0.08382)
		(layer "In9.Cu")
		(net "QSPI_2_PLD_IO3")
	)
	(segment
		(start 43.601894 -82.584544)
		(end 44.363132 -83.346036)
		(width 0.08382)
		(layer "In9.Cu")
		(net "QSPI_2_PLD_IO3")
	)
	(segment
		(start 43.165268 -82.765646)
		(end 43.34637 -82.584544)
		(width 0.08382)
		(layer "In9.Cu")
		(net "QSPI_2_PLD_IO3")
	)
	(segment
		(start 45.41266 -81.28254)
		(end 45.76318 -80.93202)
		(width 0.08382)
		(layer "In9.Cu")
		(net "QSPI_2_PLD_IO3")
	)
	(segment
		(start 28.875736 -107.97413)
		(end 29.425646 -107.42422)
		(width 0.08382)
		(layer "In9.Cu")
		(net "QSPI_2_PLD_IO3")
	)
	(segment
		(start 48.641 -76.8096)
		(end 49.896522 -75.554078)
		(width 0.08382)
		(layer "In9.Cu")
		(net "QSPI_2_PLD_IO3")
	)
	(segment
		(start 27.903424 -107.5944)
		(end 28.283154 -107.97413)
		(width 0.08382)
		(layer "In9.Cu")
		(net "QSPI_2_PLD_IO3")
	)
	(segment
		(start 40.956484 -92.11564)
		(end 40.956484 -91.020138)
		(width 0.08382)
		(layer "In9.Cu")
		(net "QSPI_2_PLD_IO3")
	)
	(segment
		(start 45.76318 -80.93202)
		(end 45.76318 -78.41742)
		(width 0.08382)
		(layer "In9.Cu")
		(net "QSPI_2_PLD_IO3")
	)
	(segment
		(start 40.227758 -92.260166)
		(end 41.22166 -93.254068)
		(width 0.08382)
		(layer "In9.Cu")
		(net "QSPI_2_PLD_IO3")
	)
	(segment
		(start 40.970708 -93.876368)
		(end 39.791132 -92.696792)
		(width 0.08382)
		(layer "In9.Cu")
		(net "QSPI_2_PLD_IO3")
	)
	(segment
		(start 39.791132 -92.696792)
		(end 39.791132 -92.441268)
		(width 0.08382)
		(layer "In9.Cu")
		(net "QSPI_2_PLD_IO3")
	)
	(segment
		(start 27.380946 -107.5944)
		(end 27.903424 -107.5944)
		(width 0.08382)
		(layer "In9.Cu")
		(net "QSPI_2_PLD_IO3")
	)
	(segment
		(start 44.12996 -83.985862)
		(end 43.165268 -83.02117)
		(width 0.08382)
		(layer "In9.Cu")
		(net "QSPI_2_PLD_IO3")
	)
	(segment
		(start 36.6268 -104.4956)
		(end 36.6268 -103.373174)
		(width 0.08382)
		(layer "In9.Cu")
		(net "QSPI_2_PLD_IO3")
	)
	(segment
		(start 43.693588 -84.422742)
		(end 43.948858 -84.422742)
		(width 0.08382)
		(layer "In9.Cu")
		(net "QSPI_2_PLD_IO3")
	)
	(segment
		(start 44.03852 -81.892394)
		(end 44.219622 -81.711292)
		(width 0.08382)
		(layer "In9.Cu")
		(net "QSPI_2_PLD_IO3")
	)
	(segment
		(start 39.82212 -93.601032)
		(end 40.534082 -94.312994)
		(width 0.08382)
		(layer "In9.Cu")
		(net "QSPI_2_PLD_IO3")
	)
	(segment
		(start 29.721302 -107.42422)
		(end 29.998162 -107.14736)
		(width 0.08382)
		(layer "In9.Cu")
		(net "QSPI_2_PLD_IO3")
	)
	(segment
		(start 45.67301 -82.291682)
		(end 45.67301 -82.036158)
		(width 0.08382)
		(layer "In9.Cu")
		(net "QSPI_2_PLD_IO3")
	)
	(segment
		(start 44.799758 -82.90941)
		(end 44.03852 -82.147918)
		(width 0.08382)
		(layer "In9.Cu")
		(net "QSPI_2_PLD_IO3")
	)
	(segment
		(start 39.791132 -92.441268)
		(end 39.972234 -92.260166)
		(width 0.08382)
		(layer "In9.Cu")
		(net "QSPI_2_PLD_IO3")
	)
	(segment
		(start 41.658286 -92.817442)
		(end 40.956484 -92.11564)
		(width 0.08382)
		(layer "In9.Cu")
		(net "QSPI_2_PLD_IO3")
	)
	(segment
		(start 44.03852 -82.147918)
		(end 44.03852 -81.892394)
		(width 0.08382)
		(layer "In9.Cu")
		(net "QSPI_2_PLD_IO3")
	)
	(segment
		(start 37.0078 -104.8766)
		(end 36.6268 -104.4956)
		(width 0.08382)
		(layer "In9.Cu")
		(net "QSPI_2_PLD_IO3")
	)
	(segment
		(start 45.236384 -82.472784)
		(end 45.491908 -82.472784)
		(width 0.08382)
		(layer "In9.Cu")
		(net "QSPI_2_PLD_IO3")
	)
	(segment
		(start 29.425646 -107.42422)
		(end 29.721302 -107.42422)
		(width 0.08382)
		(layer "In9.Cu")
		(net "QSPI_2_PLD_IO3")
	)
	(segment
		(start 39.67607 -89.739724)
		(end 39.67607 -86.33333)
		(width 0.08382)
		(layer "In9.Cu")
		(net "QSPI_2_PLD_IO3")
	)
	(segment
		(start 45.76318 -78.41742)
		(end 47.371 -76.8096)
		(width 0.08382)
		(layer "In9.Cu")
		(net "QSPI_2_PLD_IO3")
	)
	(segment
		(start 44.363132 -83.346036)
		(end 44.618656 -83.346036)
		(width 0.08382)
		(layer "In9.Cu")
		(net "QSPI_2_PLD_IO3")
	)
	(segment
		(start 41.658286 -92.936314)
		(end 41.658286 -92.817442)
		(width 0.08382)
		(layer "In9.Cu")
		(net "QSPI_2_PLD_IO3")
	)
	(segment
		(start 43.34637 -82.584544)
		(end 43.601894 -82.584544)
		(width 0.08382)
		(layer "In9.Cu")
		(net "QSPI_2_PLD_IO3")
	)
	(segment
		(start 49.896522 -75.554078)
		(end 49.896522 -74.69251)
		(width 0.08382)
		(layer "In9.Cu")
		(net "QSPI_2_PLD_IO3")
	)
	(segment
		(start 39.972234 -92.260166)
		(end 40.227758 -92.260166)
		(width 0.08382)
		(layer "In9.Cu")
		(net "QSPI_2_PLD_IO3")
	)
	(segment
		(start 44.219622 -81.711292)
		(end 44.475146 -81.711292)
		(width 0.08382)
		(layer "In9.Cu")
		(net "QSPI_2_PLD_IO3")
	)
	(segment
		(start 37.973 -99.568)
		(end 37.1094 -98.7044)
		(width 0.08382)
		(layer "In9.Cu")
		(net "QSPI_2_PLD_IO3")
	)
	(segment
		(start 44.799758 -83.164934)
		(end 44.799758 -82.90941)
		(width 0.08382)
		(layer "In9.Cu")
		(net "QSPI_2_PLD_IO3")
	)
	(segment
		(start 37.0078 -105.537)
		(end 37.0078 -104.8766)
		(width 0.08382)
		(layer "In9.Cu")
		(net "QSPI_2_PLD_IO3")
	)
	(segment
		(start 41.22166 -93.254068)
		(end 41.340532 -93.254068)
		(width 0.08382)
		(layer "In9.Cu")
		(net "QSPI_2_PLD_IO3")
	)
	(segment
		(start 45.67301 -82.036158)
		(end 45.41266 -81.775554)
		(width 0.08382)
		(layer "In9.Cu")
		(net "QSPI_2_PLD_IO3")
	)
	(segment
		(start 39.67607 -86.33333)
		(end 42.250614 -83.758786)
		(width 0.08382)
		(layer "In9.Cu")
		(net "QSPI_2_PLD_IO3")
	)
	(segment
		(start 45.491908 -82.472784)
		(end 45.67301 -82.291682)
		(width 0.08382)
		(layer "In9.Cu")
		(net "QSPI_2_PLD_IO3")
	)
	(segment
		(start 42.250614 -83.758786)
		(end 43.029632 -83.758786)
		(width 0.08382)
		(layer "In9.Cu")
		(net "QSPI_2_PLD_IO3")
	)
	(segment
		(start 47.371 -76.8096)
		(end 48.641 -76.8096)
		(width 0.08382)
		(layer "In9.Cu")
		(net "QSPI_2_PLD_IO3")
	)
	(segment
		(start 40.789606 -94.312994)
		(end 40.970708 -94.131892)
		(width 0.08382)
		(layer "In9.Cu")
		(net "QSPI_2_PLD_IO3")
	)
	(segment
		(start 32.88284 -107.14736)
		(end 33.576514 -106.453686)
		(width 0.08382)
		(layer "In9.Cu")
		(net "QSPI_2_PLD_IO3")
	)
	(segment
		(start 44.12996 -84.24164)
		(end 44.12996 -83.985862)
		(width 0.08382)
		(layer "In9.Cu")
		(net "QSPI_2_PLD_IO3")
	)
	(segment
		(start 41.340532 -93.254068)
		(end 41.658286 -92.936314)
		(width 0.08382)
		(layer "In9.Cu")
		(net "QSPI_2_PLD_IO3")
	)
	(segment
		(start 36.6268 -103.373174)
		(end 37.973 -102.026974)
		(width 0.08382)
		(layer "In9.Cu")
		(net "QSPI_2_PLD_IO3")
	)
	(segment
		(start 44.475146 -81.711292)
		(end 45.236384 -82.472784)
		(width 0.08382)
		(layer "In9.Cu")
		(net "QSPI_2_PLD_IO3")
	)
	(segment
		(start 37.973 -102.026974)
		(end 37.973 -99.568)
		(width 0.08382)
		(layer "In9.Cu")
		(net "QSPI_2_PLD_IO3")
	)
	(segment
		(start 39.566596 -93.601032)
		(end 39.82212 -93.601032)
		(width 0.08382)
		(layer "In9.Cu")
		(net "QSPI_2_PLD_IO3")
	)
	(segment
		(start 29.998162 -107.14736)
		(end 32.88284 -107.14736)
		(width 0.08382)
		(layer "In9.Cu")
		(net "QSPI_2_PLD_IO3")
	)
	(segment
		(start 44.618656 -83.346036)
		(end 44.799758 -83.164934)
		(width 0.08382)
		(layer "In9.Cu")
		(net "QSPI_2_PLD_IO3")
	)
	(segment
		(start 36.091114 -106.453686)
		(end 37.0078 -105.537)
		(width 0.08382)
		(layer "In9.Cu")
		(net "QSPI_2_PLD_IO3")
	)
	(segment
		(start 43.029632 -83.758786)
		(end 43.693588 -84.422742)
		(width 0.08382)
		(layer "In9.Cu")
		(net "QSPI_2_PLD_IO3")
	)
	(segment
		(start 28.283154 -107.97413)
		(end 28.875736 -107.97413)
		(width 0.08382)
		(layer "In9.Cu")
		(net "QSPI_2_PLD_IO3")
	)
	(segment
		(start 26.803096 -108.17225)
		(end 27.380946 -107.5944)
		(width 0.08382)
		(layer "In9.Cu")
		(net "QSPI_2_PLD_IO3")
	)
	(segment
		(start 40.534082 -94.312994)
		(end 40.789606 -94.312994)
		(width 0.08382)
		(layer "In9.Cu")
		(net "QSPI_2_PLD_IO3")
	)
	(segment
		(start 45.41266 -81.775554)
		(end 45.41266 -81.28254)
		(width 0.08382)
		(layer "In9.Cu")
		(net "QSPI_2_PLD_IO3")
	)
	(segment
		(start 26.85796 -108.620814)
		(end 26.17978 -109.298994)
		(width 0.11684)
		(layer "F.Cu")
		(net "QSPI_2_PLD_IO2")
	)
	(segment
		(start 26.17978 -109.88802)
		(end 26.17978 -110.406434)
		(width 0.11684)
		(layer "F.Cu")
		(net "QSPI_2_PLD_IO2")
	)
	(segment
		(start 26.17978 -109.298994)
		(end 26.17978 -109.88802)
		(width 0.11684)
		(layer "F.Cu")
		(net "QSPI_2_PLD_IO2")
	)
	(segment
		(start 26.444448 -107.428284)
		(end 26.85796 -107.841796)
		(width 0.11684)
		(layer "F.Cu")
		(net "QSPI_2_PLD_IO2")
	)
	(segment
		(start 54.737 -62.766194)
		(end 54.737 -62.791594)
		(width 0.11684)
		(layer "F.Cu")
		(net "QSPI_2_PLD_IO2")
	)
	(segment
		(start 54.9656 -63.764922)
		(end 55.107078 -63.9064)
		(width 0.11684)
		(layer "F.Cu")
		(net "QSPI_2_PLD_IO2")
	)
	(segment
		(start 55.27675 -63.9064)
		(end 55.4228 -64.05245)
		(width 0.11684)
		(layer "F.Cu")
		(net "QSPI_2_PLD_IO2")
	)
	(segment
		(start 26.17978 -110.406434)
		(end 28.5242 -112.750854)
		(width 0.11684)
		(layer "F.Cu")
		(net "QSPI_2_PLD_IO2")
	)
	(segment
		(start 28.5242 -112.750854)
		(end 28.5242 -115.137946)
		(width 0.11684)
		(layer "F.Cu")
		(net "QSPI_2_PLD_IO2")
	)
	(segment
		(start 55.107078 -63.9064)
		(end 55.27675 -63.9064)
		(width 0.11684)
		(layer "F.Cu")
		(net "QSPI_2_PLD_IO2")
	)
	(segment
		(start 28.144978 -115.517168)
		(end 28.144978 -118.25986)
		(width 0.11684)
		(layer "F.Cu")
		(net "QSPI_2_PLD_IO2")
	)
	(segment
		(start 54.9656 -63.020194)
		(end 54.9656 -63.764922)
		(width 0.11684)
		(layer "F.Cu")
		(net "QSPI_2_PLD_IO2")
	)
	(segment
		(start 54.737 -62.791594)
		(end 54.9656 -63.020194)
		(width 0.11684)
		(layer "F.Cu")
		(net "QSPI_2_PLD_IO2")
	)
	(segment
		(start 28.5242 -115.137946)
		(end 28.144978 -115.517168)
		(width 0.11684)
		(layer "F.Cu")
		(net "QSPI_2_PLD_IO2")
	)
	(segment
		(start 26.85796 -107.841796)
		(end 26.85796 -108.620814)
		(width 0.11684)
		(layer "F.Cu")
		(net "QSPI_2_PLD_IO2")
	)
	(via
		(at 26.444448 -107.428284)
		(size 0.508)
		(drill 0.254)
		(layers "F.Cu" "B.Cu")
		(net "QSPI_2_PLD_IO2")
	)
	(via
		(at 54.737 -62.766194)
		(size 0.508)
		(drill 0.254)
		(layers "F.Cu" "B.Cu")
		(net "QSPI_2_PLD_IO2")
	)
	(via
		(at 26.17978 -109.88802)
		(size 0.762)
		(drill 0.381)
		(layers "F.Cu" "B.Cu")
		(net "QSPI_2_PLD_IO2")
	)
	(segment
		(start 44.2468 -81.3308)
		(end 39.4208 -86.1568)
		(width 0.08382)
		(layer "In9.Cu")
		(net "QSPI_2_PLD_IO2")
	)
	(segment
		(start 47.6758 -76.4794)
		(end 47.3202 -76.4794)
		(width 0.08382)
		(layer "In9.Cu")
		(net "QSPI_2_PLD_IO2")
	)
	(segment
		(start 47.3202 -76.4794)
		(end 45.52696 -78.27264)
		(width 0.08382)
		(layer "In9.Cu")
		(net "QSPI_2_PLD_IO2")
	)
	(segment
		(start 30.620208 -106.04754)
		(end 29.581348 -107.0864)
		(width 0.08382)
		(layer "In9.Cu")
		(net "QSPI_2_PLD_IO2")
	)
	(segment
		(start 26.786332 -107.0864)
		(end 26.444448 -107.428284)
		(width 0.08382)
		(layer "In9.Cu")
		(net "QSPI_2_PLD_IO2")
	)
	(segment
		(start 50.7746 -66.10604)
		(end 50.419 -66.46164)
		(width 0.08382)
		(layer "In9.Cu")
		(net "QSPI_2_PLD_IO2")
	)
	(segment
		(start 37.63518 -101.554534)
		(end 34.8996 -104.290114)
		(width 0.08382)
		(layer "In9.Cu")
		(net "QSPI_2_PLD_IO2")
	)
	(segment
		(start 52.121816 -64.269112)
		(end 51.68138 -65.092834)
		(width 0.08382)
		(layer "In9.Cu")
		(net "QSPI_2_PLD_IO2")
	)
	(segment
		(start 39.31666 -91.722194)
		(end 39.31666 -93.373194)
		(width 0.08382)
		(layer "In9.Cu")
		(net "QSPI_2_PLD_IO2")
	)
	(segment
		(start 34.8996 -104.290114)
		(end 34.8996 -105.8164)
		(width 0.08382)
		(layer "In9.Cu")
		(net "QSPI_2_PLD_IO2")
	)
	(segment
		(start 28.735782 -107.63631)
		(end 28.423108 -107.63631)
		(width 0.08382)
		(layer "In9.Cu")
		(net "QSPI_2_PLD_IO2")
	)
	(segment
		(start 27.873198 -107.0864)
		(end 26.786332 -107.0864)
		(width 0.08382)
		(layer "In9.Cu")
		(net "QSPI_2_PLD_IO2")
	)
	(segment
		(start 45.52696 -78.27264)
		(end 45.52696 -80.12684)
		(width 0.08382)
		(layer "In9.Cu")
		(net "QSPI_2_PLD_IO2")
	)
	(segment
		(start 34.8996 -105.8164)
		(end 34.498534 -106.217466)
		(width 0.08382)
		(layer "In9.Cu")
		(net "QSPI_2_PLD_IO2")
	)
	(segment
		(start 44.2468 -80.517746)
		(end 44.2468 -81.3308)
		(width 0.08382)
		(layer "In9.Cu")
		(net "QSPI_2_PLD_IO2")
	)
	(segment
		(start 44.424346 -80.3402)
		(end 44.2468 -80.517746)
		(width 0.08382)
		(layer "In9.Cu")
		(net "QSPI_2_PLD_IO2")
	)
	(segment
		(start 33.47847 -106.217466)
		(end 33.092136 -106.6038)
		(width 0.08382)
		(layer "In9.Cu")
		(net "QSPI_2_PLD_IO2")
	)
	(segment
		(start 52.633626 -63.926974)
		(end 52.121816 -64.269112)
		(width 0.08382)
		(layer "In9.Cu")
		(net "QSPI_2_PLD_IO2")
	)
	(segment
		(start 34.498534 -106.217466)
		(end 33.47847 -106.217466)
		(width 0.08382)
		(layer "In9.Cu")
		(net "QSPI_2_PLD_IO2")
	)
	(segment
		(start 51.68138 -65.092834)
		(end 51.68138 -65.89522)
		(width 0.08382)
		(layer "In9.Cu")
		(net "QSPI_2_PLD_IO2")
	)
	(segment
		(start 45.3136 -80.3402)
		(end 44.424346 -80.3402)
		(width 0.08382)
		(layer "In9.Cu")
		(net "QSPI_2_PLD_IO2")
	)
	(segment
		(start 33.092136 -106.6038)
		(end 31.75508 -106.6038)
		(width 0.08382)
		(layer "In9.Cu")
		(net "QSPI_2_PLD_IO2")
	)
	(segment
		(start 36.8554 -95.834454)
		(end 36.8554 -98.784918)
		(width 0.08382)
		(layer "In9.Cu")
		(net "QSPI_2_PLD_IO2")
	)
	(segment
		(start 28.423108 -107.63631)
		(end 27.873198 -107.0864)
		(width 0.08382)
		(layer "In9.Cu")
		(net "QSPI_2_PLD_IO2")
	)
	(segment
		(start 48.26 -73.9902)
		(end 48.26 -75.8952)
		(width 0.08382)
		(layer "In9.Cu")
		(net "QSPI_2_PLD_IO2")
	)
	(segment
		(start 31.19882 -106.04754)
		(end 30.620208 -106.04754)
		(width 0.08382)
		(layer "In9.Cu")
		(net "QSPI_2_PLD_IO2")
	)
	(segment
		(start 36.8554 -98.784918)
		(end 37.63518 -99.564698)
		(width 0.08382)
		(layer "In9.Cu")
		(net "QSPI_2_PLD_IO2")
	)
	(segment
		(start 51.68138 -65.89522)
		(end 51.47056 -66.10604)
		(width 0.08382)
		(layer "In9.Cu")
		(net "QSPI_2_PLD_IO2")
	)
	(segment
		(start 29.581348 -107.0864)
		(end 29.285692 -107.0864)
		(width 0.08382)
		(layer "In9.Cu")
		(net "QSPI_2_PLD_IO2")
	)
	(segment
		(start 29.285692 -107.0864)
		(end 28.735782 -107.63631)
		(width 0.08382)
		(layer "In9.Cu")
		(net "QSPI_2_PLD_IO2")
	)
	(segment
		(start 37.63518 -99.564698)
		(end 37.63518 -101.554534)
		(width 0.08382)
		(layer "In9.Cu")
		(net "QSPI_2_PLD_IO2")
	)
	(segment
		(start 53.794406 -62.766194)
		(end 52.633626 -63.926974)
		(width 0.08382)
		(layer "In9.Cu")
		(net "QSPI_2_PLD_IO2")
	)
	(segment
		(start 39.4208 -86.1568)
		(end 39.4208 -91.618054)
		(width 0.08382)
		(layer "In9.Cu")
		(net "QSPI_2_PLD_IO2")
	)
	(segment
		(start 39.31666 -93.373194)
		(end 36.8554 -95.834454)
		(width 0.08382)
		(layer "In9.Cu")
		(net "QSPI_2_PLD_IO2")
	)
	(segment
		(start 54.737 -62.766194)
		(end 53.794406 -62.766194)
		(width 0.08382)
		(layer "In9.Cu")
		(net "QSPI_2_PLD_IO2")
	)
	(segment
		(start 39.4208 -91.618054)
		(end 39.31666 -91.722194)
		(width 0.08382)
		(layer "In9.Cu")
		(net "QSPI_2_PLD_IO2")
	)
	(segment
		(start 51.47056 -66.10604)
		(end 50.7746 -66.10604)
		(width 0.08382)
		(layer "In9.Cu")
		(net "QSPI_2_PLD_IO2")
	)
	(segment
		(start 31.75508 -106.6038)
		(end 31.19882 -106.04754)
		(width 0.08382)
		(layer "In9.Cu")
		(net "QSPI_2_PLD_IO2")
	)
	(segment
		(start 50.419 -71.8312)
		(end 48.26 -73.9902)
		(width 0.08382)
		(layer "In9.Cu")
		(net "QSPI_2_PLD_IO2")
	)
	(segment
		(start 50.419 -66.46164)
		(end 50.419 -71.8312)
		(width 0.08382)
		(layer "In9.Cu")
		(net "QSPI_2_PLD_IO2")
	)
	(segment
		(start 48.26 -75.8952)
		(end 47.6758 -76.4794)
		(width 0.08382)
		(layer "In9.Cu")
		(net "QSPI_2_PLD_IO2")
	)
	(segment
		(start 45.52696 -80.12684)
		(end 45.3136 -80.3402)
		(width 0.08382)
		(layer "In9.Cu")
		(net "QSPI_2_PLD_IO2")
	)
	(segment
		(start 28.744926 -115.578128)
		(end 29.2354 -115.087654)
		(width 0.11684)
		(layer "F.Cu")
		(net "QSPI_2_PLD_IO1")
	)
	(segment
		(start 29.2354 -115.087654)
		(end 29.2354 -112.827054)
		(width 0.11684)
		(layer "F.Cu")
		(net "QSPI_2_PLD_IO1")
	)
	(segment
		(start 27.2288 -106.629454)
		(end 27.610054 -106.2482)
		(width 0.11684)
		(layer "F.Cu")
		(net "QSPI_2_PLD_IO1")
	)
	(segment
		(start 27.2288 -108.839)
		(end 27.2288 -106.629454)
		(width 0.11684)
		(layer "F.Cu")
		(net "QSPI_2_PLD_IO1")
	)
	(segment
		(start 28.744926 -118.460012)
		(end 28.744926 -115.578128)
		(width 0.11684)
		(layer "F.Cu")
		(net "QSPI_2_PLD_IO1")
	)
	(segment
		(start 26.8224 -109.2454)
		(end 27.2288 -108.839)
		(width 0.11684)
		(layer "F.Cu")
		(net "QSPI_2_PLD_IO1")
	)
	(segment
		(start 29.2354 -112.827054)
		(end 26.8224 -110.414054)
		(width 0.11684)
		(layer "F.Cu")
		(net "QSPI_2_PLD_IO1")
	)
	(segment
		(start 26.8224 -110.414054)
		(end 26.8224 -109.2454)
		(width 0.11684)
		(layer "F.Cu")
		(net "QSPI_2_PLD_IO1")
	)
	(via
		(at 55.9054 -60.2488)
		(size 0.508)
		(drill 0.254)
		(layers "F.Cu" "B.Cu")
		(net "QSPI_2_PLD_IO1")
	)
	(via
		(at 27.610054 -106.2482)
		(size 0.508)
		(drill 0.254)
		(layers "F.Cu" "B.Cu")
		(net "QSPI_2_PLD_IO1")
	)
	(segment
		(start 55.9054 -60.2488)
		(end 55.54345 -60.61075)
		(width 0.11684)
		(layer "B.Cu")
		(net "QSPI_2_PLD_IO1")
	)
	(segment
		(start 55.54345 -60.61075)
		(end 55.1688 -60.61075)
		(width 0.11684)
		(layer "B.Cu")
		(net "QSPI_2_PLD_IO1")
	)
	(segment
		(start 33.15589 -103.213408)
		(end 33.15589 -101.170486)
		(width 0.08382)
		(layer "In9.Cu")
		(net "QSPI_2_PLD_IO1")
	)
	(segment
		(start 43.382946 -78.9178)
		(end 44.348146 -77.9526)
		(width 0.08382)
		(layer "In9.Cu")
		(net "QSPI_2_PLD_IO1")
	)
	(segment
		(start 48.213772 -68.473828)
		(end 48.213772 -66.200274)
		(width 0.08382)
		(layer "In9.Cu")
		(net "QSPI_2_PLD_IO1")
	)
	(segment
		(start 33.15589 -101.170486)
		(end 33.2994 -101.026976)
		(width 0.08382)
		(layer "In9.Cu")
		(net "QSPI_2_PLD_IO1")
	)
	(segment
		(start 50.363882 -64.450976)
		(end 51.405536 -63.753746)
		(width 0.08382)
		(layer "In9.Cu")
		(net "QSPI_2_PLD_IO1")
	)
	(segment
		(start 39.81831 -84.387944)
		(end 39.81831 -80.247744)
		(width 0.08382)
		(layer "In9.Cu")
		(net "QSPI_2_PLD_IO1")
	)
	(segment
		(start 44.348146 -77.9526)
		(end 44.9326 -77.9526)
		(width 0.08382)
		(layer "In9.Cu")
		(net "QSPI_2_PLD_IO1")
	)
	(segment
		(start 29.22905 -106.2482)
		(end 30.240478 -105.23728)
		(width 0.08382)
		(layer "In9.Cu")
		(net "QSPI_2_PLD_IO1")
	)
	(segment
		(start 54.30139 -60.2488)
		(end 55.9054 -60.2488)
		(width 0.08382)
		(layer "In9.Cu")
		(net "QSPI_2_PLD_IO1")
	)
	(segment
		(start 46.736 -76.1492)
		(end 46.736 -73.8886)
		(width 0.08382)
		(layer "In9.Cu")
		(net "QSPI_2_PLD_IO1")
	)
	(segment
		(start 47.412402 -70.881748)
		(end 48.01616 -69.423788)
		(width 0.08382)
		(layer "In9.Cu")
		(net "QSPI_2_PLD_IO1")
	)
	(segment
		(start 33.756346 -101.026976)
		(end 34.65703 -100.126292)
		(width 0.08382)
		(layer "In9.Cu")
		(net "QSPI_2_PLD_IO1")
	)
	(segment
		(start 36.87953 -88.39327)
		(end 36.87953 -87.326724)
		(width 0.08382)
		(layer "In9.Cu")
		(net "QSPI_2_PLD_IO1")
	)
	(segment
		(start 35.27679 -90.359738)
		(end 35.27552 -90.358468)
		(width 0.08382)
		(layer "In9.Cu")
		(net "QSPI_2_PLD_IO1")
	)
	(segment
		(start 34.90341 -95.097854)
		(end 34.90341 -92.855796)
		(width 0.08382)
		(layer "In9.Cu")
		(net "QSPI_2_PLD_IO1")
	)
	(segment
		(start 48.213772 -66.200274)
		(end 48.476154 -65.937892)
		(width 0.08382)
		(layer "In9.Cu")
		(net "QSPI_2_PLD_IO1")
	)
	(segment
		(start 35.27552 -89.99728)
		(end 36.87953 -88.39327)
		(width 0.08382)
		(layer "In9.Cu")
		(net "QSPI_2_PLD_IO1")
	)
	(segment
		(start 36.87953 -87.326724)
		(end 39.81831 -84.387944)
		(width 0.08382)
		(layer "In9.Cu")
		(net "QSPI_2_PLD_IO1")
	)
	(segment
		(start 49.841404 -65.232788)
		(end 50.35804 -64.459358)
		(width 0.08382)
		(layer "In9.Cu")
		(net "QSPI_2_PLD_IO1")
	)
	(segment
		(start 34.90341 -92.855796)
		(end 35.27679 -92.482416)
		(width 0.08382)
		(layer "In9.Cu")
		(net "QSPI_2_PLD_IO1")
	)
	(segment
		(start 34.65703 -100.126292)
		(end 34.65703 -95.692722)
		(width 0.08382)
		(layer "In9.Cu")
		(net "QSPI_2_PLD_IO1")
	)
	(segment
		(start 48.476154 -65.937892)
		(end 49.1363 -65.937892)
		(width 0.08382)
		(layer "In9.Cu")
		(net "QSPI_2_PLD_IO1")
	)
	(segment
		(start 44.9326 -77.9526)
		(end 46.736 -76.1492)
		(width 0.08382)
		(layer "In9.Cu")
		(net "QSPI_2_PLD_IO1")
	)
	(segment
		(start 50.35804 -64.459358)
		(end 50.363882 -64.450976)
		(width 0.08382)
		(layer "In9.Cu")
		(net "QSPI_2_PLD_IO1")
	)
	(segment
		(start 51.63058 -62.91961)
		(end 54.30139 -60.2488)
		(width 0.08382)
		(layer "In9.Cu")
		(net "QSPI_2_PLD_IO1")
	)
	(segment
		(start 35.27679 -92.482416)
		(end 35.27679 -90.359738)
		(width 0.08382)
		(layer "In9.Cu")
		(net "QSPI_2_PLD_IO1")
	)
	(segment
		(start 51.63058 -63.528702)
		(end 51.63058 -62.91961)
		(width 0.08382)
		(layer "In9.Cu")
		(net "QSPI_2_PLD_IO1")
	)
	(segment
		(start 48.01616 -69.423788)
		(end 48.01616 -68.67144)
		(width 0.08382)
		(layer "In9.Cu")
		(net "QSPI_2_PLD_IO1")
	)
	(segment
		(start 35.27552 -90.358468)
		(end 35.27552 -89.99728)
		(width 0.08382)
		(layer "In9.Cu")
		(net "QSPI_2_PLD_IO1")
	)
	(segment
		(start 33.2994 -101.026976)
		(end 33.756346 -101.026976)
		(width 0.08382)
		(layer "In9.Cu")
		(net "QSPI_2_PLD_IO1")
	)
	(segment
		(start 41.148254 -78.9178)
		(end 43.382946 -78.9178)
		(width 0.08382)
		(layer "In9.Cu")
		(net "QSPI_2_PLD_IO1")
	)
	(segment
		(start 30.240478 -105.23728)
		(end 31.132018 -105.23728)
		(width 0.08382)
		(layer "In9.Cu")
		(net "QSPI_2_PLD_IO1")
	)
	(segment
		(start 49.1363 -65.937892)
		(end 49.841404 -65.232788)
		(width 0.08382)
		(layer "In9.Cu")
		(net "QSPI_2_PLD_IO1")
	)
	(segment
		(start 31.132018 -105.23728)
		(end 33.15589 -103.213408)
		(width 0.08382)
		(layer "In9.Cu")
		(net "QSPI_2_PLD_IO1")
	)
	(segment
		(start 46.736 -73.8886)
		(end 47.412402 -73.212198)
		(width 0.08382)
		(layer "In9.Cu")
		(net "QSPI_2_PLD_IO1")
	)
	(segment
		(start 34.65703 -95.692722)
		(end 34.90341 -95.097854)
		(width 0.08382)
		(layer "In9.Cu")
		(net "QSPI_2_PLD_IO1")
	)
	(segment
		(start 51.405536 -63.753746)
		(end 51.63058 -63.528702)
		(width 0.08382)
		(layer "In9.Cu")
		(net "QSPI_2_PLD_IO1")
	)
	(segment
		(start 39.81831 -80.247744)
		(end 41.148254 -78.9178)
		(width 0.08382)
		(layer "In9.Cu")
		(net "QSPI_2_PLD_IO1")
	)
	(segment
		(start 48.01616 -68.67144)
		(end 48.213772 -68.473828)
		(width 0.08382)
		(layer "In9.Cu")
		(net "QSPI_2_PLD_IO1")
	)
	(segment
		(start 27.610054 -106.2482)
		(end 29.22905 -106.2482)
		(width 0.08382)
		(layer "In9.Cu")
		(net "QSPI_2_PLD_IO1")
	)
	(segment
		(start 47.412402 -73.212198)
		(end 47.412402 -70.881748)
		(width 0.08382)
		(layer "In9.Cu")
		(net "QSPI_2_PLD_IO1")
	)
	(segment
		(start 28.702 -105.7148)
		(end 28.181554 -106.234992)
		(width 0.11684)
		(layer "F.Cu")
		(net "QSPI_2_PLD_IO0")
	)
	(segment
		(start 28.2448 -110.995206)
		(end 27.3558 -110.106206)
		(width 0.11684)
		(layer "F.Cu")
		(net "QSPI_2_PLD_IO0")
	)
	(segment
		(start 27.3558 -109.270546)
		(end 28.194 -108.432346)
		(width 0.11684)
		(layer "F.Cu")
		(net "QSPI_2_PLD_IO0")
	)
	(segment
		(start 27.8892 -106.857546)
		(end 27.8892 -107.2642)
		(width 0.11684)
		(layer "F.Cu")
		(net "QSPI_2_PLD_IO0")
	)
	(segment
		(start 28.194 -108.432346)
		(end 28.194 -107.569)
		(width 0.11684)
		(layer "F.Cu")
		(net "QSPI_2_PLD_IO0")
	)
	(segment
		(start 29.345128 -115.663472)
		(end 29.718 -115.2906)
		(width 0.11684)
		(layer "F.Cu")
		(net "QSPI_2_PLD_IO0")
	)
	(segment
		(start 29.718 -112.4712)
		(end 28.2448 -110.998)
		(width 0.11684)
		(layer "F.Cu")
		(net "QSPI_2_PLD_IO0")
	)
	(segment
		(start 28.194 -107.569)
		(end 27.8892 -107.2642)
		(width 0.11684)
		(layer "F.Cu")
		(net "QSPI_2_PLD_IO0")
	)
	(segment
		(start 29.345128 -118.25986)
		(end 29.345128 -115.663472)
		(width 0.11684)
		(layer "F.Cu")
		(net "QSPI_2_PLD_IO0")
	)
	(segment
		(start 28.2448 -110.998)
		(end 28.2448 -110.995206)
		(width 0.11684)
		(layer "F.Cu")
		(net "QSPI_2_PLD_IO0")
	)
	(segment
		(start 29.718 -115.2906)
		(end 29.718 -112.4712)
		(width 0.11684)
		(layer "F.Cu")
		(net "QSPI_2_PLD_IO0")
	)
	(segment
		(start 27.3558 -110.106206)
		(end 27.3558 -109.270546)
		(width 0.11684)
		(layer "F.Cu")
		(net "QSPI_2_PLD_IO0")
	)
	(segment
		(start 28.181554 -106.234992)
		(end 27.948128 -106.798618)
		(width 0.11684)
		(layer "F.Cu")
		(net "QSPI_2_PLD_IO0")
	)
	(segment
		(start 27.948128 -106.798618)
		(end 27.8892 -106.857546)
		(width 0.11684)
		(layer "F.Cu")
		(net "QSPI_2_PLD_IO0")
	)
	(via
		(at 27.8892 -107.2642)
		(size 0.762)
		(drill 0.381)
		(layers "F.Cu" "B.Cu")
		(net "QSPI_2_PLD_IO0")
	)
	(via
		(at 46.33849 -71.576438)
		(size 0.508)
		(drill 0.254)
		(layers "F.Cu" "B.Cu")
		(net "QSPI_2_PLD_IO0")
	)
	(via
		(at 28.702 -105.7148)
		(size 0.508)
		(drill 0.254)
		(layers "F.Cu" "B.Cu")
		(net "QSPI_2_PLD_IO0")
	)
	(segment
		(start 46.33849 -71.576438)
		(end 46.413928 -71.501)
		(width 0.11684)
		(layer "B.Cu")
		(net "QSPI_2_PLD_IO0")
	)
	(segment
		(start 47.36465 -71.202296)
		(end 47.36465 -70.9168)
		(width 0.11684)
		(layer "B.Cu")
		(net "QSPI_2_PLD_IO0")
	)
	(segment
		(start 46.413928 -71.501)
		(end 47.065946 -71.501)
		(width 0.11684)
		(layer "B.Cu")
		(net "QSPI_2_PLD_IO0")
	)
	(segment
		(start 47.065946 -71.501)
		(end 47.36465 -71.202296)
		(width 0.11684)
		(layer "B.Cu")
		(net "QSPI_2_PLD_IO0")
	)
	(segment
		(start 38.88359 -84.916264)
		(end 36.64331 -87.156544)
		(width 0.08382)
		(layer "In9.Cu")
		(net "QSPI_2_PLD_IO0")
	)
	(segment
		(start 35.04057 -90.457782)
		(end 35.04057 -92.384372)
		(width 0.08382)
		(layer "In9.Cu")
		(net "QSPI_2_PLD_IO0")
	)
	(segment
		(start 46.33849 -71.576438)
		(end 46.33849 -71.66991)
		(width 0.08382)
		(layer "In9.Cu")
		(net "QSPI_2_PLD_IO0")
	)
	(segment
		(start 34.66719 -95.050864)
		(end 34.42081 -95.645732)
		(width 0.08382)
		(layer "In9.Cu")
		(net "QSPI_2_PLD_IO0")
	)
	(segment
		(start 34.42081 -100.028248)
		(end 33.658302 -100.790756)
		(width 0.08382)
		(layer "In9.Cu")
		(net "QSPI_2_PLD_IO0")
	)
	(segment
		(start 43.4086 -75.4126)
		(end 43.4086 -76.454)
		(width 0.08382)
		(layer "In9.Cu")
		(net "QSPI_2_PLD_IO0")
	)
	(segment
		(start 28.292552 -104.013)
		(end 28.201874 -104.103678)
		(width 0.08382)
		(layer "In9.Cu")
		(net "QSPI_2_PLD_IO0")
	)
	(segment
		(start 42.771314 -77.091286)
		(end 41.044368 -77.091286)
		(width 0.08382)
		(layer "In9.Cu")
		(net "QSPI_2_PLD_IO0")
	)
	(segment
		(start 34.42081 -95.645732)
		(end 34.42081 -100.028248)
		(width 0.08382)
		(layer "In9.Cu")
		(net "QSPI_2_PLD_IO0")
	)
	(segment
		(start 38.88359 -79.252064)
		(end 38.88359 -84.916264)
		(width 0.08382)
		(layer "In9.Cu")
		(net "QSPI_2_PLD_IO0")
	)
	(segment
		(start 36.64331 -88.295226)
		(end 35.0393 -89.899236)
		(width 0.08382)
		(layer "In9.Cu")
		(net "QSPI_2_PLD_IO0")
	)
	(segment
		(start 45.8724 -72.136)
		(end 45.8724 -72.9488)
		(width 0.08382)
		(layer "In9.Cu")
		(net "QSPI_2_PLD_IO0")
	)
	(segment
		(start 28.201874 -104.103678)
		(end 28.201874 -105.519474)
		(width 0.08382)
		(layer "In9.Cu")
		(net "QSPI_2_PLD_IO0")
	)
	(segment
		(start 33.143444 -100.790756)
		(end 32.91967 -101.01453)
		(width 0.08382)
		(layer "In9.Cu")
		(net "QSPI_2_PLD_IO0")
	)
	(segment
		(start 45.8724 -72.9488)
		(end 43.4086 -75.4126)
		(width 0.08382)
		(layer "In9.Cu")
		(net "QSPI_2_PLD_IO0")
	)
	(segment
		(start 46.33849 -71.66991)
		(end 45.8724 -72.136)
		(width 0.08382)
		(layer "In9.Cu")
		(net "QSPI_2_PLD_IO0")
	)
	(segment
		(start 32.91967 -101.01453)
		(end 32.91967 -102.808532)
		(width 0.08382)
		(layer "In9.Cu")
		(net "QSPI_2_PLD_IO0")
	)
	(segment
		(start 35.0393 -89.899236)
		(end 35.0393 -90.456512)
		(width 0.08382)
		(layer "In9.Cu")
		(net "QSPI_2_PLD_IO0")
	)
	(segment
		(start 34.66719 -92.757752)
		(end 34.66719 -95.050864)
		(width 0.08382)
		(layer "In9.Cu")
		(net "QSPI_2_PLD_IO0")
	)
	(segment
		(start 32.91967 -102.808532)
		(end 31.715202 -104.013)
		(width 0.08382)
		(layer "In9.Cu")
		(net "QSPI_2_PLD_IO0")
	)
	(segment
		(start 36.64331 -87.156544)
		(end 36.64331 -88.295226)
		(width 0.08382)
		(layer "In9.Cu")
		(net "QSPI_2_PLD_IO0")
	)
	(segment
		(start 33.658302 -100.790756)
		(end 33.143444 -100.790756)
		(width 0.08382)
		(layer "In9.Cu")
		(net "QSPI_2_PLD_IO0")
	)
	(segment
		(start 28.3972 -105.7148)
		(end 28.702 -105.7148)
		(width 0.08382)
		(layer "In9.Cu")
		(net "QSPI_2_PLD_IO0")
	)
	(segment
		(start 43.4086 -76.454)
		(end 42.771314 -77.091286)
		(width 0.08382)
		(layer "In9.Cu")
		(net "QSPI_2_PLD_IO0")
	)
	(segment
		(start 35.0393 -90.456512)
		(end 35.04057 -90.457782)
		(width 0.08382)
		(layer "In9.Cu")
		(net "QSPI_2_PLD_IO0")
	)
	(segment
		(start 28.201874 -105.519474)
		(end 28.3972 -105.7148)
		(width 0.08382)
		(layer "In9.Cu")
		(net "QSPI_2_PLD_IO0")
	)
	(segment
		(start 31.715202 -104.013)
		(end 28.292552 -104.013)
		(width 0.08382)
		(layer "In9.Cu")
		(net "QSPI_2_PLD_IO0")
	)
	(segment
		(start 35.04057 -92.384372)
		(end 34.66719 -92.757752)
		(width 0.08382)
		(layer "In9.Cu")
		(net "QSPI_2_PLD_IO0")
	)
	(segment
		(start 41.044368 -77.091286)
		(end 38.88359 -79.252064)
		(width 0.08382)
		(layer "In9.Cu")
		(net "QSPI_2_PLD_IO0")
	)
	(segment
		(start 28.6512 -107.0864)
		(end 28.6512 -109.2835)
		(width 0.11684)
		(layer "F.Cu")
		(net "QSPI_2_PLD_CLK")
	)
	(segment
		(start 28.6512 -109.2835)
		(end 29.43352 -110.06582)
		(width 0.11684)
		(layer "F.Cu")
		(net "QSPI_2_PLD_CLK")
	)
	(segment
		(start 29.43352 -110.06582)
		(end 29.43352 -110.637574)
		(width 0.11684)
		(layer "F.Cu")
		(net "QSPI_2_PLD_CLK")
	)
	(segment
		(start 30.545024 -115.428776)
		(end 30.545024 -118.460012)
		(width 0.11684)
		(layer "F.Cu")
		(net "QSPI_2_PLD_CLK")
	)
	(segment
		(start 52.336954 -62.969394)
		(end 52.336954 -62.589156)
		(width 0.11684)
		(layer "F.Cu")
		(net "QSPI_2_PLD_CLK")
	)
	(segment
		(start 31.0134 -114.9604)
		(end 30.545024 -115.428776)
		(width 0.11684)
		(layer "F.Cu")
		(net "QSPI_2_PLD_CLK")
	)
	(segment
		(start 29.43352 -110.637574)
		(end 31.0134 -112.217454)
		(width 0.11684)
		(layer "F.Cu")
		(net "QSPI_2_PLD_CLK")
	)
	(segment
		(start 31.0134 -112.217454)
		(end 31.0134 -114.9604)
		(width 0.11684)
		(layer "F.Cu")
		(net "QSPI_2_PLD_CLK")
	)
	(segment
		(start 52.336954 -62.589156)
		(end 52.72151 -62.2046)
		(width 0.11684)
		(layer "F.Cu")
		(net "QSPI_2_PLD_CLK")
	)
	(via
		(at 52.336954 -62.969394)
		(size 0.508)
		(drill 0.254)
		(layers "F.Cu" "B.Cu")
		(net "QSPI_2_PLD_CLK")
	)
	(via
		(at 28.6512 -107.0864)
		(size 0.508)
		(drill 0.254)
		(layers "F.Cu" "B.Cu")
		(net "QSPI_2_PLD_CLK")
	)
	(segment
		(start 47.0408 -76.2254)
		(end 45.0088 -78.2574)
		(width 0.08382)
		(layer "In9.Cu")
		(net "QSPI_2_PLD_CLK")
	)
	(segment
		(start 36.322 -95.8088)
		(end 36.322 -98.7298)
		(width 0.08382)
		(layer "In9.Cu")
		(net "QSPI_2_PLD_CLK")
	)
	(segment
		(start 37.01796 -101.81844)
		(end 33.8328 -105.0036)
		(width 0.08382)
		(layer "In9.Cu")
		(net "QSPI_2_PLD_CLK")
	)
	(segment
		(start 31.229046 -105.70972)
		(end 30.436566 -105.70972)
		(width 0.08382)
		(layer "In9.Cu")
		(net "QSPI_2_PLD_CLK")
	)
	(segment
		(start 29.407866 -106.73842)
		(end 28.99918 -106.73842)
		(width 0.08382)
		(layer "In9.Cu")
		(net "QSPI_2_PLD_CLK")
	)
	(segment
		(start 43.5356 -79.934054)
		(end 43.9674 -80.365854)
		(width 0.08382)
		(layer "In9.Cu")
		(net "QSPI_2_PLD_CLK")
	)
	(segment
		(start 36.413948 -94.624652)
		(end 36.276788 -94.761812)
		(width 0.08382)
		(layer "In9.Cu")
		(net "QSPI_2_PLD_CLK")
	)
	(segment
		(start 47.0408 -74.3204)
		(end 47.0408 -76.2254)
		(width 0.08382)
		(layer "In9.Cu")
		(net "QSPI_2_PLD_CLK")
	)
	(segment
		(start 38.97884 -92.857574)
		(end 38.97884 -93.15196)
		(width 0.08382)
		(layer "In9.Cu")
		(net "QSPI_2_PLD_CLK")
	)
	(segment
		(start 51.924204 -63.975996)
		(end 50.469292 -64.94907)
		(width 0.08382)
		(layer "In9.Cu")
		(net "QSPI_2_PLD_CLK")
	)
	(segment
		(start 38.169596 -93.767656)
		(end 37.372798 -92.970858)
		(width 0.08382)
		(layer "In9.Cu")
		(net "QSPI_2_PLD_CLK")
	)
	(segment
		(start 49.718722 -67.183)
		(end 49.699926 -67.201796)
		(width 0.08382)
		(layer "In9.Cu")
		(net "QSPI_2_PLD_CLK")
	)
	(segment
		(start 37.838888 -94.291912)
		(end 37.153596 -94.977204)
		(width 0.08382)
		(layer "In9.Cu")
		(net "QSPI_2_PLD_CLK")
	)
	(segment
		(start 36.607496 -94.624652)
		(end 36.413948 -94.624652)
		(width 0.08382)
		(layer "In9.Cu")
		(net "QSPI_2_PLD_CLK")
	)
	(segment
		(start 38.135306 -92.720668)
		(end 38.841934 -92.720668)
		(width 0.08382)
		(layer "In9.Cu")
		(net "QSPI_2_PLD_CLK")
	)
	(segment
		(start 50.469292 -64.94907)
		(end 50.187352 -65.370456)
		(width 0.08382)
		(layer "In9.Cu")
		(net "QSPI_2_PLD_CLK")
	)
	(segment
		(start 43.5356 -79.197962)
		(end 43.5356 -79.934054)
		(width 0.08382)
		(layer "In9.Cu")
		(net "QSPI_2_PLD_CLK")
	)
	(segment
		(start 50.187352 -65.370456)
		(end 49.718722 -66.501772)
		(width 0.08382)
		(layer "In9.Cu")
		(net "QSPI_2_PLD_CLK")
	)
	(segment
		(start 37.153596 -94.977204)
		(end 36.960048 -94.977204)
		(width 0.08382)
		(layer "In9.Cu")
		(net "QSPI_2_PLD_CLK")
	)
	(segment
		(start 52.336954 -62.969394)
		(end 52.336954 -63.563246)
		(width 0.08382)
		(layer "In9.Cu")
		(net "QSPI_2_PLD_CLK")
	)
	(segment
		(start 52.336954 -63.563246)
		(end 51.924204 -63.975996)
		(width 0.08382)
		(layer "In9.Cu")
		(net "QSPI_2_PLD_CLK")
	)
	(segment
		(start 49.1744 -69.23278)
		(end 49.1744 -72.1868)
		(width 0.08382)
		(layer "In9.Cu")
		(net "QSPI_2_PLD_CLK")
	)
	(segment
		(start 36.276788 -94.95536)
		(end 36.62934 -95.307912)
		(width 0.08382)
		(layer "In9.Cu")
		(net "QSPI_2_PLD_CLK")
	)
	(segment
		(start 37.9984 -92.583762)
		(end 38.135306 -92.720668)
		(width 0.08382)
		(layer "In9.Cu")
		(net "QSPI_2_PLD_CLK")
	)
	(segment
		(start 36.322 -98.7298)
		(end 37.01796 -99.42576)
		(width 0.08382)
		(layer "In9.Cu")
		(net "QSPI_2_PLD_CLK")
	)
	(segment
		(start 37.9984 -92.390214)
		(end 37.9984 -92.583762)
		(width 0.08382)
		(layer "In9.Cu")
		(net "QSPI_2_PLD_CLK")
	)
	(segment
		(start 36.276788 -94.761812)
		(end 36.276788 -94.95536)
		(width 0.08382)
		(layer "In9.Cu")
		(net "QSPI_2_PLD_CLK")
	)
	(segment
		(start 36.62934 -95.307912)
		(end 36.62934 -95.50146)
		(width 0.08382)
		(layer "In9.Cu")
		(net "QSPI_2_PLD_CLK")
	)
	(segment
		(start 37.17925 -92.970858)
		(end 37.04209 -93.108018)
		(width 0.08382)
		(layer "In9.Cu")
		(net "QSPI_2_PLD_CLK")
	)
	(segment
		(start 49.718722 -66.501772)
		(end 49.718722 -67.183)
		(width 0.08382)
		(layer "In9.Cu")
		(net "QSPI_2_PLD_CLK")
	)
	(segment
		(start 37.04209 -93.108018)
		(end 37.04209 -93.301566)
		(width 0.08382)
		(layer "In9.Cu")
		(net "QSPI_2_PLD_CLK")
	)
	(segment
		(start 38.97884 -93.15196)
		(end 38.363144 -93.767656)
		(width 0.08382)
		(layer "In9.Cu")
		(net "QSPI_2_PLD_CLK")
	)
	(segment
		(start 49.1744 -72.1868)
		(end 47.0408 -74.3204)
		(width 0.08382)
		(layer "In9.Cu")
		(net "QSPI_2_PLD_CLK")
	)
	(segment
		(start 38.363144 -93.767656)
		(end 38.169596 -93.767656)
		(width 0.08382)
		(layer "In9.Cu")
		(net "QSPI_2_PLD_CLK")
	)
	(segment
		(start 33.8328 -105.384346)
		(end 33.078166 -106.13898)
		(width 0.08382)
		(layer "In9.Cu")
		(net "QSPI_2_PLD_CLK")
	)
	(segment
		(start 30.436566 -105.70972)
		(end 29.407866 -106.73842)
		(width 0.08382)
		(layer "In9.Cu")
		(net "QSPI_2_PLD_CLK")
	)
	(segment
		(start 38.135306 -92.253308)
		(end 37.9984 -92.390214)
		(width 0.08382)
		(layer "In9.Cu")
		(net "QSPI_2_PLD_CLK")
	)
	(segment
		(start 31.658306 -106.13898)
		(end 31.229046 -105.70972)
		(width 0.08382)
		(layer "In9.Cu")
		(net "QSPI_2_PLD_CLK")
	)
	(segment
		(start 28.99918 -106.73842)
		(end 28.6512 -107.0864)
		(width 0.08382)
		(layer "In9.Cu")
		(net "QSPI_2_PLD_CLK")
	)
	(segment
		(start 36.960048 -94.977204)
		(end 36.607496 -94.624652)
		(width 0.08382)
		(layer "In9.Cu")
		(net "QSPI_2_PLD_CLK")
	)
	(segment
		(start 33.078166 -106.13898)
		(end 31.658306 -106.13898)
		(width 0.08382)
		(layer "In9.Cu")
		(net "QSPI_2_PLD_CLK")
	)
	(segment
		(start 38.97884 -88.96604)
		(end 38.97884 -92.116402)
		(width 0.08382)
		(layer "In9.Cu")
		(net "QSPI_2_PLD_CLK")
	)
	(segment
		(start 37.372798 -92.970858)
		(end 37.17925 -92.970858)
		(width 0.08382)
		(layer "In9.Cu")
		(net "QSPI_2_PLD_CLK")
	)
	(segment
		(start 38.841934 -92.253308)
		(end 38.135306 -92.253308)
		(width 0.08382)
		(layer "In9.Cu")
		(net "QSPI_2_PLD_CLK")
	)
	(segment
		(start 33.8328 -105.0036)
		(end 33.8328 -105.384346)
		(width 0.08382)
		(layer "In9.Cu")
		(net "QSPI_2_PLD_CLK")
	)
	(segment
		(start 45.0088 -78.2574)
		(end 44.476162 -78.2574)
		(width 0.08382)
		(layer "In9.Cu")
		(net "QSPI_2_PLD_CLK")
	)
	(segment
		(start 37.01796 -99.42576)
		(end 37.01796 -101.81844)
		(width 0.08382)
		(layer "In9.Cu")
		(net "QSPI_2_PLD_CLK")
	)
	(segment
		(start 37.04209 -93.301566)
		(end 37.838888 -94.098364)
		(width 0.08382)
		(layer "In9.Cu")
		(net "QSPI_2_PLD_CLK")
	)
	(segment
		(start 38.520116 -88.507316)
		(end 38.97884 -88.96604)
		(width 0.08382)
		(layer "In9.Cu")
		(net "QSPI_2_PLD_CLK")
	)
	(segment
		(start 38.97884 -92.116402)
		(end 38.841934 -92.253308)
		(width 0.08382)
		(layer "In9.Cu")
		(net "QSPI_2_PLD_CLK")
	)
	(segment
		(start 43.9674 -80.365854)
		(end 43.9674 -81.2292)
		(width 0.08382)
		(layer "In9.Cu")
		(net "QSPI_2_PLD_CLK")
	)
	(segment
		(start 38.841934 -92.720668)
		(end 38.97884 -92.857574)
		(width 0.08382)
		(layer "In9.Cu")
		(net "QSPI_2_PLD_CLK")
	)
	(segment
		(start 37.838888 -94.098364)
		(end 37.838888 -94.291912)
		(width 0.08382)
		(layer "In9.Cu")
		(net "QSPI_2_PLD_CLK")
	)
	(segment
		(start 36.62934 -95.50146)
		(end 36.322 -95.8088)
		(width 0.08382)
		(layer "In9.Cu")
		(net "QSPI_2_PLD_CLK")
	)
	(segment
		(start 38.520116 -86.676484)
		(end 38.520116 -88.507316)
		(width 0.08382)
		(layer "In9.Cu")
		(net "QSPI_2_PLD_CLK")
	)
	(segment
		(start 44.476162 -78.2574)
		(end 43.5356 -79.197962)
		(width 0.08382)
		(layer "In9.Cu")
		(net "QSPI_2_PLD_CLK")
	)
	(segment
		(start 49.699926 -67.201796)
		(end 49.699926 -68.707254)
		(width 0.08382)
		(layer "In9.Cu")
		(net "QSPI_2_PLD_CLK")
	)
	(segment
		(start 43.9674 -81.2292)
		(end 38.520116 -86.676484)
		(width 0.08382)
		(layer "In9.Cu")
		(net "QSPI_2_PLD_CLK")
	)
	(segment
		(start 49.699926 -68.707254)
		(end 49.1744 -69.23278)
		(width 0.08382)
		(layer "In9.Cu")
		(net "QSPI_2_PLD_CLK")
	)
	(via
		(at 69.78904 -26.70556)
		(size 0.508)
		(drill 0.254)
		(layers "F.Cu" "B.Cu")
		(net "SMB_BMC_MM16_SDA")
	)
	(via
		(at 49.779682 -32.840676)
		(size 0.508)
		(drill 0.254)
		(layers "F.Cu" "B.Cu")
		(net "SMB_BMC_MM16_SDA")
	)
	(segment
		(start 49.784 -29.22905)
		(end 50.1396 -29.58465)
		(width 0.11684)
		(layer "B.Cu")
		(net "SMB_BMC_MM16_SDA")
	)
	(segment
		(start 50.1396 -30.77845)
		(end 49.657 -31.26105)
		(width 0.11684)
		(layer "B.Cu")
		(net "SMB_BMC_MM16_SDA")
	)
	(segment
		(start 49.779682 -31.383732)
		(end 49.657 -31.26105)
		(width 0.11684)
		(layer "B.Cu")
		(net "SMB_BMC_MM16_SDA")
	)
	(segment
		(start 49.779682 -32.840676)
		(end 49.779682 -31.383732)
		(width 0.11684)
		(layer "B.Cu")
		(net "SMB_BMC_MM16_SDA")
	)
	(segment
		(start 49.53 -34.27095)
		(end 49.1998 -33.94075)
		(width 0.11684)
		(layer "B.Cu")
		(net "SMB_BMC_MM16_SDA")
	)
	(segment
		(start 69.119496 -26.70556)
		(end 69.008498 -26.594562)
		(width 0.11684)
		(layer "B.Cu")
		(net "SMB_BMC_MM16_SDA")
	)
	(segment
		(start 49.1998 -33.94075)
		(end 49.1998 -33.420558)
		(width 0.11684)
		(layer "B.Cu")
		(net "SMB_BMC_MM16_SDA")
	)
	(segment
		(start 49.1998 -33.420558)
		(end 49.779682 -32.840676)
		(width 0.11684)
		(layer "B.Cu")
		(net "SMB_BMC_MM16_SDA")
	)
	(segment
		(start 50.1396 -29.58465)
		(end 50.1396 -30.77845)
		(width 0.11684)
		(layer "B.Cu")
		(net "SMB_BMC_MM16_SDA")
	)
	(segment
		(start 69.78904 -26.70556)
		(end 69.119496 -26.70556)
		(width 0.11684)
		(layer "B.Cu")
		(net "SMB_BMC_MM16_SDA")
	)
	(segment
		(start 63.43269 -24.27351)
		(end 67.93611 -24.27351)
		(width 0.08382)
		(layer "In2.Cu")
		(net "SMB_BMC_MM16_SDA")
	)
	(segment
		(start 67.93611 -24.27351)
		(end 69.45122 -25.78862)
		(width 0.08382)
		(layer "In2.Cu")
		(net "SMB_BMC_MM16_SDA")
	)
	(segment
		(start 54.591712 -25.243536)
		(end 55.339996 -24.495252)
		(width 0.08382)
		(layer "In2.Cu")
		(net "SMB_BMC_MM16_SDA")
	)
	(segment
		(start 49.9364 -29.244544)
		(end 51.49723 -27.683714)
		(width 0.08382)
		(layer "In2.Cu")
		(net "SMB_BMC_MM16_SDA")
	)
	(segment
		(start 59.682888 -24.495252)
		(end 60.03925 -24.13889)
		(width 0.08382)
		(layer "In2.Cu")
		(net "SMB_BMC_MM16_SDA")
	)
	(segment
		(start 69.45122 -25.78862)
		(end 69.45122 -26.36774)
		(width 0.08382)
		(layer "In2.Cu")
		(net "SMB_BMC_MM16_SDA")
	)
	(segment
		(start 61.50229 -24.13889)
		(end 61.687202 -23.953978)
		(width 0.08382)
		(layer "In2.Cu")
		(net "SMB_BMC_MM16_SDA")
	)
	(segment
		(start 55.339996 -24.495252)
		(end 59.682888 -24.495252)
		(width 0.08382)
		(layer "In2.Cu")
		(net "SMB_BMC_MM16_SDA")
	)
	(segment
		(start 60.03925 -24.13889)
		(end 61.50229 -24.13889)
		(width 0.08382)
		(layer "In2.Cu")
		(net "SMB_BMC_MM16_SDA")
	)
	(segment
		(start 61.687202 -23.953978)
		(end 63.113158 -23.953978)
		(width 0.08382)
		(layer "In2.Cu")
		(net "SMB_BMC_MM16_SDA")
	)
	(segment
		(start 63.113158 -23.953978)
		(end 63.43269 -24.27351)
		(width 0.08382)
		(layer "In2.Cu")
		(net "SMB_BMC_MM16_SDA")
	)
	(segment
		(start 51.49723 -27.683714)
		(end 51.49723 -26.792682)
		(width 0.08382)
		(layer "In2.Cu")
		(net "SMB_BMC_MM16_SDA")
	)
	(segment
		(start 49.779682 -32.840676)
		(end 49.9364 -32.462216)
		(width 0.08382)
		(layer "In2.Cu")
		(net "SMB_BMC_MM16_SDA")
	)
	(segment
		(start 69.45122 -26.36774)
		(end 69.78904 -26.70556)
		(width 0.08382)
		(layer "In2.Cu")
		(net "SMB_BMC_MM16_SDA")
	)
	(segment
		(start 49.9364 -32.462216)
		(end 49.9364 -29.244544)
		(width 0.08382)
		(layer "In2.Cu")
		(net "SMB_BMC_MM16_SDA")
	)
	(segment
		(start 51.49723 -26.792682)
		(end 53.046376 -25.243536)
		(width 0.08382)
		(layer "In2.Cu")
		(net "SMB_BMC_MM16_SDA")
	)
	(segment
		(start 53.046376 -25.243536)
		(end 54.591712 -25.243536)
		(width 0.08382)
		(layer "In2.Cu")
		(net "SMB_BMC_MM16_SDA")
	)
	(via
		(at 69.6468 -27.813)
		(size 0.508)
		(drill 0.254)
		(layers "F.Cu" "B.Cu")
		(net "SMB_BMC_MM16_SCL")
	)
	(via
		(at 51.944016 -28.830778)
		(size 0.6604)
		(drill 0.3302)
		(layers "F.Cu" "B.Cu")
		(net "SMB_BMC_MM16_SCL")
	)
	(via
		(at 50.8 -32.706056)
		(size 0.508)
		(drill 0.254)
		(layers "F.Cu" "B.Cu")
		(net "SMB_BMC_MM16_SCL")
	)
	(segment
		(start 50.8 -29.22905)
		(end 51.198272 -28.830778)
		(width 0.11684)
		(layer "B.Cu")
		(net "SMB_BMC_MM16_SCL")
	)
	(segment
		(start 69.323204 -27.489404)
		(end 69.6468 -27.813)
		(width 0.11684)
		(layer "B.Cu")
		(net "SMB_BMC_MM16_SCL")
	)
	(segment
		(start 51.198272 -28.830778)
		(end 51.944016 -28.830778)
		(width 0.11684)
		(layer "B.Cu")
		(net "SMB_BMC_MM16_SCL")
	)
	(segment
		(start 50.292 -33.214056)
		(end 50.292 -33.99155)
		(width 0.11684)
		(layer "B.Cu")
		(net "SMB_BMC_MM16_SCL")
	)
	(segment
		(start 50.292 -33.99155)
		(end 50.546 -34.24555)
		(width 0.11684)
		(layer "B.Cu")
		(net "SMB_BMC_MM16_SCL")
	)
	(segment
		(start 50.673 -31.26105)
		(end 51.24958 -30.68447)
		(width 0.11684)
		(layer "B.Cu")
		(net "SMB_BMC_MM16_SCL")
	)
	(segment
		(start 50.8 -31.38805)
		(end 50.673 -31.26105)
		(width 0.11684)
		(layer "B.Cu")
		(net "SMB_BMC_MM16_SCL")
	)
	(segment
		(start 69.008498 -27.489404)
		(end 69.323204 -27.489404)
		(width 0.11684)
		(layer "B.Cu")
		(net "SMB_BMC_MM16_SCL")
	)
	(segment
		(start 51.24958 -29.525214)
		(end 51.944016 -28.830778)
		(width 0.11684)
		(layer "B.Cu")
		(net "SMB_BMC_MM16_SCL")
	)
	(segment
		(start 50.8 -32.706056)
		(end 50.292 -33.214056)
		(width 0.11684)
		(layer "B.Cu")
		(net "SMB_BMC_MM16_SCL")
	)
	(segment
		(start 50.8 -32.706056)
		(end 50.8 -31.38805)
		(width 0.11684)
		(layer "B.Cu")
		(net "SMB_BMC_MM16_SCL")
	)
	(segment
		(start 51.24958 -30.68447)
		(end 51.24958 -29.525214)
		(width 0.11684)
		(layer "B.Cu")
		(net "SMB_BMC_MM16_SCL")
	)
	(segment
		(start 69.0372 -27.2034)
		(end 69.0372 -25.8572)
		(width 0.08382)
		(layer "In2.Cu")
		(net "SMB_BMC_MM16_SCL")
	)
	(segment
		(start 67.76593 -24.58593)
		(end 63.30315 -24.58593)
		(width 0.08382)
		(layer "In2.Cu")
		(net "SMB_BMC_MM16_SCL")
	)
	(segment
		(start 69.6468 -27.813)
		(end 69.0372 -27.2034)
		(width 0.08382)
		(layer "In2.Cu")
		(net "SMB_BMC_MM16_SCL")
	)
	(segment
		(start 50.3174 -29.305504)
		(end 50.3174 -31.435294)
		(width 0.08382)
		(layer "In2.Cu")
		(net "SMB_BMC_MM16_SCL")
	)
	(segment
		(start 51.80965 -27.813254)
		(end 50.3174 -29.305504)
		(width 0.08382)
		(layer "In2.Cu")
		(net "SMB_BMC_MM16_SCL")
	)
	(segment
		(start 69.0372 -25.8572)
		(end 67.76593 -24.58593)
		(width 0.08382)
		(layer "In2.Cu")
		(net "SMB_BMC_MM16_SCL")
	)
	(segment
		(start 61.62548 -24.464518)
		(end 60.155582 -24.464518)
		(width 0.08382)
		(layer "In2.Cu")
		(net "SMB_BMC_MM16_SCL")
	)
	(segment
		(start 60.155582 -24.464518)
		(end 59.79033 -24.82977)
		(width 0.08382)
		(layer "In2.Cu")
		(net "SMB_BMC_MM16_SCL")
	)
	(segment
		(start 53.171344 -25.560528)
		(end 51.80965 -26.922222)
		(width 0.08382)
		(layer "In2.Cu")
		(net "SMB_BMC_MM16_SCL")
	)
	(segment
		(start 50.3174 -31.435294)
		(end 50.8 -31.917894)
		(width 0.08382)
		(layer "In2.Cu")
		(net "SMB_BMC_MM16_SCL")
	)
	(segment
		(start 54.732682 -25.560528)
		(end 53.171344 -25.560528)
		(width 0.08382)
		(layer "In2.Cu")
		(net "SMB_BMC_MM16_SCL")
	)
	(segment
		(start 61.8236 -24.266398)
		(end 61.62548 -24.464518)
		(width 0.08382)
		(layer "In2.Cu")
		(net "SMB_BMC_MM16_SCL")
	)
	(segment
		(start 55.46344 -24.82977)
		(end 54.732682 -25.560528)
		(width 0.08382)
		(layer "In2.Cu")
		(net "SMB_BMC_MM16_SCL")
	)
	(segment
		(start 59.79033 -24.82977)
		(end 55.46344 -24.82977)
		(width 0.08382)
		(layer "In2.Cu")
		(net "SMB_BMC_MM16_SCL")
	)
	(segment
		(start 51.80965 -26.922222)
		(end 51.80965 -27.813254)
		(width 0.08382)
		(layer "In2.Cu")
		(net "SMB_BMC_MM16_SCL")
	)
	(segment
		(start 63.30315 -24.58593)
		(end 62.983618 -24.266398)
		(width 0.08382)
		(layer "In2.Cu")
		(net "SMB_BMC_MM16_SCL")
	)
	(segment
		(start 50.8 -31.917894)
		(end 50.8 -32.706056)
		(width 0.08382)
		(layer "In2.Cu")
		(net "SMB_BMC_MM16_SCL")
	)
	(segment
		(start 62.983618 -24.266398)
		(end 61.8236 -24.266398)
		(width 0.08382)
		(layer "In2.Cu")
		(net "SMB_BMC_MM16_SCL")
	)
	(segment
		(start 51.295046 -42.571162)
		(end 50.899822 -42.175938)
		(width 0.11684)
		(layer "F.Cu")
		(net "SMB_BMC_MM16_R_SDA")
	)
	(via
		(at 50.9016 -38.5064)
		(size 0.6604)
		(drill 0.3302)
		(layers "F.Cu" "B.Cu")
		(net "SMB_BMC_MM16_R_SDA")
	)
	(via
		(at 50.899822 -42.175938)
		(size 0.4572)
		(drill 0.254)
		(layers "F.Cu" "B.Cu")
		(net "SMB_BMC_MM16_R_SDA")
	)
	(segment
		(start 51.306984 -40.308276)
		(end 51.306984 -41.768776)
		(width 0.11684)
		(layer "B.Cu")
		(net "SMB_BMC_MM16_R_SDA")
	)
	(segment
		(start 50.9016 -38.5064)
		(end 50.9016 -38.862)
		(width 0.11684)
		(layer "B.Cu")
		(net "SMB_BMC_MM16_R_SDA")
	)
	(segment
		(start 49.53 -35.07105)
		(end 49.84115 -35.3822)
		(width 0.11684)
		(layer "B.Cu")
		(net "SMB_BMC_MM16_R_SDA")
	)
	(segment
		(start 50.1396 -35.3822)
		(end 50.427636 -35.670236)
		(width 0.11684)
		(layer "B.Cu")
		(net "SMB_BMC_MM16_R_SDA")
	)
	(segment
		(start 51.129946 -40.131238)
		(end 51.306984 -40.308276)
		(width 0.11684)
		(layer "B.Cu")
		(net "SMB_BMC_MM16_R_SDA")
	)
	(segment
		(start 49.84115 -35.3822)
		(end 50.1396 -35.3822)
		(width 0.11684)
		(layer "B.Cu")
		(net "SMB_BMC_MM16_R_SDA")
	)
	(segment
		(start 50.427636 -35.670236)
		(end 50.427636 -37.314886)
		(width 0.11684)
		(layer "B.Cu")
		(net "SMB_BMC_MM16_R_SDA")
	)
	(segment
		(start 51.306984 -41.768776)
		(end 50.899822 -42.175938)
		(width 0.11684)
		(layer "B.Cu")
		(net "SMB_BMC_MM16_R_SDA")
	)
	(segment
		(start 50.9016 -37.78885)
		(end 50.9016 -38.5064)
		(width 0.11684)
		(layer "B.Cu")
		(net "SMB_BMC_MM16_R_SDA")
	)
	(segment
		(start 50.427636 -37.314886)
		(end 50.9016 -37.78885)
		(width 0.11684)
		(layer "B.Cu")
		(net "SMB_BMC_MM16_R_SDA")
	)
	(segment
		(start 50.9016 -38.862)
		(end 51.129946 -39.090346)
		(width 0.11684)
		(layer "B.Cu")
		(net "SMB_BMC_MM16_R_SDA")
	)
	(segment
		(start 51.129946 -39.090346)
		(end 51.129946 -40.131238)
		(width 0.11684)
		(layer "B.Cu")
		(net "SMB_BMC_MM16_R_SDA")
	)
	(segment
		(start 52.094892 -40.971216)
		(end 51.699668 -40.575992)
		(width 0.11684)
		(layer "F.Cu")
		(net "SMB_BMC_MM16_R_SCL")
	)
	(via
		(at 51.699668 -40.575992)
		(size 0.4572)
		(drill 0.254)
		(layers "F.Cu" "B.Cu")
		(net "SMB_BMC_MM16_R_SCL")
	)
	(segment
		(start 51.40452 -37.730938)
		(end 50.826162 -37.15258)
		(width 0.11684)
		(layer "B.Cu")
		(net "SMB_BMC_MM16_R_SCL")
	)
	(segment
		(start 50.567082 -35.04565)
		(end 50.546 -35.04565)
		(width 0.11684)
		(layer "B.Cu")
		(net "SMB_BMC_MM16_R_SCL")
	)
	(segment
		(start 51.40452 -38.933374)
		(end 51.40452 -37.730938)
		(width 0.11684)
		(layer "B.Cu")
		(net "SMB_BMC_MM16_R_SCL")
	)
	(segment
		(start 51.699668 -40.251888)
		(end 51.47945 -40.03167)
		(width 0.11684)
		(layer "B.Cu")
		(net "SMB_BMC_MM16_R_SCL")
	)
	(segment
		(start 50.826162 -35.30473)
		(end 50.567082 -35.04565)
		(width 0.11684)
		(layer "B.Cu")
		(net "SMB_BMC_MM16_R_SCL")
	)
	(segment
		(start 51.47945 -40.03167)
		(end 51.47945 -39.008304)
		(width 0.11684)
		(layer "B.Cu")
		(net "SMB_BMC_MM16_R_SCL")
	)
	(segment
		(start 51.47945 -39.008304)
		(end 51.40452 -38.933374)
		(width 0.11684)
		(layer "B.Cu")
		(net "SMB_BMC_MM16_R_SCL")
	)
	(segment
		(start 50.826162 -37.15258)
		(end 50.826162 -35.30473)
		(width 0.11684)
		(layer "B.Cu")
		(net "SMB_BMC_MM16_R_SCL")
	)
	(segment
		(start 51.699668 -40.575992)
		(end 51.699668 -40.251888)
		(width 0.11684)
		(layer "B.Cu")
		(net "SMB_BMC_MM16_R_SCL")
	)
	(segment
		(start 51.816 -31.26105)
		(end 51.441096 -31.26105)
		(width 0.11684)
		(layer "F.Cu")
		(net "SMB_BMC_MM15_SDA")
	)
	(segment
		(start 51.308 -31.394146)
		(end 51.308 -33.485836)
		(width 0.11684)
		(layer "F.Cu")
		(net "SMB_BMC_MM15_SDA")
	)
	(segment
		(start 51.42484 -33.602676)
		(end 51.84648 -33.602676)
		(width 0.11684)
		(layer "F.Cu")
		(net "SMB_BMC_MM15_SDA")
	)
	(segment
		(start 51.84648 -33.602676)
		(end 51.84648 -34.237676)
		(width 0.11684)
		(layer "F.Cu")
		(net "SMB_BMC_MM15_SDA")
	)
	(segment
		(start 51.308 -33.485836)
		(end 51.42484 -33.602676)
		(width 0.11684)
		(layer "F.Cu")
		(net "SMB_BMC_MM15_SDA")
	)
	(segment
		(start 51.441096 -31.26105)
		(end 51.308 -31.394146)
		(width 0.11684)
		(layer "F.Cu")
		(net "SMB_BMC_MM15_SDA")
	)
	(via
		(at 16.60652 -54.13248)
		(size 0.6604)
		(drill 0.3302)
		(layers "F.Cu" "B.Cu")
		(net "SMB_BMC_MM15_SDA")
	)
	(via
		(at 18.12798 -48.004222)
		(size 0.508)
		(drill 0.254)
		(layers "F.Cu" "B.Cu")
		(net "SMB_BMC_MM15_SDA")
	)
	(via
		(at 51.84648 -33.602676)
		(size 0.508)
		(drill 0.254)
		(layers "F.Cu" "B.Cu")
		(net "SMB_BMC_MM15_SDA")
	)
	(segment
		(start 16.60652 -54.13248)
		(end 16.38808 -53.91404)
		(width 0.11684)
		(layer "B.Cu")
		(net "SMB_BMC_MM15_SDA")
	)
	(segment
		(start 16.40078 -57.084214)
		(end 16.40078 -55.666894)
		(width 0.11684)
		(layer "B.Cu")
		(net "SMB_BMC_MM15_SDA")
	)
	(segment
		(start 17.652238 -50.800762)
		(end 18.188178 -50.264822)
		(width 0.11684)
		(layer "B.Cu")
		(net "SMB_BMC_MM15_SDA")
	)
	(segment
		(start 15.548864 -57.93613)
		(end 16.40078 -57.084214)
		(width 0.11684)
		(layer "B.Cu")
		(net "SMB_BMC_MM15_SDA")
	)
	(segment
		(start 15.548864 -58.35015)
		(end 15.548864 -57.93613)
		(width 0.11684)
		(layer "B.Cu")
		(net "SMB_BMC_MM15_SDA")
	)
	(segment
		(start 18.188178 -48.064674)
		(end 18.12798 -48.004476)
		(width 0.11684)
		(layer "B.Cu")
		(net "SMB_BMC_MM15_SDA")
	)
	(segment
		(start 16.40078 -55.666894)
		(end 16.60652 -55.461154)
		(width 0.11684)
		(layer "B.Cu")
		(net "SMB_BMC_MM15_SDA")
	)
	(segment
		(start 16.38808 -52.545996)
		(end 17.652492 -51.281584)
		(width 0.11684)
		(layer "B.Cu")
		(net "SMB_BMC_MM15_SDA")
	)
	(segment
		(start 18.188178 -50.264822)
		(end 18.188178 -48.064674)
		(width 0.11684)
		(layer "B.Cu")
		(net "SMB_BMC_MM15_SDA")
	)
	(segment
		(start 16.60652 -55.461154)
		(end 16.60652 -54.13248)
		(width 0.11684)
		(layer "B.Cu")
		(net "SMB_BMC_MM15_SDA")
	)
	(segment
		(start 17.652492 -51.281584)
		(end 17.652238 -50.800762)
		(width 0.11684)
		(layer "B.Cu")
		(net "SMB_BMC_MM15_SDA")
	)
	(segment
		(start 18.12798 -48.004476)
		(end 18.12798 -48.004222)
		(width 0.11684)
		(layer "B.Cu")
		(net "SMB_BMC_MM15_SDA")
	)
	(segment
		(start 16.38808 -53.91404)
		(end 16.38808 -52.545996)
		(width 0.11684)
		(layer "B.Cu")
		(net "SMB_BMC_MM15_SDA")
	)
	(segment
		(start 37.897054 -28.1686)
		(end 35.425888 -28.1686)
		(width 0.08382)
		(layer "In2.Cu")
		(net "SMB_BMC_MM15_SDA")
	)
	(segment
		(start 42.2402 -28.956)
		(end 38.684454 -28.956)
		(width 0.08382)
		(layer "In2.Cu")
		(net "SMB_BMC_MM15_SDA")
	)
	(segment
		(start 24.892254 -35.4076)
		(end 24.269192 -35.4076)
		(width 0.08382)
		(layer "In2.Cu")
		(net "SMB_BMC_MM15_SDA")
	)
	(segment
		(start 49.24044 -31.882334)
		(end 48.243236 -30.88513)
		(width 0.08382)
		(layer "In2.Cu")
		(net "SMB_BMC_MM15_SDA")
	)
	(segment
		(start 17.29486 -43.5356)
		(end 16.966946 -43.863514)
		(width 0.08382)
		(layer "In2.Cu")
		(net "SMB_BMC_MM15_SDA")
	)
	(segment
		(start 51.84648 -33.602676)
		(end 51.339496 -34.10966)
		(width 0.08382)
		(layer "In2.Cu")
		(net "SMB_BMC_MM15_SDA")
	)
	(segment
		(start 17.622774 -47.020734)
		(end 17.622774 -47.899574)
		(width 0.08382)
		(layer "In2.Cu")
		(net "SMB_BMC_MM15_SDA")
	)
	(segment
		(start 26.67 -33.629854)
		(end 24.892254 -35.4076)
		(width 0.08382)
		(layer "In2.Cu")
		(net "SMB_BMC_MM15_SDA")
	)
	(segment
		(start 21.047964 -42.571162)
		(end 19.902424 -42.571162)
		(width 0.08382)
		(layer "In2.Cu")
		(net "SMB_BMC_MM15_SDA")
	)
	(segment
		(start 22.94255 -40.676576)
		(end 21.047964 -42.571162)
		(width 0.08382)
		(layer "In2.Cu")
		(net "SMB_BMC_MM15_SDA")
	)
	(segment
		(start 38.684454 -28.956)
		(end 37.897054 -28.1686)
		(width 0.08382)
		(layer "In2.Cu")
		(net "SMB_BMC_MM15_SDA")
	)
	(segment
		(start 24.269192 -35.4076)
		(end 22.94255 -36.734242)
		(width 0.08382)
		(layer "In2.Cu")
		(net "SMB_BMC_MM15_SDA")
	)
	(segment
		(start 19.902424 -42.571162)
		(end 19.377914 -43.095672)
		(width 0.08382)
		(layer "In2.Cu")
		(net "SMB_BMC_MM15_SDA")
	)
	(segment
		(start 35.425888 -28.1686)
		(end 33.306766 -30.287722)
		(width 0.08382)
		(layer "In2.Cu")
		(net "SMB_BMC_MM15_SDA")
	)
	(segment
		(start 30.825186 -31.81731)
		(end 27.924252 -31.81731)
		(width 0.08382)
		(layer "In2.Cu")
		(net "SMB_BMC_MM15_SDA")
	)
	(segment
		(start 26.67 -33.071562)
		(end 26.67 -33.629854)
		(width 0.08382)
		(layer "In2.Cu")
		(net "SMB_BMC_MM15_SDA")
	)
	(segment
		(start 27.924252 -31.81731)
		(end 26.67 -33.071562)
		(width 0.08382)
		(layer "In2.Cu")
		(net "SMB_BMC_MM15_SDA")
	)
	(segment
		(start 16.9672 -45.39996)
		(end 16.9672 -46.36516)
		(width 0.08382)
		(layer "In2.Cu")
		(net "SMB_BMC_MM15_SDA")
	)
	(segment
		(start 51.339496 -34.10966)
		(end 49.42586 -34.10966)
		(width 0.08382)
		(layer "In2.Cu")
		(net "SMB_BMC_MM15_SDA")
	)
	(segment
		(start 16.966946 -45.399706)
		(end 16.9672 -45.39996)
		(width 0.08382)
		(layer "In2.Cu")
		(net "SMB_BMC_MM15_SDA")
	)
	(segment
		(start 19.377914 -43.095672)
		(end 18.536412 -43.095672)
		(width 0.08382)
		(layer "In2.Cu")
		(net "SMB_BMC_MM15_SDA")
	)
	(segment
		(start 44.16933 -30.88513)
		(end 42.2402 -28.956)
		(width 0.08382)
		(layer "In2.Cu")
		(net "SMB_BMC_MM15_SDA")
	)
	(segment
		(start 22.94255 -36.734242)
		(end 22.94255 -40.676576)
		(width 0.08382)
		(layer "In2.Cu")
		(net "SMB_BMC_MM15_SDA")
	)
	(segment
		(start 33.306766 -30.287722)
		(end 32.354774 -30.287722)
		(width 0.08382)
		(layer "In2.Cu")
		(net "SMB_BMC_MM15_SDA")
	)
	(segment
		(start 17.726914 -48.003714)
		(end 18.127472 -48.003714)
		(width 0.08382)
		(layer "In2.Cu")
		(net "SMB_BMC_MM15_SDA")
	)
	(segment
		(start 49.24044 -33.92424)
		(end 49.24044 -31.882334)
		(width 0.08382)
		(layer "In2.Cu")
		(net "SMB_BMC_MM15_SDA")
	)
	(segment
		(start 17.622774 -47.899574)
		(end 17.726914 -48.003714)
		(width 0.08382)
		(layer "In2.Cu")
		(net "SMB_BMC_MM15_SDA")
	)
	(segment
		(start 49.42586 -34.10966)
		(end 49.24044 -33.92424)
		(width 0.08382)
		(layer "In2.Cu")
		(net "SMB_BMC_MM15_SDA")
	)
	(segment
		(start 16.9672 -46.36516)
		(end 17.622774 -47.020734)
		(width 0.08382)
		(layer "In2.Cu")
		(net "SMB_BMC_MM15_SDA")
	)
	(segment
		(start 18.536412 -43.095672)
		(end 18.096484 -43.5356)
		(width 0.08382)
		(layer "In2.Cu")
		(net "SMB_BMC_MM15_SDA")
	)
	(segment
		(start 48.243236 -30.88513)
		(end 44.16933 -30.88513)
		(width 0.08382)
		(layer "In2.Cu")
		(net "SMB_BMC_MM15_SDA")
	)
	(segment
		(start 32.354774 -30.287722)
		(end 30.825186 -31.81731)
		(width 0.08382)
		(layer "In2.Cu")
		(net "SMB_BMC_MM15_SDA")
	)
	(segment
		(start 16.966946 -43.863514)
		(end 16.966946 -45.399706)
		(width 0.08382)
		(layer "In2.Cu")
		(net "SMB_BMC_MM15_SDA")
	)
	(segment
		(start 18.127472 -48.003714)
		(end 18.12798 -48.004222)
		(width 0.08382)
		(layer "In2.Cu")
		(net "SMB_BMC_MM15_SDA")
	)
	(segment
		(start 18.096484 -43.5356)
		(end 17.29486 -43.5356)
		(width 0.08382)
		(layer "In2.Cu")
		(net "SMB_BMC_MM15_SDA")
	)
	(via
		(at 18.071084 -47.368206)
		(size 0.508)
		(drill 0.254)
		(layers "F.Cu" "B.Cu")
		(net "SMB_BMC_MM15_SCL")
	)
	(via
		(at 48.636428 -32.840676)
		(size 0.508)
		(drill 0.254)
		(layers "F.Cu" "B.Cu")
		(net "SMB_BMC_MM15_SCL")
	)
	(via
		(at 16.9418 -56.01208)
		(size 0.6604)
		(drill 0.3302)
		(layers "F.Cu" "B.Cu")
		(net "SMB_BMC_MM15_SCL")
	)
	(segment
		(start 16.9418 -57.175654)
		(end 16.564864 -57.55259)
		(width 0.11684)
		(layer "B.Cu")
		(net "SMB_BMC_MM15_SCL")
	)
	(segment
		(start 16.9418 -56.01208)
		(end 16.9418 -57.175654)
		(width 0.11684)
		(layer "B.Cu")
		(net "SMB_BMC_MM15_SCL")
	)
	(segment
		(start 48.624236 -31.257748)
		(end 48.624236 -32.828484)
		(width 0.11684)
		(layer "B.Cu")
		(net "SMB_BMC_MM15_SCL")
	)
	(segment
		(start 17.2085 -53.58384)
		(end 17.2085 -55.74538)
		(width 0.11684)
		(layer "B.Cu")
		(net "SMB_BMC_MM15_SCL")
	)
	(segment
		(start 18.071084 -47.368206)
		(end 18.14957 -47.368206)
		(width 0.11684)
		(layer "B.Cu")
		(net "SMB_BMC_MM15_SCL")
	)
	(segment
		(start 17.958054 -51.5366)
		(end 16.78432 -52.710334)
		(width 0.11684)
		(layer "B.Cu")
		(net "SMB_BMC_MM15_SCL")
	)
	(segment
		(start 48.624236 -32.828484)
		(end 48.636428 -32.840676)
		(width 0.11684)
		(layer "B.Cu")
		(net "SMB_BMC_MM15_SCL")
	)
	(segment
		(start 48.514 -33.452054)
		(end 48.514 -34.27095)
		(width 0.11684)
		(layer "B.Cu")
		(net "SMB_BMC_MM15_SCL")
	)
	(segment
		(start 19.2278 -50.8)
		(end 18.4912 -51.5366)
		(width 0.11684)
		(layer "B.Cu")
		(net "SMB_BMC_MM15_SCL")
	)
	(segment
		(start 18.4912 -51.5366)
		(end 17.958054 -51.5366)
		(width 0.11684)
		(layer "B.Cu")
		(net "SMB_BMC_MM15_SCL")
	)
	(segment
		(start 19.2278 -48.446436)
		(end 19.2278 -50.8)
		(width 0.11684)
		(layer "B.Cu")
		(net "SMB_BMC_MM15_SCL")
	)
	(segment
		(start 16.78432 -53.15966)
		(end 17.2085 -53.58384)
		(width 0.11684)
		(layer "B.Cu")
		(net "SMB_BMC_MM15_SCL")
	)
	(segment
		(start 17.2085 -55.74538)
		(end 16.9418 -56.01208)
		(width 0.11684)
		(layer "B.Cu")
		(net "SMB_BMC_MM15_SCL")
	)
	(segment
		(start 16.78432 -52.710334)
		(end 16.78432 -53.15966)
		(width 0.11684)
		(layer "B.Cu")
		(net "SMB_BMC_MM15_SCL")
	)
	(segment
		(start 18.14957 -47.368206)
		(end 19.2278 -48.446436)
		(width 0.11684)
		(layer "B.Cu")
		(net "SMB_BMC_MM15_SCL")
	)
	(segment
		(start 16.564864 -57.55259)
		(end 16.564864 -58.35015)
		(width 0.11684)
		(layer "B.Cu")
		(net "SMB_BMC_MM15_SCL")
	)
	(segment
		(start 48.636428 -32.840676)
		(end 48.636428 -33.329626)
		(width 0.11684)
		(layer "B.Cu")
		(net "SMB_BMC_MM15_SCL")
	)
	(segment
		(start 48.636428 -33.329626)
		(end 48.514 -33.452054)
		(width 0.11684)
		(layer "B.Cu")
		(net "SMB_BMC_MM15_SCL")
	)
	(segment
		(start 18.936208 -45.47489)
		(end 19.396456 -45.47489)
		(width 0.08382)
		(layer "In2.Cu")
		(net "SMB_BMC_MM15_SCL")
	)
	(segment
		(start 48.636428 -31.720536)
		(end 48.636428 -32.840676)
		(width 0.08382)
		(layer "In2.Cu")
		(net "SMB_BMC_MM15_SCL")
	)
	(segment
		(start 32.13481 -32.463994)
		(end 35.218116 -29.380688)
		(width 0.08382)
		(layer "In2.Cu")
		(net "SMB_BMC_MM15_SCL")
	)
	(segment
		(start 20.496784 -43.396154)
		(end 21.107146 -43.396154)
		(width 0.08382)
		(layer "In2.Cu")
		(net "SMB_BMC_MM15_SCL")
	)
	(segment
		(start 18.673826 -46.19752)
		(end 18.673826 -45.737272)
		(width 0.08382)
		(layer "In2.Cu")
		(net "SMB_BMC_MM15_SCL")
	)
	(segment
		(start 35.218116 -29.380688)
		(end 36.289234 -29.380688)
		(width 0.08382)
		(layer "In2.Cu")
		(net "SMB_BMC_MM15_SCL")
	)
	(segment
		(start 24.297386 -36.424362)
		(end 25.35682 -36.424362)
		(width 0.08382)
		(layer "In2.Cu")
		(net "SMB_BMC_MM15_SCL")
	)
	(segment
		(start 48.113442 -31.19755)
		(end 48.636428 -31.720536)
		(width 0.08382)
		(layer "In2.Cu")
		(net "SMB_BMC_MM15_SCL")
	)
	(segment
		(start 18.071084 -46.800262)
		(end 18.673826 -46.19752)
		(width 0.08382)
		(layer "In2.Cu")
		(net "SMB_BMC_MM15_SCL")
	)
	(segment
		(start 29.317188 -32.463994)
		(end 32.13481 -32.463994)
		(width 0.08382)
		(layer "In2.Cu")
		(net "SMB_BMC_MM15_SCL")
	)
	(segment
		(start 43.068748 -30.241748)
		(end 44.02455 -31.19755)
		(width 0.08382)
		(layer "In2.Cu")
		(net "SMB_BMC_MM15_SCL")
	)
	(segment
		(start 44.02455 -31.19755)
		(end 48.113442 -31.19755)
		(width 0.08382)
		(layer "In2.Cu")
		(net "SMB_BMC_MM15_SCL")
	)
	(segment
		(start 19.396456 -45.47489)
		(end 19.5834 -45.287946)
		(width 0.08382)
		(layer "In2.Cu")
		(net "SMB_BMC_MM15_SCL")
	)
	(segment
		(start 37.150294 -30.241748)
		(end 43.068748 -30.241748)
		(width 0.08382)
		(layer "In2.Cu")
		(net "SMB_BMC_MM15_SCL")
	)
	(segment
		(start 19.5834 -44.309538)
		(end 20.496784 -43.396154)
		(width 0.08382)
		(layer "In2.Cu")
		(net "SMB_BMC_MM15_SCL")
	)
	(segment
		(start 18.673826 -45.737272)
		(end 18.936208 -45.47489)
		(width 0.08382)
		(layer "In2.Cu")
		(net "SMB_BMC_MM15_SCL")
	)
	(segment
		(start 36.289234 -29.380688)
		(end 37.150294 -30.241748)
		(width 0.08382)
		(layer "In2.Cu")
		(net "SMB_BMC_MM15_SCL")
	)
	(segment
		(start 21.107146 -43.396154)
		(end 23.5966 -40.9067)
		(width 0.08382)
		(layer "In2.Cu")
		(net "SMB_BMC_MM15_SCL")
	)
	(segment
		(start 19.5834 -45.287946)
		(end 19.5834 -44.309538)
		(width 0.08382)
		(layer "In2.Cu")
		(net "SMB_BMC_MM15_SCL")
	)
	(segment
		(start 18.071084 -47.368206)
		(end 18.071084 -46.800262)
		(width 0.08382)
		(layer "In2.Cu")
		(net "SMB_BMC_MM15_SCL")
	)
	(segment
		(start 23.5966 -40.9067)
		(end 23.5966 -37.125148)
		(width 0.08382)
		(layer "In2.Cu")
		(net "SMB_BMC_MM15_SCL")
	)
	(segment
		(start 25.35682 -36.424362)
		(end 29.317188 -32.463994)
		(width 0.08382)
		(layer "In2.Cu")
		(net "SMB_BMC_MM15_SCL")
	)
	(segment
		(start 23.5966 -37.125148)
		(end 24.297386 -36.424362)
		(width 0.08382)
		(layer "In2.Cu")
		(net "SMB_BMC_MM15_SCL")
	)
	(segment
		(start 51.726592 -36.413948)
		(end 51.726592 -37.472112)
		(width 0.11684)
		(layer "F.Cu")
		(net "SMB_BMC_MM15_R_SDA")
	)
	(segment
		(start 51.726592 -36.386008)
		(end 51.740562 -36.399978)
		(width 0.11684)
		(layer "F.Cu")
		(net "SMB_BMC_MM15_R_SDA")
	)
	(segment
		(start 51.84648 -35.037776)
		(end 51.726592 -35.157664)
		(width 0.11684)
		(layer "F.Cu")
		(net "SMB_BMC_MM15_R_SDA")
	)
	(segment
		(start 51.726592 -35.157664)
		(end 51.726592 -36.386008)
		(width 0.11684)
		(layer "F.Cu")
		(net "SMB_BMC_MM15_R_SDA")
	)
	(segment
		(start 51.68392 -38.91788)
		(end 51.68392 -39.760398)
		(width 0.11684)
		(layer "F.Cu")
		(net "SMB_BMC_MM15_R_SDA")
	)
	(segment
		(start 51.84648 -37.592)
		(end 51.84648 -38.75532)
		(width 0.11684)
		(layer "F.Cu")
		(net "SMB_BMC_MM15_R_SDA")
	)
	(segment
		(start 51.740562 -36.399978)
		(end 51.726592 -36.413948)
		(width 0.11684)
		(layer "F.Cu")
		(net "SMB_BMC_MM15_R_SDA")
	)
	(segment
		(start 51.68392 -39.760398)
		(end 52.094892 -40.17137)
		(width 0.11684)
		(layer "F.Cu")
		(net "SMB_BMC_MM15_R_SDA")
	)
	(segment
		(start 51.726592 -37.472112)
		(end 51.84648 -37.592)
		(width 0.11684)
		(layer "F.Cu")
		(net "SMB_BMC_MM15_R_SDA")
	)
	(segment
		(start 51.84648 -38.75532)
		(end 51.68392 -38.91788)
		(width 0.11684)
		(layer "F.Cu")
		(net "SMB_BMC_MM15_R_SDA")
	)
	(via
		(at 51.740562 -36.399978)
		(size 0.762)
		(drill 0.381)
		(layers "F.Cu" "B.Cu")
		(net "SMB_BMC_MM15_R_SDA")
	)
	(segment
		(start 51.295046 -41.771316)
		(end 50.899822 -41.376092)
		(width 0.11684)
		(layer "F.Cu")
		(net "SMB_BMC_MM15_R_SCL")
	)
	(via
		(at 50.899822 -41.376092)
		(size 0.4572)
		(drill 0.254)
		(layers "F.Cu" "B.Cu")
		(net "SMB_BMC_MM15_R_SCL")
	)
	(segment
		(start 49.3014 -36.881054)
		(end 49.3014 -35.85845)
		(width 0.11684)
		(layer "B.Cu")
		(net "SMB_BMC_MM15_R_SCL")
	)
	(segment
		(start 49.9364 -38.125146)
		(end 49.432718 -37.621464)
		(width 0.11684)
		(layer "B.Cu")
		(net "SMB_BMC_MM15_R_SCL")
	)
	(segment
		(start 49.9364 -39.042086)
		(end 49.9364 -38.125146)
		(width 0.11684)
		(layer "B.Cu")
		(net "SMB_BMC_MM15_R_SCL")
	)
	(segment
		(start 49.432718 -37.012372)
		(end 49.3014 -36.881054)
		(width 0.11684)
		(layer "B.Cu")
		(net "SMB_BMC_MM15_R_SCL")
	)
	(segment
		(start 50.899822 -41.376092)
		(end 50.899822 -41.128442)
		(width 0.11684)
		(layer "B.Cu")
		(net "SMB_BMC_MM15_R_SCL")
	)
	(segment
		(start 49.3014 -35.85845)
		(end 48.514 -35.07105)
		(width 0.11684)
		(layer "B.Cu")
		(net "SMB_BMC_MM15_R_SCL")
	)
	(segment
		(start 50.899822 -41.128442)
		(end 50.50155 -40.73017)
		(width 0.11684)
		(layer "B.Cu")
		(net "SMB_BMC_MM15_R_SCL")
	)
	(segment
		(start 50.50155 -39.607236)
		(end 49.9364 -39.042086)
		(width 0.11684)
		(layer "B.Cu")
		(net "SMB_BMC_MM15_R_SCL")
	)
	(segment
		(start 49.432718 -37.621464)
		(end 49.432718 -37.012372)
		(width 0.11684)
		(layer "B.Cu")
		(net "SMB_BMC_MM15_R_SCL")
	)
	(segment
		(start 50.50155 -40.73017)
		(end 50.50155 -39.607236)
		(width 0.11684)
		(layer "B.Cu")
		(net "SMB_BMC_MM15_R_SCL")
	)
	(via
		(at 33.927288 -107.67949)
		(size 0.508)
		(drill 0.254)
		(layers "F.Cu" "B.Cu")
		(net "SMB_BMC_MM12_SDA")
	)
	(via
		(at 40.954198 -46.16069)
		(size 0.508)
		(drill 0.254)
		(layers "F.Cu" "B.Cu")
		(net "SMB_BMC_MM12_SDA")
	)
	(via
		(at 34.24047 -108.55833)
		(size 0.6604)
		(drill 0.3302)
		(layers "F.Cu" "B.Cu")
		(net "SMB_BMC_MM12_SDA")
	)
	(segment
		(start 35.93592 -113.077244)
		(end 34.99612 -112.137444)
		(width 0.11684)
		(layer "B.Cu")
		(net "SMB_BMC_MM12_SDA")
	)
	(segment
		(start 36.9824 -115.674902)
		(end 35.93592 -114.628422)
		(width 0.11684)
		(layer "B.Cu")
		(net "SMB_BMC_MM12_SDA")
	)
	(segment
		(start 35.93592 -114.628422)
		(end 35.93592 -113.077244)
		(width 0.11684)
		(layer "B.Cu")
		(net "SMB_BMC_MM12_SDA")
	)
	(segment
		(start 34.99612 -109.31398)
		(end 34.24047 -108.55833)
		(width 0.11684)
		(layer "B.Cu")
		(net "SMB_BMC_MM12_SDA")
	)
	(segment
		(start 36.9824 -116.9924)
		(end 36.9824 -115.674902)
		(width 0.11684)
		(layer "B.Cu")
		(net "SMB_BMC_MM12_SDA")
	)
	(segment
		(start 34.99612 -112.137444)
		(end 34.99612 -109.31398)
		(width 0.11684)
		(layer "B.Cu")
		(net "SMB_BMC_MM12_SDA")
	)
	(segment
		(start 34.24047 -108.55833)
		(end 33.927288 -108.245148)
		(width 0.11684)
		(layer "B.Cu")
		(net "SMB_BMC_MM12_SDA")
	)
	(segment
		(start 37.254942 -117.264942)
		(end 36.9824 -116.9924)
		(width 0.11684)
		(layer "B.Cu")
		(net "SMB_BMC_MM12_SDA")
	)
	(segment
		(start 37.254942 -118.25986)
		(end 37.254942 -117.264942)
		(width 0.11684)
		(layer "B.Cu")
		(net "SMB_BMC_MM12_SDA")
	)
	(segment
		(start 40.954198 -46.16069)
		(end 41.566084 -46.16069)
		(width 0.11684)
		(layer "B.Cu")
		(net "SMB_BMC_MM12_SDA")
	)
	(segment
		(start 33.927288 -108.245148)
		(end 33.927288 -107.67949)
		(width 0.11684)
		(layer "B.Cu")
		(net "SMB_BMC_MM12_SDA")
	)
	(segment
		(start 40.33012 -46.119542)
		(end 40.91305 -46.119542)
		(width 0.11684)
		(layer "B.Cu")
		(net "SMB_BMC_MM12_SDA")
	)
	(segment
		(start 40.91305 -46.119542)
		(end 40.954198 -46.16069)
		(width 0.11684)
		(layer "B.Cu")
		(net "SMB_BMC_MM12_SDA")
	)
	(segment
		(start 37.5666 -63.1444)
		(end 37.44976 -63.26124)
		(width 0.10668)
		(layer "In4.Cu")
		(net "SMB_BMC_MM12_SDA")
	)
	(segment
		(start 38.684454 -47.128176)
		(end 38.415214 -47.397416)
		(width 0.10668)
		(layer "In4.Cu")
		(net "SMB_BMC_MM12_SDA")
	)
	(segment
		(start 37.5666 -62.6872)
		(end 37.5666 -63.1444)
		(width 0.10668)
		(layer "In4.Cu")
		(net "SMB_BMC_MM12_SDA")
	)
	(segment
		(start 39.6748 -49.038002)
		(end 39.6748 -50.9016)
		(width 0.10668)
		(layer "In4.Cu")
		(net "SMB_BMC_MM12_SDA")
	)
	(segment
		(start 32.5501 -89.937082)
		(end 32.77108 -90.158062)
		(width 0.10668)
		(layer "In4.Cu")
		(net "SMB_BMC_MM12_SDA")
	)
	(segment
		(start 37.44976 -63.26124)
		(end 37.44976 -65.7098)
		(width 0.10668)
		(layer "In4.Cu")
		(net "SMB_BMC_MM12_SDA")
	)
	(segment
		(start 39.6748 -50.9016)
		(end 39.2176 -51.3588)
		(width 0.10668)
		(layer "In4.Cu")
		(net "SMB_BMC_MM12_SDA")
	)
	(segment
		(start 33.66262 -76.29271)
		(end 35.794696 -78.424786)
		(width 0.10668)
		(layer "In4.Cu")
		(net "SMB_BMC_MM12_SDA")
	)
	(segment
		(start 36.4998 -78.69428)
		(end 36.4998 -79.0956)
		(width 0.10668)
		(layer "In4.Cu")
		(net "SMB_BMC_MM12_SDA")
	)
	(segment
		(start 38.48608 -58.916062)
		(end 37.871654 -59.530488)
		(width 0.10668)
		(layer "In4.Cu")
		(net "SMB_BMC_MM12_SDA")
	)
	(segment
		(start 36.23056 -78.42504)
		(end 36.4998 -78.69428)
		(width 0.10668)
		(layer "In4.Cu")
		(net "SMB_BMC_MM12_SDA")
	)
	(segment
		(start 34.26587 -106.293666)
		(end 34.26587 -107.106466)
		(width 0.10668)
		(layer "In4.Cu")
		(net "SMB_BMC_MM12_SDA")
	)
	(segment
		(start 34.5948 -105.964736)
		(end 34.26587 -106.293666)
		(width 0.10668)
		(layer "In4.Cu")
		(net "SMB_BMC_MM12_SDA")
	)
	(segment
		(start 37.06114 -68.789296)
		(end 37.243004 -69.228716)
		(width 0.10668)
		(layer "In4.Cu")
		(net "SMB_BMC_MM12_SDA")
	)
	(segment
		(start 34.42589 -73.467722)
		(end 33.66262 -74.230992)
		(width 0.10668)
		(layer "In4.Cu")
		(net "SMB_BMC_MM12_SDA")
	)
	(segment
		(start 35.794696 -78.424786)
		(end 36.00704 -78.424786)
		(width 0.10668)
		(layer "In4.Cu")
		(net "SMB_BMC_MM12_SDA")
	)
	(segment
		(start 36.007294 -78.42504)
		(end 36.23056 -78.42504)
		(width 0.10668)
		(layer "In4.Cu")
		(net "SMB_BMC_MM12_SDA")
	)
	(segment
		(start 39.2176 -52.197)
		(end 38.1 -53.3146)
		(width 0.10668)
		(layer "In4.Cu")
		(net "SMB_BMC_MM12_SDA")
	)
	(segment
		(start 33.7058 -83.1342)
		(end 32.5501 -84.2899)
		(width 0.10668)
		(layer "In4.Cu")
		(net "SMB_BMC_MM12_SDA")
	)
	(segment
		(start 38.1 -53.3146)
		(end 38.1 -54.278022)
		(width 0.10668)
		(layer "In4.Cu")
		(net "SMB_BMC_MM12_SDA")
	)
	(segment
		(start 32.77108 -94.190312)
		(end 31.9278 -95.033592)
		(width 0.10668)
		(layer "In4.Cu")
		(net "SMB_BMC_MM12_SDA")
	)
	(segment
		(start 36.4998 -79.0956)
		(end 35.179 -80.4164)
		(width 0.10668)
		(layer "In4.Cu")
		(net "SMB_BMC_MM12_SDA")
	)
	(segment
		(start 32.77108 -98.38436)
		(end 31.4833 -99.67214)
		(width 0.10668)
		(layer "In4.Cu")
		(net "SMB_BMC_MM12_SDA")
	)
	(segment
		(start 40.954198 -46.16069)
		(end 40.81907 -46.16069)
		(width 0.10668)
		(layer "In4.Cu")
		(net "SMB_BMC_MM12_SDA")
	)
	(segment
		(start 37.23132 -61.076078)
		(end 37.23132 -62.35192)
		(width 0.10668)
		(layer "In4.Cu")
		(net "SMB_BMC_MM12_SDA")
	)
	(segment
		(start 37.23132 -62.35192)
		(end 37.5666 -62.6872)
		(width 0.10668)
		(layer "In4.Cu")
		(net "SMB_BMC_MM12_SDA")
	)
	(segment
		(start 32.77108 -90.158062)
		(end 32.77108 -94.190312)
		(width 0.10668)
		(layer "In4.Cu")
		(net "SMB_BMC_MM12_SDA")
	)
	(segment
		(start 36.961064 -71.974456)
		(end 35.46729 -73.467722)
		(width 0.10668)
		(layer "In4.Cu")
		(net "SMB_BMC_MM12_SDA")
	)
	(segment
		(start 31.4833 -99.67214)
		(end 31.025592 -99.67214)
		(width 0.10668)
		(layer "In4.Cu")
		(net "SMB_BMC_MM12_SDA")
	)
	(segment
		(start 36.00704 -78.424786)
		(end 36.007294 -78.42504)
		(width 0.10668)
		(layer "In4.Cu")
		(net "SMB_BMC_MM12_SDA")
	)
	(segment
		(start 38.4048 -56.321706)
		(end 38.48608 -56.402986)
		(width 0.10668)
		(layer "In4.Cu")
		(net "SMB_BMC_MM12_SDA")
	)
	(segment
		(start 31.025592 -99.67214)
		(end 30.764988 -99.932744)
		(width 0.10668)
		(layer "In4.Cu")
		(net "SMB_BMC_MM12_SDA")
	)
	(segment
		(start 30.6578 -100.19157)
		(end 30.6578 -100.5586)
		(width 0.10668)
		(layer "In4.Cu")
		(net "SMB_BMC_MM12_SDA")
	)
	(segment
		(start 30.764988 -99.932744)
		(end 30.6578 -100.19157)
		(width 0.10668)
		(layer "In4.Cu")
		(net "SMB_BMC_MM12_SDA")
	)
	(segment
		(start 39.2176 -51.3588)
		(end 39.2176 -52.197)
		(width 0.10668)
		(layer "In4.Cu")
		(net "SMB_BMC_MM12_SDA")
	)
	(segment
		(start 37.243004 -69.228716)
		(end 37.243004 -71.373746)
		(width 0.10668)
		(layer "In4.Cu")
		(net "SMB_BMC_MM12_SDA")
	)
	(segment
		(start 33.85312 -103.17988)
		(end 34.5948 -103.92156)
		(width 0.10668)
		(layer "In4.Cu")
		(net "SMB_BMC_MM12_SDA")
	)
	(segment
		(start 33.27908 -103.17988)
		(end 33.85312 -103.17988)
		(width 0.10668)
		(layer "In4.Cu")
		(net "SMB_BMC_MM12_SDA")
	)
	(segment
		(start 30.6578 -100.5586)
		(end 33.27908 -103.17988)
		(width 0.10668)
		(layer "In4.Cu")
		(net "SMB_BMC_MM12_SDA")
	)
	(segment
		(start 34.26587 -107.106466)
		(end 33.927288 -107.445048)
		(width 0.10668)
		(layer "In4.Cu")
		(net "SMB_BMC_MM12_SDA")
	)
	(segment
		(start 37.871654 -59.530488)
		(end 37.23132 -61.076078)
		(width 0.10668)
		(layer "In4.Cu")
		(net "SMB_BMC_MM12_SDA")
	)
	(segment
		(start 32.77108 -97.23628)
		(end 32.77108 -98.38436)
		(width 0.10668)
		(layer "In4.Cu")
		(net "SMB_BMC_MM12_SDA")
	)
	(segment
		(start 32.5501 -84.2899)
		(end 32.5501 -89.937082)
		(width 0.10668)
		(layer "In4.Cu")
		(net "SMB_BMC_MM12_SDA")
	)
	(segment
		(start 34.5948 -103.92156)
		(end 34.5948 -105.964736)
		(width 0.10668)
		(layer "In4.Cu")
		(net "SMB_BMC_MM12_SDA")
	)
	(segment
		(start 33.7058 -81.252822)
		(end 33.7058 -83.1342)
		(width 0.10668)
		(layer "In4.Cu")
		(net "SMB_BMC_MM12_SDA")
	)
	(segment
		(start 37.243004 -71.373746)
		(end 36.961064 -71.974456)
		(width 0.10668)
		(layer "In4.Cu")
		(net "SMB_BMC_MM12_SDA")
	)
	(segment
		(start 38.415214 -47.778416)
		(end 39.6748 -49.038002)
		(width 0.10668)
		(layer "In4.Cu")
		(net "SMB_BMC_MM12_SDA")
	)
	(segment
		(start 38.4048 -55.014114)
		(end 38.4048 -56.321706)
		(width 0.10668)
		(layer "In4.Cu")
		(net "SMB_BMC_MM12_SDA")
	)
	(segment
		(start 38.415214 -47.397416)
		(end 38.415214 -47.778416)
		(width 0.10668)
		(layer "In4.Cu")
		(net "SMB_BMC_MM12_SDA")
	)
	(segment
		(start 38.48608 -56.402986)
		(end 38.48608 -58.916062)
		(width 0.10668)
		(layer "In4.Cu")
		(net "SMB_BMC_MM12_SDA")
	)
	(segment
		(start 39.851584 -47.128176)
		(end 38.684454 -47.128176)
		(width 0.10668)
		(layer "In4.Cu")
		(net "SMB_BMC_MM12_SDA")
	)
	(segment
		(start 33.66262 -74.230992)
		(end 33.66262 -76.29271)
		(width 0.10668)
		(layer "In4.Cu")
		(net "SMB_BMC_MM12_SDA")
	)
	(segment
		(start 31.9278 -95.033592)
		(end 31.9278 -96.393)
		(width 0.10668)
		(layer "In4.Cu")
		(net "SMB_BMC_MM12_SDA")
	)
	(segment
		(start 34.542222 -80.4164)
		(end 33.7058 -81.252822)
		(width 0.10668)
		(layer "In4.Cu")
		(net "SMB_BMC_MM12_SDA")
	)
	(segment
		(start 35.46729 -73.467722)
		(end 34.42589 -73.467722)
		(width 0.10668)
		(layer "In4.Cu")
		(net "SMB_BMC_MM12_SDA")
	)
	(segment
		(start 33.927288 -107.445048)
		(end 33.927288 -107.67949)
		(width 0.10668)
		(layer "In4.Cu")
		(net "SMB_BMC_MM12_SDA")
	)
	(segment
		(start 35.179 -80.4164)
		(end 34.542222 -80.4164)
		(width 0.10668)
		(layer "In4.Cu")
		(net "SMB_BMC_MM12_SDA")
	)
	(segment
		(start 37.06114 -66.09842)
		(end 37.06114 -68.789296)
		(width 0.10668)
		(layer "In4.Cu")
		(net "SMB_BMC_MM12_SDA")
	)
	(segment
		(start 38.1 -54.278022)
		(end 38.4048 -55.014114)
		(width 0.10668)
		(layer "In4.Cu")
		(net "SMB_BMC_MM12_SDA")
	)
	(segment
		(start 40.81907 -46.16069)
		(end 39.851584 -47.128176)
		(width 0.10668)
		(layer "In4.Cu")
		(net "SMB_BMC_MM12_SDA")
	)
	(segment
		(start 31.9278 -96.393)
		(end 32.77108 -97.23628)
		(width 0.10668)
		(layer "In4.Cu")
		(net "SMB_BMC_MM12_SDA")
	)
	(segment
		(start 37.44976 -65.7098)
		(end 37.06114 -66.09842)
		(width 0.10668)
		(layer "In4.Cu")
		(net "SMB_BMC_MM12_SDA")
	)
	(segment
		(start 38.874954 -47.587916)
		(end 39.54145 -47.587916)
		(width 0.11684)
		(layer "F.Cu")
		(net "SMB_BMC_MM12_SCL")
	)
	(segment
		(start 38.265354 -47.587916)
		(end 38.874954 -47.587916)
		(width 0.11684)
		(layer "F.Cu")
		(net "SMB_BMC_MM12_SCL")
	)
	(via
		(at 35.76828 -109.98962)
		(size 0.6604)
		(drill 0.3302)
		(layers "F.Cu" "B.Cu")
		(net "SMB_BMC_MM12_SCL")
	)
	(via
		(at 38.874954 -47.587916)
		(size 0.508)
		(drill 0.254)
		(layers "F.Cu" "B.Cu")
		(net "SMB_BMC_MM12_SCL")
	)
	(via
		(at 35.302698 -107.67949)
		(size 0.508)
		(drill 0.254)
		(layers "F.Cu" "B.Cu")
		(net "SMB_BMC_MM12_SCL")
	)
	(segment
		(start 37.85489 -117.29339)
		(end 37.85489 -118.460012)
		(width 0.11684)
		(layer "B.Cu")
		(net "SMB_BMC_MM12_SCL")
	)
	(segment
		(start 36.33216 -112.912906)
		(end 36.33216 -114.464084)
		(width 0.11684)
		(layer "B.Cu")
		(net "SMB_BMC_MM12_SCL")
	)
	(segment
		(start 35.302698 -108.845858)
		(end 35.76828 -109.31144)
		(width 0.11684)
		(layer "B.Cu")
		(net "SMB_BMC_MM12_SCL")
	)
	(segment
		(start 35.302698 -107.67949)
		(end 35.302698 -108.845858)
		(width 0.11684)
		(layer "B.Cu")
		(net "SMB_BMC_MM12_SCL")
	)
	(segment
		(start 35.76828 -112.349026)
		(end 36.33216 -112.912906)
		(width 0.11684)
		(layer "B.Cu")
		(net "SMB_BMC_MM12_SCL")
	)
	(segment
		(start 37.38118 -115.513104)
		(end 37.38118 -116.81968)
		(width 0.11684)
		(layer "B.Cu")
		(net "SMB_BMC_MM12_SCL")
	)
	(segment
		(start 37.38118 -116.81968)
		(end 37.85489 -117.29339)
		(width 0.11684)
		(layer "B.Cu")
		(net "SMB_BMC_MM12_SCL")
	)
	(segment
		(start 36.33216 -114.464084)
		(end 37.38118 -115.513104)
		(width 0.11684)
		(layer "B.Cu")
		(net "SMB_BMC_MM12_SCL")
	)
	(segment
		(start 35.76828 -109.31144)
		(end 35.76828 -109.98962)
		(width 0.11684)
		(layer "B.Cu")
		(net "SMB_BMC_MM12_SCL")
	)
	(segment
		(start 35.76828 -109.98962)
		(end 35.76828 -112.349026)
		(width 0.11684)
		(layer "B.Cu")
		(net "SMB_BMC_MM12_SCL")
	)
	(segment
		(start 35.302698 -107.67949)
		(end 35.302698 -106.402378)
		(width 0.10668)
		(layer "In4.Cu")
		(net "SMB_BMC_MM12_SCL")
	)
	(segment
		(start 33.909 -100.507292)
		(end 33.909 -100.09886)
		(width 0.10668)
		(layer "In4.Cu")
		(net "SMB_BMC_MM12_SCL")
	)
	(segment
		(start 37.78504 -66.4083)
		(end 37.78504 -63.43396)
		(width 0.10668)
		(layer "In4.Cu")
		(net "SMB_BMC_MM12_SCL")
	)
	(segment
		(start 35.179 -81.08696)
		(end 35.179254 -81.087214)
		(width 0.10668)
		(layer "In4.Cu")
		(net "SMB_BMC_MM12_SCL")
	)
	(segment
		(start 37.5666 -61.14288)
		(end 38.15588 -59.72048)
		(width 0.10668)
		(layer "In4.Cu")
		(net "SMB_BMC_MM12_SCL")
	)
	(segment
		(start 37.6555 -73.96861)
		(end 37.92474 -73.69937)
		(width 0.10668)
		(layer "In4.Cu")
		(net "SMB_BMC_MM12_SCL")
	)
	(segment
		(start 38.1762 -62.7126)
		(end 37.5666 -62.103)
		(width 0.10668)
		(layer "In4.Cu")
		(net "SMB_BMC_MM12_SCL")
	)
	(segment
		(start 33.22066 -89.532206)
		(end 33.22066 -84.58454)
		(width 0.10668)
		(layer "In4.Cu")
		(net "SMB_BMC_MM12_SCL")
	)
	(segment
		(start 35.915092 -73.96861)
		(end 37.6555 -73.96861)
		(width 0.10668)
		(layer "In4.Cu")
		(net "SMB_BMC_MM12_SCL")
	)
	(segment
		(start 33.782 -100.634292)
		(end 33.909 -100.507292)
		(width 0.10668)
		(layer "In4.Cu")
		(net "SMB_BMC_MM12_SCL")
	)
	(segment
		(start 33.22066 -84.58454)
		(end 34.544 -83.2612)
		(width 0.10668)
		(layer "In4.Cu")
		(net "SMB_BMC_MM12_SCL")
	)
	(segment
		(start 33.44164 -99.6315)
		(end 33.44164 -96.153986)
		(width 0.10668)
		(layer "In4.Cu")
		(net "SMB_BMC_MM12_SCL")
	)
	(segment
		(start 35.456622 -81.087214)
		(end 37.17036 -79.373476)
		(width 0.10668)
		(layer "In4.Cu")
		(net "SMB_BMC_MM12_SCL")
	)
	(segment
		(start 36.508182 -77.754226)
		(end 36.072572 -77.754226)
		(width 0.10668)
		(layer "In4.Cu")
		(net "SMB_BMC_MM12_SCL")
	)
	(segment
		(start 39.52494 -54.3941)
		(end 39.5224 -54.39156)
		(width 0.10668)
		(layer "In4.Cu")
		(net "SMB_BMC_MM12_SCL")
	)
	(segment
		(start 34.9504 -102.3112)
		(end 34.8234 -102.1842)
		(width 0.10668)
		(layer "In4.Cu")
		(net "SMB_BMC_MM12_SCL")
	)
	(segment
		(start 37.578284 -71.450962)
		(end 37.578284 -68.979034)
		(width 0.10668)
		(layer "In4.Cu")
		(net "SMB_BMC_MM12_SCL")
	)
	(segment
		(start 39.5224 -55.40756)
		(end 39.5224 -54.77764)
		(width 0.10668)
		(layer "In4.Cu")
		(net "SMB_BMC_MM12_SCL")
	)
	(segment
		(start 34.26714 -92.02166)
		(end 34.26714 -90.578686)
		(width 0.10668)
		(layer "In4.Cu")
		(net "SMB_BMC_MM12_SCL")
	)
	(segment
		(start 38.82136 -56.1086)
		(end 39.5224 -55.40756)
		(width 0.10668)
		(layer "In4.Cu")
		(net "SMB_BMC_MM12_SCL")
	)
	(segment
		(start 38.1762 -63.0428)
		(end 38.1762 -62.7126)
		(width 0.10668)
		(layer "In4.Cu")
		(net "SMB_BMC_MM12_SCL")
	)
	(segment
		(start 34.820098 -81.08696)
		(end 35.179 -81.08696)
		(width 0.10668)
		(layer "In4.Cu")
		(net "SMB_BMC_MM12_SCL")
	)
	(segment
		(start 34.703766 -74.138282)
		(end 35.74542 -74.138282)
		(width 0.10668)
		(layer "In4.Cu")
		(net "SMB_BMC_MM12_SCL")
	)
	(segment
		(start 34.544 -83.2612)
		(end 34.544 -81.363058)
		(width 0.10668)
		(layer "In4.Cu")
		(net "SMB_BMC_MM12_SCL")
	)
	(segment
		(start 33.782 -101.7016)
		(end 33.782 -100.634292)
		(width 0.10668)
		(layer "In4.Cu")
		(net "SMB_BMC_MM12_SCL")
	)
	(segment
		(start 39.5224 -52.6542)
		(end 40.4876 -51.689)
		(width 0.10668)
		(layer "In4.Cu")
		(net "SMB_BMC_MM12_SCL")
	)
	(segment
		(start 40.4876 -51.689)
		(end 40.4876 -49.200562)
		(width 0.10668)
		(layer "In4.Cu")
		(net "SMB_BMC_MM12_SCL")
	)
	(segment
		(start 35.302698 -106.402378)
		(end 34.9504 -106.05008)
		(width 0.10668)
		(layer "In4.Cu")
		(net "SMB_BMC_MM12_SCL")
	)
	(segment
		(start 34.544 -81.363058)
		(end 34.820098 -81.08696)
		(width 0.10668)
		(layer "In4.Cu")
		(net "SMB_BMC_MM12_SCL")
	)
	(segment
		(start 34.9504 -106.05008)
		(end 34.9504 -102.3112)
		(width 0.10668)
		(layer "In4.Cu")
		(net "SMB_BMC_MM12_SCL")
	)
	(segment
		(start 39.5224 -54.77764)
		(end 39.52494 -54.7751)
		(width 0.10668)
		(layer "In4.Cu")
		(net "SMB_BMC_MM12_SCL")
	)
	(segment
		(start 34.33318 -74.508868)
		(end 34.703766 -74.138282)
		(width 0.10668)
		(layer "In4.Cu")
		(net "SMB_BMC_MM12_SCL")
	)
	(segment
		(start 39.5224 -54.39156)
		(end 39.5224 -52.6542)
		(width 0.10668)
		(layer "In4.Cu")
		(net "SMB_BMC_MM12_SCL")
	)
	(segment
		(start 35.74542 -74.138282)
		(end 35.915092 -73.96861)
		(width 0.10668)
		(layer "In4.Cu")
		(net "SMB_BMC_MM12_SCL")
	)
	(segment
		(start 40.4876 -49.200562)
		(end 38.874954 -47.587916)
		(width 0.10668)
		(layer "In4.Cu")
		(net "SMB_BMC_MM12_SCL")
	)
	(segment
		(start 34.26714 -90.578686)
		(end 33.22066 -89.532206)
		(width 0.10668)
		(layer "In4.Cu")
		(net "SMB_BMC_MM12_SCL")
	)
	(segment
		(start 38.15588 -59.72048)
		(end 38.82136 -59.055)
		(width 0.10668)
		(layer "In4.Cu")
		(net "SMB_BMC_MM12_SCL")
	)
	(segment
		(start 37.17036 -79.373476)
		(end 37.17036 -78.416404)
		(width 0.10668)
		(layer "In4.Cu")
		(net "SMB_BMC_MM12_SCL")
	)
	(segment
		(start 36.072572 -77.754226)
		(end 34.33318 -76.014834)
		(width 0.10668)
		(layer "In4.Cu")
		(net "SMB_BMC_MM12_SCL")
	)
	(segment
		(start 38.82136 -59.055)
		(end 38.82136 -56.1086)
		(width 0.10668)
		(layer "In4.Cu")
		(net "SMB_BMC_MM12_SCL")
	)
	(segment
		(start 34.33318 -76.014834)
		(end 34.33318 -74.508868)
		(width 0.10668)
		(layer "In4.Cu")
		(net "SMB_BMC_MM12_SCL")
	)
	(segment
		(start 34.8234 -102.1842)
		(end 34.2646 -102.1842)
		(width 0.10668)
		(layer "In4.Cu")
		(net "SMB_BMC_MM12_SCL")
	)
	(segment
		(start 37.42182 -66.77152)
		(end 37.78504 -66.4083)
		(width 0.10668)
		(layer "In4.Cu")
		(net "SMB_BMC_MM12_SCL")
	)
	(segment
		(start 37.54628 -71.519034)
		(end 37.578284 -71.450962)
		(width 0.10668)
		(layer "In4.Cu")
		(net "SMB_BMC_MM12_SCL")
	)
	(segment
		(start 34.2646 -102.1842)
		(end 33.782 -101.7016)
		(width 0.10668)
		(layer "In4.Cu")
		(net "SMB_BMC_MM12_SCL")
	)
	(segment
		(start 37.92474 -73.31837)
		(end 37.54628 -72.93991)
		(width 0.10668)
		(layer "In4.Cu")
		(net "SMB_BMC_MM12_SCL")
	)
	(segment
		(start 37.78504 -63.43396)
		(end 38.1762 -63.0428)
		(width 0.10668)
		(layer "In4.Cu")
		(net "SMB_BMC_MM12_SCL")
	)
	(segment
		(start 37.54628 -72.93991)
		(end 37.54628 -71.519034)
		(width 0.10668)
		(layer "In4.Cu")
		(net "SMB_BMC_MM12_SCL")
	)
	(segment
		(start 37.5666 -62.103)
		(end 37.5666 -61.14288)
		(width 0.10668)
		(layer "In4.Cu")
		(net "SMB_BMC_MM12_SCL")
	)
	(segment
		(start 37.17036 -78.416404)
		(end 36.508182 -77.754226)
		(width 0.10668)
		(layer "In4.Cu")
		(net "SMB_BMC_MM12_SCL")
	)
	(segment
		(start 37.42182 -68.601082)
		(end 37.42182 -66.77152)
		(width 0.10668)
		(layer "In4.Cu")
		(net "SMB_BMC_MM12_SCL")
	)
	(segment
		(start 35.179254 -81.087214)
		(end 35.456622 -81.087214)
		(width 0.10668)
		(layer "In4.Cu")
		(net "SMB_BMC_MM12_SCL")
	)
	(segment
		(start 33.44164 -96.153986)
		(end 33.65754 -95.938086)
		(width 0.10668)
		(layer "In4.Cu")
		(net "SMB_BMC_MM12_SCL")
	)
	(segment
		(start 37.92474 -73.69937)
		(end 37.92474 -73.31837)
		(width 0.10668)
		(layer "In4.Cu")
		(net "SMB_BMC_MM12_SCL")
	)
	(segment
		(start 33.65754 -92.63126)
		(end 34.26714 -92.02166)
		(width 0.10668)
		(layer "In4.Cu")
		(net "SMB_BMC_MM12_SCL")
	)
	(segment
		(start 33.909 -100.09886)
		(end 33.44164 -99.6315)
		(width 0.10668)
		(layer "In4.Cu")
		(net "SMB_BMC_MM12_SCL")
	)
	(segment
		(start 33.65754 -95.938086)
		(end 33.65754 -92.63126)
		(width 0.10668)
		(layer "In4.Cu")
		(net "SMB_BMC_MM12_SCL")
	)
	(segment
		(start 39.52494 -54.7751)
		(end 39.52494 -54.3941)
		(width 0.10668)
		(layer "In4.Cu")
		(net "SMB_BMC_MM12_SCL")
	)
	(segment
		(start 37.578284 -68.979034)
		(end 37.42182 -68.601082)
		(width 0.10668)
		(layer "In4.Cu")
		(net "SMB_BMC_MM12_SCL")
	)
	(segment
		(start 43.014646 -44.445428)
		(end 41.764204 -44.445428)
		(width 0.11684)
		(layer "F.Cu")
		(net "FM_ME_BT_DONE")
	)
	(segment
		(start 44.340526 -45.771308)
		(end 44.895008 -45.771308)
		(width 0.11684)
		(layer "F.Cu")
		(net "FM_ME_BT_DONE")
	)
	(segment
		(start 23.054564 -89.591896)
		(end 22.65934 -89.98712)
		(width 0.11684)
		(layer "F.Cu")
		(net "FM_ME_BT_DONE")
	)
	(segment
		(start 44.340526 -45.771308)
		(end 43.014646 -44.445428)
		(width 0.11684)
		(layer "F.Cu")
		(net "FM_ME_BT_DONE")
	)
	(segment
		(start 41.764204 -44.445428)
		(end 40.752776 -43.434)
		(width 0.11684)
		(layer "F.Cu")
		(net "FM_ME_BT_DONE")
	)
	(segment
		(start 40.752776 -43.434)
		(end 40.32885 -43.434)
		(width 0.11684)
		(layer "F.Cu")
		(net "FM_ME_BT_DONE")
	)
	(via
		(at 23.054564 -89.591896)
		(size 0.4572)
		(drill 0.254)
		(layers "F.Cu" "B.Cu")
		(net "FM_ME_BT_DONE")
	)
	(via
		(at 44.340526 -45.771308)
		(size 0.4572)
		(drill 0.254)
		(layers "F.Cu" "B.Cu")
		(net "FM_ME_BT_DONE")
	)
	(via
		(at 41.764204 -44.445428)
		(size 0.762)
		(drill 0.381)
		(layers "F.Cu" "B.Cu")
		(net "FM_ME_BT_DONE")
	)
	(via
		(at 20.92198 -50.04054)
		(size 0.508)
		(drill 0.254)
		(layers "F.Cu" "B.Cu")
		(net "FM_ME_BT_DONE")
	)
	(segment
		(start 40.54221 -45.61459)
		(end 41.140888 -45.61459)
		(width 0.08382)
		(layer "In2.Cu")
		(net "FM_ME_BT_DONE")
	)
	(segment
		(start 31.877508 -47.243746)
		(end 36.677854 -47.243746)
		(width 0.08382)
		(layer "In2.Cu")
		(net "FM_ME_BT_DONE")
	)
	(segment
		(start 41.140888 -45.61459)
		(end 41.441878 -45.3136)
		(width 0.08382)
		(layer "In2.Cu")
		(net "FM_ME_BT_DONE")
	)
	(segment
		(start 22.526752 -44.837604)
		(end 25.304496 -42.05986)
		(width 0.08382)
		(layer "In2.Cu")
		(net "FM_ME_BT_DONE")
	)
	(segment
		(start 39.6494 -46.5074)
		(end 40.54221 -45.61459)
		(width 0.08382)
		(layer "In2.Cu")
		(net "FM_ME_BT_DONE")
	)
	(segment
		(start 28.715716 -42.05986)
		(end 31.34614 -44.690284)
		(width 0.08382)
		(layer "In2.Cu")
		(net "FM_ME_BT_DONE")
	)
	(segment
		(start 21.10486 -50.04054)
		(end 22.526752 -48.618648)
		(width 0.08382)
		(layer "In2.Cu")
		(net "FM_ME_BT_DONE")
	)
	(segment
		(start 20.92198 -50.04054)
		(end 21.10486 -50.04054)
		(width 0.08382)
		(layer "In2.Cu")
		(net "FM_ME_BT_DONE")
	)
	(segment
		(start 36.677854 -47.243746)
		(end 37.4142 -46.5074)
		(width 0.08382)
		(layer "In2.Cu")
		(net "FM_ME_BT_DONE")
	)
	(segment
		(start 43.234102 -45.3136)
		(end 44.340526 -45.771308)
		(width 0.08382)
		(layer "In2.Cu")
		(net "FM_ME_BT_DONE")
	)
	(segment
		(start 22.526752 -48.618648)
		(end 22.526752 -44.837604)
		(width 0.08382)
		(layer "In2.Cu")
		(net "FM_ME_BT_DONE")
	)
	(segment
		(start 31.34614 -44.690284)
		(end 31.34614 -46.712378)
		(width 0.08382)
		(layer "In2.Cu")
		(net "FM_ME_BT_DONE")
	)
	(segment
		(start 25.304496 -42.05986)
		(end 28.715716 -42.05986)
		(width 0.08382)
		(layer "In2.Cu")
		(net "FM_ME_BT_DONE")
	)
	(segment
		(start 41.441878 -45.3136)
		(end 43.234102 -45.3136)
		(width 0.08382)
		(layer "In2.Cu")
		(net "FM_ME_BT_DONE")
	)
	(segment
		(start 31.34614 -46.712378)
		(end 31.877508 -47.243746)
		(width 0.08382)
		(layer "In2.Cu")
		(net "FM_ME_BT_DONE")
	)
	(segment
		(start 37.4142 -46.5074)
		(end 39.6494 -46.5074)
		(width 0.08382)
		(layer "In2.Cu")
		(net "FM_ME_BT_DONE")
	)
	(segment
		(start 23.6855 -60.114942)
		(end 21.02866 -57.458102)
		(width 0.10668)
		(layer "In4.Cu")
		(net "FM_ME_BT_DONE")
	)
	(segment
		(start 24.0792 -89.9922)
		(end 24.238204 -89.833196)
		(width 0.10668)
		(layer "In4.Cu")
		(net "FM_ME_BT_DONE")
	)
	(segment
		(start 23.054564 -89.591896)
		(end 23.454868 -89.9922)
		(width 0.10668)
		(layer "In4.Cu")
		(net "FM_ME_BT_DONE")
	)
	(segment
		(start 22.7584 -67.158362)
		(end 24.66594 -65.250822)
		(width 0.10668)
		(layer "In4.Cu")
		(net "FM_ME_BT_DONE")
	)
	(segment
		(start 25.85974 -83.910678)
		(end 25.98674 -83.783678)
		(width 0.10668)
		(layer "In4.Cu")
		(net "FM_ME_BT_DONE")
	)
	(segment
		(start 23.6855 -61.50356)
		(end 23.6855 -60.114942)
		(width 0.10668)
		(layer "In4.Cu")
		(net "FM_ME_BT_DONE")
	)
	(segment
		(start 25.98674 -83.783678)
		(end 25.98674 -83.11134)
		(width 0.10668)
		(layer "In4.Cu")
		(net "FM_ME_BT_DONE")
	)
	(segment
		(start 24.64054 -75.9714)
		(end 24.64054 -73.103994)
		(width 0.10668)
		(layer "In4.Cu")
		(net "FM_ME_BT_DONE")
	)
	(segment
		(start 23.61692 -84.621878)
		(end 24.32812 -83.910678)
		(width 0.10668)
		(layer "In4.Cu")
		(net "FM_ME_BT_DONE")
	)
	(segment
		(start 25.86736 -80.62976)
		(end 25.86736 -78.7781)
		(width 0.10668)
		(layer "In4.Cu")
		(net "FM_ME_BT_DONE")
	)
	(segment
		(start 24.238204 -89.833196)
		(end 24.238204 -88.093804)
		(width 0.10668)
		(layer "In4.Cu")
		(net "FM_ME_BT_DONE")
	)
	(segment
		(start 23.90394 -71.4629)
		(end 22.7584 -70.31736)
		(width 0.10668)
		(layer "In4.Cu")
		(net "FM_ME_BT_DONE")
	)
	(segment
		(start 24.238204 -88.093804)
		(end 23.61692 -87.47252)
		(width 0.10668)
		(layer "In4.Cu")
		(net "FM_ME_BT_DONE")
	)
	(segment
		(start 25.86482 -77.19568)
		(end 24.64054 -75.9714)
		(width 0.10668)
		(layer "In4.Cu")
		(net "FM_ME_BT_DONE")
	)
	(segment
		(start 24.32812 -83.910678)
		(end 25.85974 -83.910678)
		(width 0.10668)
		(layer "In4.Cu")
		(net "FM_ME_BT_DONE")
	)
	(segment
		(start 25.86482 -78.77556)
		(end 25.86482 -77.19568)
		(width 0.10668)
		(layer "In4.Cu")
		(net "FM_ME_BT_DONE")
	)
	(segment
		(start 24.66594 -65.250822)
		(end 24.66594 -62.484)
		(width 0.10668)
		(layer "In4.Cu")
		(net "FM_ME_BT_DONE")
	)
	(segment
		(start 21.02866 -57.458102)
		(end 21.02866 -50.14722)
		(width 0.10668)
		(layer "In4.Cu")
		(net "FM_ME_BT_DONE")
	)
	(segment
		(start 21.02866 -50.14722)
		(end 20.92198 -50.04054)
		(width 0.10668)
		(layer "In4.Cu")
		(net "FM_ME_BT_DONE")
	)
	(segment
		(start 22.7584 -70.31736)
		(end 22.7584 -67.158362)
		(width 0.10668)
		(layer "In4.Cu")
		(net "FM_ME_BT_DONE")
	)
	(segment
		(start 25.63622 -80.8609)
		(end 25.86736 -80.62976)
		(width 0.10668)
		(layer "In4.Cu")
		(net "FM_ME_BT_DONE")
	)
	(segment
		(start 23.61692 -87.47252)
		(end 23.61692 -84.621878)
		(width 0.10668)
		(layer "In4.Cu")
		(net "FM_ME_BT_DONE")
	)
	(segment
		(start 23.90394 -72.367394)
		(end 23.90394 -71.4629)
		(width 0.10668)
		(layer "In4.Cu")
		(net "FM_ME_BT_DONE")
	)
	(segment
		(start 25.63622 -82.76082)
		(end 25.63622 -80.8609)
		(width 0.10668)
		(layer "In4.Cu")
		(net "FM_ME_BT_DONE")
	)
	(segment
		(start 25.86736 -78.7781)
		(end 25.86482 -78.77556)
		(width 0.10668)
		(layer "In4.Cu")
		(net "FM_ME_BT_DONE")
	)
	(segment
		(start 24.66594 -62.484)
		(end 23.6855 -61.50356)
		(width 0.10668)
		(layer "In4.Cu")
		(net "FM_ME_BT_DONE")
	)
	(segment
		(start 23.454868 -89.9922)
		(end 24.0792 -89.9922)
		(width 0.10668)
		(layer "In4.Cu")
		(net "FM_ME_BT_DONE")
	)
	(segment
		(start 24.64054 -73.103994)
		(end 23.90394 -72.367394)
		(width 0.10668)
		(layer "In4.Cu")
		(net "FM_ME_BT_DONE")
	)
	(segment
		(start 25.98674 -83.11134)
		(end 25.63622 -82.76082)
		(width 0.10668)
		(layer "In4.Cu")
		(net "FM_ME_BT_DONE")
	)
	(segment
		(start 48.499776 -42.175938)
		(end 48.895 -41.780714)
		(width 0.11684)
		(layer "F.Cu")
		(net "SMB_BMC_ALERT15_N")
	)
	(segment
		(start 48.895 -41.780714)
		(end 48.895 -41.771316)
		(width 0.11684)
		(layer "F.Cu")
		(net "SMB_BMC_ALERT15_N")
	)
	(via
		(at 48.499776 -42.175938)
		(size 0.4572)
		(drill 0.254)
		(layers "F.Cu" "B.Cu")
		(net "SMB_BMC_ALERT15_N")
	)
	(via
		(at 60.108592 -25.587706)
		(size 0.508)
		(drill 0.254)
		(layers "F.Cu" "B.Cu")
		(net "SMB_BMC_ALERT15_N")
	)
	(segment
		(start 60.108592 -25.587706)
		(end 61.996828 -27.475942)
		(width 0.11684)
		(layer "B.Cu")
		(net "SMB_BMC_ALERT15_N")
	)
	(segment
		(start 59.055 -26.31821)
		(end 59.787028 -25.586182)
		(width 0.10668)
		(layer "In7.Cu")
		(net "SMB_BMC_ALERT15_N")
	)
	(segment
		(start 59.71032 -27.873198)
		(end 59.055 -27.217878)
		(width 0.10668)
		(layer "In7.Cu")
		(net "SMB_BMC_ALERT15_N")
	)
	(segment
		(start 59.78906 -32.687006)
		(end 59.660028 -32.557974)
		(width 0.10668)
		(layer "In7.Cu")
		(net "SMB_BMC_ALERT15_N")
	)
	(segment
		(start 50.49774 -42.39006)
		(end 50.49774 -40.32758)
		(width 0.10668)
		(layer "In7.Cu")
		(net "SMB_BMC_ALERT15_N")
	)
	(segment
		(start 59.055 -27.217878)
		(end 59.055 -26.31821)
		(width 0.10668)
		(layer "In7.Cu")
		(net "SMB_BMC_ALERT15_N")
	)
	(segment
		(start 56.896 -36.779454)
		(end 59.78906 -33.886394)
		(width 0.10668)
		(layer "In7.Cu")
		(net "SMB_BMC_ALERT15_N")
	)
	(segment
		(start 59.660028 -32.557974)
		(end 59.40044 -32.45104)
		(width 0.10668)
		(layer "In7.Cu")
		(net "SMB_BMC_ALERT15_N")
	)
	(segment
		(start 50.63998 -40.18534)
		(end 56.6674 -40.18534)
		(width 0.10668)
		(layer "In7.Cu")
		(net "SMB_BMC_ALERT15_N")
	)
	(segment
		(start 50.49774 -40.32758)
		(end 50.63998 -40.18534)
		(width 0.10668)
		(layer "In7.Cu")
		(net "SMB_BMC_ALERT15_N")
	)
	(segment
		(start 48.914558 -42.59072)
		(end 50.29708 -42.59072)
		(width 0.10668)
		(layer "In7.Cu")
		(net "SMB_BMC_ALERT15_N")
	)
	(segment
		(start 59.78906 -33.886394)
		(end 59.78906 -32.687006)
		(width 0.10668)
		(layer "In7.Cu")
		(net "SMB_BMC_ALERT15_N")
	)
	(segment
		(start 59.40044 -32.45104)
		(end 59.15914 -32.20974)
		(width 0.10668)
		(layer "In7.Cu")
		(net "SMB_BMC_ALERT15_N")
	)
	(segment
		(start 59.71032 -28.93568)
		(end 59.71032 -27.873198)
		(width 0.10668)
		(layer "In7.Cu")
		(net "SMB_BMC_ALERT15_N")
	)
	(segment
		(start 59.15914 -32.20974)
		(end 59.15914 -31.7119)
		(width 0.10668)
		(layer "In7.Cu")
		(net "SMB_BMC_ALERT15_N")
	)
	(segment
		(start 56.896 -39.95674)
		(end 56.896 -36.779454)
		(width 0.10668)
		(layer "In7.Cu")
		(net "SMB_BMC_ALERT15_N")
	)
	(segment
		(start 48.499776 -42.175938)
		(end 48.914558 -42.59072)
		(width 0.10668)
		(layer "In7.Cu")
		(net "SMB_BMC_ALERT15_N")
	)
	(segment
		(start 59.055 -29.591)
		(end 59.71032 -28.93568)
		(width 0.10668)
		(layer "In7.Cu")
		(net "SMB_BMC_ALERT15_N")
	)
	(segment
		(start 60.107068 -25.586182)
		(end 60.108592 -25.587706)
		(width 0.10668)
		(layer "In7.Cu")
		(net "SMB_BMC_ALERT15_N")
	)
	(segment
		(start 59.055 -31.60776)
		(end 59.055 -29.591)
		(width 0.10668)
		(layer "In7.Cu")
		(net "SMB_BMC_ALERT15_N")
	)
	(segment
		(start 50.29708 -42.59072)
		(end 50.49774 -42.39006)
		(width 0.10668)
		(layer "In7.Cu")
		(net "SMB_BMC_ALERT15_N")
	)
	(segment
		(start 59.15914 -31.7119)
		(end 59.055 -31.60776)
		(width 0.10668)
		(layer "In7.Cu")
		(net "SMB_BMC_ALERT15_N")
	)
	(segment
		(start 56.6674 -40.18534)
		(end 56.896 -39.95674)
		(width 0.10668)
		(layer "In7.Cu")
		(net "SMB_BMC_ALERT15_N")
	)
	(segment
		(start 59.787028 -25.586182)
		(end 60.107068 -25.586182)
		(width 0.10668)
		(layer "In7.Cu")
		(net "SMB_BMC_ALERT15_N")
	)
	(segment
		(start 46.494954 -47.371254)
		(end 46.09973 -46.97603)
		(width 0.11684)
		(layer "F.Cu")
		(net "SMB_BMC_MM13_R_SDA")
	)
	(via
		(at 46.09973 -46.97603)
		(size 0.4572)
		(drill 0.254)
		(layers "F.Cu" "B.Cu")
		(net "SMB_BMC_MM13_R_SDA")
	)
	(segment
		(start 44.999656 -47.380144)
		(end 45.45711 -47.380144)
		(width 0.11684)
		(layer "B.Cu")
		(net "SMB_BMC_MM13_R_SDA")
	)
	(segment
		(start 44.6532 -47.7266)
		(end 44.999656 -47.380144)
		(width 0.11684)
		(layer "B.Cu")
		(net "SMB_BMC_MM13_R_SDA")
	)
	(segment
		(start 42.366184 -47.565564)
		(end 42.154348 -47.7774)
		(width 0.11684)
		(layer "B.Cu")
		(net "SMB_BMC_MM13_R_SDA")
	)
	(segment
		(start 43.182032 -47.7266)
		(end 44.6532 -47.7266)
		(width 0.11684)
		(layer "B.Cu")
		(net "SMB_BMC_MM13_R_SDA")
	)
	(segment
		(start 42.366184 -47.231808)
		(end 42.366184 -47.565564)
		(width 0.11684)
		(layer "B.Cu")
		(net "SMB_BMC_MM13_R_SDA")
	)
	(segment
		(start 40.335454 -48.026828)
		(end 40.330882 -48.026828)
		(width 0.11684)
		(layer "B.Cu")
		(net "SMB_BMC_MM13_R_SDA")
	)
	(segment
		(start 40.584882 -47.7774)
		(end 40.335454 -48.026828)
		(width 0.11684)
		(layer "B.Cu")
		(net "SMB_BMC_MM13_R_SDA")
	)
	(segment
		(start 42.68724 -47.231808)
		(end 43.182032 -47.7266)
		(width 0.11684)
		(layer "B.Cu")
		(net "SMB_BMC_MM13_R_SDA")
	)
	(segment
		(start 42.366184 -47.231808)
		(end 42.68724 -47.231808)
		(width 0.11684)
		(layer "B.Cu")
		(net "SMB_BMC_MM13_R_SDA")
	)
	(segment
		(start 45.45711 -47.380144)
		(end 45.692568 -47.144686)
		(width 0.11684)
		(layer "B.Cu")
		(net "SMB_BMC_MM13_R_SDA")
	)
	(segment
		(start 45.692568 -47.144686)
		(end 46.09973 -46.97603)
		(width 0.11684)
		(layer "B.Cu")
		(net "SMB_BMC_MM13_R_SDA")
	)
	(segment
		(start 42.154348 -47.7774)
		(end 40.584882 -47.7774)
		(width 0.11684)
		(layer "B.Cu")
		(net "SMB_BMC_MM13_R_SDA")
	)
	(segment
		(start 47.295054 -47.371254)
		(end 46.89983 -46.97603)
		(width 0.11684)
		(layer "F.Cu")
		(net "SMB_BMC_MM14_R_SCL")
	)
	(via
		(at 46.89983 -46.97603)
		(size 0.4572)
		(drill 0.254)
		(layers "F.Cu" "B.Cu")
		(net "SMB_BMC_MM14_R_SCL")
	)
	(via
		(at 44.9072 -49.3268)
		(size 0.6604)
		(drill 0.3302)
		(layers "F.Cu" "B.Cu")
		(net "SMB_BMC_MM14_R_SCL")
	)
	(segment
		(start 44.9072 -49.3268)
		(end 44.9072 -48.3616)
		(width 0.11684)
		(layer "B.Cu")
		(net "SMB_BMC_MM14_R_SCL")
	)
	(segment
		(start 44.290488 -49.53)
		(end 44.704 -49.53)
		(width 0.11684)
		(layer "B.Cu")
		(net "SMB_BMC_MM14_R_SCL")
	)
	(segment
		(start 43.382692 -48.310292)
		(end 43.892724 -48.820324)
		(width 0.11684)
		(layer "B.Cu")
		(net "SMB_BMC_MM14_R_SCL")
	)
	(segment
		(start 45.938694 -47.38751)
		(end 46.48835 -47.38751)
		(width 0.11684)
		(layer "B.Cu")
		(net "SMB_BMC_MM14_R_SCL")
	)
	(segment
		(start 43.892724 -48.820324)
		(end 43.892724 -49.132236)
		(width 0.11684)
		(layer "B.Cu")
		(net "SMB_BMC_MM14_R_SCL")
	)
	(segment
		(start 45.688504 -47.6377)
		(end 45.938694 -47.38751)
		(width 0.11684)
		(layer "B.Cu")
		(net "SMB_BMC_MM14_R_SCL")
	)
	(segment
		(start 45.46092 -48.16475)
		(end 45.688504 -47.937166)
		(width 0.11684)
		(layer "B.Cu")
		(net "SMB_BMC_MM14_R_SCL")
	)
	(segment
		(start 43.892724 -49.132236)
		(end 44.290488 -49.53)
		(width 0.11684)
		(layer "B.Cu")
		(net "SMB_BMC_MM14_R_SCL")
	)
	(segment
		(start 45.688504 -47.937166)
		(end 45.688504 -47.6377)
		(width 0.11684)
		(layer "B.Cu")
		(net "SMB_BMC_MM14_R_SCL")
	)
	(segment
		(start 44.9072 -48.3616)
		(end 45.10405 -48.16475)
		(width 0.11684)
		(layer "B.Cu")
		(net "SMB_BMC_MM14_R_SCL")
	)
	(segment
		(start 46.48835 -47.38751)
		(end 46.89983 -46.97603)
		(width 0.11684)
		(layer "B.Cu")
		(net "SMB_BMC_MM14_R_SCL")
	)
	(segment
		(start 42.366184 -48.44415)
		(end 42.366184 -48.667416)
		(width 0.11684)
		(layer "B.Cu")
		(net "SMB_BMC_MM14_R_SCL")
	)
	(segment
		(start 42.117772 -48.915828)
		(end 40.330882 -48.915828)
		(width 0.11684)
		(layer "B.Cu")
		(net "SMB_BMC_MM14_R_SCL")
	)
	(segment
		(start 42.366184 -48.44415)
		(end 42.500042 -48.310292)
		(width 0.11684)
		(layer "B.Cu")
		(net "SMB_BMC_MM14_R_SCL")
	)
	(segment
		(start 44.704 -49.53)
		(end 44.9072 -49.3268)
		(width 0.11684)
		(layer "B.Cu")
		(net "SMB_BMC_MM14_R_SCL")
	)
	(segment
		(start 42.366184 -48.667416)
		(end 42.117772 -48.915828)
		(width 0.11684)
		(layer "B.Cu")
		(net "SMB_BMC_MM14_R_SCL")
	)
	(segment
		(start 42.500042 -48.310292)
		(end 43.382692 -48.310292)
		(width 0.11684)
		(layer "B.Cu")
		(net "SMB_BMC_MM14_R_SCL")
	)
	(segment
		(start 45.10405 -48.16475)
		(end 45.46092 -48.16475)
		(width 0.11684)
		(layer "B.Cu")
		(net "SMB_BMC_MM14_R_SCL")
	)
	(segment
		(start 43.18 -45.2374)
		(end 44.116498 -46.173898)
		(width 0.11684)
		(layer "F.Cu")
		(net "SMB_BMC_MM14_R_SDA")
	)
	(segment
		(start 41.68902 -45.2374)
		(end 43.18 -45.2374)
		(width 0.11684)
		(layer "F.Cu")
		(net "SMB_BMC_MM14_R_SDA")
	)
	(segment
		(start 40.32885 -45.380402)
		(end 40.332914 -45.384466)
		(width 0.11684)
		(layer "F.Cu")
		(net "SMB_BMC_MM14_R_SDA")
	)
	(segment
		(start 44.116498 -46.173898)
		(end 45.297852 -46.173898)
		(width 0.11684)
		(layer "F.Cu")
		(net "SMB_BMC_MM14_R_SDA")
	)
	(segment
		(start 40.32885 -44.3992)
		(end 40.85082 -44.3992)
		(width 0.11684)
		(layer "F.Cu")
		(net "SMB_BMC_MM14_R_SDA")
	)
	(segment
		(start 40.32885 -44.3992)
		(end 40.32885 -45.380402)
		(width 0.11684)
		(layer "F.Cu")
		(net "SMB_BMC_MM14_R_SDA")
	)
	(segment
		(start 40.85082 -44.3992)
		(end 41.68902 -45.2374)
		(width 0.11684)
		(layer "F.Cu")
		(net "SMB_BMC_MM14_R_SDA")
	)
	(segment
		(start 45.297852 -46.173898)
		(end 45.695108 -46.571154)
		(width 0.11684)
		(layer "F.Cu")
		(net "SMB_BMC_MM14_R_SDA")
	)
	(segment
		(start 40.55745 -46.64329)
		(end 41.264332 -46.64329)
		(width 0.11684)
		(layer "F.Cu")
		(net "SMB_BMC_MM13_R_SCL")
	)
	(segment
		(start 40.305736 -46.391576)
		(end 40.55745 -46.64329)
		(width 0.11684)
		(layer "F.Cu")
		(net "SMB_BMC_MM13_R_SCL")
	)
	(segment
		(start 41.264332 -46.64329)
		(end 41.808654 -46.098968)
		(width 0.11684)
		(layer "F.Cu")
		(net "SMB_BMC_MM13_R_SCL")
	)
	(segment
		(start 44.895008 -46.571154)
		(end 42.28084 -46.571154)
		(width 0.11684)
		(layer "F.Cu")
		(net "SMB_BMC_MM13_R_SCL")
	)
	(segment
		(start 39.986712 -46.992032)
		(end 40.305736 -46.673008)
		(width 0.11684)
		(layer "F.Cu")
		(net "SMB_BMC_MM13_R_SCL")
	)
	(segment
		(start 40.305736 -46.673008)
		(end 40.305736 -46.391576)
		(width 0.11684)
		(layer "F.Cu")
		(net "SMB_BMC_MM13_R_SCL")
	)
	(segment
		(start 42.28084 -46.571154)
		(end 41.808654 -46.098968)
		(width 0.11684)
		(layer "F.Cu")
		(net "SMB_BMC_MM13_R_SCL")
	)
	(segment
		(start 38.523926 -46.378876)
		(end 38.523926 -46.400212)
		(width 0.11684)
		(layer "F.Cu")
		(net "SMB_BMC_MM13_R_SCL")
	)
	(segment
		(start 38.523926 -46.400212)
		(end 39.115746 -46.992032)
		(width 0.11684)
		(layer "F.Cu")
		(net "SMB_BMC_MM13_R_SCL")
	)
	(segment
		(start 39.115746 -46.992032)
		(end 39.986712 -46.992032)
		(width 0.11684)
		(layer "F.Cu")
		(net "SMB_BMC_MM13_R_SCL")
	)
	(via
		(at 41.808654 -46.098968)
		(size 0.762)
		(drill 0.381)
		(layers "F.Cu" "B.Cu")
		(net "SMB_BMC_MM13_R_SCL")
	)
	(segment
		(start 4.318 -81.788)
		(end 4.318 -81.29905)
		(width 0.11684)
		(layer "F.Cu")
		(net "RST_SRST_PLD_BMC_R_N")
	)
	(segment
		(start 6.039104 -81.915)
		(end 4.445 -81.915)
		(width 0.11684)
		(layer "F.Cu")
		(net "RST_SRST_PLD_BMC_R_N")
	)
	(segment
		(start 4.445 -81.915)
		(end 4.318 -81.788)
		(width 0.11684)
		(layer "F.Cu")
		(net "RST_SRST_PLD_BMC_R_N")
	)
	(segment
		(start 69.85508 -116.55552)
		(end 69.85508 -117.0051)
		(width 0.11684)
		(layer "F.Cu")
		(net "RST_SRST_PLD_BMC_R_N")
	)
	(segment
		(start 69.85508 -117.0051)
		(end 69.660008 -117.200172)
		(width 0.11684)
		(layer "F.Cu")
		(net "RST_SRST_PLD_BMC_R_N")
	)
	(segment
		(start 71.0438 -111.4552)
		(end 71.0438 -115.3668)
		(width 0.11684)
		(layer "F.Cu")
		(net "RST_SRST_PLD_BMC_R_N")
	)
	(segment
		(start 69.660008 -117.200172)
		(end 69.660008 -118.25986)
		(width 0.11684)
		(layer "F.Cu")
		(net "RST_SRST_PLD_BMC_R_N")
	)
	(segment
		(start 6.04774 -81.923636)
		(end 6.039104 -81.915)
		(width 0.11684)
		(layer "F.Cu")
		(net "RST_SRST_PLD_BMC_R_N")
	)
	(segment
		(start 71.0438 -115.3668)
		(end 69.85508 -116.55552)
		(width 0.11684)
		(layer "F.Cu")
		(net "RST_SRST_PLD_BMC_R_N")
	)
	(segment
		(start 70.2056 -109.67974)
		(end 70.2056 -110.617)
		(width 0.11684)
		(layer "F.Cu")
		(net "RST_SRST_PLD_BMC_R_N")
	)
	(segment
		(start 70.2056 -110.617)
		(end 71.0438 -111.4552)
		(width 0.11684)
		(layer "F.Cu")
		(net "RST_SRST_PLD_BMC_R_N")
	)
	(via
		(at 3.522726 -89.468706)
		(size 0.508)
		(drill 0.254)
		(layers "F.Cu" "B.Cu")
		(net "RST_SRST_PLD_BMC_R_N")
	)
	(via
		(at 70.2056 -109.67974)
		(size 0.508)
		(drill 0.254)
		(layers "F.Cu" "B.Cu")
		(net "RST_SRST_PLD_BMC_R_N")
	)
	(via
		(at 6.013958 -107.294426)
		(size 0.508)
		(drill 0.254)
		(layers "F.Cu" "B.Cu")
		(net "RST_SRST_PLD_BMC_R_N")
	)
	(via
		(at 6.04774 -81.923636)
		(size 0.508)
		(drill 0.254)
		(layers "F.Cu" "B.Cu")
		(net "RST_SRST_PLD_BMC_R_N")
	)
	(segment
		(start 6.037326 -81.93405)
		(end 6.04774 -81.923636)
		(width 0.11684)
		(layer "B.Cu")
		(net "RST_SRST_PLD_BMC_R_N")
	)
	(segment
		(start 5.334 -81.93405)
		(end 6.037326 -81.93405)
		(width 0.11684)
		(layer "B.Cu")
		(net "RST_SRST_PLD_BMC_R_N")
	)
	(segment
		(start 5.842254 -109.982254)
		(end 6.2992 -110.4392)
		(width 0.08382)
		(layer "In2.Cu")
		(net "RST_SRST_PLD_BMC_R_N")
	)
	(segment
		(start 28.7782 -111.6584)
		(end 29.2862 -111.1504)
		(width 0.08382)
		(layer "In2.Cu")
		(net "RST_SRST_PLD_BMC_R_N")
	)
	(segment
		(start 58.801 -111.7854)
		(end 59.2328 -111.3536)
		(width 0.08382)
		(layer "In2.Cu")
		(net "RST_SRST_PLD_BMC_R_N")
	)
	(segment
		(start 36.322 -111.1504)
		(end 36.9062 -111.7346)
		(width 0.08382)
		(layer "In2.Cu")
		(net "RST_SRST_PLD_BMC_R_N")
	)
	(segment
		(start 43.1038 -112.3442)
		(end 44.0182 -111.4298)
		(width 0.08382)
		(layer "In2.Cu")
		(net "RST_SRST_PLD_BMC_R_N")
	)
	(segment
		(start 19.558 -111.7092)
		(end 20.54225 -110.72495)
		(width 0.08382)
		(layer "In2.Cu")
		(net "RST_SRST_PLD_BMC_R_N")
	)
	(segment
		(start 67.5132 -108.712)
		(end 68.9864 -110.1852)
		(width 0.08382)
		(layer "In2.Cu")
		(net "RST_SRST_PLD_BMC_R_N")
	)
	(segment
		(start 69.6976 -110.1852)
		(end 70.20306 -109.67974)
		(width 0.08382)
		(layer "In2.Cu")
		(net "RST_SRST_PLD_BMC_R_N")
	)
	(segment
		(start 59.2328 -111.3536)
		(end 61.9252 -111.3536)
		(width 0.08382)
		(layer "In2.Cu")
		(net "RST_SRST_PLD_BMC_R_N")
	)
	(segment
		(start 17.2974 -111.1504)
		(end 17.8562 -111.7092)
		(width 0.08382)
		(layer "In2.Cu")
		(net "RST_SRST_PLD_BMC_R_N")
	)
	(segment
		(start 68.9864 -110.1852)
		(end 69.6976 -110.1852)
		(width 0.08382)
		(layer "In2.Cu")
		(net "RST_SRST_PLD_BMC_R_N")
	)
	(segment
		(start 40.386 -111.7346)
		(end 40.9956 -112.3442)
		(width 0.08382)
		(layer "In2.Cu")
		(net "RST_SRST_PLD_BMC_R_N")
	)
	(segment
		(start 47.0916 -111.4298)
		(end 48.03267 -112.37087)
		(width 0.08382)
		(layer "In2.Cu")
		(net "RST_SRST_PLD_BMC_R_N")
	)
	(segment
		(start 17.8562 -111.7092)
		(end 19.558 -111.7092)
		(width 0.08382)
		(layer "In2.Cu")
		(net "RST_SRST_PLD_BMC_R_N")
	)
	(segment
		(start 29.2862 -111.1504)
		(end 36.322 -111.1504)
		(width 0.08382)
		(layer "In2.Cu")
		(net "RST_SRST_PLD_BMC_R_N")
	)
	(segment
		(start 12.2936 -109.8042)
		(end 13.6398 -111.1504)
		(width 0.08382)
		(layer "In2.Cu")
		(net "RST_SRST_PLD_BMC_R_N")
	)
	(segment
		(start 40.9956 -112.3442)
		(end 43.1038 -112.3442)
		(width 0.08382)
		(layer "In2.Cu")
		(net "RST_SRST_PLD_BMC_R_N")
	)
	(segment
		(start 5.842254 -107.46613)
		(end 5.842254 -109.982254)
		(width 0.08382)
		(layer "In2.Cu")
		(net "RST_SRST_PLD_BMC_R_N")
	)
	(segment
		(start 36.9062 -111.7346)
		(end 40.386 -111.7346)
		(width 0.08382)
		(layer "In2.Cu")
		(net "RST_SRST_PLD_BMC_R_N")
	)
	(segment
		(start 70.20306 -109.67974)
		(end 70.2056 -109.67974)
		(width 0.08382)
		(layer "In2.Cu")
		(net "RST_SRST_PLD_BMC_R_N")
	)
	(segment
		(start 65.8876 -108.712)
		(end 67.5132 -108.712)
		(width 0.08382)
		(layer "In2.Cu")
		(net "RST_SRST_PLD_BMC_R_N")
	)
	(segment
		(start 10.0838 -109.8042)
		(end 12.2936 -109.8042)
		(width 0.08382)
		(layer "In2.Cu")
		(net "RST_SRST_PLD_BMC_R_N")
	)
	(segment
		(start 20.54225 -110.72495)
		(end 24.64435 -110.72495)
		(width 0.08382)
		(layer "In2.Cu")
		(net "RST_SRST_PLD_BMC_R_N")
	)
	(segment
		(start 64.7954 -109.8042)
		(end 65.8876 -108.712)
		(width 0.08382)
		(layer "In2.Cu")
		(net "RST_SRST_PLD_BMC_R_N")
	)
	(segment
		(start 6.013958 -107.294426)
		(end 5.842254 -107.46613)
		(width 0.08382)
		(layer "In2.Cu")
		(net "RST_SRST_PLD_BMC_R_N")
	)
	(segment
		(start 52.9844 -111.7854)
		(end 58.801 -111.7854)
		(width 0.08382)
		(layer "In2.Cu")
		(net "RST_SRST_PLD_BMC_R_N")
	)
	(segment
		(start 48.03267 -112.37087)
		(end 52.39893 -112.37087)
		(width 0.08382)
		(layer "In2.Cu")
		(net "RST_SRST_PLD_BMC_R_N")
	)
	(segment
		(start 44.0182 -111.4298)
		(end 47.0916 -111.4298)
		(width 0.08382)
		(layer "In2.Cu")
		(net "RST_SRST_PLD_BMC_R_N")
	)
	(segment
		(start 63.4746 -109.8042)
		(end 64.7954 -109.8042)
		(width 0.08382)
		(layer "In2.Cu")
		(net "RST_SRST_PLD_BMC_R_N")
	)
	(segment
		(start 52.39893 -112.37087)
		(end 52.9844 -111.7854)
		(width 0.08382)
		(layer "In2.Cu")
		(net "RST_SRST_PLD_BMC_R_N")
	)
	(segment
		(start 25.5778 -111.6584)
		(end 28.7782 -111.6584)
		(width 0.08382)
		(layer "In2.Cu")
		(net "RST_SRST_PLD_BMC_R_N")
	)
	(segment
		(start 24.64435 -110.72495)
		(end 25.5778 -111.6584)
		(width 0.08382)
		(layer "In2.Cu")
		(net "RST_SRST_PLD_BMC_R_N")
	)
	(segment
		(start 61.9252 -111.3536)
		(end 63.4746 -109.8042)
		(width 0.08382)
		(layer "In2.Cu")
		(net "RST_SRST_PLD_BMC_R_N")
	)
	(segment
		(start 6.2992 -110.4392)
		(end 9.4488 -110.4392)
		(width 0.08382)
		(layer "In2.Cu")
		(net "RST_SRST_PLD_BMC_R_N")
	)
	(segment
		(start 13.6398 -111.1504)
		(end 17.2974 -111.1504)
		(width 0.08382)
		(layer "In2.Cu")
		(net "RST_SRST_PLD_BMC_R_N")
	)
	(segment
		(start 9.4488 -110.4392)
		(end 10.0838 -109.8042)
		(width 0.08382)
		(layer "In2.Cu")
		(net "RST_SRST_PLD_BMC_R_N")
	)
	(segment
		(start 5.7658 -84.8106)
		(end 6.2992 -84.8106)
		(width 0.10668)
		(layer "In7.Cu")
		(net "RST_SRST_PLD_BMC_R_N")
	)
	(segment
		(start 6.5278 -83.2104)
		(end 5.8928 -82.5754)
		(width 0.10668)
		(layer "In7.Cu")
		(net "RST_SRST_PLD_BMC_R_N")
	)
	(segment
		(start 4.9276 -86.15426)
		(end 5.284978 -85.291422)
		(width 0.10668)
		(layer "In7.Cu")
		(net "RST_SRST_PLD_BMC_R_N")
	)
	(segment
		(start 5.284978 -85.291422)
		(end 5.7658 -84.8106)
		(width 0.10668)
		(layer "In7.Cu")
		(net "RST_SRST_PLD_BMC_R_N")
	)
	(segment
		(start 6.5278 -84.582)
		(end 6.5278 -83.2104)
		(width 0.10668)
		(layer "In7.Cu")
		(net "RST_SRST_PLD_BMC_R_N")
	)
	(segment
		(start 4.9276 -86.9696)
		(end 4.9276 -86.15426)
		(width 0.10668)
		(layer "In7.Cu")
		(net "RST_SRST_PLD_BMC_R_N")
	)
	(segment
		(start 5.8928 -82.5754)
		(end 5.8928 -82.078576)
		(width 0.10668)
		(layer "In7.Cu")
		(net "RST_SRST_PLD_BMC_R_N")
	)
	(segment
		(start 3.522726 -89.468706)
		(end 3.522726 -88.374474)
		(width 0.10668)
		(layer "In7.Cu")
		(net "RST_SRST_PLD_BMC_R_N")
	)
	(segment
		(start 3.522726 -88.374474)
		(end 4.9276 -86.9696)
		(width 0.10668)
		(layer "In7.Cu")
		(net "RST_SRST_PLD_BMC_R_N")
	)
	(segment
		(start 6.2992 -84.8106)
		(end 6.5278 -84.582)
		(width 0.10668)
		(layer "In7.Cu")
		(net "RST_SRST_PLD_BMC_R_N")
	)
	(segment
		(start 5.8928 -82.078576)
		(end 6.04774 -81.923636)
		(width 0.10668)
		(layer "In7.Cu")
		(net "RST_SRST_PLD_BMC_R_N")
	)
	(segment
		(start 3.522726 -89.468706)
		(end 4.264406 -90.210386)
		(width 0.08382)
		(layer "In9.Cu")
		(net "RST_SRST_PLD_BMC_R_N")
	)
	(segment
		(start 4.264406 -90.210386)
		(end 4.264406 -104.951784)
		(width 0.08382)
		(layer "In9.Cu")
		(net "RST_SRST_PLD_BMC_R_N")
	)
	(segment
		(start 4.264406 -104.951784)
		(end 6.013958 -106.701336)
		(width 0.08382)
		(layer "In9.Cu")
		(net "RST_SRST_PLD_BMC_R_N")
	)
	(segment
		(start 6.013958 -106.701336)
		(end 6.013958 -107.294426)
		(width 0.08382)
		(layer "In9.Cu")
		(net "RST_SRST_PLD_BMC_R_N")
	)
	(segment
		(start 35.7886 -107.2261)
		(end 35.7886 -108.1786)
		(width 0.11684)
		(layer "F.Cu")
		(net "RST_SGPIO_RESET_N")
	)
	(segment
		(start 35.92576 -109.629956)
		(end 35.808666 -109.74705)
		(width 0.11684)
		(layer "F.Cu")
		(net "RST_SGPIO_RESET_N")
	)
	(segment
		(start 35.52317 -111.117634)
		(end 37.338 -112.932464)
		(width 0.11684)
		(layer "F.Cu")
		(net "RST_SGPIO_RESET_N")
	)
	(segment
		(start 37.338 -117.094254)
		(end 37.254942 -117.177312)
		(width 0.11684)
		(layer "F.Cu")
		(net "RST_SGPIO_RESET_N")
	)
	(segment
		(start 11.91895 -87.08644)
		(end 11.74369 -86.91118)
		(width 0.11684)
		(layer "F.Cu")
		(net "RST_SGPIO_RESET_N")
	)
	(segment
		(start 36.046156 -108.436156)
		(end 36.046156 -109.064044)
		(width 0.11684)
		(layer "F.Cu")
		(net "RST_SGPIO_RESET_N")
	)
	(segment
		(start 37.338 -112.932464)
		(end 37.338 -117.094254)
		(width 0.11684)
		(layer "F.Cu")
		(net "RST_SGPIO_RESET_N")
	)
	(segment
		(start 11.91895 -87.376)
		(end 11.91895 -87.08644)
		(width 0.11684)
		(layer "F.Cu")
		(net "RST_SGPIO_RESET_N")
	)
	(segment
		(start 35.808666 -109.74705)
		(end 35.5346 -109.74705)
		(width 0.11684)
		(layer "F.Cu")
		(net "RST_SGPIO_RESET_N")
	)
	(segment
		(start 37.254942 -117.177312)
		(end 37.254942 -118.25986)
		(width 0.11684)
		(layer "F.Cu")
		(net "RST_SGPIO_RESET_N")
	)
	(segment
		(start 11.527028 -86.91118)
		(end 11.23188 -86.616032)
		(width 0.11684)
		(layer "F.Cu")
		(net "RST_SGPIO_RESET_N")
	)
	(segment
		(start 35.92576 -109.18444)
		(end 35.92576 -109.629956)
		(width 0.11684)
		(layer "F.Cu")
		(net "RST_SGPIO_RESET_N")
	)
	(segment
		(start 35.7886 -108.1786)
		(end 36.046156 -108.436156)
		(width 0.11684)
		(layer "F.Cu")
		(net "RST_SGPIO_RESET_N")
	)
	(segment
		(start 11.74369 -86.91118)
		(end 11.527028 -86.91118)
		(width 0.11684)
		(layer "F.Cu")
		(net "RST_SGPIO_RESET_N")
	)
	(segment
		(start 35.5346 -109.74705)
		(end 35.52317 -109.75848)
		(width 0.11684)
		(layer "F.Cu")
		(net "RST_SGPIO_RESET_N")
	)
	(segment
		(start 33.79978 -106.901996)
		(end 35.464496 -106.901996)
		(width 0.11684)
		(layer "F.Cu")
		(net "RST_SGPIO_RESET_N")
	)
	(segment
		(start 36.046156 -109.064044)
		(end 35.92576 -109.18444)
		(width 0.11684)
		(layer "F.Cu")
		(net "RST_SGPIO_RESET_N")
	)
	(segment
		(start 35.464496 -106.901996)
		(end 35.7886 -107.2261)
		(width 0.11684)
		(layer "F.Cu")
		(net "RST_SGPIO_RESET_N")
	)
	(segment
		(start 35.52317 -109.75848)
		(end 35.52317 -111.117634)
		(width 0.11684)
		(layer "F.Cu")
		(net "RST_SGPIO_RESET_N")
	)
	(via
		(at 11.23188 -86.616032)
		(size 0.508)
		(drill 0.254)
		(layers "F.Cu" "B.Cu")
		(net "RST_SGPIO_RESET_N")
	)
	(via
		(at 33.79978 -106.901996)
		(size 0.508)
		(drill 0.254)
		(layers "F.Cu" "B.Cu")
		(net "RST_SGPIO_RESET_N")
	)
	(via
		(at 41.314878 -29.793438)
		(size 0.508)
		(drill 0.254)
		(layers "F.Cu" "B.Cu")
		(net "RST_SGPIO_RESET_N")
	)
	(via
		(at 26.20772 -85.416644)
		(size 0.508)
		(drill 0.254)
		(layers "F.Cu" "B.Cu")
		(net "RST_SGPIO_RESET_N")
	)
	(segment
		(start 41.314878 -29.793438)
		(end 41.314878 -30.416754)
		(width 0.11684)
		(layer "B.Cu")
		(net "RST_SGPIO_RESET_N")
	)
	(segment
		(start 11.483848 -86.868)
		(end 11.8618 -86.868)
		(width 0.08382)
		(layer "In2.Cu")
		(net "RST_SGPIO_RESET_N")
	)
	(segment
		(start 24.450294 -84.464906)
		(end 24.944578 -84.464906)
		(width 0.08382)
		(layer "In2.Cu")
		(net "RST_SGPIO_RESET_N")
	)
	(segment
		(start 11.23188 -86.616032)
		(end 11.483848 -86.868)
		(width 0.08382)
		(layer "In2.Cu")
		(net "RST_SGPIO_RESET_N")
	)
	(segment
		(start 17.924272 -84.33689)
		(end 19.869658 -84.33689)
		(width 0.08382)
		(layer "In2.Cu")
		(net "RST_SGPIO_RESET_N")
	)
	(segment
		(start 20.310348 -83.8962)
		(end 21.7932 -83.8962)
		(width 0.08382)
		(layer "In2.Cu")
		(net "RST_SGPIO_RESET_N")
	)
	(segment
		(start 22.6314 -84.7344)
		(end 24.1808 -84.7344)
		(width 0.08382)
		(layer "In2.Cu")
		(net "RST_SGPIO_RESET_N")
	)
	(segment
		(start 14.1224 -84.6074)
		(end 17.653762 -84.6074)
		(width 0.08382)
		(layer "In2.Cu")
		(net "RST_SGPIO_RESET_N")
	)
	(segment
		(start 26.10612 -85.416644)
		(end 26.20772 -85.416644)
		(width 0.08382)
		(layer "In2.Cu")
		(net "RST_SGPIO_RESET_N")
	)
	(segment
		(start 11.8618 -86.868)
		(end 14.1224 -84.6074)
		(width 0.08382)
		(layer "In2.Cu")
		(net "RST_SGPIO_RESET_N")
	)
	(segment
		(start 24.944578 -84.464906)
		(end 25.302718 -84.613242)
		(width 0.08382)
		(layer "In2.Cu")
		(net "RST_SGPIO_RESET_N")
	)
	(segment
		(start 21.7932 -83.8962)
		(end 22.6314 -84.7344)
		(width 0.08382)
		(layer "In2.Cu")
		(net "RST_SGPIO_RESET_N")
	)
	(segment
		(start 19.869658 -84.33689)
		(end 20.310348 -83.8962)
		(width 0.08382)
		(layer "In2.Cu")
		(net "RST_SGPIO_RESET_N")
	)
	(segment
		(start 17.653762 -84.6074)
		(end 17.924272 -84.33689)
		(width 0.08382)
		(layer "In2.Cu")
		(net "RST_SGPIO_RESET_N")
	)
	(segment
		(start 24.1808 -84.7344)
		(end 24.450294 -84.464906)
		(width 0.08382)
		(layer "In2.Cu")
		(net "RST_SGPIO_RESET_N")
	)
	(segment
		(start 25.302718 -84.613242)
		(end 26.10612 -85.416644)
		(width 0.08382)
		(layer "In2.Cu")
		(net "RST_SGPIO_RESET_N")
	)
	(segment
		(start 28.48864 -67.2719)
		(end 28.90012 -66.86042)
		(width 0.10668)
		(layer "In4.Cu")
		(net "RST_SGPIO_RESET_N")
	)
	(segment
		(start 28.48864 -68.29298)
		(end 28.48864 -67.2719)
		(width 0.10668)
		(layer "In4.Cu")
		(net "RST_SGPIO_RESET_N")
	)
	(segment
		(start 32.4485 -43.1673)
		(end 34.06648 -43.1673)
		(width 0.10668)
		(layer "In4.Cu")
		(net "RST_SGPIO_RESET_N")
	)
	(segment
		(start 31.46044 -47.49038)
		(end 31.46044 -44.15536)
		(width 0.10668)
		(layer "In4.Cu")
		(net "RST_SGPIO_RESET_N")
	)
	(segment
		(start 27.69108 -69.09054)
		(end 28.48864 -68.29298)
		(width 0.10668)
		(layer "In4.Cu")
		(net "RST_SGPIO_RESET_N")
	)
	(segment
		(start 37.901372 -38.68928)
		(end 41.417748 -38.68928)
		(width 0.10668)
		(layer "In4.Cu")
		(net "RST_SGPIO_RESET_N")
	)
	(segment
		(start 41.417748 -38.68928)
		(end 41.58234 -38.524688)
		(width 0.10668)
		(layer "In4.Cu")
		(net "RST_SGPIO_RESET_N")
	)
	(segment
		(start 30.324044 -55.571136)
		(end 30.47746 -54.799992)
		(width 0.10668)
		(layer "In4.Cu")
		(net "RST_SGPIO_RESET_N")
	)
	(segment
		(start 30.786832 -50.3301)
		(end 31.17088 -49.946052)
		(width 0.10668)
		(layer "In4.Cu")
		(net "RST_SGPIO_RESET_N")
	)
	(segment
		(start 28.90012 -66.86042)
		(end 28.90012 -66.19494)
		(width 0.10668)
		(layer "In4.Cu")
		(net "RST_SGPIO_RESET_N")
	)
	(segment
		(start 37.23386 -39.356792)
		(end 37.901372 -38.68928)
		(width 0.10668)
		(layer "In4.Cu")
		(net "RST_SGPIO_RESET_N")
	)
	(segment
		(start 46.79442 -33.712658)
		(end 46.79442 -32.550354)
		(width 0.10668)
		(layer "In4.Cu")
		(net "RST_SGPIO_RESET_N")
	)
	(segment
		(start 29.156406 -73.396856)
		(end 28.805886 -73.046336)
		(width 0.10668)
		(layer "In4.Cu")
		(net "RST_SGPIO_RESET_N")
	)
	(segment
		(start 28.805886 -73.046336)
		(end 28.805886 -72.213216)
		(width 0.10668)
		(layer "In4.Cu")
		(net "RST_SGPIO_RESET_N")
	)
	(segment
		(start 45.520102 -34.986976)
		(end 46.79442 -33.712658)
		(width 0.10668)
		(layer "In4.Cu")
		(net "RST_SGPIO_RESET_N")
	)
	(segment
		(start 28.90012 -66.19494)
		(end 27.69616 -64.99098)
		(width 0.10668)
		(layer "In4.Cu")
		(net "RST_SGPIO_RESET_N")
	)
	(segment
		(start 44.160186 -29.91612)
		(end 41.43756 -29.91612)
		(width 0.10668)
		(layer "In4.Cu")
		(net "RST_SGPIO_RESET_N")
	)
	(segment
		(start 30.47746 -54.799992)
		(end 30.47746 -52.681886)
		(width 0.10668)
		(layer "In4.Cu")
		(net "RST_SGPIO_RESET_N")
	)
	(segment
		(start 30.786832 -52.372514)
		(end 30.786832 -50.3301)
		(width 0.10668)
		(layer "In4.Cu")
		(net "RST_SGPIO_RESET_N")
	)
	(segment
		(start 27.69616 -58.59526)
		(end 30.043882 -56.247538)
		(width 0.10668)
		(layer "In4.Cu")
		(net "RST_SGPIO_RESET_N")
	)
	(segment
		(start 41.58234 -36.226496)
		(end 42.82186 -34.986976)
		(width 0.10668)
		(layer "In4.Cu")
		(net "RST_SGPIO_RESET_N")
	)
	(segment
		(start 37.23386 -40.15994)
		(end 37.23386 -39.356792)
		(width 0.10668)
		(layer "In4.Cu")
		(net "RST_SGPIO_RESET_N")
	)
	(segment
		(start 28.805886 -72.213216)
		(end 28.80614 -72.212962)
		(width 0.10668)
		(layer "In4.Cu")
		(net "RST_SGPIO_RESET_N")
	)
	(segment
		(start 28.31338 -83.878166)
		(end 28.31338 -77.37602)
		(width 0.10668)
		(layer "In4.Cu")
		(net "RST_SGPIO_RESET_N")
	)
	(segment
		(start 28.80614 -72.212962)
		(end 28.80614 -71.444358)
		(width 0.10668)
		(layer "In4.Cu")
		(net "RST_SGPIO_RESET_N")
	)
	(segment
		(start 30.043882 -56.247538)
		(end 30.324044 -55.571136)
		(width 0.10668)
		(layer "In4.Cu")
		(net "RST_SGPIO_RESET_N")
	)
	(segment
		(start 31.17088 -49.946052)
		(end 31.17088 -47.77994)
		(width 0.10668)
		(layer "In4.Cu")
		(net "RST_SGPIO_RESET_N")
	)
	(segment
		(start 29.156406 -76.532994)
		(end 29.156406 -73.396856)
		(width 0.10668)
		(layer "In4.Cu")
		(net "RST_SGPIO_RESET_N")
	)
	(segment
		(start 26.774902 -85.416644)
		(end 28.31338 -83.878166)
		(width 0.10668)
		(layer "In4.Cu")
		(net "RST_SGPIO_RESET_N")
	)
	(segment
		(start 27.69108 -70.329298)
		(end 27.69108 -69.09054)
		(width 0.10668)
		(layer "In4.Cu")
		(net "RST_SGPIO_RESET_N")
	)
	(segment
		(start 31.17088 -47.77994)
		(end 31.46044 -47.49038)
		(width 0.10668)
		(layer "In4.Cu")
		(net "RST_SGPIO_RESET_N")
	)
	(segment
		(start 30.47746 -52.681886)
		(end 30.786832 -52.372514)
		(width 0.10668)
		(layer "In4.Cu")
		(net "RST_SGPIO_RESET_N")
	)
	(segment
		(start 26.20772 -85.416644)
		(end 26.774902 -85.416644)
		(width 0.10668)
		(layer "In4.Cu")
		(net "RST_SGPIO_RESET_N")
	)
	(segment
		(start 31.46044 -44.15536)
		(end 32.4485 -43.1673)
		(width 0.10668)
		(layer "In4.Cu")
		(net "RST_SGPIO_RESET_N")
	)
	(segment
		(start 42.82186 -34.986976)
		(end 45.520102 -34.986976)
		(width 0.10668)
		(layer "In4.Cu")
		(net "RST_SGPIO_RESET_N")
	)
	(segment
		(start 28.80614 -71.444358)
		(end 27.69108 -70.329298)
		(width 0.10668)
		(layer "In4.Cu")
		(net "RST_SGPIO_RESET_N")
	)
	(segment
		(start 35.19932 -42.03446)
		(end 35.35934 -42.03446)
		(width 0.10668)
		(layer "In4.Cu")
		(net "RST_SGPIO_RESET_N")
	)
	(segment
		(start 41.43756 -29.91612)
		(end 41.314878 -29.793438)
		(width 0.10668)
		(layer "In4.Cu")
		(net "RST_SGPIO_RESET_N")
	)
	(segment
		(start 41.58234 -38.524688)
		(end 41.58234 -36.226496)
		(width 0.10668)
		(layer "In4.Cu")
		(net "RST_SGPIO_RESET_N")
	)
	(segment
		(start 46.79442 -32.550354)
		(end 44.160186 -29.91612)
		(width 0.10668)
		(layer "In4.Cu")
		(net "RST_SGPIO_RESET_N")
	)
	(segment
		(start 35.35934 -42.03446)
		(end 37.23386 -40.15994)
		(width 0.10668)
		(layer "In4.Cu")
		(net "RST_SGPIO_RESET_N")
	)
	(segment
		(start 34.06648 -43.1673)
		(end 35.19932 -42.03446)
		(width 0.10668)
		(layer "In4.Cu")
		(net "RST_SGPIO_RESET_N")
	)
	(segment
		(start 28.31338 -77.37602)
		(end 29.156406 -76.532994)
		(width 0.10668)
		(layer "In4.Cu")
		(net "RST_SGPIO_RESET_N")
	)
	(segment
		(start 27.69616 -64.99098)
		(end 27.69616 -58.59526)
		(width 0.10668)
		(layer "In4.Cu")
		(net "RST_SGPIO_RESET_N")
	)
	(segment
		(start 28.1051 -92.3544)
		(end 28.5877 -92.3544)
		(width 0.10668)
		(layer "In7.Cu")
		(net "RST_SGPIO_RESET_N")
	)
	(segment
		(start 32.17672 -103.493062)
		(end 32.17672 -102.974902)
		(width 0.10668)
		(layer "In7.Cu")
		(net "RST_SGPIO_RESET_N")
	)
	(segment
		(start 28.067 -87.750396)
		(end 26.20772 -85.891116)
		(width 0.10668)
		(layer "In7.Cu")
		(net "RST_SGPIO_RESET_N")
	)
	(segment
		(start 32.17672 -102.974902)
		(end 28.64612 -99.444302)
		(width 0.10668)
		(layer "In7.Cu")
		(net "RST_SGPIO_RESET_N")
	)
	(segment
		(start 31.96336 -103.706422)
		(end 32.17672 -103.493062)
		(width 0.10668)
		(layer "In7.Cu")
		(net "RST_SGPIO_RESET_N")
	)
	(segment
		(start 31.96336 -105.87736)
		(end 31.96336 -103.706422)
		(width 0.10668)
		(layer "In7.Cu")
		(net "RST_SGPIO_RESET_N")
	)
	(segment
		(start 27.77236 -92.68714)
		(end 28.1051 -92.3544)
		(width 0.10668)
		(layer "In7.Cu")
		(net "RST_SGPIO_RESET_N")
	)
	(segment
		(start 28.5877 -92.3544)
		(end 28.81122 -92.13088)
		(width 0.10668)
		(layer "In7.Cu")
		(net "RST_SGPIO_RESET_N")
	)
	(segment
		(start 28.81122 -92.13088)
		(end 28.81122 -90.66022)
		(width 0.10668)
		(layer "In7.Cu")
		(net "RST_SGPIO_RESET_N")
	)
	(segment
		(start 32.987996 -106.901996)
		(end 31.96336 -105.87736)
		(width 0.10668)
		(layer "In7.Cu")
		(net "RST_SGPIO_RESET_N")
	)
	(segment
		(start 27.77236 -94.294706)
		(end 27.77236 -92.68714)
		(width 0.10668)
		(layer "In7.Cu")
		(net "RST_SGPIO_RESET_N")
	)
	(segment
		(start 28.81122 -90.66022)
		(end 28.067 -89.916)
		(width 0.10668)
		(layer "In7.Cu")
		(net "RST_SGPIO_RESET_N")
	)
	(segment
		(start 28.067 -89.916)
		(end 28.067 -87.750396)
		(width 0.10668)
		(layer "In7.Cu")
		(net "RST_SGPIO_RESET_N")
	)
	(segment
		(start 28.64612 -99.444302)
		(end 28.64612 -95.168466)
		(width 0.10668)
		(layer "In7.Cu")
		(net "RST_SGPIO_RESET_N")
	)
	(segment
		(start 33.79978 -106.901996)
		(end 32.987996 -106.901996)
		(width 0.10668)
		(layer "In7.Cu")
		(net "RST_SGPIO_RESET_N")
	)
	(segment
		(start 26.20772 -85.891116)
		(end 26.20772 -85.416644)
		(width 0.10668)
		(layer "In7.Cu")
		(net "RST_SGPIO_RESET_N")
	)
	(segment
		(start 28.64612 -95.168466)
		(end 27.77236 -94.294706)
		(width 0.10668)
		(layer "In7.Cu")
		(net "RST_SGPIO_RESET_N")
	)
	(segment
		(start 47.295054 -44.971208)
		(end 46.89983 -44.575984)
		(width 0.11684)
		(layer "F.Cu")
		(net "RST_SGPIO_RESET_BMC_N")
	)
	(via
		(at 43.7134 -37.1602)
		(size 0.508)
		(drill 0.254)
		(layers "F.Cu" "B.Cu")
		(net "RST_SGPIO_RESET_BMC_N")
	)
	(via
		(at 46.89983 -44.575984)
		(size 0.4572)
		(drill 0.254)
		(layers "F.Cu" "B.Cu")
		(net "RST_SGPIO_RESET_BMC_N")
	)
	(segment
		(start 41.674034 -34.359342)
		(end 41.674034 -35.248088)
		(width 0.11684)
		(layer "B.Cu")
		(net "RST_SGPIO_RESET_BMC_N")
	)
	(segment
		(start 41.314878 -31.216854)
		(end 41.314878 -32.026098)
		(width 0.11684)
		(layer "B.Cu")
		(net "RST_SGPIO_RESET_BMC_N")
	)
	(segment
		(start 42.6974 -35.7124)
		(end 43.2562 -36.2712)
		(width 0.11684)
		(layer "B.Cu")
		(net "RST_SGPIO_RESET_BMC_N")
	)
	(segment
		(start 41.674034 -35.248088)
		(end 42.138346 -35.7124)
		(width 0.11684)
		(layer "B.Cu")
		(net "RST_SGPIO_RESET_BMC_N")
	)
	(segment
		(start 42.138346 -35.7124)
		(end 42.6974 -35.7124)
		(width 0.11684)
		(layer "B.Cu")
		(net "RST_SGPIO_RESET_BMC_N")
	)
	(segment
		(start 40.631872 -32.709104)
		(end 40.631872 -33.31718)
		(width 0.11684)
		(layer "B.Cu")
		(net "RST_SGPIO_RESET_BMC_N")
	)
	(segment
		(start 43.2562 -36.2712)
		(end 43.2562 -36.703)
		(width 0.11684)
		(layer "B.Cu")
		(net "RST_SGPIO_RESET_BMC_N")
	)
	(segment
		(start 43.2562 -36.703)
		(end 43.7134 -37.1602)
		(width 0.11684)
		(layer "B.Cu")
		(net "RST_SGPIO_RESET_BMC_N")
	)
	(segment
		(start 40.631872 -33.31718)
		(end 41.674034 -34.359342)
		(width 0.11684)
		(layer "B.Cu")
		(net "RST_SGPIO_RESET_BMC_N")
	)
	(segment
		(start 41.314878 -32.026098)
		(end 40.631872 -32.709104)
		(width 0.11684)
		(layer "B.Cu")
		(net "RST_SGPIO_RESET_BMC_N")
	)
	(segment
		(start 48.4632 -38.1)
		(end 47.5234 -37.1602)
		(width 0.10668)
		(layer "In7.Cu")
		(net "RST_SGPIO_RESET_BMC_N")
	)
	(segment
		(start 46.51629 -42.817034)
		(end 46.740826 -42.592498)
		(width 0.10668)
		(layer "In7.Cu")
		(net "RST_SGPIO_RESET_BMC_N")
	)
	(segment
		(start 47.894748 -41.792398)
		(end 48.083216 -41.60393)
		(width 0.10668)
		(layer "In7.Cu")
		(net "RST_SGPIO_RESET_BMC_N")
	)
	(segment
		(start 48.4632 -40.006016)
		(end 48.4632 -38.1)
		(width 0.10668)
		(layer "In7.Cu")
		(net "RST_SGPIO_RESET_BMC_N")
	)
	(segment
		(start 47.316136 -42.016934)
		(end 47.540672 -41.792398)
		(width 0.10668)
		(layer "In7.Cu")
		(net "RST_SGPIO_RESET_BMC_N")
	)
	(segment
		(start 48.083216 -40.386)
		(end 48.4632 -40.006016)
		(width 0.10668)
		(layer "In7.Cu")
		(net "RST_SGPIO_RESET_BMC_N")
	)
	(segment
		(start 46.740826 -42.592498)
		(end 47.094648 -42.592498)
		(width 0.10668)
		(layer "In7.Cu")
		(net "RST_SGPIO_RESET_BMC_N")
	)
	(segment
		(start 47.094648 -42.592498)
		(end 47.316136 -42.37101)
		(width 0.10668)
		(layer "In7.Cu")
		(net "RST_SGPIO_RESET_BMC_N")
	)
	(segment
		(start 46.89983 -44.575984)
		(end 46.51629 -44.192444)
		(width 0.10668)
		(layer "In7.Cu")
		(net "RST_SGPIO_RESET_BMC_N")
	)
	(segment
		(start 47.5234 -37.1602)
		(end 43.7134 -37.1602)
		(width 0.10668)
		(layer "In7.Cu")
		(net "RST_SGPIO_RESET_BMC_N")
	)
	(segment
		(start 46.51629 -44.192444)
		(end 46.51629 -42.817034)
		(width 0.10668)
		(layer "In7.Cu")
		(net "RST_SGPIO_RESET_BMC_N")
	)
	(segment
		(start 47.316136 -42.37101)
		(end 47.316136 -42.016934)
		(width 0.10668)
		(layer "In7.Cu")
		(net "RST_SGPIO_RESET_BMC_N")
	)
	(segment
		(start 48.083216 -41.60393)
		(end 48.083216 -40.386)
		(width 0.10668)
		(layer "In7.Cu")
		(net "RST_SGPIO_RESET_BMC_N")
	)
	(segment
		(start 47.540672 -41.792398)
		(end 47.894748 -41.792398)
		(width 0.10668)
		(layer "In7.Cu")
		(net "RST_SGPIO_RESET_BMC_N")
	)
	(segment
		(start 30.15615 -86.995)
		(end 25.65146 -86.995)
		(width 0.11684)
		(layer "F.Cu")
		(net "RST_PLTRST_R1_N")
	)
	(segment
		(start 25.65146 -86.995)
		(end 25.059386 -87.587074)
		(width 0.11684)
		(layer "F.Cu")
		(net "RST_PLTRST_R1_N")
	)
	(segment
		(start 19.064224 -92.791788)
		(end 19.459448 -93.187012)
		(width 0.11684)
		(layer "F.Cu")
		(net "RST_MB_STBY_R_N")
	)
	(via
		(at 19.064224 -92.791788)
		(size 0.4572)
		(drill 0.254)
		(layers "F.Cu" "B.Cu")
		(net "RST_MB_STBY_R_N")
	)
	(segment
		(start 18.808954 -93.408246)
		(end 19.064224 -92.791788)
		(width 0.11684)
		(layer "B.Cu")
		(net "RST_MB_STBY_R_N")
	)
	(segment
		(start 16.891254 -93.904054)
		(end 18.313146 -93.904054)
		(width 0.11684)
		(layer "B.Cu")
		(net "RST_MB_STBY_R_N")
	)
	(segment
		(start 18.313146 -93.904054)
		(end 18.808954 -93.408246)
		(width 0.11684)
		(layer "B.Cu")
		(net "RST_MB_STBY_R_N")
	)
	(segment
		(start 16.383 -93.3958)
		(end 16.891254 -93.904054)
		(width 0.11684)
		(layer "B.Cu")
		(net "RST_MB_STBY_R_N")
	)
	(segment
		(start 15.25905 -93.3958)
		(end 16.383 -93.3958)
		(width 0.11684)
		(layer "B.Cu")
		(net "RST_MB_STBY_R_N")
	)
	(via
		(at 14.044676 -93.911166)
		(size 0.508)
		(drill 0.254)
		(layers "F.Cu" "B.Cu")
		(net "RST_MB_STBY_N")
	)
	(via
		(at 31.9151 -93.6371)
		(size 0.508)
		(drill 0.254)
		(layers "F.Cu" "B.Cu")
		(net "RST_MB_STBY_N")
	)
	(via
		(at 28.32354 -110.41634)
		(size 0.508)
		(drill 0.254)
		(layers "F.Cu" "B.Cu")
		(net "RST_MB_STBY_N")
	)
	(segment
		(start 28.744926 -118.460012)
		(end 28.744926 -117.15242)
		(width 0.11684)
		(layer "B.Cu")
		(net "RST_MB_STBY_N")
	)
	(segment
		(start 29.3497 -111.4425)
		(end 28.32354 -110.41634)
		(width 0.11684)
		(layer "B.Cu")
		(net "RST_MB_STBY_N")
	)
	(segment
		(start 14.161516 -93.3958)
		(end 14.044676 -93.51264)
		(width 0.11684)
		(layer "B.Cu")
		(net "RST_MB_STBY_N")
	)
	(segment
		(start 28.744926 -117.15242)
		(end 29.3497 -116.547646)
		(width 0.11684)
		(layer "B.Cu")
		(net "RST_MB_STBY_N")
	)
	(segment
		(start 14.45895 -93.3958)
		(end 14.161516 -93.3958)
		(width 0.11684)
		(layer "B.Cu")
		(net "RST_MB_STBY_N")
	)
	(segment
		(start 29.3497 -116.547646)
		(end 29.3497 -111.4425)
		(width 0.11684)
		(layer "B.Cu")
		(net "RST_MB_STBY_N")
	)
	(segment
		(start 14.044676 -93.51264)
		(end 14.044676 -93.911166)
		(width 0.11684)
		(layer "B.Cu")
		(net "RST_MB_STBY_N")
	)
	(segment
		(start 14.382242 -93.5736)
		(end 14.044676 -93.911166)
		(width 0.08382)
		(layer "In2.Cu")
		(net "RST_MB_STBY_N")
	)
	(segment
		(start 28.97632 -94.77248)
		(end 27.78252 -94.77248)
		(width 0.08382)
		(layer "In2.Cu")
		(net "RST_MB_STBY_N")
	)
	(segment
		(start 17.3482 -93.5736)
		(end 14.382242 -93.5736)
		(width 0.08382)
		(layer "In2.Cu")
		(net "RST_MB_STBY_N")
	)
	(segment
		(start 31.9151 -93.6371)
		(end 30.1117 -93.6371)
		(width 0.08382)
		(layer "In2.Cu")
		(net "RST_MB_STBY_N")
	)
	(segment
		(start 30.1117 -93.6371)
		(end 28.97632 -94.77248)
		(width 0.08382)
		(layer "In2.Cu")
		(net "RST_MB_STBY_N")
	)
	(segment
		(start 17.5006 -93.4212)
		(end 17.3482 -93.5736)
		(width 0.08382)
		(layer "In2.Cu")
		(net "RST_MB_STBY_N")
	)
	(segment
		(start 26.43124 -93.4212)
		(end 17.5006 -93.4212)
		(width 0.08382)
		(layer "In2.Cu")
		(net "RST_MB_STBY_N")
	)
	(segment
		(start 27.78252 -94.77248)
		(end 26.43124 -93.4212)
		(width 0.08382)
		(layer "In2.Cu")
		(net "RST_MB_STBY_N")
	)
	(segment
		(start 30.540198 -94.363286)
		(end 30.540198 -94.835218)
		(width 0.10668)
		(layer "In4.Cu")
		(net "RST_MB_STBY_N")
	)
	(segment
		(start 33.65246 -105.959656)
		(end 33.655 -105.962196)
		(width 0.10668)
		(layer "In4.Cu")
		(net "RST_MB_STBY_N")
	)
	(segment
		(start 30.540198 -94.835218)
		(end 30.7594 -95.05442)
		(width 0.10668)
		(layer "In4.Cu")
		(net "RST_MB_STBY_N")
	)
	(segment
		(start 33.29686 -103.794052)
		(end 33.29686 -104.95026)
		(width 0.10668)
		(layer "In4.Cu")
		(net "RST_MB_STBY_N")
	)
	(segment
		(start 30.910784 -93.9927)
		(end 30.540198 -94.363286)
		(width 0.10668)
		(layer "In4.Cu")
		(net "RST_MB_STBY_N")
	)
	(segment
		(start 31.5595 -93.9927)
		(end 30.910784 -93.9927)
		(width 0.10668)
		(layer "In4.Cu")
		(net "RST_MB_STBY_N")
	)
	(segment
		(start 33.655 -105.3084)
		(end 33.655 -105.576116)
		(width 0.10668)
		(layer "In4.Cu")
		(net "RST_MB_STBY_N")
	)
	(segment
		(start 33.65246 -105.578656)
		(end 33.65246 -105.959656)
		(width 0.10668)
		(layer "In4.Cu")
		(net "RST_MB_STBY_N")
	)
	(segment
		(start 33.655 -105.576116)
		(end 33.65246 -105.578656)
		(width 0.10668)
		(layer "In4.Cu")
		(net "RST_MB_STBY_N")
	)
	(segment
		(start 33.34004 -106.711496)
		(end 33.34004 -107.894882)
		(width 0.10668)
		(layer "In4.Cu")
		(net "RST_MB_STBY_N")
	)
	(segment
		(start 33.29686 -104.95026)
		(end 33.655 -105.3084)
		(width 0.10668)
		(layer "In4.Cu")
		(net "RST_MB_STBY_N")
	)
	(segment
		(start 30.7594 -97.050098)
		(end 29.6418 -98.167698)
		(width 0.10668)
		(layer "In4.Cu")
		(net "RST_MB_STBY_N")
	)
	(segment
		(start 29.6418 -98.167698)
		(end 29.6418 -100.138992)
		(width 0.10668)
		(layer "In4.Cu")
		(net "RST_MB_STBY_N")
	)
	(segment
		(start 30.7594 -95.05442)
		(end 30.7594 -97.050098)
		(width 0.10668)
		(layer "In4.Cu")
		(net "RST_MB_STBY_N")
	)
	(segment
		(start 33.655 -105.962196)
		(end 33.655 -106.396536)
		(width 0.10668)
		(layer "In4.Cu")
		(net "RST_MB_STBY_N")
	)
	(segment
		(start 33.34004 -107.894882)
		(end 34.9631 -109.517942)
		(width 0.10668)
		(layer "In4.Cu")
		(net "RST_MB_STBY_N")
	)
	(segment
		(start 29.39796 -111.49076)
		(end 28.32354 -110.41634)
		(width 0.10668)
		(layer "In4.Cu")
		(net "RST_MB_STBY_N")
	)
	(segment
		(start 34.9631 -109.517942)
		(end 34.9631 -110.62716)
		(width 0.10668)
		(layer "In4.Cu")
		(net "RST_MB_STBY_N")
	)
	(segment
		(start 34.9631 -110.62716)
		(end 34.0995 -111.49076)
		(width 0.10668)
		(layer "In4.Cu")
		(net "RST_MB_STBY_N")
	)
	(segment
		(start 34.0995 -111.49076)
		(end 29.39796 -111.49076)
		(width 0.10668)
		(layer "In4.Cu")
		(net "RST_MB_STBY_N")
	)
	(segment
		(start 29.6418 -100.138992)
		(end 33.29686 -103.794052)
		(width 0.10668)
		(layer "In4.Cu")
		(net "RST_MB_STBY_N")
	)
	(segment
		(start 31.9151 -93.6371)
		(end 31.5595 -93.9927)
		(width 0.10668)
		(layer "In4.Cu")
		(net "RST_MB_STBY_N")
	)
	(segment
		(start 33.655 -106.396536)
		(end 33.34004 -106.711496)
		(width 0.10668)
		(layer "In4.Cu")
		(net "RST_MB_STBY_N")
	)
	(segment
		(start 61.665104 -118.25986)
		(end 61.665104 -114.483896)
		(width 0.11684)
		(layer "F.Cu")
		(net "RST_BMC_LPC_ESPI_N")
	)
	(segment
		(start 61.81725 -114.33175)
		(end 61.81725 -113.88725)
		(width 0.11684)
		(layer "F.Cu")
		(net "RST_BMC_LPC_ESPI_N")
	)
	(segment
		(start 61.665104 -114.483896)
		(end 61.81725 -114.33175)
		(width 0.11684)
		(layer "F.Cu")
		(net "RST_BMC_LPC_ESPI_N")
	)
	(via
		(at 61.81725 -113.88725)
		(size 0.508)
		(drill 0.254)
		(layers "F.Cu" "B.Cu")
		(net "RST_BMC_LPC_ESPI_N")
	)
	(via
		(at 65.5574 -74.95032)
		(size 0.508)
		(drill 0.254)
		(layers "F.Cu" "B.Cu")
		(net "RST_BMC_LPC_ESPI_N")
	)
	(segment
		(start 64.4906 -71.628)
		(end 65.024 -72.1614)
		(width 0.11684)
		(layer "B.Cu")
		(net "RST_BMC_LPC_ESPI_N")
	)
	(segment
		(start 65.024 -72.1614)
		(end 65.024 -74.41692)
		(width 0.11684)
		(layer "B.Cu")
		(net "RST_BMC_LPC_ESPI_N")
	)
	(segment
		(start 65.323974 -70.296024)
		(end 65.405 -70.37705)
		(width 0.11684)
		(layer "B.Cu")
		(net "RST_BMC_LPC_ESPI_N")
	)
	(segment
		(start 64.364108 -71.317612)
		(end 64.4906 -71.444104)
		(width 0.11684)
		(layer "B.Cu")
		(net "RST_BMC_LPC_ESPI_N")
	)
	(segment
		(start 65.024 -74.41692)
		(end 65.5574 -74.95032)
		(width 0.11684)
		(layer "B.Cu")
		(net "RST_BMC_LPC_ESPI_N")
	)
	(segment
		(start 64.364108 -71.317612)
		(end 64.364108 -70.296024)
		(width 0.11684)
		(layer "B.Cu")
		(net "RST_BMC_LPC_ESPI_N")
	)
	(segment
		(start 64.4906 -71.444104)
		(end 64.4906 -71.628)
		(width 0.11684)
		(layer "B.Cu")
		(net "RST_BMC_LPC_ESPI_N")
	)
	(segment
		(start 64.364108 -70.296024)
		(end 65.323974 -70.296024)
		(width 0.11684)
		(layer "B.Cu")
		(net "RST_BMC_LPC_ESPI_N")
	)
	(segment
		(start 65.53454 -85.03666)
		(end 65.98666 -84.58454)
		(width 0.10668)
		(layer "In4.Cu")
		(net "RST_BMC_LPC_ESPI_N")
	)
	(segment
		(start 67.75196 -79.9592)
		(end 67.4878 -79.69504)
		(width 0.10668)
		(layer "In4.Cu")
		(net "RST_BMC_LPC_ESPI_N")
	)
	(segment
		(start 67.75196 -83.03006)
		(end 67.75196 -79.9592)
		(width 0.10668)
		(layer "In4.Cu")
		(net "RST_BMC_LPC_ESPI_N")
	)
	(segment
		(start 66.69278 -83.87842)
		(end 66.9036 -83.87842)
		(width 0.10668)
		(layer "In4.Cu")
		(net "RST_BMC_LPC_ESPI_N")
	)
	(segment
		(start 64.5922 -88.011)
		(end 64.5922 -86.98738)
		(width 0.10668)
		(layer "In4.Cu")
		(net "RST_BMC_LPC_ESPI_N")
	)
	(segment
		(start 65.53454 -86.04504)
		(end 65.53454 -85.03666)
		(width 0.10668)
		(layer "In4.Cu")
		(net "RST_BMC_LPC_ESPI_N")
	)
	(segment
		(start 65.98666 -84.58454)
		(end 65.98666 -84.5693)
		(width 0.10668)
		(layer "In4.Cu")
		(net "RST_BMC_LPC_ESPI_N")
	)
	(segment
		(start 64.79794 -102.73284)
		(end 64.79794 -88.21674)
		(width 0.10668)
		(layer "In4.Cu")
		(net "RST_BMC_LPC_ESPI_N")
	)
	(segment
		(start 66.32194 -77.65034)
		(end 66.32194 -75.71486)
		(width 0.10668)
		(layer "In4.Cu")
		(net "RST_BMC_LPC_ESPI_N")
	)
	(segment
		(start 61.81725 -112.57915)
		(end 65.1256 -109.2708)
		(width 0.10668)
		(layer "In4.Cu")
		(net "RST_BMC_LPC_ESPI_N")
	)
	(segment
		(start 67.4878 -79.69504)
		(end 67.4878 -78.8162)
		(width 0.10668)
		(layer "In4.Cu")
		(net "RST_BMC_LPC_ESPI_N")
	)
	(segment
		(start 64.5922 -86.98738)
		(end 65.53454 -86.04504)
		(width 0.10668)
		(layer "In4.Cu")
		(net "RST_BMC_LPC_ESPI_N")
	)
	(segment
		(start 66.32194 -75.71486)
		(end 65.5574 -74.95032)
		(width 0.10668)
		(layer "In4.Cu")
		(net "RST_BMC_LPC_ESPI_N")
	)
	(segment
		(start 67.4878 -78.8162)
		(end 66.32194 -77.65034)
		(width 0.10668)
		(layer "In4.Cu")
		(net "RST_BMC_LPC_ESPI_N")
	)
	(segment
		(start 61.81725 -113.88725)
		(end 61.81725 -112.57915)
		(width 0.10668)
		(layer "In4.Cu")
		(net "RST_BMC_LPC_ESPI_N")
	)
	(segment
		(start 65.1256 -103.0605)
		(end 64.79794 -102.73284)
		(width 0.10668)
		(layer "In4.Cu")
		(net "RST_BMC_LPC_ESPI_N")
	)
	(segment
		(start 65.98666 -84.5693)
		(end 66.2559 -84.30006)
		(width 0.10668)
		(layer "In4.Cu")
		(net "RST_BMC_LPC_ESPI_N")
	)
	(segment
		(start 66.9036 -83.87842)
		(end 67.75196 -83.03006)
		(width 0.10668)
		(layer "In4.Cu")
		(net "RST_BMC_LPC_ESPI_N")
	)
	(segment
		(start 66.2559 -84.30006)
		(end 66.27114 -84.30006)
		(width 0.10668)
		(layer "In4.Cu")
		(net "RST_BMC_LPC_ESPI_N")
	)
	(segment
		(start 64.79794 -88.21674)
		(end 64.5922 -88.011)
		(width 0.10668)
		(layer "In4.Cu")
		(net "RST_BMC_LPC_ESPI_N")
	)
	(segment
		(start 66.27114 -84.30006)
		(end 66.69278 -83.87842)
		(width 0.10668)
		(layer "In4.Cu")
		(net "RST_BMC_LPC_ESPI_N")
	)
	(segment
		(start 65.1256 -109.2708)
		(end 65.1256 -103.0605)
		(width 0.10668)
		(layer "In4.Cu")
		(net "RST_BMC_LPC_ESPI_N")
	)
	(via
		(at 75.87107 -93.758258)
		(size 0.6604)
		(drill 0.3302)
		(layers "F.Cu" "B.Cu")
		(net "Q7_D")
	)
	(segment
		(start 74.717148 -93.758258)
		(end 75.87107 -93.758258)
		(width 0.11684)
		(layer "B.Cu")
		(net "Q7_D")
	)
	(segment
		(start 75.75677 -95.509842)
		(end 75.87107 -95.395542)
		(width 0.11684)
		(layer "B.Cu")
		(net "Q7_D")
	)
	(segment
		(start 75.87107 -95.395542)
		(end 75.87107 -93.758258)
		(width 0.11684)
		(layer "B.Cu")
		(net "Q7_D")
	)
	(segment
		(start 74.715878 -95.509842)
		(end 75.75677 -95.509842)
		(width 0.11684)
		(layer "B.Cu")
		(net "Q7_D")
	)
	(segment
		(start 11.91895 -97.536)
		(end 11.30935 -97.536)
		(width 0.11684)
		(layer "F.Cu")
		(net "PWRGD_SYS_PWROK")
	)
	(segment
		(start 56.7182 -30.46095)
		(end 56.7182 -29.8196)
		(width 0.11684)
		(layer "F.Cu")
		(net "PWRGD_SYS_PWROK")
	)
	(via
		(at 56.7182 -29.8196)
		(size 0.508)
		(drill 0.254)
		(layers "F.Cu" "B.Cu")
		(net "PWRGD_SYS_PWROK")
	)
	(via
		(at 49.4792 -86.7918)
		(size 0.508)
		(drill 0.254)
		(layers "F.Cu" "B.Cu")
		(net "PWRGD_SYS_PWROK")
	)
	(via
		(at 23.687786 -107.7468)
		(size 0.508)
		(drill 0.254)
		(layers "F.Cu" "B.Cu")
		(net "PWRGD_SYS_PWROK")
	)
	(via
		(at 11.30935 -97.536)
		(size 0.508)
		(drill 0.254)
		(layers "F.Cu" "B.Cu")
		(net "PWRGD_SYS_PWROK")
	)
	(via
		(at 7.4676 -109.4486)
		(size 0.508)
		(drill 0.254)
		(layers "F.Cu" "B.Cu")
		(net "PWRGD_SYS_PWROK")
	)
	(via
		(at 51.8414 -17.1196)
		(size 0.508)
		(drill 0.254)
		(layers "F.Cu" "B.Cu")
		(net "PWRGD_SYS_PWROK")
	)
	(segment
		(start 9.0424 -99.1616)
		(end 9.0424 -99.6696)
		(width 0.11684)
		(layer "B.Cu")
		(net "PWRGD_SYS_PWROK")
	)
	(segment
		(start 8.8392 -99.8728)
		(end 8.8392 -102.613968)
		(width 0.11684)
		(layer "B.Cu")
		(net "PWRGD_SYS_PWROK")
	)
	(segment
		(start 51.8414 -17.73936)
		(end 54.5592 -20.45716)
		(width 0.11684)
		(layer "B.Cu")
		(net "PWRGD_SYS_PWROK")
	)
	(segment
		(start 28.55722 -116.171726)
		(end 28.55722 -112.806988)
		(width 0.11684)
		(layer "B.Cu")
		(net "PWRGD_SYS_PWROK")
	)
	(segment
		(start 23.687786 -107.937554)
		(end 23.687786 -107.7468)
		(width 0.11684)
		(layer "B.Cu")
		(net "PWRGD_SYS_PWROK")
	)
	(segment
		(start 23.687786 -107.7468)
		(end 23.687786 -107.02417)
		(width 0.11684)
		(layer "B.Cu")
		(net "PWRGD_SYS_PWROK")
	)
	(segment
		(start 54.2544 -28.5496)
		(end 55.5244 -29.8196)
		(width 0.11684)
		(layer "B.Cu")
		(net "PWRGD_SYS_PWROK")
	)
	(segment
		(start 27.54503 -118.25986)
		(end 27.54503 -117.183916)
		(width 0.11684)
		(layer "B.Cu")
		(net "PWRGD_SYS_PWROK")
	)
	(segment
		(start 51.8414 -17.1196)
		(end 51.8414 -17.73936)
		(width 0.11684)
		(layer "B.Cu")
		(net "PWRGD_SYS_PWROK")
	)
	(segment
		(start 54.5592 -26.5176)
		(end 54.2544 -26.8224)
		(width 0.11684)
		(layer "B.Cu")
		(net "PWRGD_SYS_PWROK")
	)
	(segment
		(start 9.0424 -99.6696)
		(end 8.8392 -99.8728)
		(width 0.11684)
		(layer "B.Cu")
		(net "PWRGD_SYS_PWROK")
	)
	(segment
		(start 50.2285 -86.0425)
		(end 50.97145 -86.0425)
		(width 0.11684)
		(layer "B.Cu")
		(net "PWRGD_SYS_PWROK")
	)
	(segment
		(start 10.668 -97.536)
		(end 9.0424 -99.1616)
		(width 0.11684)
		(layer "B.Cu")
		(net "PWRGD_SYS_PWROK")
	)
	(segment
		(start 11.30935 -97.536)
		(end 10.668 -97.536)
		(width 0.11684)
		(layer "B.Cu")
		(net "PWRGD_SYS_PWROK")
	)
	(segment
		(start 7.1628 -109.1438)
		(end 7.4676 -109.4486)
		(width 0.11684)
		(layer "B.Cu")
		(net "PWRGD_SYS_PWROK")
	)
	(segment
		(start 28.55722 -112.806988)
		(end 23.687786 -107.937554)
		(width 0.11684)
		(layer "B.Cu")
		(net "PWRGD_SYS_PWROK")
	)
	(segment
		(start 49.4792 -86.7918)
		(end 50.2285 -86.0425)
		(width 0.11684)
		(layer "B.Cu")
		(net "PWRGD_SYS_PWROK")
	)
	(segment
		(start 8.8392 -102.613968)
		(end 7.1628 -104.290368)
		(width 0.11684)
		(layer "B.Cu")
		(net "PWRGD_SYS_PWROK")
	)
	(segment
		(start 23.687786 -107.02417)
		(end 23.573486 -106.90987)
		(width 0.11684)
		(layer "B.Cu")
		(net "PWRGD_SYS_PWROK")
	)
	(segment
		(start 54.2544 -26.8224)
		(end 54.2544 -28.5496)
		(width 0.11684)
		(layer "B.Cu")
		(net "PWRGD_SYS_PWROK")
	)
	(segment
		(start 27.54503 -117.183916)
		(end 28.55722 -116.171726)
		(width 0.11684)
		(layer "B.Cu")
		(net "PWRGD_SYS_PWROK")
	)
	(segment
		(start 55.5244 -29.8196)
		(end 56.7182 -29.8196)
		(width 0.11684)
		(layer "B.Cu")
		(net "PWRGD_SYS_PWROK")
	)
	(segment
		(start 7.1628 -104.290368)
		(end 7.1628 -109.1438)
		(width 0.11684)
		(layer "B.Cu")
		(net "PWRGD_SYS_PWROK")
	)
	(segment
		(start 54.5592 -20.45716)
		(end 54.5592 -26.5176)
		(width 0.11684)
		(layer "B.Cu")
		(net "PWRGD_SYS_PWROK")
	)
	(segment
		(start 10.42162 -94.11462)
		(end 10.4902 -94.04604)
		(width 0.08382)
		(layer "In2.Cu")
		(net "PWRGD_SYS_PWROK")
	)
	(segment
		(start 15.239746 -87.5792)
		(end 20.9804 -87.5792)
		(width 0.08382)
		(layer "In2.Cu")
		(net "PWRGD_SYS_PWROK")
	)
	(segment
		(start 8.1788 -109.4486)
		(end 9.22147 -108.40593)
		(width 0.08382)
		(layer "In2.Cu")
		(net "PWRGD_SYS_PWROK")
	)
	(segment
		(start 24.44115 -87.217504)
		(end 24.739854 -86.9188)
		(width 0.08382)
		(layer "In2.Cu")
		(net "PWRGD_SYS_PWROK")
	)
	(segment
		(start 20.9804 -87.5792)
		(end 21.342096 -87.217504)
		(width 0.08382)
		(layer "In2.Cu")
		(net "PWRGD_SYS_PWROK")
	)
	(segment
		(start 35.36696 -89.027)
		(end 37.727128 -89.027)
		(width 0.08382)
		(layer "In2.Cu")
		(net "PWRGD_SYS_PWROK")
	)
	(segment
		(start 47.371 -87.87384)
		(end 47.371 -87.26424)
		(width 0.08382)
		(layer "In2.Cu")
		(net "PWRGD_SYS_PWROK")
	)
	(segment
		(start 11.72718 -89.72042)
		(end 14.1478 -87.2998)
		(width 0.08382)
		(layer "In2.Cu")
		(net "PWRGD_SYS_PWROK")
	)
	(segment
		(start 15.316454 -106.958892)
		(end 17.171162 -108.8136)
		(width 0.08382)
		(layer "In2.Cu")
		(net "PWRGD_SYS_PWROK")
	)
	(segment
		(start 27.694382 -87.0458)
		(end 30.006036 -87.0458)
		(width 0.08382)
		(layer "In2.Cu")
		(net "PWRGD_SYS_PWROK")
	)
	(segment
		(start 11.30935 -97.536)
		(end 10.42162 -96.64827)
		(width 0.08382)
		(layer "In2.Cu")
		(net "PWRGD_SYS_PWROK")
	)
	(segment
		(start 7.4676 -109.4486)
		(end 8.1788 -109.4486)
		(width 0.08382)
		(layer "In2.Cu")
		(net "PWRGD_SYS_PWROK")
	)
	(segment
		(start 11.94943 -108.40593)
		(end 13.396468 -106.958892)
		(width 0.08382)
		(layer "In2.Cu")
		(net "PWRGD_SYS_PWROK")
	)
	(segment
		(start 33.27654 -86.93658)
		(end 35.36696 -89.027)
		(width 0.08382)
		(layer "In2.Cu")
		(net "PWRGD_SYS_PWROK")
	)
	(segment
		(start 30.115256 -86.93658)
		(end 33.27654 -86.93658)
		(width 0.08382)
		(layer "In2.Cu")
		(net "PWRGD_SYS_PWROK")
	)
	(segment
		(start 10.42162 -96.64827)
		(end 10.42162 -94.11462)
		(width 0.08382)
		(layer "In2.Cu")
		(net "PWRGD_SYS_PWROK")
	)
	(segment
		(start 11.683746 -89.7636)
		(end 11.726926 -89.72042)
		(width 0.08382)
		(layer "In2.Cu")
		(net "PWRGD_SYS_PWROK")
	)
	(segment
		(start 14.1478 -87.2998)
		(end 14.960346 -87.2998)
		(width 0.08382)
		(layer "In2.Cu")
		(net "PWRGD_SYS_PWROK")
	)
	(segment
		(start 9.22147 -108.40593)
		(end 11.94943 -108.40593)
		(width 0.08382)
		(layer "In2.Cu")
		(net "PWRGD_SYS_PWROK")
	)
	(segment
		(start 23.687786 -108.366814)
		(end 23.687786 -107.7468)
		(width 0.08382)
		(layer "In2.Cu")
		(net "PWRGD_SYS_PWROK")
	)
	(segment
		(start 13.396468 -106.958892)
		(end 15.316454 -106.958892)
		(width 0.08382)
		(layer "In2.Cu")
		(net "PWRGD_SYS_PWROK")
	)
	(segment
		(start 10.4902 -94.04604)
		(end 10.4902 -90.233246)
		(width 0.08382)
		(layer "In2.Cu")
		(net "PWRGD_SYS_PWROK")
	)
	(segment
		(start 24.739854 -86.9188)
		(end 24.883618 -86.9188)
		(width 0.08382)
		(layer "In2.Cu")
		(net "PWRGD_SYS_PWROK")
	)
	(segment
		(start 40.411908 -91.71178)
		(end 43.53306 -91.71178)
		(width 0.08382)
		(layer "In2.Cu")
		(net "PWRGD_SYS_PWROK")
	)
	(segment
		(start 10.4902 -90.233246)
		(end 10.959846 -89.7636)
		(width 0.08382)
		(layer "In2.Cu")
		(net "PWRGD_SYS_PWROK")
	)
	(segment
		(start 30.006036 -87.0458)
		(end 30.115256 -86.93658)
		(width 0.08382)
		(layer "In2.Cu")
		(net "PWRGD_SYS_PWROK")
	)
	(segment
		(start 24.883618 -86.9188)
		(end 24.891238 -86.91118)
		(width 0.08382)
		(layer "In2.Cu")
		(net "PWRGD_SYS_PWROK")
	)
	(segment
		(start 47.911766 -86.723474)
		(end 49.410874 -86.723474)
		(width 0.08382)
		(layer "In2.Cu")
		(net "PWRGD_SYS_PWROK")
	)
	(segment
		(start 10.959846 -89.7636)
		(end 11.683746 -89.7636)
		(width 0.08382)
		(layer "In2.Cu")
		(net "PWRGD_SYS_PWROK")
	)
	(segment
		(start 17.171162 -108.8136)
		(end 23.241 -108.8136)
		(width 0.08382)
		(layer "In2.Cu")
		(net "PWRGD_SYS_PWROK")
	)
	(segment
		(start 47.371 -87.26424)
		(end 47.911766 -86.723474)
		(width 0.08382)
		(layer "In2.Cu")
		(net "PWRGD_SYS_PWROK")
	)
	(segment
		(start 27.559762 -86.91118)
		(end 27.694382 -87.0458)
		(width 0.08382)
		(layer "In2.Cu")
		(net "PWRGD_SYS_PWROK")
	)
	(segment
		(start 21.342096 -87.217504)
		(end 24.44115 -87.217504)
		(width 0.08382)
		(layer "In2.Cu")
		(net "PWRGD_SYS_PWROK")
	)
	(segment
		(start 23.241 -108.8136)
		(end 23.687786 -108.366814)
		(width 0.08382)
		(layer "In2.Cu")
		(net "PWRGD_SYS_PWROK")
	)
	(segment
		(start 49.410874 -86.723474)
		(end 49.4792 -86.7918)
		(width 0.08382)
		(layer "In2.Cu")
		(net "PWRGD_SYS_PWROK")
	)
	(segment
		(start 14.960346 -87.2998)
		(end 15.239746 -87.5792)
		(width 0.08382)
		(layer "In2.Cu")
		(net "PWRGD_SYS_PWROK")
	)
	(segment
		(start 37.727128 -89.027)
		(end 40.411908 -91.71178)
		(width 0.08382)
		(layer "In2.Cu")
		(net "PWRGD_SYS_PWROK")
	)
	(segment
		(start 24.891238 -86.91118)
		(end 27.559762 -86.91118)
		(width 0.08382)
		(layer "In2.Cu")
		(net "PWRGD_SYS_PWROK")
	)
	(segment
		(start 11.726926 -89.72042)
		(end 11.72718 -89.72042)
		(width 0.08382)
		(layer "In2.Cu")
		(net "PWRGD_SYS_PWROK")
	)
	(segment
		(start 43.53306 -91.71178)
		(end 47.371 -87.87384)
		(width 0.08382)
		(layer "In2.Cu")
		(net "PWRGD_SYS_PWROK")
	)
	(segment
		(start 37.730938 -13.87348)
		(end 35.217862 -13.87348)
		(width 0.10668)
		(layer "In7.Cu")
		(net "PWRGD_SYS_PWROK")
	)
	(segment
		(start 2.176272 -77.58049)
		(end 4.926076 -80.330294)
		(width 0.10668)
		(layer "In7.Cu")
		(net "PWRGD_SYS_PWROK")
	)
	(segment
		(start 39.153338 -12.45108)
		(end 37.730938 -13.87348)
		(width 0.10668)
		(layer "In7.Cu")
		(net "PWRGD_SYS_PWROK")
	)
	(segment
		(start 33.525968 -12.181586)
		(end 33.525968 -11.624818)
		(width 0.10668)
		(layer "In7.Cu")
		(net "PWRGD_SYS_PWROK")
	)
	(segment
		(start 26.0858 -9.4742)
		(end 25.37968 -8.76808)
		(width 0.10668)
		(layer "In7.Cu")
		(net "PWRGD_SYS_PWROK")
	)
	(segment
		(start 8.8392 -19.4818)
		(end 4.778248 -19.4818)
		(width 0.10668)
		(layer "In7.Cu")
		(net "PWRGD_SYS_PWROK")
	)
	(segment
		(start 25.37968 -8.76808)
		(end 14.688566 -8.76808)
		(width 0.10668)
		(layer "In7.Cu")
		(net "PWRGD_SYS_PWROK")
	)
	(segment
		(start 2.959354 -87.575898)
		(end 2.959354 -89.948004)
		(width 0.10668)
		(layer "In7.Cu")
		(net "PWRGD_SYS_PWROK")
	)
	(segment
		(start 26.245312 -13.293852)
		(end 26.0858 -13.13434)
		(width 0.10668)
		(layer "In7.Cu")
		(net "PWRGD_SYS_PWROK")
	)
	(segment
		(start 4.01574 -106.32694)
		(end 7.1374 -109.4486)
		(width 0.10668)
		(layer "In7.Cu")
		(net "PWRGD_SYS_PWROK")
	)
	(segment
		(start 12.297664 -8.657336)
		(end 9.906 -11.049)
		(width 0.10668)
		(layer "In7.Cu")
		(net "PWRGD_SYS_PWROK")
	)
	(segment
		(start 14.688566 -8.76808)
		(end 14.577822 -8.657336)
		(width 0.10668)
		(layer "In7.Cu")
		(net "PWRGD_SYS_PWROK")
	)
	(segment
		(start 2.176272 -22.083776)
		(end 2.176272 -77.58049)
		(width 0.10668)
		(layer "In7.Cu")
		(net "PWRGD_SYS_PWROK")
	)
	(segment
		(start 2.959354 -89.948004)
		(end 4.01574 -91.00439)
		(width 0.10668)
		(layer "In7.Cu")
		(net "PWRGD_SYS_PWROK")
	)
	(segment
		(start 14.577822 -8.657336)
		(end 12.297664 -8.657336)
		(width 0.10668)
		(layer "In7.Cu")
		(net "PWRGD_SYS_PWROK")
	)
	(segment
		(start 30.665928 -12.145264)
		(end 28.103068 -12.145264)
		(width 0.10668)
		(layer "In7.Cu")
		(net "PWRGD_SYS_PWROK")
	)
	(segment
		(start 9.906 -18.415)
		(end 8.8392 -19.4818)
		(width 0.10668)
		(layer "In7.Cu")
		(net "PWRGD_SYS_PWROK")
	)
	(segment
		(start 4.926076 -85.03285)
		(end 4.51866 -86.016592)
		(width 0.10668)
		(layer "In7.Cu")
		(net "PWRGD_SYS_PWROK")
	)
	(segment
		(start 26.0858 -13.13434)
		(end 26.0858 -9.4742)
		(width 0.10668)
		(layer "In7.Cu")
		(net "PWRGD_SYS_PWROK")
	)
	(segment
		(start 4.926076 -80.330294)
		(end 4.926076 -85.03285)
		(width 0.10668)
		(layer "In7.Cu")
		(net "PWRGD_SYS_PWROK")
	)
	(segment
		(start 4.01574 -91.00439)
		(end 4.01574 -106.32694)
		(width 0.10668)
		(layer "In7.Cu")
		(net "PWRGD_SYS_PWROK")
	)
	(segment
		(start 51.51882 -17.1196)
		(end 46.8503 -12.45108)
		(width 0.10668)
		(layer "In7.Cu")
		(net "PWRGD_SYS_PWROK")
	)
	(segment
		(start 7.1374 -109.4486)
		(end 7.4676 -109.4486)
		(width 0.10668)
		(layer "In7.Cu")
		(net "PWRGD_SYS_PWROK")
	)
	(segment
		(start 4.51866 -86.016592)
		(end 2.959354 -87.575898)
		(width 0.10668)
		(layer "In7.Cu")
		(net "PWRGD_SYS_PWROK")
	)
	(segment
		(start 33.525968 -11.624818)
		(end 32.822896 -10.921746)
		(width 0.10668)
		(layer "In7.Cu")
		(net "PWRGD_SYS_PWROK")
	)
	(segment
		(start 31.889446 -10.921746)
		(end 30.665928 -12.145264)
		(width 0.10668)
		(layer "In7.Cu")
		(net "PWRGD_SYS_PWROK")
	)
	(segment
		(start 4.778248 -19.4818)
		(end 2.176272 -22.083776)
		(width 0.10668)
		(layer "In7.Cu")
		(net "PWRGD_SYS_PWROK")
	)
	(segment
		(start 26.95448 -13.293852)
		(end 26.245312 -13.293852)
		(width 0.10668)
		(layer "In7.Cu")
		(net "PWRGD_SYS_PWROK")
	)
	(segment
		(start 35.217862 -13.87348)
		(end 33.525968 -12.181586)
		(width 0.10668)
		(layer "In7.Cu")
		(net "PWRGD_SYS_PWROK")
	)
	(segment
		(start 28.103068 -12.145264)
		(end 26.95448 -13.293852)
		(width 0.10668)
		(layer "In7.Cu")
		(net "PWRGD_SYS_PWROK")
	)
	(segment
		(start 46.8503 -12.45108)
		(end 39.153338 -12.45108)
		(width 0.10668)
		(layer "In7.Cu")
		(net "PWRGD_SYS_PWROK")
	)
	(segment
		(start 51.8414 -17.1196)
		(end 51.51882 -17.1196)
		(width 0.10668)
		(layer "In7.Cu")
		(net "PWRGD_SYS_PWROK")
	)
	(segment
		(start 32.822896 -10.921746)
		(end 31.889446 -10.921746)
		(width 0.10668)
		(layer "In7.Cu")
		(net "PWRGD_SYS_PWROK")
	)
	(segment
		(start 9.906 -11.049)
		(end 9.906 -18.415)
		(width 0.10668)
		(layer "In7.Cu")
		(net "PWRGD_SYS_PWROK")
	)
	(segment
		(start 32.7914 -85.6742)
		(end 35.0266 -85.6742)
		(width 0.11684)
		(layer "F.Cu")
		(net "PWRGD_PSU_AC_PWROK")
	)
	(segment
		(start 30.108144 -85.14969)
		(end 31.369254 -86.4108)
		(width 0.11684)
		(layer "F.Cu")
		(net "PWRGD_PSU_AC_PWROK")
	)
	(segment
		(start 3.24358 -107.76458)
		(end 3.429 -107.95)
		(width 0.11684)
		(layer "F.Cu")
		(net "PWRGD_PSU_AC_PWROK")
	)
	(segment
		(start 39.2684 -82.8548)
		(end 38.2524 -82.8548)
		(width 0.11684)
		(layer "F.Cu")
		(net "PWRGD_PSU_AC_PWROK")
	)
	(segment
		(start 32.0548 -86.4108)
		(end 32.7914 -85.6742)
		(width 0.11684)
		(layer "F.Cu")
		(net "PWRGD_PSU_AC_PWROK")
	)
	(segment
		(start 35.33902 -85.98662)
		(end 38.11778 -85.98662)
		(width 0.11684)
		(layer "F.Cu")
		(net "PWRGD_PSU_AC_PWROK")
	)
	(segment
		(start 4.0259 -105.516172)
		(end 3.24358 -106.298492)
		(width 0.11684)
		(layer "F.Cu")
		(net "PWRGD_PSU_AC_PWROK")
	)
	(segment
		(start 58.2422 -30.07614)
		(end 58.2422 -30.28315)
		(width 0.11684)
		(layer "F.Cu")
		(net "PWRGD_PSU_AC_PWROK")
	)
	(segment
		(start 3.24358 -106.298492)
		(end 3.24358 -107.76458)
		(width 0.11684)
		(layer "F.Cu")
		(net "PWRGD_PSU_AC_PWROK")
	)
	(segment
		(start 47.752 -88.392)
		(end 48.19396 -87.95004)
		(width 0.11684)
		(layer "F.Cu")
		(net "PWRGD_PSU_AC_PWROK")
	)
	(segment
		(start 45.30344 -86.274402)
		(end 45.30344 -87.008462)
		(width 0.11684)
		(layer "F.Cu")
		(net "PWRGD_PSU_AC_PWROK")
	)
	(segment
		(start 29.34589 -85.14969)
		(end 30.108144 -85.14969)
		(width 0.11684)
		(layer "F.Cu")
		(net "PWRGD_PSU_AC_PWROK")
	)
	(segment
		(start 45.30344 -87.008462)
		(end 46.634146 -88.339168)
		(width 0.11684)
		(layer "F.Cu")
		(net "PWRGD_PSU_AC_PWROK")
	)
	(segment
		(start 4.27355 -83.4644)
		(end 4.27355 -85.20049)
		(width 0.11684)
		(layer "F.Cu")
		(net "PWRGD_PSU_AC_PWROK")
	)
	(segment
		(start 31.369254 -86.4108)
		(end 32.0548 -86.4108)
		(width 0.11684)
		(layer "F.Cu")
		(net "PWRGD_PSU_AC_PWROK")
	)
	(segment
		(start 35.0266 -85.6742)
		(end 35.33902 -85.98662)
		(width 0.11684)
		(layer "F.Cu")
		(net "PWRGD_PSU_AC_PWROK")
	)
	(segment
		(start 48.19396 -87.95004)
		(end 50.144172 -87.95004)
		(width 0.11684)
		(layer "F.Cu")
		(net "PWRGD_PSU_AC_PWROK")
	)
	(segment
		(start 58.2422 -30.28315)
		(end 58.0644 -30.46095)
		(width 0.11684)
		(layer "F.Cu")
		(net "PWRGD_PSU_AC_PWROK")
	)
	(segment
		(start 39.689278 -80.66024)
		(end 45.30344 -86.274402)
		(width 0.11684)
		(layer "F.Cu")
		(net "PWRGD_PSU_AC_PWROK")
	)
	(segment
		(start 5.64515 -84.836)
		(end 6.926326 -84.836)
		(width 0.11684)
		(layer "F.Cu")
		(net "PWRGD_PSU_AC_PWROK")
	)
	(segment
		(start 46.634146 -88.339168)
		(end 46.7614 -88.392)
		(width 0.11684)
		(layer "F.Cu")
		(net "PWRGD_PSU_AC_PWROK")
	)
	(segment
		(start 38.11778 -85.98662)
		(end 39.5986 -84.5058)
		(width 0.11684)
		(layer "F.Cu")
		(net "PWRGD_PSU_AC_PWROK")
	)
	(segment
		(start 6.926326 -84.836)
		(end 7.942326 -85.852)
		(width 0.11684)
		(layer "F.Cu")
		(net "PWRGD_PSU_AC_PWROK")
	)
	(segment
		(start 4.27355 -85.20049)
		(end 4.0259 -85.44814)
		(width 0.11684)
		(layer "F.Cu")
		(net "PWRGD_PSU_AC_PWROK")
	)
	(segment
		(start 3.429 -107.95)
		(end 3.7338 -107.95)
		(width 0.11684)
		(layer "F.Cu")
		(net "PWRGD_PSU_AC_PWROK")
	)
	(segment
		(start 39.5986 -84.5058)
		(end 39.5986 -83.185)
		(width 0.11684)
		(layer "F.Cu")
		(net "PWRGD_PSU_AC_PWROK")
	)
	(segment
		(start 4.27355 -83.4644)
		(end 5.64515 -84.836)
		(width 0.11684)
		(layer "F.Cu")
		(net "PWRGD_PSU_AC_PWROK")
	)
	(segment
		(start 38.97376 -80.66024)
		(end 39.689278 -80.66024)
		(width 0.11684)
		(layer "F.Cu")
		(net "PWRGD_PSU_AC_PWROK")
	)
	(segment
		(start 58.494422 -29.823918)
		(end 58.2422 -30.07614)
		(width 0.11684)
		(layer "F.Cu")
		(net "PWRGD_PSU_AC_PWROK")
	)
	(segment
		(start 39.5986 -83.185)
		(end 39.2684 -82.8548)
		(width 0.11684)
		(layer "F.Cu")
		(net "PWRGD_PSU_AC_PWROK")
	)
	(segment
		(start 4.0259 -85.44814)
		(end 4.0259 -105.516172)
		(width 0.11684)
		(layer "F.Cu")
		(net "PWRGD_PSU_AC_PWROK")
	)
	(segment
		(start 38.2524 -82.8548)
		(end 37.8968 -82.4992)
		(width 0.11684)
		(layer "F.Cu")
		(net "PWRGD_PSU_AC_PWROK")
	)
	(segment
		(start 37.8968 -82.4992)
		(end 37.8968 -81.7372)
		(width 0.11684)
		(layer "F.Cu")
		(net "PWRGD_PSU_AC_PWROK")
	)
	(segment
		(start 50.144172 -87.95004)
		(end 50.23485 -88.040718)
		(width 0.11684)
		(layer "F.Cu")
		(net "PWRGD_PSU_AC_PWROK")
	)
	(segment
		(start 7.942326 -85.852)
		(end 8.87095 -85.852)
		(width 0.11684)
		(layer "F.Cu")
		(net "PWRGD_PSU_AC_PWROK")
	)
	(segment
		(start 37.8968 -81.7372)
		(end 38.97376 -80.66024)
		(width 0.11684)
		(layer "F.Cu")
		(net "PWRGD_PSU_AC_PWROK")
	)
	(segment
		(start 46.7614 -88.392)
		(end 47.752 -88.392)
		(width 0.11684)
		(layer "F.Cu")
		(net "PWRGD_PSU_AC_PWROK")
	)
	(via
		(at 40.8178 -113.1697)
		(size 0.508)
		(drill 0.254)
		(layers "F.Cu" "B.Cu")
		(net "PWRGD_PSU_AC_PWROK")
	)
	(via
		(at 3.7338 -107.95)
		(size 0.508)
		(drill 0.254)
		(layers "F.Cu" "B.Cu")
		(net "PWRGD_PSU_AC_PWROK")
	)
	(via
		(at 32.80029 -104.2035)
		(size 0.508)
		(drill 0.254)
		(layers "F.Cu" "B.Cu")
		(net "PWRGD_PSU_AC_PWROK")
	)
	(via
		(at 29.34589 -85.14969)
		(size 0.508)
		(drill 0.254)
		(layers "F.Cu" "B.Cu")
		(net "PWRGD_PSU_AC_PWROK")
	)
	(via
		(at 50.23485 -88.040718)
		(size 0.508)
		(drill 0.254)
		(layers "F.Cu" "B.Cu")
		(net "PWRGD_PSU_AC_PWROK")
	)
	(via
		(at 58.494422 -29.823918)
		(size 0.508)
		(drill 0.254)
		(layers "F.Cu" "B.Cu")
		(net "PWRGD_PSU_AC_PWROK")
	)
	(via
		(at 37.1602 -40.89654)
		(size 0.508)
		(drill 0.254)
		(layers "F.Cu" "B.Cu")
		(net "PWRGD_PSU_AC_PWROK")
	)
	(via
		(at 49.403 -102.2604)
		(size 0.508)
		(drill 0.254)
		(layers "F.Cu" "B.Cu")
		(net "PWRGD_PSU_AC_PWROK")
	)
	(segment
		(start 32.639 -106.15295)
		(end 32.29356 -105.80751)
		(width 0.11684)
		(layer "B.Cu")
		(net "PWRGD_PSU_AC_PWROK")
	)
	(segment
		(start 32.800036 -104.2035)
		(end 32.80029 -104.2035)
		(width 0.11684)
		(layer "B.Cu")
		(net "PWRGD_PSU_AC_PWROK")
	)
	(segment
		(start 32.29356 -105.80751)
		(end 32.29356 -104.709976)
		(width 0.11684)
		(layer "B.Cu")
		(net "PWRGD_PSU_AC_PWROK")
	)
	(segment
		(start 50.455068 -87.8205)
		(end 50.23485 -88.040718)
		(width 0.11684)
		(layer "B.Cu")
		(net "PWRGD_PSU_AC_PWROK")
	)
	(segment
		(start 32.29356 -104.709976)
		(end 32.800036 -104.2035)
		(width 0.11684)
		(layer "B.Cu")
		(net "PWRGD_PSU_AC_PWROK")
	)
	(segment
		(start 28.35656 -85.14969)
		(end 29.34589 -85.14969)
		(width 0.11684)
		(layer "B.Cu")
		(net "PWRGD_PSU_AC_PWROK")
	)
	(segment
		(start 50.84445 -87.8205)
		(end 50.455068 -87.8205)
		(width 0.11684)
		(layer "B.Cu")
		(net "PWRGD_PSU_AC_PWROK")
	)
	(segment
		(start 27.73045 -85.7758)
		(end 28.35656 -85.14969)
		(width 0.11684)
		(layer "B.Cu")
		(net "PWRGD_PSU_AC_PWROK")
	)
	(segment
		(start 34.27095 -104.36225)
		(end 34.81451 -103.81869)
		(width 0.08382)
		(layer "In2.Cu")
		(net "PWRGD_PSU_AC_PWROK")
	)
	(segment
		(start 40.8178 -113.1697)
		(end 37.8079 -113.1697)
		(width 0.08382)
		(layer "In2.Cu")
		(net "PWRGD_PSU_AC_PWROK")
	)
	(segment
		(start 49.047654 -103.2764)
		(end 49.403 -102.921054)
		(width 0.08382)
		(layer "In2.Cu")
		(net "PWRGD_PSU_AC_PWROK")
	)
	(segment
		(start 32.95904 -104.36225)
		(end 34.27095 -104.36225)
		(width 0.08382)
		(layer "In2.Cu")
		(net "PWRGD_PSU_AC_PWROK")
	)
	(segment
		(start 37.8079 -113.1697)
		(end 36.48202 -111.84382)
		(width 0.08382)
		(layer "In2.Cu")
		(net "PWRGD_PSU_AC_PWROK")
	)
	(segment
		(start 36.48202 -111.84382)
		(end 29.17952 -111.84382)
		(width 0.08382)
		(layer "In2.Cu")
		(net "PWRGD_PSU_AC_PWROK")
	)
	(segment
		(start 32.80029 -104.2035)
		(end 32.95904 -104.36225)
		(width 0.08382)
		(layer "In2.Cu")
		(net "PWRGD_PSU_AC_PWROK")
	)
	(segment
		(start 9.702546 -110.871)
		(end 5.3848 -110.871)
		(width 0.08382)
		(layer "In2.Cu")
		(net "PWRGD_PSU_AC_PWROK")
	)
	(segment
		(start 49.403 -102.921054)
		(end 49.403 -102.2604)
		(width 0.08382)
		(layer "In2.Cu")
		(net "PWRGD_PSU_AC_PWROK")
	)
	(segment
		(start 3.7338 -109.22)
		(end 3.7338 -107.95)
		(width 0.08382)
		(layer "In2.Cu")
		(net "PWRGD_PSU_AC_PWROK")
	)
	(segment
		(start 10.413746 -110.1598)
		(end 9.702546 -110.871)
		(width 0.08382)
		(layer "In2.Cu")
		(net "PWRGD_PSU_AC_PWROK")
	)
	(segment
		(start 5.3848 -110.871)
		(end 3.7338 -109.22)
		(width 0.08382)
		(layer "In2.Cu")
		(net "PWRGD_PSU_AC_PWROK")
	)
	(segment
		(start 34.81451 -103.81869)
		(end 47.18431 -103.81869)
		(width 0.08382)
		(layer "In2.Cu")
		(net "PWRGD_PSU_AC_PWROK")
	)
	(segment
		(start 17.43456 -112.0394)
		(end 17.10436 -111.7092)
		(width 0.08382)
		(layer "In2.Cu")
		(net "PWRGD_PSU_AC_PWROK")
	)
	(segment
		(start 47.18431 -103.81869)
		(end 47.7266 -103.2764)
		(width 0.08382)
		(layer "In2.Cu")
		(net "PWRGD_PSU_AC_PWROK")
	)
	(segment
		(start 17.10436 -111.7092)
		(end 13.716254 -111.7092)
		(width 0.08382)
		(layer "In2.Cu")
		(net "PWRGD_PSU_AC_PWROK")
	)
	(segment
		(start 29.17952 -111.84382)
		(end 28.98394 -112.0394)
		(width 0.08382)
		(layer "In2.Cu")
		(net "PWRGD_PSU_AC_PWROK")
	)
	(segment
		(start 13.716254 -111.7092)
		(end 12.166854 -110.1598)
		(width 0.08382)
		(layer "In2.Cu")
		(net "PWRGD_PSU_AC_PWROK")
	)
	(segment
		(start 28.98394 -112.0394)
		(end 17.43456 -112.0394)
		(width 0.08382)
		(layer "In2.Cu")
		(net "PWRGD_PSU_AC_PWROK")
	)
	(segment
		(start 12.166854 -110.1598)
		(end 10.413746 -110.1598)
		(width 0.08382)
		(layer "In2.Cu")
		(net "PWRGD_PSU_AC_PWROK")
	)
	(segment
		(start 47.7266 -103.2764)
		(end 49.047654 -103.2764)
		(width 0.08382)
		(layer "In2.Cu")
		(net "PWRGD_PSU_AC_PWROK")
	)
	(segment
		(start 41.54678 -113.1697)
		(end 45.1358 -109.58068)
		(width 0.10668)
		(layer "In4.Cu")
		(net "PWRGD_PSU_AC_PWROK")
	)
	(segment
		(start 50.94732 -92.012516)
		(end 50.384456 -92.57538)
		(width 0.10668)
		(layer "In4.Cu")
		(net "PWRGD_PSU_AC_PWROK")
	)
	(segment
		(start 28.36672 -62.978538)
		(end 29.129736 -63.741554)
		(width 0.10668)
		(layer "In4.Cu")
		(net "PWRGD_PSU_AC_PWROK")
	)
	(segment
		(start 31.122112 -52.511452)
		(end 30.81274 -52.820824)
		(width 0.10668)
		(layer "In4.Cu")
		(net "PWRGD_PSU_AC_PWROK")
	)
	(segment
		(start 28.956 -59.204606)
		(end 28.956 -59.37504)
		(width 0.10668)
		(layer "In4.Cu")
		(net "PWRGD_PSU_AC_PWROK")
	)
	(segment
		(start 29.826966 -73.11898)
		(end 29.826966 -76.81087)
		(width 0.10668)
		(layer "In4.Cu")
		(net "PWRGD_PSU_AC_PWROK")
	)
	(segment
		(start 29.458412 -67.361308)
		(end 29.35986 -67.599306)
		(width 0.10668)
		(layer "In4.Cu")
		(net "PWRGD_PSU_AC_PWROK")
	)
	(segment
		(start 29.129736 -64.852296)
		(end 29.76372 -65.48628)
		(width 0.10668)
		(layer "In4.Cu")
		(net "PWRGD_PSU_AC_PWROK")
	)
	(segment
		(start 31.71444 -48.27778)
		(end 31.71444 -49.991772)
		(width 0.10668)
		(layer "In4.Cu")
		(net "PWRGD_PSU_AC_PWROK")
	)
	(segment
		(start 29.67482 -70.27672)
		(end 29.4767 -70.47484)
		(width 0.10668)
		(layer "In4.Cu")
		(net "PWRGD_PSU_AC_PWROK")
	)
	(segment
		(start 29.4767 -72.490838)
		(end 29.476446 -72.491092)
		(width 0.10668)
		(layer "In4.Cu")
		(net "PWRGD_PSU_AC_PWROK")
	)
	(segment
		(start 30.81274 -52.820824)
		(end 30.81274 -55.166514)
		(width 0.10668)
		(layer "In4.Cu")
		(net "PWRGD_PSU_AC_PWROK")
	)
	(segment
		(start 47.64786 -106.47934)
		(end 47.64786 -105.66654)
		(width 0.10668)
		(layer "In4.Cu")
		(net "PWRGD_PSU_AC_PWROK")
	)
	(segment
		(start 40.8178 -113.1697)
		(end 41.54678 -113.1697)
		(width 0.10668)
		(layer "In4.Cu")
		(net "PWRGD_PSU_AC_PWROK")
	)
	(segment
		(start 29.129736 -63.741554)
		(end 29.129736 -64.852296)
		(width 0.10668)
		(layer "In4.Cu")
		(net "PWRGD_PSU_AC_PWROK")
	)
	(segment
		(start 30.81274 -55.166514)
		(end 30.48 -56.264048)
		(width 0.10668)
		(layer "In4.Cu")
		(net "PWRGD_PSU_AC_PWROK")
	)
	(segment
		(start 28.781248 -58.358024)
		(end 28.781248 -59.029854)
		(width 0.10668)
		(layer "In4.Cu")
		(net "PWRGD_PSU_AC_PWROK")
	)
	(segment
		(start 29.76372 -65.48628)
		(end 29.76372 -67.056)
		(width 0.10668)
		(layer "In4.Cu")
		(net "PWRGD_PSU_AC_PWROK")
	)
	(segment
		(start 28.95854 -60.01766)
		(end 29.1592 -60.21832)
		(width 0.10668)
		(layer "In4.Cu")
		(net "PWRGD_PSU_AC_PWROK")
	)
	(segment
		(start 28.36672 -61.82614)
		(end 28.36672 -62.978538)
		(width 0.10668)
		(layer "In4.Cu")
		(net "PWRGD_PSU_AC_PWROK")
	)
	(segment
		(start 29.1592 -60.21832)
		(end 29.1592 -61.03366)
		(width 0.10668)
		(layer "In4.Cu")
		(net "PWRGD_PSU_AC_PWROK")
	)
	(segment
		(start 31.122112 -50.5841)
		(end 31.122112 -52.511452)
		(width 0.10668)
		(layer "In4.Cu")
		(net "PWRGD_PSU_AC_PWROK")
	)
	(segment
		(start 50.23485 -88.040718)
		(end 50.94732 -88.753188)
		(width 0.10668)
		(layer "In4.Cu")
		(net "PWRGD_PSU_AC_PWROK")
	)
	(segment
		(start 49.24298 -98.654362)
		(end 49.24298 -101.874828)
		(width 0.10668)
		(layer "In4.Cu")
		(net "PWRGD_PSU_AC_PWROK")
	)
	(segment
		(start 28.95854 -59.37758)
		(end 28.95854 -60.01766)
		(width 0.10668)
		(layer "In4.Cu")
		(net "PWRGD_PSU_AC_PWROK")
	)
	(segment
		(start 29.476446 -72.76846)
		(end 29.826966 -73.11898)
		(width 0.10668)
		(layer "In4.Cu")
		(net "PWRGD_PSU_AC_PWROK")
	)
	(segment
		(start 32.72282 -44.4754)
		(end 32.72282 -47.2694)
		(width 0.10668)
		(layer "In4.Cu")
		(net "PWRGD_PSU_AC_PWROK")
	)
	(segment
		(start 49.24298 -101.874828)
		(end 49.403 -102.2604)
		(width 0.10668)
		(layer "In4.Cu")
		(net "PWRGD_PSU_AC_PWROK")
	)
	(segment
		(start 49.34458 -93.040962)
		(end 49.34458 -93.615256)
		(width 0.10668)
		(layer "In4.Cu")
		(net "PWRGD_PSU_AC_PWROK")
	)
	(segment
		(start 37.1602 -40.89654)
		(end 35.610292 -42.446448)
		(width 0.10668)
		(layer "In4.Cu")
		(net "PWRGD_PSU_AC_PWROK")
	)
	(segment
		(start 29.76372 -67.056)
		(end 29.458412 -67.361308)
		(width 0.10668)
		(layer "In4.Cu")
		(net "PWRGD_PSU_AC_PWROK")
	)
	(segment
		(start 45.1358 -109.58068)
		(end 45.1358 -108.9914)
		(width 0.10668)
		(layer "In4.Cu")
		(net "PWRGD_PSU_AC_PWROK")
	)
	(segment
		(start 33.60801 -43.59021)
		(end 32.72282 -44.4754)
		(width 0.10668)
		(layer "In4.Cu")
		(net "PWRGD_PSU_AC_PWROK")
	)
	(segment
		(start 47.64786 -105.66654)
		(end 49.403 -103.9114)
		(width 0.10668)
		(layer "In4.Cu")
		(net "PWRGD_PSU_AC_PWROK")
	)
	(segment
		(start 29.35986 -67.599306)
		(end 29.35986 -68.40982)
		(width 0.10668)
		(layer "In4.Cu")
		(net "PWRGD_PSU_AC_PWROK")
	)
	(segment
		(start 29.476446 -72.491092)
		(end 29.476446 -72.76846)
		(width 0.10668)
		(layer "In4.Cu")
		(net "PWRGD_PSU_AC_PWROK")
	)
	(segment
		(start 28.781248 -59.029854)
		(end 28.956 -59.204606)
		(width 0.10668)
		(layer "In4.Cu")
		(net "PWRGD_PSU_AC_PWROK")
	)
	(segment
		(start 35.610292 -42.446448)
		(end 35.371532 -42.446448)
		(width 0.10668)
		(layer "In4.Cu")
		(net "PWRGD_PSU_AC_PWROK")
	)
	(segment
		(start 48.70196 -98.113342)
		(end 49.24298 -98.654362)
		(width 0.10668)
		(layer "In4.Cu")
		(net "PWRGD_PSU_AC_PWROK")
	)
	(segment
		(start 48.70196 -94.257876)
		(end 48.70196 -98.113342)
		(width 0.10668)
		(layer "In4.Cu")
		(net "PWRGD_PSU_AC_PWROK")
	)
	(segment
		(start 49.403 -103.9114)
		(end 49.403 -102.2604)
		(width 0.10668)
		(layer "In4.Cu")
		(net "PWRGD_PSU_AC_PWROK")
	)
	(segment
		(start 35.371532 -42.446448)
		(end 34.22777 -43.59021)
		(width 0.10668)
		(layer "In4.Cu")
		(net "PWRGD_PSU_AC_PWROK")
	)
	(segment
		(start 50.94732 -88.753188)
		(end 50.94732 -92.012516)
		(width 0.10668)
		(layer "In4.Cu")
		(net "PWRGD_PSU_AC_PWROK")
	)
	(segment
		(start 49.34458 -93.615256)
		(end 48.70196 -94.257876)
		(width 0.10668)
		(layer "In4.Cu")
		(net "PWRGD_PSU_AC_PWROK")
	)
	(segment
		(start 50.384456 -92.57538)
		(end 49.810162 -92.57538)
		(width 0.10668)
		(layer "In4.Cu")
		(net "PWRGD_PSU_AC_PWROK")
	)
	(segment
		(start 34.22777 -43.59021)
		(end 33.60801 -43.59021)
		(width 0.10668)
		(layer "In4.Cu")
		(net "PWRGD_PSU_AC_PWROK")
	)
	(segment
		(start 29.1592 -61.03366)
		(end 28.36672 -61.82614)
		(width 0.10668)
		(layer "In4.Cu")
		(net "PWRGD_PSU_AC_PWROK")
	)
	(segment
		(start 28.956 -59.37504)
		(end 28.95854 -59.37758)
		(width 0.10668)
		(layer "In4.Cu")
		(net "PWRGD_PSU_AC_PWROK")
	)
	(segment
		(start 28.98394 -84.78774)
		(end 29.34589 -85.14969)
		(width 0.10668)
		(layer "In4.Cu")
		(net "PWRGD_PSU_AC_PWROK")
	)
	(segment
		(start 32.72282 -47.2694)
		(end 31.71444 -48.27778)
		(width 0.10668)
		(layer "In4.Cu")
		(net "PWRGD_PSU_AC_PWROK")
	)
	(segment
		(start 29.67482 -68.72478)
		(end 29.67482 -70.27672)
		(width 0.10668)
		(layer "In4.Cu")
		(net "PWRGD_PSU_AC_PWROK")
	)
	(segment
		(start 30.48 -56.264048)
		(end 29.683964 -57.455308)
		(width 0.10668)
		(layer "In4.Cu")
		(net "PWRGD_PSU_AC_PWROK")
	)
	(segment
		(start 49.810162 -92.57538)
		(end 49.34458 -93.040962)
		(width 0.10668)
		(layer "In4.Cu")
		(net "PWRGD_PSU_AC_PWROK")
	)
	(segment
		(start 29.683964 -57.455308)
		(end 28.781248 -58.358024)
		(width 0.10668)
		(layer "In4.Cu")
		(net "PWRGD_PSU_AC_PWROK")
	)
	(segment
		(start 29.35986 -68.40982)
		(end 29.67482 -68.72478)
		(width 0.10668)
		(layer "In4.Cu")
		(net "PWRGD_PSU_AC_PWROK")
	)
	(segment
		(start 45.1358 -108.9914)
		(end 47.64786 -106.47934)
		(width 0.10668)
		(layer "In4.Cu")
		(net "PWRGD_PSU_AC_PWROK")
	)
	(segment
		(start 29.4767 -70.47484)
		(end 29.4767 -72.490838)
		(width 0.10668)
		(layer "In4.Cu")
		(net "PWRGD_PSU_AC_PWROK")
	)
	(segment
		(start 29.826966 -76.81087)
		(end 28.98394 -77.653896)
		(width 0.10668)
		(layer "In4.Cu")
		(net "PWRGD_PSU_AC_PWROK")
	)
	(segment
		(start 28.98394 -77.653896)
		(end 28.98394 -84.78774)
		(width 0.10668)
		(layer "In4.Cu")
		(net "PWRGD_PSU_AC_PWROK")
	)
	(segment
		(start 31.71444 -49.991772)
		(end 31.122112 -50.5841)
		(width 0.10668)
		(layer "In4.Cu")
		(net "PWRGD_PSU_AC_PWROK")
	)
	(segment
		(start 34.8742 -32.639)
		(end 34.8742 -30.393132)
		(width 0.08382)
		(layer "In9.Cu")
		(net "PWRGD_PSU_AC_PWROK")
	)
	(segment
		(start 33.2486 -40.5892)
		(end 33.2486 -39.8272)
		(width 0.08382)
		(layer "In9.Cu")
		(net "PWRGD_PSU_AC_PWROK")
	)
	(segment
		(start 53.295042 -30.384242)
		(end 57.934098 -30.384242)
		(width 0.08382)
		(layer "In9.Cu")
		(net "PWRGD_PSU_AC_PWROK")
	)
	(segment
		(start 36.350448 -29.71546)
		(end 40.310308 -25.7556)
		(width 0.08382)
		(layer "In9.Cu")
		(net "PWRGD_PSU_AC_PWROK")
	)
	(segment
		(start 57.934098 -30.384242)
		(end 58.494422 -29.823918)
		(width 0.08382)
		(layer "In9.Cu")
		(net "PWRGD_PSU_AC_PWROK")
	)
	(segment
		(start 42.0116 -25.7556)
		(end 43.5356 -27.2796)
		(width 0.08382)
		(layer "In9.Cu")
		(net "PWRGD_PSU_AC_PWROK")
	)
	(segment
		(start 34.8742 -30.393132)
		(end 35.551872 -29.71546)
		(width 0.08382)
		(layer "In9.Cu")
		(net "PWRGD_PSU_AC_PWROK")
	)
	(segment
		(start 43.5356 -27.2796)
		(end 50.1904 -27.2796)
		(width 0.08382)
		(layer "In9.Cu")
		(net "PWRGD_PSU_AC_PWROK")
	)
	(segment
		(start 35.551872 -29.71546)
		(end 36.350448 -29.71546)
		(width 0.08382)
		(layer "In9.Cu")
		(net "PWRGD_PSU_AC_PWROK")
	)
	(segment
		(start 37.1602 -40.89654)
		(end 36.98494 -41.0718)
		(width 0.08382)
		(layer "In9.Cu")
		(net "PWRGD_PSU_AC_PWROK")
	)
	(segment
		(start 33.2486 -39.8272)
		(end 32.8168 -39.3954)
		(width 0.08382)
		(layer "In9.Cu")
		(net "PWRGD_PSU_AC_PWROK")
	)
	(segment
		(start 40.310308 -25.7556)
		(end 42.0116 -25.7556)
		(width 0.08382)
		(layer "In9.Cu")
		(net "PWRGD_PSU_AC_PWROK")
	)
	(segment
		(start 50.1904 -27.2796)
		(end 53.295042 -30.384242)
		(width 0.08382)
		(layer "In9.Cu")
		(net "PWRGD_PSU_AC_PWROK")
	)
	(segment
		(start 33.7312 -41.0718)
		(end 33.2486 -40.5892)
		(width 0.08382)
		(layer "In9.Cu")
		(net "PWRGD_PSU_AC_PWROK")
	)
	(segment
		(start 32.8168 -34.6964)
		(end 34.8742 -32.639)
		(width 0.08382)
		(layer "In9.Cu")
		(net "PWRGD_PSU_AC_PWROK")
	)
	(segment
		(start 32.8168 -39.3954)
		(end 32.8168 -34.6964)
		(width 0.08382)
		(layer "In9.Cu")
		(net "PWRGD_PSU_AC_PWROK")
	)
	(segment
		(start 36.98494 -41.0718)
		(end 33.7312 -41.0718)
		(width 0.08382)
		(layer "In9.Cu")
		(net "PWRGD_PSU_AC_PWROK")
	)
	(segment
		(start 71.4375 -29.44495)
		(end 72.11695 -29.44495)
		(width 0.11684)
		(layer "F.Cu")
		(net "PWRGD_P3V3_RGM")
	)
	(segment
		(start 31.08071 -65.22085)
		(end 30.48508 -64.62522)
		(width 0.11684)
		(layer "F.Cu")
		(net "PWRGD_P3V3_RGM")
	)
	(segment
		(start 31.115 -65.22085)
		(end 31.08071 -65.22085)
		(width 0.11684)
		(layer "F.Cu")
		(net "PWRGD_P3V3_RGM")
	)
	(segment
		(start 72.11695 -29.44495)
		(end 72.4535 -29.7815)
		(width 0.11684)
		(layer "F.Cu")
		(net "PWRGD_P3V3_RGM")
	)
	(via
		(at 76.931266 -71.751698)
		(size 0.508)
		(drill 0.254)
		(layers "F.Cu" "B.Cu")
		(net "PWRGD_P3V3_RGM")
	)
	(via
		(at 19.668998 -66.74104)
		(size 0.508)
		(drill 0.254)
		(layers "F.Cu" "B.Cu")
		(net "PWRGD_P3V3_RGM")
	)
	(via
		(at 72.050656 -96.325944)
		(size 0.508)
		(drill 0.254)
		(layers "F.Cu" "B.Cu")
		(net "PWRGD_P3V3_RGM")
	)
	(via
		(at 13.8176 -95.1738)
		(size 0.508)
		(drill 0.254)
		(layers "F.Cu" "B.Cu")
		(net "PWRGD_P3V3_RGM")
	)
	(via
		(at 16.845026 -105.026968)
		(size 0.508)
		(drill 0.254)
		(layers "F.Cu" "B.Cu")
		(net "PWRGD_P3V3_RGM")
	)
	(via
		(at 72.4535 -29.7815)
		(size 0.508)
		(drill 0.254)
		(layers "F.Cu" "B.Cu")
		(net "PWRGD_P3V3_RGM")
	)
	(via
		(at 30.48508 -64.62522)
		(size 0.508)
		(drill 0.254)
		(layers "F.Cu" "B.Cu")
		(net "PWRGD_P3V3_RGM")
	)
	(segment
		(start 18.17878 -104.02062)
		(end 17.8943 -104.3051)
		(width 0.11684)
		(layer "B.Cu")
		(net "PWRGD_P3V3_RGM")
	)
	(segment
		(start 18.923 -102.38105)
		(end 18.17878 -103.12527)
		(width 0.11684)
		(layer "B.Cu")
		(net "PWRGD_P3V3_RGM")
	)
	(segment
		(start 17.8943 -104.3051)
		(end 17.3355 -104.3051)
		(width 0.11684)
		(layer "B.Cu")
		(net "PWRGD_P3V3_RGM")
	)
	(segment
		(start 18.17878 -103.12527)
		(end 18.17878 -104.02062)
		(width 0.11684)
		(layer "B.Cu")
		(net "PWRGD_P3V3_RGM")
	)
	(segment
		(start 78.7146 -68.8086)
		(end 79.375 -68.8086)
		(width 0.11684)
		(layer "B.Cu")
		(net "PWRGD_P3V3_RGM")
	)
	(segment
		(start 16.845026 -104.795574)
		(end 16.845026 -105.026968)
		(width 0.11684)
		(layer "B.Cu")
		(net "PWRGD_P3V3_RGM")
	)
	(segment
		(start 17.3355 -104.3051)
		(end 16.845026 -104.795574)
		(width 0.11684)
		(layer "B.Cu")
		(net "PWRGD_P3V3_RGM")
	)
	(segment
		(start 78.4606 -69.0626)
		(end 78.7146 -68.8086)
		(width 0.11684)
		(layer "B.Cu")
		(net "PWRGD_P3V3_RGM")
	)
	(segment
		(start 76.931266 -71.751698)
		(end 77.371702 -71.751698)
		(width 0.11684)
		(layer "B.Cu")
		(net "PWRGD_P3V3_RGM")
	)
	(segment
		(start 78.4606 -70.6628)
		(end 78.4606 -69.0626)
		(width 0.11684)
		(layer "B.Cu")
		(net "PWRGD_P3V3_RGM")
	)
	(segment
		(start 79.375 -68.8086)
		(end 79.7814 -69.215)
		(width 0.11684)
		(layer "B.Cu")
		(net "PWRGD_P3V3_RGM")
	)
	(segment
		(start 79.7814 -69.215)
		(end 79.7814 -69.618606)
		(width 0.11684)
		(layer "B.Cu")
		(net "PWRGD_P3V3_RGM")
	)
	(segment
		(start 77.371702 -71.751698)
		(end 78.4606 -70.6628)
		(width 0.11684)
		(layer "B.Cu")
		(net "PWRGD_P3V3_RGM")
	)
	(segment
		(start 70.82536 -97.55124)
		(end 64.769746 -97.55124)
		(width 0.08382)
		(layer "In2.Cu")
		(net "PWRGD_P3V3_RGM")
	)
	(segment
		(start 21.521928 -66.83756)
		(end 21.697188 -66.6623)
		(width 0.08382)
		(layer "In2.Cu")
		(net "PWRGD_P3V3_RGM")
	)
	(segment
		(start 21.329396 -102.288594)
		(end 18.424906 -102.288594)
		(width 0.08382)
		(layer "In2.Cu")
		(net "PWRGD_P3V3_RGM")
	)
	(segment
		(start 64.259206 -97.0407)
		(end 62.812422 -97.0407)
		(width 0.08382)
		(layer "In2.Cu")
		(net "PWRGD_P3V3_RGM")
	)
	(segment
		(start 24.17064 -65.999868)
		(end 24.17064 -65.552574)
		(width 0.08382)
		(layer "In2.Cu")
		(net "PWRGD_P3V3_RGM")
	)
	(segment
		(start 53.83022 -96.61144)
		(end 53.80736 -96.58858)
		(width 0.08382)
		(layer "In2.Cu")
		(net "PWRGD_P3V3_RGM")
	)
	(segment
		(start 23.98776 -101.5746)
		(end 23.35022 -102.21214)
		(width 0.08382)
		(layer "In2.Cu")
		(net "PWRGD_P3V3_RGM")
	)
	(segment
		(start 32.314388 -100.16871)
		(end 31.806388 -100.67671)
		(width 0.08382)
		(layer "In2.Cu")
		(net "PWRGD_P3V3_RGM")
	)
	(segment
		(start 16.845026 -104.348026)
		(end 16.845026 -105.026968)
		(width 0.08382)
		(layer "In2.Cu")
		(net "PWRGD_P3V3_RGM")
	)
	(segment
		(start 23.508208 -66.6623)
		(end 24.17064 -65.999868)
		(width 0.08382)
		(layer "In2.Cu")
		(net "PWRGD_P3V3_RGM")
	)
	(segment
		(start 58.89498 -98.49612)
		(end 57.76722 -98.49612)
		(width 0.08382)
		(layer "In2.Cu")
		(net "PWRGD_P3V3_RGM")
	)
	(segment
		(start 29.77642 -64.62522)
		(end 30.48508 -64.62522)
		(width 0.08382)
		(layer "In2.Cu")
		(net "PWRGD_P3V3_RGM")
	)
	(segment
		(start 27.83078 -63.988696)
		(end 28.082494 -64.24041)
		(width 0.08382)
		(layer "In2.Cu")
		(net "PWRGD_P3V3_RGM")
	)
	(segment
		(start 34.97453 -98.92411)
		(end 34.216594 -99.682046)
		(width 0.08382)
		(layer "In2.Cu")
		(net "PWRGD_P3V3_RGM")
	)
	(segment
		(start 36.733988 -98.92411)
		(end 34.97453 -98.92411)
		(width 0.08382)
		(layer "In2.Cu")
		(net "PWRGD_P3V3_RGM")
	)
	(segment
		(start 28.625546 -101.5746)
		(end 23.98776 -101.5746)
		(width 0.08382)
		(layer "In2.Cu")
		(net "PWRGD_P3V3_RGM")
	)
	(segment
		(start 57.01538 -99.24796)
		(end 56.54548 -99.24796)
		(width 0.08382)
		(layer "In2.Cu")
		(net "PWRGD_P3V3_RGM")
	)
	(segment
		(start 61.222382 -98.63074)
		(end 59.0296 -98.63074)
		(width 0.08382)
		(layer "In2.Cu")
		(net "PWRGD_P3V3_RGM")
	)
	(segment
		(start 45.486828 -96.81591)
		(end 42.39768 -99.905058)
		(width 0.08382)
		(layer "In2.Cu")
		(net "PWRGD_P3V3_RGM")
	)
	(segment
		(start 21.40585 -102.21214)
		(end 21.329396 -102.288594)
		(width 0.08382)
		(layer "In2.Cu")
		(net "PWRGD_P3V3_RGM")
	)
	(segment
		(start 32.520128 -100.16871)
		(end 32.314388 -100.16871)
		(width 0.08382)
		(layer "In2.Cu")
		(net "PWRGD_P3V3_RGM")
	)
	(segment
		(start 72.050656 -96.325944)
		(end 70.82536 -97.55124)
		(width 0.08382)
		(layer "In2.Cu")
		(net "PWRGD_P3V3_RGM")
	)
	(segment
		(start 64.769746 -97.55124)
		(end 64.259206 -97.0407)
		(width 0.08382)
		(layer "In2.Cu")
		(net "PWRGD_P3V3_RGM")
	)
	(segment
		(start 34.216594 -99.682046)
		(end 33.006792 -99.682046)
		(width 0.08382)
		(layer "In2.Cu")
		(net "PWRGD_P3V3_RGM")
	)
	(segment
		(start 16.5608 -103.5812)
		(end 16.5608 -104.0638)
		(width 0.08382)
		(layer "In2.Cu")
		(net "PWRGD_P3V3_RGM")
	)
	(segment
		(start 29.523436 -100.67671)
		(end 28.625546 -101.5746)
		(width 0.08382)
		(layer "In2.Cu")
		(net "PWRGD_P3V3_RGM")
	)
	(segment
		(start 25.734518 -63.988696)
		(end 27.83078 -63.988696)
		(width 0.08382)
		(layer "In2.Cu")
		(net "PWRGD_P3V3_RGM")
	)
	(segment
		(start 28.082494 -64.24041)
		(end 29.39161 -64.24041)
		(width 0.08382)
		(layer "In2.Cu")
		(net "PWRGD_P3V3_RGM")
	)
	(segment
		(start 19.765518 -66.83756)
		(end 21.521928 -66.83756)
		(width 0.08382)
		(layer "In2.Cu")
		(net "PWRGD_P3V3_RGM")
	)
	(segment
		(start 18.424906 -102.288594)
		(end 17.4625 -103.251)
		(width 0.08382)
		(layer "In2.Cu")
		(net "PWRGD_P3V3_RGM")
	)
	(segment
		(start 17.4625 -103.251)
		(end 16.891 -103.251)
		(width 0.08382)
		(layer "In2.Cu")
		(net "PWRGD_P3V3_RGM")
	)
	(segment
		(start 42.39768 -99.905058)
		(end 37.714936 -99.905058)
		(width 0.08382)
		(layer "In2.Cu")
		(net "PWRGD_P3V3_RGM")
	)
	(segment
		(start 19.668998 -66.74104)
		(end 19.765518 -66.83756)
		(width 0.08382)
		(layer "In2.Cu")
		(net "PWRGD_P3V3_RGM")
	)
	(segment
		(start 37.714936 -99.905058)
		(end 36.733988 -98.92411)
		(width 0.08382)
		(layer "In2.Cu")
		(net "PWRGD_P3V3_RGM")
	)
	(segment
		(start 48.012858 -96.58858)
		(end 47.785528 -96.81591)
		(width 0.08382)
		(layer "In2.Cu")
		(net "PWRGD_P3V3_RGM")
	)
	(segment
		(start 23.35022 -102.21214)
		(end 21.40585 -102.21214)
		(width 0.08382)
		(layer "In2.Cu")
		(net "PWRGD_P3V3_RGM")
	)
	(segment
		(start 31.806388 -100.67671)
		(end 29.523436 -100.67671)
		(width 0.08382)
		(layer "In2.Cu")
		(net "PWRGD_P3V3_RGM")
	)
	(segment
		(start 29.39161 -64.24041)
		(end 29.77642 -64.62522)
		(width 0.08382)
		(layer "In2.Cu")
		(net "PWRGD_P3V3_RGM")
	)
	(segment
		(start 47.785528 -96.81591)
		(end 45.486828 -96.81591)
		(width 0.08382)
		(layer "In2.Cu")
		(net "PWRGD_P3V3_RGM")
	)
	(segment
		(start 62.812422 -97.0407)
		(end 61.222382 -98.63074)
		(width 0.08382)
		(layer "In2.Cu")
		(net "PWRGD_P3V3_RGM")
	)
	(segment
		(start 59.0296 -98.63074)
		(end 58.89498 -98.49612)
		(width 0.08382)
		(layer "In2.Cu")
		(net "PWRGD_P3V3_RGM")
	)
	(segment
		(start 56.54548 -99.24796)
		(end 53.90896 -96.61144)
		(width 0.08382)
		(layer "In2.Cu")
		(net "PWRGD_P3V3_RGM")
	)
	(segment
		(start 33.006792 -99.682046)
		(end 32.520128 -100.16871)
		(width 0.08382)
		(layer "In2.Cu")
		(net "PWRGD_P3V3_RGM")
	)
	(segment
		(start 24.17064 -65.552574)
		(end 25.734518 -63.988696)
		(width 0.08382)
		(layer "In2.Cu")
		(net "PWRGD_P3V3_RGM")
	)
	(segment
		(start 21.697188 -66.6623)
		(end 23.508208 -66.6623)
		(width 0.08382)
		(layer "In2.Cu")
		(net "PWRGD_P3V3_RGM")
	)
	(segment
		(start 16.5608 -104.0638)
		(end 16.845026 -104.348026)
		(width 0.08382)
		(layer "In2.Cu")
		(net "PWRGD_P3V3_RGM")
	)
	(segment
		(start 16.891 -103.251)
		(end 16.5608 -103.5812)
		(width 0.08382)
		(layer "In2.Cu")
		(net "PWRGD_P3V3_RGM")
	)
	(segment
		(start 53.80736 -96.58858)
		(end 48.012858 -96.58858)
		(width 0.08382)
		(layer "In2.Cu")
		(net "PWRGD_P3V3_RGM")
	)
	(segment
		(start 53.90896 -96.61144)
		(end 53.83022 -96.61144)
		(width 0.08382)
		(layer "In2.Cu")
		(net "PWRGD_P3V3_RGM")
	)
	(segment
		(start 57.76722 -98.49612)
		(end 57.01538 -99.24796)
		(width 0.08382)
		(layer "In2.Cu")
		(net "PWRGD_P3V3_RGM")
	)
	(segment
		(start 13.1064 -94.9452)
		(end 13.335 -95.1738)
		(width 0.10668)
		(layer "In4.Cu")
		(net "PWRGD_P3V3_RGM")
	)
	(segment
		(start 74.168 -77.0128)
		(end 74.168 -78.6892)
		(width 0.10668)
		(layer "In4.Cu")
		(net "PWRGD_P3V3_RGM")
	)
	(segment
		(start 14.097 -92.9386)
		(end 13.1064 -93.9292)
		(width 0.10668)
		(layer "In4.Cu")
		(net "PWRGD_P3V3_RGM")
	)
	(segment
		(start 16.891 -85.74786)
		(end 16.54048 -86.09838)
		(width 0.10668)
		(layer "In4.Cu")
		(net "PWRGD_P3V3_RGM")
	)
	(segment
		(start 72.0598 -96.325944)
		(end 72.050656 -96.325944)
		(width 0.10668)
		(layer "In4.Cu")
		(net "PWRGD_P3V3_RGM")
	)
	(segment
		(start 20.57908 -73.4314)
		(end 20.57908 -74.131932)
		(width 0.10668)
		(layer "In4.Cu")
		(net "PWRGD_P3V3_RGM")
	)
	(segment
		(start 13.335 -95.1738)
		(end 13.8176 -95.1738)
		(width 0.10668)
		(layer "In4.Cu")
		(net "PWRGD_P3V3_RGM")
	)
	(segment
		(start 73.756012 -80.705452)
		(end 74.177398 -80.705452)
		(width 0.10668)
		(layer "In4.Cu")
		(net "PWRGD_P3V3_RGM")
	)
	(segment
		(start 15.0876 -75.59548)
		(end 15.0876 -77.063854)
		(width 0.10668)
		(layer "In4.Cu")
		(net "PWRGD_P3V3_RGM")
	)
	(segment
		(start 17.8054 -68.604638)
		(end 17.8054 -69.593206)
		(width 0.10668)
		(layer "In4.Cu")
		(net "PWRGD_P3V3_RGM")
	)
	(segment
		(start 16.83258 -73.8505)
		(end 15.0876 -75.59548)
		(width 0.10668)
		(layer "In4.Cu")
		(net "PWRGD_P3V3_RGM")
	)
	(segment
		(start 74.93 -81.458054)
		(end 74.93 -84.328254)
		(width 0.10668)
		(layer "In4.Cu")
		(net "PWRGD_P3V3_RGM")
	)
	(segment
		(start 19.354546 -72.9996)
		(end 20.14728 -72.9996)
		(width 0.10668)
		(layer "In4.Cu")
		(net "PWRGD_P3V3_RGM")
	)
	(segment
		(start 74.168 -78.6892)
		(end 73.1774 -79.6798)
		(width 0.10668)
		(layer "In4.Cu")
		(net "PWRGD_P3V3_RGM")
	)
	(segment
		(start 18.50644 -73.8505)
		(end 16.83258 -73.8505)
		(width 0.10668)
		(layer "In4.Cu")
		(net "PWRGD_P3V3_RGM")
	)
	(segment
		(start 73.1774 -80.12684)
		(end 73.756012 -80.705452)
		(width 0.10668)
		(layer "In4.Cu")
		(net "PWRGD_P3V3_RGM")
	)
	(segment
		(start 15.0876 -77.063854)
		(end 15.940278 -77.916532)
		(width 0.10668)
		(layer "In4.Cu")
		(net "PWRGD_P3V3_RGM")
	)
	(segment
		(start 17.8054 -69.593206)
		(end 18.8341 -70.621906)
		(width 0.10668)
		(layer "In4.Cu")
		(net "PWRGD_P3V3_RGM")
	)
	(segment
		(start 75.565 -91.2114)
		(end 72.0598 -94.7166)
		(width 0.10668)
		(layer "In4.Cu")
		(net "PWRGD_P3V3_RGM")
	)
	(segment
		(start 15.2908 -88.646)
		(end 14.097 -89.8398)
		(width 0.10668)
		(layer "In4.Cu")
		(net "PWRGD_P3V3_RGM")
	)
	(segment
		(start 76.931266 -71.751698)
		(end 77.47 -72.290432)
		(width 0.10668)
		(layer "In4.Cu")
		(net "PWRGD_P3V3_RGM")
	)
	(segment
		(start 16.891 -79.234792)
		(end 16.891 -85.74786)
		(width 0.10668)
		(layer "In4.Cu")
		(net "PWRGD_P3V3_RGM")
	)
	(segment
		(start 18.8341 -70.621906)
		(end 18.8341 -72.479154)
		(width 0.10668)
		(layer "In4.Cu")
		(net "PWRGD_P3V3_RGM")
	)
	(segment
		(start 75.565 -84.963254)
		(end 75.565 -91.2114)
		(width 0.10668)
		(layer "In4.Cu")
		(net "PWRGD_P3V3_RGM")
	)
	(segment
		(start 20.289012 -74.422)
		(end 19.07794 -74.422)
		(width 0.10668)
		(layer "In4.Cu")
		(net "PWRGD_P3V3_RGM")
	)
	(segment
		(start 74.93 -84.328254)
		(end 75.565 -84.963254)
		(width 0.10668)
		(layer "In4.Cu")
		(net "PWRGD_P3V3_RGM")
	)
	(segment
		(start 13.1064 -93.9292)
		(end 13.1064 -94.9452)
		(width 0.10668)
		(layer "In4.Cu")
		(net "PWRGD_P3V3_RGM")
	)
	(segment
		(start 16.54048 -88.18372)
		(end 16.0782 -88.646)
		(width 0.10668)
		(layer "In4.Cu")
		(net "PWRGD_P3V3_RGM")
	)
	(segment
		(start 74.177398 -80.705452)
		(end 74.93 -81.458054)
		(width 0.10668)
		(layer "In4.Cu")
		(net "PWRGD_P3V3_RGM")
	)
	(segment
		(start 72.0598 -94.7166)
		(end 72.0598 -96.325944)
		(width 0.10668)
		(layer "In4.Cu")
		(net "PWRGD_P3V3_RGM")
	)
	(segment
		(start 73.1774 -79.6798)
		(end 73.1774 -80.12684)
		(width 0.10668)
		(layer "In4.Cu")
		(net "PWRGD_P3V3_RGM")
	)
	(segment
		(start 16.54048 -86.09838)
		(end 16.54048 -88.18372)
		(width 0.10668)
		(layer "In4.Cu")
		(net "PWRGD_P3V3_RGM")
	)
	(segment
		(start 19.07794 -74.422)
		(end 18.50644 -73.8505)
		(width 0.10668)
		(layer "In4.Cu")
		(net "PWRGD_P3V3_RGM")
	)
	(segment
		(start 77.47 -72.290432)
		(end 77.47 -73.7108)
		(width 0.10668)
		(layer "In4.Cu")
		(net "PWRGD_P3V3_RGM")
	)
	(segment
		(start 15.940278 -78.28407)
		(end 16.891 -79.234792)
		(width 0.10668)
		(layer "In4.Cu")
		(net "PWRGD_P3V3_RGM")
	)
	(segment
		(start 14.097 -89.8398)
		(end 14.097 -92.9386)
		(width 0.10668)
		(layer "In4.Cu")
		(net "PWRGD_P3V3_RGM")
	)
	(segment
		(start 16.0782 -88.646)
		(end 15.2908 -88.646)
		(width 0.10668)
		(layer "In4.Cu")
		(net "PWRGD_P3V3_RGM")
	)
	(segment
		(start 77.47 -73.7108)
		(end 74.168 -77.0128)
		(width 0.10668)
		(layer "In4.Cu")
		(net "PWRGD_P3V3_RGM")
	)
	(segment
		(start 18.8341 -72.479154)
		(end 19.354546 -72.9996)
		(width 0.10668)
		(layer "In4.Cu")
		(net "PWRGD_P3V3_RGM")
	)
	(segment
		(start 19.668998 -66.74104)
		(end 17.8054 -68.604638)
		(width 0.10668)
		(layer "In4.Cu")
		(net "PWRGD_P3V3_RGM")
	)
	(segment
		(start 20.57908 -74.131932)
		(end 20.289012 -74.422)
		(width 0.10668)
		(layer "In4.Cu")
		(net "PWRGD_P3V3_RGM")
	)
	(segment
		(start 20.14728 -72.9996)
		(end 20.57908 -73.4314)
		(width 0.10668)
		(layer "In4.Cu")
		(net "PWRGD_P3V3_RGM")
	)
	(segment
		(start 15.940278 -77.916532)
		(end 15.940278 -78.28407)
		(width 0.10668)
		(layer "In4.Cu")
		(net "PWRGD_P3V3_RGM")
	)
	(segment
		(start 13.97 -99.20224)
		(end 13.39596 -99.77628)
		(width 0.10668)
		(layer "In7.Cu")
		(net "PWRGD_P3V3_RGM")
	)
	(segment
		(start 13.8176 -95.1738)
		(end 13.97 -95.3262)
		(width 0.10668)
		(layer "In7.Cu")
		(net "PWRGD_P3V3_RGM")
	)
	(segment
		(start 78.657958 -61.659008)
		(end 78.657958 -70.025006)
		(width 0.10668)
		(layer "In7.Cu")
		(net "PWRGD_P3V3_RGM")
	)
	(segment
		(start 72.4535 -29.7815)
		(end 73.83526 -28.39974)
		(width 0.10668)
		(layer "In7.Cu")
		(net "PWRGD_P3V3_RGM")
	)
	(segment
		(start 79.220314 -57.101486)
		(end 79.220314 -61.096652)
		(width 0.10668)
		(layer "In7.Cu")
		(net "PWRGD_P3V3_RGM")
	)
	(segment
		(start 87.55888 -29.588968)
		(end 87.55888 -55.687722)
		(width 0.10668)
		(layer "In7.Cu")
		(net "PWRGD_P3V3_RGM")
	)
	(segment
		(start 16.0274 -104.5718)
		(end 16.389858 -104.5718)
		(width 0.10668)
		(layer "In7.Cu")
		(net "PWRGD_P3V3_RGM")
	)
	(segment
		(start 84.127848 -29.083)
		(end 87.052912 -29.083)
		(width 0.10668)
		(layer "In7.Cu")
		(net "PWRGD_P3V3_RGM")
	)
	(segment
		(start 79.732378 -25.401778)
		(end 81.847944 -27.517344)
		(width 0.10668)
		(layer "In7.Cu")
		(net "PWRGD_P3V3_RGM")
	)
	(segment
		(start 15.5194 -103.784654)
		(end 15.5194 -104.0638)
		(width 0.10668)
		(layer "In7.Cu")
		(net "PWRGD_P3V3_RGM")
	)
	(segment
		(start 79.86141 -56.46039)
		(end 79.220314 -57.101486)
		(width 0.10668)
		(layer "In7.Cu")
		(net "PWRGD_P3V3_RGM")
	)
	(segment
		(start 75.664568 -25.401778)
		(end 79.732378 -25.401778)
		(width 0.10668)
		(layer "In7.Cu")
		(net "PWRGD_P3V3_RGM")
	)
	(segment
		(start 81.847944 -27.517344)
		(end 82.562192 -27.517344)
		(width 0.10668)
		(layer "In7.Cu")
		(net "PWRGD_P3V3_RGM")
	)
	(segment
		(start 87.052912 -29.083)
		(end 87.55888 -29.588968)
		(width 0.10668)
		(layer "In7.Cu")
		(net "PWRGD_P3V3_RGM")
	)
	(segment
		(start 15.5194 -104.0638)
		(end 16.0274 -104.5718)
		(width 0.10668)
		(layer "In7.Cu")
		(net "PWRGD_P3V3_RGM")
	)
	(segment
		(start 87.55888 -55.687722)
		(end 86.786212 -56.46039)
		(width 0.10668)
		(layer "In7.Cu")
		(net "PWRGD_P3V3_RGM")
	)
	(segment
		(start 78.657958 -70.025006)
		(end 76.931266 -71.751698)
		(width 0.10668)
		(layer "In7.Cu")
		(net "PWRGD_P3V3_RGM")
	)
	(segment
		(start 13.39596 -101.661214)
		(end 15.5194 -103.784654)
		(width 0.10668)
		(layer "In7.Cu")
		(net "PWRGD_P3V3_RGM")
	)
	(segment
		(start 79.220314 -61.096652)
		(end 78.657958 -61.659008)
		(width 0.10668)
		(layer "In7.Cu")
		(net "PWRGD_P3V3_RGM")
	)
	(segment
		(start 86.786212 -56.46039)
		(end 79.86141 -56.46039)
		(width 0.10668)
		(layer "In7.Cu")
		(net "PWRGD_P3V3_RGM")
	)
	(segment
		(start 16.389858 -104.5718)
		(end 16.845026 -105.026968)
		(width 0.10668)
		(layer "In7.Cu")
		(net "PWRGD_P3V3_RGM")
	)
	(segment
		(start 73.83526 -27.231086)
		(end 75.664568 -25.401778)
		(width 0.10668)
		(layer "In7.Cu")
		(net "PWRGD_P3V3_RGM")
	)
	(segment
		(start 13.97 -95.3262)
		(end 13.97 -99.20224)
		(width 0.10668)
		(layer "In7.Cu")
		(net "PWRGD_P3V3_RGM")
	)
	(segment
		(start 13.39596 -99.77628)
		(end 13.39596 -101.661214)
		(width 0.10668)
		(layer "In7.Cu")
		(net "PWRGD_P3V3_RGM")
	)
	(segment
		(start 82.562192 -27.517344)
		(end 84.127848 -29.083)
		(width 0.10668)
		(layer "In7.Cu")
		(net "PWRGD_P3V3_RGM")
	)
	(segment
		(start 73.83526 -28.39974)
		(end 73.83526 -27.231086)
		(width 0.10668)
		(layer "In7.Cu")
		(net "PWRGD_P3V3_RGM")
	)
	(segment
		(start 9.525 -84.709)
		(end 9.525 -85.217)
		(width 0.11684)
		(layer "F.Cu")
		(net "PWRGD_P1V0_AUX_DELAY")
	)
	(segment
		(start 8.255 -86.487)
		(end 7.62 -86.487)
		(width 0.11684)
		(layer "F.Cu")
		(net "PWRGD_P1V0_AUX_DELAY")
	)
	(segment
		(start 9.2456 -84.4296)
		(end 9.525 -84.709)
		(width 0.11684)
		(layer "F.Cu")
		(net "PWRGD_P1V0_AUX_DELAY")
	)
	(segment
		(start 6.6294 -87.4776)
		(end 4.54914 -87.4776)
		(width 0.11684)
		(layer "F.Cu")
		(net "PWRGD_P1V0_AUX_DELAY")
	)
	(segment
		(start 9.647936 -85.339936)
		(end 9.647936 -85.828886)
		(width 0.11684)
		(layer "F.Cu")
		(net "PWRGD_P1V0_AUX_DELAY")
	)
	(segment
		(start 23.4188 -35.95116)
		(end 22.64918 -35.95116)
		(width 0.11684)
		(layer "F.Cu")
		(net "PWRGD_P1V0_AUX_DELAY")
	)
	(segment
		(start 4.42214 -105.680764)
		(end 3.7084 -106.394504)
		(width 0.11684)
		(layer "F.Cu")
		(net "PWRGD_P1V0_AUX_DELAY")
	)
	(segment
		(start 44.3484 -28.13685)
		(end 45.212 -27.27325)
		(width 0.11684)
		(layer "F.Cu")
		(net "PWRGD_P1V0_AUX_DELAY")
	)
	(segment
		(start 9.647936 -85.828886)
		(end 9.67105 -85.852)
		(width 0.11684)
		(layer "F.Cu")
		(net "PWRGD_P1V0_AUX_DELAY")
	)
	(segment
		(start 3.7084 -106.394504)
		(end 3.7084 -107.315)
		(width 0.11684)
		(layer "F.Cu")
		(net "PWRGD_P1V0_AUX_DELAY")
	)
	(segment
		(start 7.17804 -83.199986)
		(end 7.17804 -84.038186)
		(width 0.11684)
		(layer "F.Cu")
		(net "PWRGD_P1V0_AUX_DELAY")
	)
	(segment
		(start 31.764732 -36.923218)
		(end 32.893 -35.79495)
		(width 0.11684)
		(layer "F.Cu")
		(net "PWRGD_P1V0_AUX_DELAY")
	)
	(segment
		(start 8.763 -86.995)
		(end 8.255 -86.487)
		(width 0.11684)
		(layer "F.Cu")
		(net "PWRGD_P1V0_AUX_DELAY")
	)
	(segment
		(start 61.563758 -11.317478)
		(end 61.705236 -11.176)
		(width 0.11684)
		(layer "F.Cu")
		(net "PWRGD_P1V0_AUX_DELAY")
	)
	(segment
		(start 23.75916 -35.95116)
		(end 26.106374 -36.923218)
		(width 0.11684)
		(layer "F.Cu")
		(net "PWRGD_P1V0_AUX_DELAY")
	)
	(segment
		(start 63.36665 -14.176248)
		(end 63.36665 -13.719048)
		(width 0.11684)
		(layer "F.Cu")
		(net "PWRGD_P1V0_AUX_DELAY")
	)
	(segment
		(start 63.36665 -13.719048)
		(end 61.563758 -11.916156)
		(width 0.11684)
		(layer "F.Cu")
		(net "PWRGD_P1V0_AUX_DELAY")
	)
	(segment
		(start 7.569454 -84.4296)
		(end 9.2456 -84.4296)
		(width 0.11684)
		(layer "F.Cu")
		(net "PWRGD_P1V0_AUX_DELAY")
	)
	(segment
		(start 61.705236 -11.176)
		(end 62.42304 -11.176)
		(width 0.11684)
		(layer "F.Cu")
		(net "PWRGD_P1V0_AUX_DELAY")
	)
	(segment
		(start 44.3484 -28.956)
		(end 44.3484 -28.13685)
		(width 0.11684)
		(layer "F.Cu")
		(net "PWRGD_P1V0_AUX_DELAY")
	)
	(segment
		(start 7.17804 -84.038186)
		(end 7.569454 -84.4296)
		(width 0.11684)
		(layer "F.Cu")
		(net "PWRGD_P1V0_AUX_DELAY")
	)
	(segment
		(start 4.54914 -87.4776)
		(end 4.42214 -87.6046)
		(width 0.11684)
		(layer "F.Cu")
		(net "PWRGD_P1V0_AUX_DELAY")
	)
	(segment
		(start 61.563758 -11.916156)
		(end 61.563758 -11.317478)
		(width 0.11684)
		(layer "F.Cu")
		(net "PWRGD_P1V0_AUX_DELAY")
	)
	(segment
		(start 26.106374 -36.923218)
		(end 31.764732 -36.923218)
		(width 0.11684)
		(layer "F.Cu")
		(net "PWRGD_P1V0_AUX_DELAY")
	)
	(segment
		(start 4.42214 -87.6046)
		(end 4.42214 -105.680764)
		(width 0.11684)
		(layer "F.Cu")
		(net "PWRGD_P1V0_AUX_DELAY")
	)
	(segment
		(start 9.525 -85.217)
		(end 9.647936 -85.339936)
		(width 0.11684)
		(layer "F.Cu")
		(net "PWRGD_P1V0_AUX_DELAY")
	)
	(segment
		(start 9.525 -86.995)
		(end 8.763 -86.995)
		(width 0.11684)
		(layer "F.Cu")
		(net "PWRGD_P1V0_AUX_DELAY")
	)
	(segment
		(start 23.4188 -35.95116)
		(end 23.75916 -35.95116)
		(width 0.11684)
		(layer "F.Cu")
		(net "PWRGD_P1V0_AUX_DELAY")
	)
	(segment
		(start 7.62 -86.487)
		(end 6.6294 -87.4776)
		(width 0.11684)
		(layer "F.Cu")
		(net "PWRGD_P1V0_AUX_DELAY")
	)
	(segment
		(start 9.67105 -85.852)
		(end 9.67105 -86.84895)
		(width 0.11684)
		(layer "F.Cu")
		(net "PWRGD_P1V0_AUX_DELAY")
	)
	(segment
		(start 9.67105 -86.84895)
		(end 9.525 -86.995)
		(width 0.11684)
		(layer "F.Cu")
		(net "PWRGD_P1V0_AUX_DELAY")
	)
	(via
		(at 3.7084 -107.315)
		(size 0.508)
		(drill 0.254)
		(layers "F.Cu" "B.Cu")
		(net "PWRGD_P1V0_AUX_DELAY")
	)
	(via
		(at 44.3484 -28.956)
		(size 0.508)
		(drill 0.254)
		(layers "F.Cu" "B.Cu")
		(net "PWRGD_P1V0_AUX_DELAY")
	)
	(via
		(at 63.36665 -14.176248)
		(size 0.508)
		(drill 0.254)
		(layers "F.Cu" "B.Cu")
		(net "PWRGD_P1V0_AUX_DELAY")
	)
	(via
		(at 66.827908 -23.29815)
		(size 0.508)
		(drill 0.254)
		(layers "F.Cu" "B.Cu")
		(net "PWRGD_P1V0_AUX_DELAY")
	)
	(via
		(at 23.4188 -35.95116)
		(size 0.762)
		(drill 0.381)
		(layers "F.Cu" "B.Cu")
		(net "PWRGD_P1V0_AUX_DELAY")
	)
	(via
		(at 22.64918 -35.95116)
		(size 0.508)
		(drill 0.254)
		(layers "F.Cu" "B.Cu")
		(net "PWRGD_P1V0_AUX_DELAY")
	)
	(segment
		(start 49.51984 -29.572712)
		(end 49.51984 -28.141676)
		(width 0.08382)
		(layer "In2.Cu")
		(net "PWRGD_P1V0_AUX_DELAY")
	)
	(segment
		(start 59.486292 -24.160988)
		(end 59.82081 -23.82647)
		(width 0.08382)
		(layer "In2.Cu")
		(net "PWRGD_P1V0_AUX_DELAY")
	)
	(segment
		(start 62.58941 -23.48738)
		(end 63.570866 -22.505924)
		(width 0.08382)
		(layer "In2.Cu")
		(net "PWRGD_P1V0_AUX_DELAY")
	)
	(segment
		(start 25.2476 -32.893)
		(end 26.2128 -32.893)
		(width 0.08382)
		(layer "In2.Cu")
		(net "PWRGD_P1V0_AUX_DELAY")
	)
	(segment
		(start 41.595548 -28.067)
		(end 43.4594 -28.067)
		(width 0.08382)
		(layer "In2.Cu")
		(net "PWRGD_P1V0_AUX_DELAY")
	)
	(segment
		(start 44.3484 -28.956)
		(end 44.3484 -29.45384)
		(width 0.08382)
		(layer "In2.Cu")
		(net "PWRGD_P1V0_AUX_DELAY")
	)
	(segment
		(start 64.618362 -22.505924)
		(end 65.47231 -23.359872)
		(width 0.08382)
		(layer "In2.Cu")
		(net "PWRGD_P1V0_AUX_DELAY")
	)
	(segment
		(start 48.701198 -30.391354)
		(end 49.51984 -29.572712)
		(width 0.08382)
		(layer "In2.Cu")
		(net "PWRGD_P1V0_AUX_DELAY")
	)
	(segment
		(start 45.285914 -30.391354)
		(end 48.701198 -30.391354)
		(width 0.08382)
		(layer "In2.Cu")
		(net "PWRGD_P1V0_AUX_DELAY")
	)
	(segment
		(start 33.460944 -29.6672)
		(end 35.391344 -27.7368)
		(width 0.08382)
		(layer "In2.Cu")
		(net "PWRGD_P1V0_AUX_DELAY")
	)
	(segment
		(start 49.51984 -28.141676)
		(end 52.989988 -24.671528)
		(width 0.08382)
		(layer "In2.Cu")
		(net "PWRGD_P1V0_AUX_DELAY")
	)
	(segment
		(start 59.82081 -23.82647)
		(end 61.268864 -23.82647)
		(width 0.08382)
		(layer "In2.Cu")
		(net "PWRGD_P1V0_AUX_DELAY")
	)
	(segment
		(start 32.3342 -29.6672)
		(end 33.460944 -29.6672)
		(width 0.08382)
		(layer "In2.Cu")
		(net "PWRGD_P1V0_AUX_DELAY")
	)
	(segment
		(start 22.64918 -35.95116)
		(end 23.5458 -35.05454)
		(width 0.08382)
		(layer "In2.Cu")
		(net "PWRGD_P1V0_AUX_DELAY")
	)
	(segment
		(start 26.2128 -32.893)
		(end 28.8544 -30.2514)
		(width 0.08382)
		(layer "In2.Cu")
		(net "PWRGD_P1V0_AUX_DELAY")
	)
	(segment
		(start 63.570866 -22.505924)
		(end 64.618362 -22.505924)
		(width 0.08382)
		(layer "In2.Cu")
		(net "PWRGD_P1V0_AUX_DELAY")
	)
	(segment
		(start 35.391344 -27.7368)
		(end 41.265348 -27.7368)
		(width 0.08382)
		(layer "In2.Cu")
		(net "PWRGD_P1V0_AUX_DELAY")
	)
	(segment
		(start 54.548024 -24.671528)
		(end 55.058564 -24.160988)
		(width 0.08382)
		(layer "In2.Cu")
		(net "PWRGD_P1V0_AUX_DELAY")
	)
	(segment
		(start 61.268864 -23.82647)
		(end 61.607954 -23.48738)
		(width 0.08382)
		(layer "In2.Cu")
		(net "PWRGD_P1V0_AUX_DELAY")
	)
	(segment
		(start 41.265348 -27.7368)
		(end 41.595548 -28.067)
		(width 0.08382)
		(layer "In2.Cu")
		(net "PWRGD_P1V0_AUX_DELAY")
	)
	(segment
		(start 23.5458 -35.05454)
		(end 23.5458 -34.5948)
		(width 0.08382)
		(layer "In2.Cu")
		(net "PWRGD_P1V0_AUX_DELAY")
	)
	(segment
		(start 23.5458 -34.5948)
		(end 25.2476 -32.893)
		(width 0.08382)
		(layer "In2.Cu")
		(net "PWRGD_P1V0_AUX_DELAY")
	)
	(segment
		(start 44.3484 -29.45384)
		(end 45.285914 -30.391354)
		(width 0.08382)
		(layer "In2.Cu")
		(net "PWRGD_P1V0_AUX_DELAY")
	)
	(segment
		(start 52.989988 -24.671528)
		(end 54.548024 -24.671528)
		(width 0.08382)
		(layer "In2.Cu")
		(net "PWRGD_P1V0_AUX_DELAY")
	)
	(segment
		(start 28.8544 -30.2514)
		(end 31.75 -30.2514)
		(width 0.08382)
		(layer "In2.Cu")
		(net "PWRGD_P1V0_AUX_DELAY")
	)
	(segment
		(start 31.75 -30.2514)
		(end 32.3342 -29.6672)
		(width 0.08382)
		(layer "In2.Cu")
		(net "PWRGD_P1V0_AUX_DELAY")
	)
	(segment
		(start 65.47231 -23.359872)
		(end 66.766186 -23.359872)
		(width 0.08382)
		(layer "In2.Cu")
		(net "PWRGD_P1V0_AUX_DELAY")
	)
	(segment
		(start 55.058564 -24.160988)
		(end 59.486292 -24.160988)
		(width 0.08382)
		(layer "In2.Cu")
		(net "PWRGD_P1V0_AUX_DELAY")
	)
	(segment
		(start 43.4594 -28.067)
		(end 44.3484 -28.956)
		(width 0.08382)
		(layer "In2.Cu")
		(net "PWRGD_P1V0_AUX_DELAY")
	)
	(segment
		(start 61.607954 -23.48738)
		(end 62.58941 -23.48738)
		(width 0.08382)
		(layer "In2.Cu")
		(net "PWRGD_P1V0_AUX_DELAY")
	)
	(segment
		(start 66.766186 -23.359872)
		(end 66.827908 -23.29815)
		(width 0.08382)
		(layer "In2.Cu")
		(net "PWRGD_P1V0_AUX_DELAY")
	)
	(segment
		(start 13.63599 -78.082902)
		(end 13.63599 -63.67907)
		(width 0.08382)
		(layer "In9.Cu")
		(net "PWRGD_P1V0_AUX_DELAY")
	)
	(segment
		(start 4.031488 -107.315)
		(end 4.715256 -107.998768)
		(width 0.08382)
		(layer "In9.Cu")
		(net "PWRGD_P1V0_AUX_DELAY")
	)
	(segment
		(start 11.081512 -87.9348)
		(end 11.3792 -87.9348)
		(width 0.08382)
		(layer "In9.Cu")
		(net "PWRGD_P1V0_AUX_DELAY")
	)
	(segment
		(start 66.69405 -23.164292)
		(end 66.69024 -23.164292)
		(width 0.08382)
		(layer "In9.Cu")
		(net "PWRGD_P1V0_AUX_DELAY")
	)
	(segment
		(start 12.40536 -98.657664)
		(end 11.791696 -98.044)
		(width 0.08382)
		(layer "In9.Cu")
		(net "PWRGD_P1V0_AUX_DELAY")
	)
	(segment
		(start 12.88288 -84.19592)
		(end 12.88288 -81.589626)
		(width 0.08382)
		(layer "In9.Cu")
		(net "PWRGD_P1V0_AUX_DELAY")
	)
	(segment
		(start 15.72641 -48.68418)
		(end 15.513304 -48.471074)
		(width 0.08382)
		(layer "In9.Cu")
		(net "PWRGD_P1V0_AUX_DELAY")
	)
	(segment
		(start 12.88288 -81.589626)
		(end 13.38961 -81.082896)
		(width 0.08382)
		(layer "In9.Cu")
		(net "PWRGD_P1V0_AUX_DELAY")
	)
	(segment
		(start 17.572736 -41.88841)
		(end 19.71421 -41.88841)
		(width 0.08382)
		(layer "In9.Cu")
		(net "PWRGD_P1V0_AUX_DELAY")
	)
	(segment
		(start 16.449294 -43.011852)
		(end 17.572736 -41.88841)
		(width 0.08382)
		(layer "In9.Cu")
		(net "PWRGD_P1V0_AUX_DELAY")
	)
	(segment
		(start 11.7856 -85.2932)
		(end 12.88288 -84.19592)
		(width 0.08382)
		(layer "In9.Cu")
		(net "PWRGD_P1V0_AUX_DELAY")
	)
	(segment
		(start 15.50924 -59.180984)
		(end 15.50924 -57.318148)
		(width 0.08382)
		(layer "In9.Cu")
		(net "PWRGD_P1V0_AUX_DELAY")
	)
	(segment
		(start 10.16 -88.856312)
		(end 11.081512 -87.9348)
		(width 0.08382)
		(layer "In9.Cu")
		(net "PWRGD_P1V0_AUX_DELAY")
	)
	(segment
		(start 13.38961 -81.082896)
		(end 13.38961 -80.616044)
		(width 0.08382)
		(layer "In9.Cu")
		(net "PWRGD_P1V0_AUX_DELAY")
	)
	(segment
		(start 14.33195 -78.778862)
		(end 13.63599 -78.082902)
		(width 0.08382)
		(layer "In9.Cu")
		(net "PWRGD_P1V0_AUX_DELAY")
	)
	(segment
		(start 19.71421 -41.88841)
		(end 19.9136 -42.0878)
		(width 0.08382)
		(layer "In9.Cu")
		(net "PWRGD_P1V0_AUX_DELAY")
	)
	(segment
		(start 11.791696 -98.044)
		(end 10.871454 -98.044)
		(width 0.08382)
		(layer "In9.Cu")
		(net "PWRGD_P1V0_AUX_DELAY")
	)
	(segment
		(start 10.65276 -104.267)
		(end 10.65276 -103.219504)
		(width 0.08382)
		(layer "In9.Cu")
		(net "PWRGD_P1V0_AUX_DELAY")
	)
	(segment
		(start 6.167882 -108.66755)
		(end 6.819392 -108.66755)
		(width 0.08382)
		(layer "In9.Cu")
		(net "PWRGD_P1V0_AUX_DELAY")
	)
	(segment
		(start 10.65276 -103.219504)
		(end 11.76528 -102.106984)
		(width 0.08382)
		(layer "In9.Cu")
		(net "PWRGD_P1V0_AUX_DELAY")
	)
	(segment
		(start 10.7188 -96.5708)
		(end 10.16 -96.012)
		(width 0.08382)
		(layer "In9.Cu")
		(net "PWRGD_P1V0_AUX_DELAY")
	)
	(segment
		(start 66.69024 -23.164292)
		(end 66.60642 -23.080472)
		(width 0.08382)
		(layer "In9.Cu")
		(net "PWRGD_P1V0_AUX_DELAY")
	)
	(segment
		(start 16.449294 -46.31055)
		(end 16.449294 -43.011852)
		(width 0.08382)
		(layer "In9.Cu")
		(net "PWRGD_P1V0_AUX_DELAY")
	)
	(segment
		(start 63.36665 -16.764254)
		(end 63.36665 -14.176248)
		(width 0.08382)
		(layer "In9.Cu")
		(net "PWRGD_P1V0_AUX_DELAY")
	)
	(segment
		(start 15.5448 -61.77026)
		(end 15.5448 -60.2234)
		(width 0.08382)
		(layer "In9.Cu")
		(net "PWRGD_P1V0_AUX_DELAY")
	)
	(segment
		(start 5.4991 -107.998768)
		(end 6.167882 -108.66755)
		(width 0.08382)
		(layer "In9.Cu")
		(net "PWRGD_P1V0_AUX_DELAY")
	)
	(segment
		(start 10.871454 -98.044)
		(end 10.7188 -97.891346)
		(width 0.08382)
		(layer "In9.Cu")
		(net "PWRGD_P1V0_AUX_DELAY")
	)
	(segment
		(start 4.715256 -107.998768)
		(end 5.4991 -107.998768)
		(width 0.08382)
		(layer "In9.Cu")
		(net "PWRGD_P1V0_AUX_DELAY")
	)
	(segment
		(start 21.12391 -42.0878)
		(end 22.82571 -40.386)
		(width 0.08382)
		(layer "In9.Cu")
		(net "PWRGD_P1V0_AUX_DELAY")
	)
	(segment
		(start 11.76528 -102.106984)
		(end 11.76528 -100.458016)
		(width 0.08382)
		(layer "In9.Cu")
		(net "PWRGD_P1V0_AUX_DELAY")
	)
	(segment
		(start 15.513304 -48.471074)
		(end 15.513304 -47.24654)
		(width 0.08382)
		(layer "In9.Cu")
		(net "PWRGD_P1V0_AUX_DELAY")
	)
	(segment
		(start 10.16 -96.012)
		(end 10.16 -88.856312)
		(width 0.08382)
		(layer "In9.Cu")
		(net "PWRGD_P1V0_AUX_DELAY")
	)
	(segment
		(start 14.33195 -79.673704)
		(end 14.33195 -78.778862)
		(width 0.08382)
		(layer "In9.Cu")
		(net "PWRGD_P1V0_AUX_DELAY")
	)
	(segment
		(start 15.5448 -60.2234)
		(end 15.8242 -59.944)
		(width 0.08382)
		(layer "In9.Cu")
		(net "PWRGD_P1V0_AUX_DELAY")
	)
	(segment
		(start 15.8242 -59.944)
		(end 15.8242 -59.495944)
		(width 0.08382)
		(layer "In9.Cu")
		(net "PWRGD_P1V0_AUX_DELAY")
	)
	(segment
		(start 11.7856 -87.5284)
		(end 11.7856 -85.2932)
		(width 0.08382)
		(layer "In9.Cu")
		(net "PWRGD_P1V0_AUX_DELAY")
	)
	(segment
		(start 19.9136 -42.0878)
		(end 21.12391 -42.0878)
		(width 0.08382)
		(layer "In9.Cu")
		(net "PWRGD_P1V0_AUX_DELAY")
	)
	(segment
		(start 22.82571 -40.386)
		(end 22.82571 -36.12769)
		(width 0.08382)
		(layer "In9.Cu")
		(net "PWRGD_P1V0_AUX_DELAY")
	)
	(segment
		(start 10.7188 -97.891346)
		(end 10.7188 -96.5708)
		(width 0.08382)
		(layer "In9.Cu")
		(net "PWRGD_P1V0_AUX_DELAY")
	)
	(segment
		(start 12.40536 -99.817936)
		(end 12.40536 -98.657664)
		(width 0.08382)
		(layer "In9.Cu")
		(net "PWRGD_P1V0_AUX_DELAY")
	)
	(segment
		(start 8.43026 -107.056682)
		(end 8.43026 -106.4895)
		(width 0.08382)
		(layer "In9.Cu")
		(net "PWRGD_P1V0_AUX_DELAY")
	)
	(segment
		(start 8.43026 -106.4895)
		(end 10.65276 -104.267)
		(width 0.08382)
		(layer "In9.Cu")
		(net "PWRGD_P1V0_AUX_DELAY")
	)
	(segment
		(start 66.827908 -23.29815)
		(end 66.69405 -23.164292)
		(width 0.08382)
		(layer "In9.Cu")
		(net "PWRGD_P1V0_AUX_DELAY")
	)
	(segment
		(start 15.8242 -59.495944)
		(end 15.50924 -59.180984)
		(width 0.08382)
		(layer "In9.Cu")
		(net "PWRGD_P1V0_AUX_DELAY")
	)
	(segment
		(start 66.60642 -23.080472)
		(end 66.60642 -20.004024)
		(width 0.08382)
		(layer "In9.Cu")
		(net "PWRGD_P1V0_AUX_DELAY")
	)
	(segment
		(start 11.3792 -87.9348)
		(end 11.7856 -87.5284)
		(width 0.08382)
		(layer "In9.Cu")
		(net "PWRGD_P1V0_AUX_DELAY")
	)
	(segment
		(start 13.63599 -63.67907)
		(end 15.5448 -61.77026)
		(width 0.08382)
		(layer "In9.Cu")
		(net "PWRGD_P1V0_AUX_DELAY")
	)
	(segment
		(start 15.72641 -57.100978)
		(end 15.72641 -48.68418)
		(width 0.08382)
		(layer "In9.Cu")
		(net "PWRGD_P1V0_AUX_DELAY")
	)
	(segment
		(start 11.76528 -100.458016)
		(end 12.40536 -99.817936)
		(width 0.08382)
		(layer "In9.Cu")
		(net "PWRGD_P1V0_AUX_DELAY")
	)
	(segment
		(start 15.513304 -47.24654)
		(end 16.449294 -46.31055)
		(width 0.08382)
		(layer "In9.Cu")
		(net "PWRGD_P1V0_AUX_DELAY")
	)
	(segment
		(start 6.819392 -108.66755)
		(end 8.43026 -107.056682)
		(width 0.08382)
		(layer "In9.Cu")
		(net "PWRGD_P1V0_AUX_DELAY")
	)
	(segment
		(start 22.82571 -36.12769)
		(end 22.64918 -35.95116)
		(width 0.08382)
		(layer "In9.Cu")
		(net "PWRGD_P1V0_AUX_DELAY")
	)
	(segment
		(start 66.60642 -20.004024)
		(end 63.36665 -16.764254)
		(width 0.08382)
		(layer "In9.Cu")
		(net "PWRGD_P1V0_AUX_DELAY")
	)
	(segment
		(start 3.7084 -107.315)
		(end 4.031488 -107.315)
		(width 0.08382)
		(layer "In9.Cu")
		(net "PWRGD_P1V0_AUX_DELAY")
	)
	(segment
		(start 13.38961 -80.616044)
		(end 14.33195 -79.673704)
		(width 0.08382)
		(layer "In9.Cu")
		(net "PWRGD_P1V0_AUX_DELAY")
	)
	(segment
		(start 15.50924 -57.318148)
		(end 15.72641 -57.100978)
		(width 0.08382)
		(layer "In9.Cu")
		(net "PWRGD_P1V0_AUX_DELAY")
	)
	(via
		(at 32.639 -108.22178)
		(size 0.6604)
		(drill 0.3302)
		(layers "F.Cu" "B.Cu")
		(net "PWRGD_PSU_AC_PWROK_R")
	)
	(segment
		(start 30.353 -110.91926)
		(end 30.353 -116.7892)
		(width 0.11684)
		(layer "B.Cu")
		(net "PWRGD_PSU_AC_PWROK_R")
	)
	(segment
		(start 30.82036 -110.4519)
		(end 30.353 -110.91926)
		(width 0.11684)
		(layer "B.Cu")
		(net "PWRGD_PSU_AC_PWROK_R")
	)
	(segment
		(start 31.00324 -109.521244)
		(end 30.82036 -109.704124)
		(width 0.11684)
		(layer "B.Cu")
		(net "PWRGD_PSU_AC_PWROK_R")
	)
	(segment
		(start 32.134302 -109.521244)
		(end 31.00324 -109.521244)
		(width 0.11684)
		(layer "B.Cu")
		(net "PWRGD_PSU_AC_PWROK_R")
	)
	(segment
		(start 29.945076 -117.197124)
		(end 29.945076 -118.25986)
		(width 0.11684)
		(layer "B.Cu")
		(net "PWRGD_PSU_AC_PWROK_R")
	)
	(segment
		(start 32.639 -108.22178)
		(end 32.639 -109.016546)
		(width 0.11684)
		(layer "B.Cu")
		(net "PWRGD_PSU_AC_PWROK_R")
	)
	(segment
		(start 30.353 -116.7892)
		(end 29.945076 -117.197124)
		(width 0.11684)
		(layer "B.Cu")
		(net "PWRGD_PSU_AC_PWROK_R")
	)
	(segment
		(start 32.639 -106.95305)
		(end 32.639 -108.22178)
		(width 0.11684)
		(layer "B.Cu")
		(net "PWRGD_PSU_AC_PWROK_R")
	)
	(segment
		(start 30.82036 -109.704124)
		(end 30.82036 -110.4519)
		(width 0.11684)
		(layer "B.Cu")
		(net "PWRGD_PSU_AC_PWROK_R")
	)
	(segment
		(start 32.639 -109.016546)
		(end 32.134302 -109.521244)
		(width 0.11684)
		(layer "B.Cu")
		(net "PWRGD_PSU_AC_PWROK_R")
	)
	(segment
		(start 58.320432 -59.775598)
		(end 58.320432 -61.226192)
		(width 0.11684)
		(layer "F.Cu")
		(net "PU_SPI1WP_N")
	)
	(segment
		(start 59.12485 -64.763904)
		(end 59.12485 -65.5828)
		(width 0.11684)
		(layer "F.Cu")
		(net "PU_SPI1WP_N")
	)
	(segment
		(start 59.02071 -62.312042)
		(end 58.5216 -62.811152)
		(width 0.11684)
		(layer "F.Cu")
		(net "PU_SPI1WP_N")
	)
	(segment
		(start 58.090308 -59.545474)
		(end 58.320432 -59.775598)
		(width 0.11684)
		(layer "F.Cu")
		(net "PU_SPI1WP_N")
	)
	(segment
		(start 59.02071 -61.92647)
		(end 59.02071 -62.312042)
		(width 0.11684)
		(layer "F.Cu")
		(net "PU_SPI1WP_N")
	)
	(segment
		(start 58.5216 -62.811152)
		(end 58.5216 -63.3984)
		(width 0.11684)
		(layer "F.Cu")
		(net "PU_SPI1WP_N")
	)
	(segment
		(start 58.090308 -58.966354)
		(end 58.090308 -59.545474)
		(width 0.11684)
		(layer "F.Cu")
		(net "PU_SPI1WP_N")
	)
	(segment
		(start 58.5216 -64.160654)
		(end 59.12485 -64.763904)
		(width 0.11684)
		(layer "F.Cu")
		(net "PU_SPI1WP_N")
	)
	(segment
		(start 58.320432 -61.226192)
		(end 59.02071 -61.92647)
		(width 0.11684)
		(layer "F.Cu")
		(net "PU_SPI1WP_N")
	)
	(segment
		(start 58.5216 -63.3984)
		(end 58.5216 -64.160654)
		(width 0.11684)
		(layer "F.Cu")
		(net "PU_SPI1WP_N")
	)
	(segment
		(start 57.695084 -58.57113)
		(end 58.090308 -58.966354)
		(width 0.11684)
		(layer "F.Cu")
		(net "PU_SPI1WP_N")
	)
	(via
		(at 58.5216 -63.3984)
		(size 0.762)
		(drill 0.381)
		(layers "F.Cu" "B.Cu")
		(net "PU_SPI1WP_N")
	)
	(segment
		(start 57.695084 -57.771284)
		(end 58.090308 -58.166508)
		(width 0.11684)
		(layer "F.Cu")
		(net "PU_SPI1ABR")
	)
	(via
		(at 58.090308 -58.166508)
		(size 0.4572)
		(drill 0.254)
		(layers "F.Cu" "B.Cu")
		(net "PU_SPI1ABR")
	)
	(via
		(at 58.32602 -67.158616)
		(size 0.508)
		(drill 0.254)
		(layers "F.Cu" "B.Cu")
		(net "PU_SPI1ABR")
	)
	(segment
		(start 58.32602 -67.025012)
		(end 58.23331 -66.800984)
		(width 0.11684)
		(layer "B.Cu")
		(net "PU_SPI1ABR")
	)
	(segment
		(start 58.23331 -66.800984)
		(end 58.23331 -66.547492)
		(width 0.11684)
		(layer "B.Cu")
		(net "PU_SPI1ABR")
	)
	(segment
		(start 58.32602 -67.158616)
		(end 58.32602 -67.025012)
		(width 0.11684)
		(layer "B.Cu")
		(net "PU_SPI1ABR")
	)
	(segment
		(start 59.13882 -65.091564)
		(end 59.029346 -65.355978)
		(width 0.10668)
		(layer "In4.Cu")
		(net "PU_SPI1ABR")
	)
	(segment
		(start 58.090308 -58.166508)
		(end 57.7342 -58.522616)
		(width 0.10668)
		(layer "In4.Cu")
		(net "PU_SPI1ABR")
	)
	(segment
		(start 59.029346 -65.355978)
		(end 58.32602 -66.059304)
		(width 0.10668)
		(layer "In4.Cu")
		(net "PU_SPI1ABR")
	)
	(segment
		(start 58.01868 -60.866782)
		(end 58.01868 -63.30188)
		(width 0.10668)
		(layer "In4.Cu")
		(net "PU_SPI1ABR")
	)
	(segment
		(start 59.13882 -64.42202)
		(end 59.13882 -65.091564)
		(width 0.10668)
		(layer "In4.Cu")
		(net "PU_SPI1ABR")
	)
	(segment
		(start 57.7342 -60.582302)
		(end 58.01868 -60.866782)
		(width 0.10668)
		(layer "In4.Cu")
		(net "PU_SPI1ABR")
	)
	(segment
		(start 57.7342 -58.522616)
		(end 57.7342 -60.582302)
		(width 0.10668)
		(layer "In4.Cu")
		(net "PU_SPI1ABR")
	)
	(segment
		(start 58.32602 -66.059304)
		(end 58.32602 -67.158616)
		(width 0.10668)
		(layer "In4.Cu")
		(net "PU_SPI1ABR")
	)
	(segment
		(start 58.01868 -63.30188)
		(end 59.13882 -64.42202)
		(width 0.10668)
		(layer "In4.Cu")
		(net "PU_SPI1ABR")
	)
	(segment
		(start 57.242202 -66.46545)
		(end 57.242202 -66.919348)
		(width 0.11684)
		(layer "B.Cu")
		(net "PU_FWSPIWP_N")
	)
	(segment
		(start 57.242202 -66.919348)
		(end 56.7436 -67.41795)
		(width 0.11684)
		(layer "B.Cu")
		(net "PU_FWSPIWP_N")
	)
	(segment
		(start 55.778654 -62.4332)
		(end 55.73395 -62.4332)
		(width 0.11684)
		(layer "B.Cu")
		(net "PU_BMC_FWSPIABR_N")
	)
	(segment
		(start 56.140604 -62.979554)
		(end 56.140604 -62.79515)
		(width 0.11684)
		(layer "B.Cu")
		(net "PU_BMC_FWSPIABR_N")
	)
	(segment
		(start 56.6674 -63.30315)
		(end 56.55945 -63.1952)
		(width 0.11684)
		(layer "B.Cu")
		(net "PU_BMC_FWSPIABR_N")
	)
	(segment
		(start 56.55945 -63.1952)
		(end 56.35625 -63.1952)
		(width 0.11684)
		(layer "B.Cu")
		(net "PU_BMC_FWSPIABR_N")
	)
	(segment
		(start 56.140604 -62.79515)
		(end 55.778654 -62.4332)
		(width 0.11684)
		(layer "B.Cu")
		(net "PU_BMC_FWSPIABR_N")
	)
	(segment
		(start 56.35625 -63.1952)
		(end 56.140604 -62.979554)
		(width 0.11684)
		(layer "B.Cu")
		(net "PU_BMC_FWSPIABR_N")
	)
	(segment
		(start 50.494946 -56.171338)
		(end 50.099722 -56.566562)
		(width 0.11684)
		(layer "F.Cu")
		(net "PGPPA_BMC_AUX_SENSOR")
	)
	(via
		(at 59.190382 -67.686682)
		(size 0.508)
		(drill 0.254)
		(layers "F.Cu" "B.Cu")
		(net "PGPPA_BMC_AUX_SENSOR")
	)
	(via
		(at 59.676284 -68.909692)
		(size 0.6604)
		(drill 0.3302)
		(layers "F.Cu" "B.Cu")
		(net "PGPPA_BMC_AUX_SENSOR")
	)
	(via
		(at 50.099722 -56.566562)
		(size 0.4572)
		(drill 0.254)
		(layers "F.Cu" "B.Cu")
		(net "PGPPA_BMC_AUX_SENSOR")
	)
	(via
		(at 59.717432 -66.74612)
		(size 0.6604)
		(drill 0.3302)
		(layers "F.Cu" "B.Cu")
		(net "PGPPA_BMC_AUX_SENSOR")
	)
	(via
		(at 69.98208 -90.90914)
		(size 0.508)
		(drill 0.254)
		(layers "F.Cu" "B.Cu")
		(net "PGPPA_BMC_AUX_L")
	)
	(via
		(at 65.532 -67.6402)
		(size 0.508)
		(drill 0.254)
		(layers "F.Cu" "B.Cu")
		(net "PGPPA_BMC_AUX_L")
	)
	(via
		(at 65.2018 -67.0052)
		(size 0.508)
		(drill 0.254)
		(layers "F.Cu" "B.Cu")
		(net "PGPPA_BMC_AUX_L")
	)
	(via
		(at 69.48932 -89.9795)
		(size 0.762)
		(drill 0.254)
		(layers "F.Cu" "B.Cu")
		(net "PGPPA_BMC_AUX_L")
	)
	(via
		(at 66.62674 -79.05115)
		(size 0.508)
		(drill 0.254)
		(layers "F.Cu" "B.Cu")
		(net "PGPPA_BMC_AUX_L")
	)
	(via
		(at 70.43166 -90.37828)
		(size 0.508)
		(drill 0.254)
		(layers "F.Cu" "B.Cu")
		(net "PGPPA_BMC_AUX_L")
	)
	(segment
		(start 51.295046 -56.971184)
		(end 50.899822 -57.366408)
		(width 0.3556)
		(layer "F.Cu")
		(net "P5V_SENSOR")
	)
	(via
		(at 50.899822 -57.366408)
		(size 0.4572)
		(drill 0.254)
		(layers "F.Cu" "B.Cu")
		(net "P5V_SENSOR")
	)
	(via
		(at 63.870586 -72.019668)
		(size 0.508)
		(drill 0.254)
		(layers "F.Cu" "B.Cu")
		(net "P5V_SENSOR")
	)
	(via
		(at 60.882022 -73.38822)
		(size 0.6604)
		(drill 0.3302)
		(layers "F.Cu" "B.Cu")
		(net "P5V_SENSOR")
	)
	(via
		(at 59.612022 -73.38822)
		(size 0.6604)
		(drill 0.3302)
		(layers "F.Cu" "B.Cu")
		(net "P5V_SENSOR")
	)
	(via
		(at 63.870586 -72.781668)
		(size 0.508)
		(drill 0.254)
		(layers "F.Cu" "B.Cu")
		(net "P5V_SENSOR")
	)
	(segment
		(start 51.295046 -58.57113)
		(end 50.899822 -58.966354)
		(width 0.381)
		(layer "F.Cu")
		(net "P3V_BAT_SENSOR")
	)
	(via
		(at 43.936158 -70.358)
		(size 0.508)
		(drill 0.254)
		(layers "F.Cu" "B.Cu")
		(net "P3V_BAT_SENSOR")
	)
	(via
		(at 50.899822 -58.966354)
		(size 0.4572)
		(drill 0.254)
		(layers "F.Cu" "B.Cu")
		(net "P3V_BAT_SENSOR")
	)
	(via
		(at 44.453302 -71.522082)
		(size 0.6604)
		(drill 0.3302)
		(layers "F.Cu" "B.Cu")
		(net "P3V_BAT_SENSOR")
	)
	(segment
		(start 47.45482 -71.92137)
		(end 47.45482 -72.954134)
		(width 0.381)
		(layer "B.Cu")
		(net "P3V_BAT_SENSOR")
	)
	(segment
		(start 44.453302 -70.938898)
		(end 44.453302 -71.522082)
		(width 0.381)
		(layer "B.Cu")
		(net "P3V_BAT_SENSOR")
	)
	(segment
		(start 47.45482 -72.954134)
		(end 44.632118 -72.954134)
		(width 0.381)
		(layer "B.Cu")
		(net "P3V_BAT_SENSOR")
	)
	(segment
		(start 44.632118 -72.954134)
		(end 44.631102 -72.95515)
		(width 0.381)
		(layer "B.Cu")
		(net "P3V_BAT_SENSOR")
	)
	(segment
		(start 44.453302 -71.522082)
		(end 44.453302 -72.77735)
		(width 0.381)
		(layer "B.Cu")
		(net "P3V_BAT_SENSOR")
	)
	(segment
		(start 43.936158 -70.421754)
		(end 44.453302 -70.938898)
		(width 0.381)
		(layer "B.Cu")
		(net "P3V_BAT_SENSOR")
	)
	(segment
		(start 44.453302 -72.77735)
		(end 44.631102 -72.95515)
		(width 0.381)
		(layer "B.Cu")
		(net "P3V_BAT_SENSOR")
	)
	(segment
		(start 43.936158 -70.358)
		(end 43.936158 -70.421754)
		(width 0.381)
		(layer "B.Cu")
		(net "P3V_BAT_SENSOR")
	)
	(segment
		(start 46.4566 -66.237104)
		(end 46.4566 -65.5828)
		(width 0.381)
		(layer "In9.Cu")
		(net "P3V_BAT_SENSOR")
	)
	(segment
		(start 46.4566 -65.5828)
		(end 46.2788 -65.15354)
		(width 0.381)
		(layer "In9.Cu")
		(net "P3V_BAT_SENSOR")
	)
	(segment
		(start 50.899822 -59.702954)
		(end 50.899822 -58.966354)
		(width 0.381)
		(layer "In9.Cu")
		(net "P3V_BAT_SENSOR")
	)
	(segment
		(start 49.847246 -60.287154)
		(end 50.315622 -60.287154)
		(width 0.381)
		(layer "In9.Cu")
		(net "P3V_BAT_SENSOR")
	)
	(segment
		(start 50.315622 -60.287154)
		(end 50.899822 -59.702954)
		(width 0.381)
		(layer "In9.Cu")
		(net "P3V_BAT_SENSOR")
	)
	(segment
		(start 44.3357 -68.358004)
		(end 46.4566 -66.237104)
		(width 0.381)
		(layer "In9.Cu")
		(net "P3V_BAT_SENSOR")
	)
	(segment
		(start 46.2788 -65.15354)
		(end 46.2788 -62.940946)
		(width 0.381)
		(layer "In9.Cu")
		(net "P3V_BAT_SENSOR")
	)
	(segment
		(start 43.936158 -70.358)
		(end 44.3357 -69.958458)
		(width 0.381)
		(layer "In9.Cu")
		(net "P3V_BAT_SENSOR")
	)
	(segment
		(start 46.2788 -62.940946)
		(end 47.599346 -61.6204)
		(width 0.381)
		(layer "In9.Cu")
		(net "P3V_BAT_SENSOR")
	)
	(segment
		(start 44.3357 -69.958458)
		(end 44.3357 -68.358004)
		(width 0.381)
		(layer "In9.Cu")
		(net "P3V_BAT_SENSOR")
	)
	(segment
		(start 47.599346 -61.6204)
		(end 48.514 -61.6204)
		(width 0.381)
		(layer "In9.Cu")
		(net "P3V_BAT_SENSOR")
	)
	(segment
		(start 48.514 -61.6204)
		(end 49.847246 -60.287154)
		(width 0.381)
		(layer "In9.Cu")
		(net "P3V_BAT_SENSOR")
	)
	(via
		(at 40.7162 -71.589392)
		(size 0.6604)
		(drill 0.3302)
		(layers "F.Cu" "B.Cu")
		(net "P3V_BAT_R1")
	)
	(segment
		(start 42.5323 -73.814178)
		(end 42.5323 -71.612506)
		(width 0.381)
		(layer "B.Cu")
		(net "P3V_BAT_R1")
	)
	(segment
		(start 42.39133 -73.955148)
		(end 42.5323 -73.814178)
		(width 0.381)
		(layer "B.Cu")
		(net "P3V_BAT_R1")
	)
	(segment
		(start 42.5323 -71.612506)
		(end 42.509186 -71.589392)
		(width 0.381)
		(layer "B.Cu")
		(net "P3V_BAT_R1")
	)
	(segment
		(start 40.7162 -71.589392)
		(end 42.509186 -71.589392)
		(width 0.11684)
		(layer "B.Cu")
		(net "P3V_BAT_R1")
	)
	(segment
		(start 36.055046 -116.843048)
		(end 36.21278 -116.685314)
		(width 0.381)
		(layer "F.Cu")
		(net "P3V_BAT_R")
	)
	(segment
		(start 32.8422 -109.111034)
		(end 33.51784 -109.786674)
		(width 0.381)
		(layer "F.Cu")
		(net "P3V_BAT_R")
	)
	(segment
		(start 36.21278 -113.43513)
		(end 33.75406 -110.97641)
		(width 0.381)
		(layer "F.Cu")
		(net "P3V_BAT_R")
	)
	(segment
		(start 36.055046 -118.460012)
		(end 36.055046 -116.843048)
		(width 0.381)
		(layer "F.Cu")
		(net "P3V_BAT_R")
	)
	(segment
		(start 36.21278 -116.685314)
		(end 36.21278 -113.43513)
		(width 0.381)
		(layer "F.Cu")
		(net "P3V_BAT_R")
	)
	(segment
		(start 32.8422 -108.98505)
		(end 32.8422 -109.111034)
		(width 0.381)
		(layer "F.Cu")
		(net "P3V_BAT_R")
	)
	(segment
		(start 33.51784 -109.786674)
		(end 33.51784 -109.982)
		(width 0.381)
		(layer "F.Cu")
		(net "P3V_BAT_R")
	)
	(segment
		(start 33.75406 -110.21822)
		(end 33.54578 -110.00994)
		(width 0.381)
		(layer "F.Cu")
		(net "P3V_BAT_R")
	)
	(segment
		(start 33.51784 -109.982)
		(end 33.54578 -110.00994)
		(width 0.381)
		(layer "F.Cu")
		(net "P3V_BAT_R")
	)
	(segment
		(start 33.75406 -110.97641)
		(end 33.75406 -110.21822)
		(width 0.381)
		(layer "F.Cu")
		(net "P3V_BAT_R")
	)
	(via
		(at 45.9867 -84.3915)
		(size 0.508)
		(drill 0.254)
		(layers "F.Cu" "B.Cu")
		(net "P3V_BAT_R")
	)
	(via
		(at 41.5798 -107.218226)
		(size 0.508)
		(drill 0.254)
		(layers "F.Cu" "B.Cu")
		(net "P3V_BAT_R")
	)
	(via
		(at 33.54578 -110.00994)
		(size 0.508)
		(drill 0.254)
		(layers "F.Cu" "B.Cu")
		(net "P3V_BAT_R")
	)
	(via
		(at 40.51554 -79.375)
		(size 0.6604)
		(drill 0.3302)
		(layers "F.Cu" "B.Cu")
		(net "P3V_BAT_R")
	)
	(segment
		(start 41.3512 -78.8416)
		(end 41.7322 -78.4606)
		(width 0.381)
		(layer "B.Cu")
		(net "P3V_BAT_R")
	)
	(segment
		(start 41.7322 -78.4606)
		(end 41.7322 -75.41895)
		(width 0.381)
		(layer "B.Cu")
		(net "P3V_BAT_R")
	)
	(segment
		(start 40.51554 -79.375)
		(end 40.613584 -79.375)
		(width 0.381)
		(layer "B.Cu")
		(net "P3V_BAT_R")
	)
	(segment
		(start 43.5356 -71.815706)
		(end 43.309286 -71.589392)
		(width 0.381)
		(layer "B.Cu")
		(net "P3V_BAT_R")
	)
	(segment
		(start 41.5544 -82.2452)
		(end 40.4114 -81.1022)
		(width 0.381)
		(layer "B.Cu")
		(net "P3V_BAT_R")
	)
	(segment
		(start 41.7322 -75.41895)
		(end 42.31767 -74.83348)
		(width 0.381)
		(layer "B.Cu")
		(net "P3V_BAT_R")
	)
	(segment
		(start 42.924476 -82.2452)
		(end 41.5544 -82.2452)
		(width 0.381)
		(layer "B.Cu")
		(net "P3V_BAT_R")
	)
	(segment
		(start 45.058076 -84.3788)
		(end 42.924476 -82.2452)
		(width 0.381)
		(layer "B.Cu")
		(net "P3V_BAT_R")
	)
	(segment
		(start 41.5798 -107.218226)
		(end 41.5798 -106.736642)
		(width 0.381)
		(layer "B.Cu")
		(net "P3V_BAT_R")
	)
	(segment
		(start 40.613584 -79.375)
		(end 41.146984 -78.8416)
		(width 0.381)
		(layer "B.Cu")
		(net "P3V_BAT_R")
	)
	(segment
		(start 40.4114 -79.47914)
		(end 40.51554 -79.375)
		(width 0.381)
		(layer "B.Cu")
		(net "P3V_BAT_R")
	)
	(segment
		(start 41.146984 -78.8416)
		(end 41.3512 -78.8416)
		(width 0.381)
		(layer "B.Cu")
		(net "P3V_BAT_R")
	)
	(segment
		(start 45.9867 -84.3915)
		(end 45.974 -84.3788)
		(width 0.381)
		(layer "B.Cu")
		(net "P3V_BAT_R")
	)
	(segment
		(start 41.5798 -106.736642)
		(end 42.967402 -105.34904)
		(width 0.381)
		(layer "B.Cu")
		(net "P3V_BAT_R")
	)
	(segment
		(start 45.974 -84.3788)
		(end 45.058076 -84.3788)
		(width 0.381)
		(layer "B.Cu")
		(net "P3V_BAT_R")
	)
	(segment
		(start 42.31767 -74.83348)
		(end 43.14952 -74.83348)
		(width 0.381)
		(layer "B.Cu")
		(net "P3V_BAT_R")
	)
	(segment
		(start 43.5356 -74.4474)
		(end 43.5356 -71.815706)
		(width 0.381)
		(layer "B.Cu")
		(net "P3V_BAT_R")
	)
	(segment
		(start 43.14952 -74.83348)
		(end 43.5356 -74.4474)
		(width 0.381)
		(layer "B.Cu")
		(net "P3V_BAT_R")
	)
	(segment
		(start 40.4114 -81.1022)
		(end 40.4114 -79.47914)
		(width 0.381)
		(layer "B.Cu")
		(net "P3V_BAT_R")
	)
	(segment
		(start 34.110676 -109.389164)
		(end 33.54578 -109.95406)
		(width 0.381)
		(layer "In2.Cu")
		(net "P3V_BAT_R")
	)
	(segment
		(start 39.987982 -109.389164)
		(end 34.110676 -109.389164)
		(width 0.381)
		(layer "In2.Cu")
		(net "P3V_BAT_R")
	)
	(segment
		(start 41.5798 -107.218226)
		(end 41.5798 -107.797346)
		(width 0.381)
		(layer "In2.Cu")
		(net "P3V_BAT_R")
	)
	(segment
		(start 33.54578 -109.95406)
		(end 33.54578 -110.00994)
		(width 0.381)
		(layer "In2.Cu")
		(net "P3V_BAT_R")
	)
	(segment
		(start 41.5798 -107.797346)
		(end 39.987982 -109.389164)
		(width 0.381)
		(layer "In2.Cu")
		(net "P3V_BAT_R")
	)
	(segment
		(start 44.9834 -100.5078)
		(end 44.3484 -99.8728)
		(width 0.381)
		(layer "In4.Cu")
		(net "P3V_BAT_R")
	)
	(segment
		(start 45.7073 -84.6709)
		(end 45.9867 -84.3915)
		(width 0.381)
		(layer "In4.Cu")
		(net "P3V_BAT_R")
	)
	(segment
		(start 44.3484 -99.8728)
		(end 44.3484 -97.2566)
		(width 0.381)
		(layer "In4.Cu")
		(net "P3V_BAT_R")
	)
	(segment
		(start 47.22368 -94.38132)
		(end 47.22368 -90.40368)
		(width 0.381)
		(layer "In4.Cu")
		(net "P3V_BAT_R")
	)
	(segment
		(start 45.7073 -88.8873)
		(end 45.7073 -84.6709)
		(width 0.381)
		(layer "In4.Cu")
		(net "P3V_BAT_R")
	)
	(segment
		(start 44.3484 -97.2566)
		(end 47.22368 -94.38132)
		(width 0.381)
		(layer "In4.Cu")
		(net "P3V_BAT_R")
	)
	(segment
		(start 41.5798 -107.218226)
		(end 41.5798 -106.9848)
		(width 0.381)
		(layer "In4.Cu")
		(net "P3V_BAT_R")
	)
	(segment
		(start 44.9834 -103.5812)
		(end 44.9834 -100.5078)
		(width 0.381)
		(layer "In4.Cu")
		(net "P3V_BAT_R")
	)
	(segment
		(start 41.5798 -106.9848)
		(end 44.9834 -103.5812)
		(width 0.381)
		(layer "In4.Cu")
		(net "P3V_BAT_R")
	)
	(segment
		(start 47.22368 -90.40368)
		(end 45.7073 -88.8873)
		(width 0.381)
		(layer "In4.Cu")
		(net "P3V_BAT_R")
	)
	(segment
		(start 50.494946 -58.57113)
		(end 50.099722 -58.966354)
		(width 0.3556)
		(layer "F.Cu")
		(net "P3V3_SENSOR")
	)
	(via
		(at 50.099722 -58.966354)
		(size 0.4572)
		(drill 0.254)
		(layers "F.Cu" "B.Cu")
		(net "P3V3_SENSOR")
	)
	(via
		(at 51.58486 -68.384166)
		(size 0.508)
		(drill 0.254)
		(layers "F.Cu" "B.Cu")
		(net "P3V3_SENSOR")
	)
	(via
		(at 52.21986 -68.358766)
		(size 0.508)
		(drill 0.254)
		(layers "F.Cu" "B.Cu")
		(net "P3V3_SENSOR")
	)
	(segment
		(start 50.494946 -57.771284)
		(end 50.099722 -58.166508)
		(width 0.3556)
		(layer "F.Cu")
		(net "P2V5_SENSOR")
	)
	(via
		(at 55.4736 -68.6816)
		(size 0.6604)
		(drill 0.3302)
		(layers "F.Cu" "B.Cu")
		(net "P2V5_SENSOR")
	)
	(via
		(at 54.167532 -69.40931)
		(size 0.508)
		(drill 0.254)
		(layers "F.Cu" "B.Cu")
		(net "P2V5_SENSOR")
	)
	(via
		(at 50.099722 -58.166508)
		(size 0.4572)
		(drill 0.254)
		(layers "F.Cu" "B.Cu")
		(net "P2V5_SENSOR")
	)
	(segment
		(start 50.494946 -56.971184)
		(end 50.099722 -57.366408)
		(width 0.3556)
		(layer "F.Cu")
		(net "P1V8_SENSOR")
	)
	(via
		(at 49.8094 -71.58228)
		(size 0.508)
		(drill 0.254)
		(layers "F.Cu" "B.Cu")
		(net "P1V8_SENSOR")
	)
	(via
		(at 49.8348 -70.6628)
		(size 0.508)
		(drill 0.254)
		(layers "F.Cu" "B.Cu")
		(net "P1V8_SENSOR")
	)
	(via
		(at 50.099722 -57.366408)
		(size 0.4572)
		(drill 0.254)
		(layers "F.Cu" "B.Cu")
		(net "P1V8_SENSOR")
	)
	(via
		(at 49.089818 -70.695312)
		(size 0.6604)
		(drill 0.3302)
		(layers "F.Cu" "B.Cu")
		(net "P1V8_SENSOR")
	)
	(segment
		(start 51.295046 -56.171338)
		(end 50.899822 -56.566562)
		(width 0.3556)
		(layer "F.Cu")
		(net "P1V2_SENSOR")
	)
	(via
		(at 50.899822 -56.566562)
		(size 0.4572)
		(drill 0.254)
		(layers "F.Cu" "B.Cu")
		(net "P1V2_SENSOR")
	)
	(via
		(at 54.079394 -74.642726)
		(size 0.508)
		(drill 0.254)
		(layers "F.Cu" "B.Cu")
		(net "P1V2_SENSOR")
	)
	(segment
		(start 54.079394 -74.642726)
		(end 55.14848 -74.642726)
		(width 0.381)
		(layer "B.Cu")
		(net "P1V2_SENSOR")
	)
	(segment
		(start 55.14848 -74.642726)
		(end 56.173116 -74.642726)
		(width 0.381)
		(layer "B.Cu")
		(net "P1V2_SENSOR")
	)
	(segment
		(start 52.094892 -56.171338)
		(end 51.699668 -56.566562)
		(width 0.3556)
		(layer "F.Cu")
		(net "P1V0_SENSOR")
	)
	(via
		(at 51.699668 -56.566562)
		(size 0.4572)
		(drill 0.254)
		(layers "F.Cu" "B.Cu")
		(net "P1V0_SENSOR")
	)
	(via
		(at 51.054 -66.675)
		(size 0.508)
		(drill 0.254)
		(layers "F.Cu" "B.Cu")
		(net "P1V0_SENSOR")
	)
	(segment
		(start 50.43805 -67.11315)
		(end 50.8762 -66.675)
		(width 0.3302)
		(layer "B.Cu")
		(net "P1V0_SENSOR")
	)
	(segment
		(start 50.8762 -66.675)
		(end 51.054 -66.675)
		(width 0.3302)
		(layer "B.Cu")
		(net "P1V0_SENSOR")
	)
	(segment
		(start 50.2539 -67.12585)
		(end 50.2666 -67.11315)
		(width 0.3302)
		(layer "B.Cu")
		(net "P1V0_SENSOR")
	)
	(segment
		(start 50.292 -67.11315)
		(end 50.43805 -67.11315)
		(width 0.3302)
		(layer "B.Cu")
		(net "P1V0_SENSOR")
	)
	(segment
		(start 50.2666 -67.11315)
		(end 50.292 -67.11315)
		(width 0.3302)
		(layer "B.Cu")
		(net "P1V0_SENSOR")
	)
	(segment
		(start 49.30648 -67.12585)
		(end 50.2539 -67.12585)
		(width 0.3302)
		(layer "B.Cu")
		(net "P1V0_SENSOR")
	)
	(segment
		(start 49.3014 -67.12077)
		(end 49.30648 -67.12585)
		(width 0.3302)
		(layer "B.Cu")
		(net "P1V0_SENSOR")
	)
	(segment
		(start 49.6951 -57.771284)
		(end 49.299876 -58.166508)
		(width 0.3556)
		(layer "F.Cu")
		(net "P12V_SENSOR")
	)
	(via
		(at 33.062418 -59.622182)
		(size 0.508)
		(drill 0.254)
		(layers "F.Cu" "B.Cu")
		(net "P12V_SENSOR")
	)
	(via
		(at 35.206432 -59.690254)
		(size 0.6604)
		(drill 0.3302)
		(layers "F.Cu" "B.Cu")
		(net "P12V_SENSOR")
	)
	(via
		(at 33.936432 -59.690254)
		(size 0.6604)
		(drill 0.3302)
		(layers "F.Cu" "B.Cu")
		(net "P12V_SENSOR")
	)
	(via
		(at 49.299876 -58.166508)
		(size 0.4572)
		(drill 0.254)
		(layers "F.Cu" "B.Cu")
		(net "P12V_SENSOR")
	)
	(via
		(at 72.509888 -100.224082)
		(size 0.6604)
		(drill 0.3302)
		(layers "F.Cu" "B.Cu")
		(net "LPC_ESPI_SEL_R1")
	)
	(segment
		(start 73.342246 -99.906328)
		(end 73.024492 -100.224082)
		(width 0.11684)
		(layer "B.Cu")
		(net "LPC_ESPI_SEL_R1")
	)
	(segment
		(start 73.765918 -97.509838)
		(end 72.825102 -97.509838)
		(width 0.11684)
		(layer "B.Cu")
		(net "LPC_ESPI_SEL_R1")
	)
	(segment
		(start 73.024492 -100.224082)
		(end 72.509888 -100.224082)
		(width 0.11684)
		(layer "B.Cu")
		(net "LPC_ESPI_SEL_R1")
	)
	(segment
		(start 73.695306 -100.93071)
		(end 73.695306 -99.906328)
		(width 0.11684)
		(layer "B.Cu")
		(net "LPC_ESPI_SEL_R1")
	)
	(segment
		(start 72.439022 -100.224082)
		(end 72.509888 -100.224082)
		(width 0.11684)
		(layer "B.Cu")
		(net "LPC_ESPI_SEL_R1")
	)
	(segment
		(start 72.825102 -97.509838)
		(end 72.521064 -97.813876)
		(width 0.11684)
		(layer "B.Cu")
		(net "LPC_ESPI_SEL_R1")
	)
	(segment
		(start 73.695306 -99.906328)
		(end 73.342246 -99.906328)
		(width 0.11684)
		(layer "B.Cu")
		(net "LPC_ESPI_SEL_R1")
	)
	(segment
		(start 71.797418 -97.940876)
		(end 71.797418 -99.582478)
		(width 0.11684)
		(layer "B.Cu")
		(net "LPC_ESPI_SEL_R1")
	)
	(segment
		(start 72.521064 -97.813876)
		(end 71.924418 -97.813876)
		(width 0.11684)
		(layer "B.Cu")
		(net "LPC_ESPI_SEL_R1")
	)
	(segment
		(start 71.924418 -97.813876)
		(end 71.797418 -97.940876)
		(width 0.11684)
		(layer "B.Cu")
		(net "LPC_ESPI_SEL_R1")
	)
	(segment
		(start 71.797418 -99.582478)
		(end 72.439022 -100.224082)
		(width 0.11684)
		(layer "B.Cu")
		(net "LPC_ESPI_SEL_R1")
	)
	(via
		(at 78.849474 -99.911408)
		(size 0.6604)
		(drill 0.3302)
		(layers "F.Cu" "B.Cu")
		(net "LPC_ESPI_SEL_R")
	)
	(segment
		(start 78.849474 -98.99777)
		(end 78.849474 -99.911408)
		(width 0.11684)
		(layer "B.Cu")
		(net "LPC_ESPI_SEL_R")
	)
	(segment
		(start 77.67955 -99.911408)
		(end 78.849474 -99.911408)
		(width 0.11684)
		(layer "B.Cu")
		(net "LPC_ESPI_SEL_R")
	)
	(segment
		(start 77.970888 -98.119184)
		(end 78.849474 -98.99777)
		(width 0.11684)
		(layer "B.Cu")
		(net "LPC_ESPI_SEL_R")
	)
	(segment
		(start 77.405484 -98.119184)
		(end 77.970888 -98.119184)
		(width 0.11684)
		(layer "B.Cu")
		(net "LPC_ESPI_SEL_R")
	)
	(segment
		(start 77.67955 -100.935028)
		(end 77.67955 -99.911408)
		(width 0.11684)
		(layer "B.Cu")
		(net "LPC_ESPI_SEL_R")
	)
	(via
		(at 79.22895 -93.08465)
		(size 0.508)
		(drill 0.254)
		(layers "F.Cu" "B.Cu")
		(net "LPC_ESPI_SEL_N")
	)
	(via
		(at 67.3354 -100.3554)
		(size 0.508)
		(drill 0.254)
		(layers "F.Cu" "B.Cu")
		(net "LPC_ESPI_SEL_N")
	)
	(via
		(at 77.978 -93.345)
		(size 0.6604)
		(drill 0.3302)
		(layers "F.Cu" "B.Cu")
		(net "LPC_ESPI_SEL_N")
	)
	(segment
		(start 66.336672 -101.215698)
		(end 67.223894 -101.215698)
		(width 0.11684)
		(layer "B.Cu")
		(net "LPC_ESPI_SEL_N")
	)
	(segment
		(start 78.84795 -93.345)
		(end 79.22895 -93.726)
		(width 0.11684)
		(layer "B.Cu")
		(net "LPC_ESPI_SEL_N")
	)
	(segment
		(start 79.22895 -93.726)
		(end 79.22895 -93.08465)
		(width 0.11684)
		(layer "B.Cu")
		(net "LPC_ESPI_SEL_N")
	)
	(segment
		(start 77.978 -94.38005)
		(end 77.978 -93.345)
		(width 0.11684)
		(layer "B.Cu")
		(net "LPC_ESPI_SEL_N")
	)
	(segment
		(start 78.33995 -94.742)
		(end 77.978 -94.38005)
		(width 0.11684)
		(layer "B.Cu")
		(net "LPC_ESPI_SEL_N")
	)
	(segment
		(start 66.5861 -100.3554)
		(end 66.336672 -100.604828)
		(width 0.11684)
		(layer "B.Cu")
		(net "LPC_ESPI_SEL_N")
	)
	(segment
		(start 68.1482 -98.678746)
		(end 67.87515 -98.405696)
		(width 0.11684)
		(layer "B.Cu")
		(net "LPC_ESPI_SEL_N")
	)
	(segment
		(start 66.336672 -100.604828)
		(end 66.336672 -101.215698)
		(width 0.11684)
		(layer "B.Cu")
		(net "LPC_ESPI_SEL_N")
	)
	(segment
		(start 67.87515 -98.405696)
		(end 67.87515 -97.5614)
		(width 0.11684)
		(layer "B.Cu")
		(net "LPC_ESPI_SEL_N")
	)
	(segment
		(start 67.87515 -97.540064)
		(end 67.87515 -97.5614)
		(width 0.11684)
		(layer "B.Cu")
		(net "LPC_ESPI_SEL_N")
	)
	(segment
		(start 67.05346 -96.718374)
		(end 67.87515 -97.540064)
		(width 0.11684)
		(layer "B.Cu")
		(net "LPC_ESPI_SEL_N")
	)
	(segment
		(start 77.978 -93.345)
		(end 78.84795 -93.345)
		(width 0.11684)
		(layer "B.Cu")
		(net "LPC_ESPI_SEL_N")
	)
	(segment
		(start 78.355444 -94.757494)
		(end 78.33995 -94.742)
		(width 0.11684)
		(layer "B.Cu")
		(net "LPC_ESPI_SEL_N")
	)
	(segment
		(start 67.223894 -101.215698)
		(end 68.1482 -100.291392)
		(width 0.11684)
		(layer "B.Cu")
		(net "LPC_ESPI_SEL_N")
	)
	(segment
		(start 67.3354 -100.3554)
		(end 66.5861 -100.3554)
		(width 0.11684)
		(layer "B.Cu")
		(net "LPC_ESPI_SEL_N")
	)
	(segment
		(start 68.1482 -100.291392)
		(end 68.1482 -98.678746)
		(width 0.11684)
		(layer "B.Cu")
		(net "LPC_ESPI_SEL_N")
	)
	(segment
		(start 78.355444 -96.119188)
		(end 78.355444 -94.757494)
		(width 0.11684)
		(layer "B.Cu")
		(net "LPC_ESPI_SEL_N")
	)
	(segment
		(start 67.05346 -96.018096)
		(end 67.05346 -96.718374)
		(width 0.11684)
		(layer "B.Cu")
		(net "LPC_ESPI_SEL_N")
	)
	(segment
		(start 67.3354 -100.3554)
		(end 68.57238 -99.11842)
		(width 0.08382)
		(layer "In2.Cu")
		(net "LPC_ESPI_SEL_N")
	)
	(segment
		(start 68.57238 -99.11842)
		(end 70.78218 -99.11842)
		(width 0.08382)
		(layer "In2.Cu")
		(net "LPC_ESPI_SEL_N")
	)
	(segment
		(start 73.251314 -100.1522)
		(end 79.22895 -94.174564)
		(width 0.08382)
		(layer "In2.Cu")
		(net "LPC_ESPI_SEL_N")
	)
	(segment
		(start 71.81596 -100.1522)
		(end 73.251314 -100.1522)
		(width 0.08382)
		(layer "In2.Cu")
		(net "LPC_ESPI_SEL_N")
	)
	(segment
		(start 70.78218 -99.11842)
		(end 71.81596 -100.1522)
		(width 0.08382)
		(layer "In2.Cu")
		(net "LPC_ESPI_SEL_N")
	)
	(segment
		(start 79.22895 -94.174564)
		(end 79.22895 -93.08465)
		(width 0.08382)
		(layer "In2.Cu")
		(net "LPC_ESPI_SEL_N")
	)
	(segment
		(start 57.9755 -115.7097)
		(end 58.66511 -116.39931)
		(width 0.11684)
		(layer "F.Cu")
		(net "LPC_ESPI_SEL")
	)
	(segment
		(start 56.68518 -110.200186)
		(end 57.177432 -110.692438)
		(width 0.11684)
		(layer "F.Cu")
		(net "LPC_ESPI_SEL")
	)
	(segment
		(start 56.68518 -108.22178)
		(end 56.68518 -110.200186)
		(width 0.11684)
		(layer "F.Cu")
		(net "LPC_ESPI_SEL")
	)
	(segment
		(start 57.9755 -112.619282)
		(end 57.9755 -115.7097)
		(width 0.11684)
		(layer "F.Cu")
		(net "LPC_ESPI_SEL")
	)
	(segment
		(start 58.66511 -116.39931)
		(end 58.66511 -118.25986)
		(width 0.11684)
		(layer "F.Cu")
		(net "LPC_ESPI_SEL")
	)
	(segment
		(start 57.177432 -110.692438)
		(end 57.9755 -112.619282)
		(width 0.11684)
		(layer "F.Cu")
		(net "LPC_ESPI_SEL")
	)
	(segment
		(start 55.6895 -107.2261)
		(end 56.68518 -108.22178)
		(width 0.11684)
		(layer "F.Cu")
		(net "LPC_ESPI_SEL")
	)
	(via
		(at 55.6895 -107.2261)
		(size 0.508)
		(drill 0.254)
		(layers "F.Cu" "B.Cu")
		(net "LPC_ESPI_SEL")
	)
	(via
		(at 75.730608 -99.906328)
		(size 0.508)
		(drill 0.254)
		(layers "F.Cu" "B.Cu")
		(net "LPC_ESPI_SEL")
	)
	(segment
		(start 76.87945 -99.911408)
		(end 76.87437 -99.906328)
		(width 0.11684)
		(layer "B.Cu")
		(net "LPC_ESPI_SEL")
	)
	(segment
		(start 76.87437 -99.906328)
		(end 75.730608 -99.906328)
		(width 0.11684)
		(layer "B.Cu")
		(net "LPC_ESPI_SEL")
	)
	(segment
		(start 74.495406 -99.906328)
		(end 75.730608 -99.906328)
		(width 0.11684)
		(layer "B.Cu")
		(net "LPC_ESPI_SEL")
	)
	(segment
		(start 54.99735 -107.2261)
		(end 54.8132 -107.41025)
		(width 0.11684)
		(layer "B.Cu")
		(net "LPC_ESPI_SEL")
	)
	(segment
		(start 55.6895 -107.2261)
		(end 54.99735 -107.2261)
		(width 0.11684)
		(layer "B.Cu")
		(net "LPC_ESPI_SEL")
	)
	(segment
		(start 56.2356 -106.155744)
		(end 59.667902 -102.723442)
		(width 0.08382)
		(layer "In2.Cu")
		(net "LPC_ESPI_SEL")
	)
	(segment
		(start 73.643236 -101.9937)
		(end 75.730608 -99.906328)
		(width 0.08382)
		(layer "In2.Cu")
		(net "LPC_ESPI_SEL")
	)
	(segment
		(start 56.2356 -106.68)
		(end 56.2356 -106.155744)
		(width 0.08382)
		(layer "In2.Cu")
		(net "LPC_ESPI_SEL")
	)
	(segment
		(start 59.667902 -102.723442)
		(end 68.863718 -102.723442)
		(width 0.08382)
		(layer "In2.Cu")
		(net "LPC_ESPI_SEL")
	)
	(segment
		(start 68.863718 -102.723442)
		(end 69.59346 -101.9937)
		(width 0.08382)
		(layer "In2.Cu")
		(net "LPC_ESPI_SEL")
	)
	(segment
		(start 55.6895 -107.2261)
		(end 56.2356 -106.68)
		(width 0.08382)
		(layer "In2.Cu")
		(net "LPC_ESPI_SEL")
	)
	(segment
		(start 69.59346 -101.9937)
		(end 73.643236 -101.9937)
		(width 0.08382)
		(layer "In2.Cu")
		(net "LPC_ESPI_SEL")
	)
	(segment
		(start 39.063676 -48.6156)
		(end 38.252654 -48.6156)
		(width 0.11684)
		(layer "F.Cu")
		(net "H_CPU1_PROCHOT_LVC1_R_N")
	)
	(segment
		(start 38.252654 -48.6156)
		(end 37.671756 -49.196498)
		(width 0.11684)
		(layer "F.Cu")
		(net "H_CPU1_PROCHOT_LVC1_R_N")
	)
	(segment
		(start 36.374832 -50.067464)
		(end 35.789362 -50.652934)
		(width 0.11684)
		(layer "F.Cu")
		(net "H_CPU1_PROCHOT_LVC1_R_N")
	)
	(segment
		(start 37.671756 -49.196498)
		(end 36.80079 -50.067464)
		(width 0.11684)
		(layer "F.Cu")
		(net "H_CPU1_PROCHOT_LVC1_R_N")
	)
	(segment
		(start 36.80079 -50.067464)
		(end 36.374832 -50.067464)
		(width 0.11684)
		(layer "F.Cu")
		(net "H_CPU1_PROCHOT_LVC1_R_N")
	)
	(segment
		(start 39.55415 -48.6918)
		(end 39.139876 -48.6918)
		(width 0.11684)
		(layer "F.Cu")
		(net "H_CPU1_PROCHOT_LVC1_R_N")
	)
	(segment
		(start 39.139876 -48.6918)
		(end 39.063676 -48.6156)
		(width 0.11684)
		(layer "F.Cu")
		(net "H_CPU1_PROCHOT_LVC1_R_N")
	)
	(segment
		(start 20.66417 -90.391742)
		(end 21.059394 -90.786966)
		(width 0.11684)
		(layer "F.Cu")
		(net "H_CPU1_PROCHOT_LVC1_R_N")
	)
	(via
		(at 20.66417 -90.391742)
		(size 0.4572)
		(drill 0.254)
		(layers "F.Cu" "B.Cu")
		(net "H_CPU1_PROCHOT_LVC1_R_N")
	)
	(via
		(at 19.47418 -53.028088)
		(size 0.508)
		(drill 0.254)
		(layers "F.Cu" "B.Cu")
		(net "H_CPU1_PROCHOT_LVC1_R_N")
	)
	(via
		(at 37.671756 -49.196498)
		(size 0.762)
		(drill 0.381)
		(layers "F.Cu" "B.Cu")
		(net "H_CPU1_PROCHOT_LVC1_R_N")
	)
	(via
		(at 35.789362 -50.652934)
		(size 0.508)
		(drill 0.254)
		(layers "F.Cu" "B.Cu")
		(net "H_CPU1_PROCHOT_LVC1_R_N")
	)
	(segment
		(start 30.1752 -55.53964)
		(end 30.1752 -51.5366)
		(width 0.08382)
		(layer "In2.Cu")
		(net "H_CPU1_PROCHOT_LVC1_R_N")
	)
	(segment
		(start 28.986988 -56.727852)
		(end 30.1752 -55.53964)
		(width 0.08382)
		(layer "In2.Cu")
		(net "H_CPU1_PROCHOT_LVC1_R_N")
	)
	(segment
		(start 28.382976 -57.131458)
		(end 28.986988 -56.727852)
		(width 0.08382)
		(layer "In2.Cu")
		(net "H_CPU1_PROCHOT_LVC1_R_N")
	)
	(segment
		(start 35.707828 -50.5714)
		(end 35.789362 -50.652934)
		(width 0.08382)
		(layer "In2.Cu")
		(net "H_CPU1_PROCHOT_LVC1_R_N")
	)
	(segment
		(start 24.872188 -57.155588)
		(end 25.821386 -57.54878)
		(width 0.08382)
		(layer "In2.Cu")
		(net "H_CPU1_PROCHOT_LVC1_R_N")
	)
	(segment
		(start 20.744688 -53.028088)
		(end 24.872188 -57.155588)
		(width 0.08382)
		(layer "In2.Cu")
		(net "H_CPU1_PROCHOT_LVC1_R_N")
	)
	(segment
		(start 32.765746 -50.5714)
		(end 35.707828 -50.5714)
		(width 0.08382)
		(layer "In2.Cu")
		(net "H_CPU1_PROCHOT_LVC1_R_N")
	)
	(segment
		(start 30.1752 -51.5366)
		(end 31.6484 -50.0634)
		(width 0.08382)
		(layer "In2.Cu")
		(net "H_CPU1_PROCHOT_LVC1_R_N")
	)
	(segment
		(start 32.257746 -50.0634)
		(end 32.765746 -50.5714)
		(width 0.08382)
		(layer "In2.Cu")
		(net "H_CPU1_PROCHOT_LVC1_R_N")
	)
	(segment
		(start 25.821386 -57.54878)
		(end 27.375612 -57.54878)
		(width 0.08382)
		(layer "In2.Cu")
		(net "H_CPU1_PROCHOT_LVC1_R_N")
	)
	(segment
		(start 27.375612 -57.54878)
		(end 28.382976 -57.131458)
		(width 0.08382)
		(layer "In2.Cu")
		(net "H_CPU1_PROCHOT_LVC1_R_N")
	)
	(segment
		(start 31.6484 -50.0634)
		(end 32.257746 -50.0634)
		(width 0.08382)
		(layer "In2.Cu")
		(net "H_CPU1_PROCHOT_LVC1_R_N")
	)
	(segment
		(start 19.47418 -53.028088)
		(end 20.744688 -53.028088)
		(width 0.08382)
		(layer "In2.Cu")
		(net "H_CPU1_PROCHOT_LVC1_R_N")
	)
	(segment
		(start 19.014948 -75.01636)
		(end 18.21688 -75.814428)
		(width 0.10668)
		(layer "In4.Cu")
		(net "H_CPU1_PROCHOT_LVC1_R_N")
	)
	(segment
		(start 18.034 -79.33436)
		(end 18.034 -80.33512)
		(width 0.10668)
		(layer "In4.Cu")
		(net "H_CPU1_PROCHOT_LVC1_R_N")
	)
	(segment
		(start 21.7678 -63.764922)
		(end 20.40128 -65.131442)
		(width 0.10668)
		(layer "In4.Cu")
		(net "H_CPU1_PROCHOT_LVC1_R_N")
	)
	(segment
		(start 21.17344 -73.131172)
		(end 21.17344 -74.378312)
		(width 0.10668)
		(layer "In4.Cu")
		(net "H_CPU1_PROCHOT_LVC1_R_N")
	)
	(segment
		(start 18.28038 -79.08798)
		(end 18.034 -79.33436)
		(width 0.10668)
		(layer "In4.Cu")
		(net "H_CPU1_PROCHOT_LVC1_R_N")
	)
	(segment
		(start 20.73148 -72.689212)
		(end 21.17344 -73.131172)
		(width 0.10668)
		(layer "In4.Cu")
		(net "H_CPU1_PROCHOT_LVC1_R_N")
	)
	(segment
		(start 18.21688 -75.814428)
		(end 17.927828 -76.512674)
		(width 0.10668)
		(layer "In4.Cu")
		(net "H_CPU1_PROCHOT_LVC1_R_N")
	)
	(segment
		(start 18.28038 -78.16596)
		(end 18.28038 -79.08798)
		(width 0.10668)
		(layer "In4.Cu")
		(net "H_CPU1_PROCHOT_LVC1_R_N")
	)
	(segment
		(start 19.68754 -53.241448)
		(end 19.68754 -58.947304)
		(width 0.10668)
		(layer "In4.Cu")
		(net "H_CPU1_PROCHOT_LVC1_R_N")
	)
	(segment
		(start 18.034 -80.33512)
		(end 18.542 -80.84312)
		(width 0.10668)
		(layer "In4.Cu")
		(net "H_CPU1_PROCHOT_LVC1_R_N")
	)
	(segment
		(start 17.927828 -76.512674)
		(end 17.927828 -77.813408)
		(width 0.10668)
		(layer "In4.Cu")
		(net "H_CPU1_PROCHOT_LVC1_R_N")
	)
	(segment
		(start 19.47418 -53.028088)
		(end 19.68754 -53.241448)
		(width 0.10668)
		(layer "In4.Cu")
		(net "H_CPU1_PROCHOT_LVC1_R_N")
	)
	(segment
		(start 21.17344 -74.378312)
		(end 20.535392 -75.01636)
		(width 0.10668)
		(layer "In4.Cu")
		(net "H_CPU1_PROCHOT_LVC1_R_N")
	)
	(segment
		(start 20.0152 -69.35216)
		(end 20.24634 -69.5833)
		(width 0.10668)
		(layer "In4.Cu")
		(net "H_CPU1_PROCHOT_LVC1_R_N")
	)
	(segment
		(start 20.40128 -67.02552)
		(end 20.0152 -67.4116)
		(width 0.10668)
		(layer "In4.Cu")
		(net "H_CPU1_PROCHOT_LVC1_R_N")
	)
	(segment
		(start 20.73148 -71.50608)
		(end 20.73148 -72.689212)
		(width 0.10668)
		(layer "In4.Cu")
		(net "H_CPU1_PROCHOT_LVC1_R_N")
	)
	(segment
		(start 22.638258 -88.632792)
		(end 22.638258 -90.550746)
		(width 0.10668)
		(layer "In4.Cu")
		(net "H_CPU1_PROCHOT_LVC1_R_N")
	)
	(segment
		(start 22.2758 -88.270334)
		(end 22.638258 -88.632792)
		(width 0.10668)
		(layer "In4.Cu")
		(net "H_CPU1_PROCHOT_LVC1_R_N")
	)
	(segment
		(start 20.0152 -67.4116)
		(end 20.0152 -69.35216)
		(width 0.10668)
		(layer "In4.Cu")
		(net "H_CPU1_PROCHOT_LVC1_R_N")
	)
	(segment
		(start 17.927828 -77.813408)
		(end 18.28038 -78.16596)
		(width 0.10668)
		(layer "In4.Cu")
		(net "H_CPU1_PROCHOT_LVC1_R_N")
	)
	(segment
		(start 22.03704 -84.6963)
		(end 22.2758 -84.93506)
		(width 0.10668)
		(layer "In4.Cu")
		(net "H_CPU1_PROCHOT_LVC1_R_N")
	)
	(segment
		(start 20.24634 -71.02094)
		(end 20.73148 -71.50608)
		(width 0.10668)
		(layer "In4.Cu")
		(net "H_CPU1_PROCHOT_LVC1_R_N")
	)
	(segment
		(start 18.542 -80.84312)
		(end 21.636228 -80.84312)
		(width 0.10668)
		(layer "In4.Cu")
		(net "H_CPU1_PROCHOT_LVC1_R_N")
	)
	(segment
		(start 20.24634 -69.5833)
		(end 20.24634 -71.02094)
		(width 0.10668)
		(layer "In4.Cu")
		(net "H_CPU1_PROCHOT_LVC1_R_N")
	)
	(segment
		(start 22.638258 -90.550746)
		(end 22.413722 -90.775282)
		(width 0.10668)
		(layer "In4.Cu")
		(net "H_CPU1_PROCHOT_LVC1_R_N")
	)
	(segment
		(start 22.2758 -84.93506)
		(end 22.2758 -88.270334)
		(width 0.10668)
		(layer "In4.Cu")
		(net "H_CPU1_PROCHOT_LVC1_R_N")
	)
	(segment
		(start 21.7678 -61.027564)
		(end 21.7678 -63.764922)
		(width 0.10668)
		(layer "In4.Cu")
		(net "H_CPU1_PROCHOT_LVC1_R_N")
	)
	(segment
		(start 19.68754 -58.947304)
		(end 21.7678 -61.027564)
		(width 0.10668)
		(layer "In4.Cu")
		(net "H_CPU1_PROCHOT_LVC1_R_N")
	)
	(segment
		(start 21.04771 -90.775282)
		(end 20.66417 -90.391742)
		(width 0.10668)
		(layer "In4.Cu")
		(net "H_CPU1_PROCHOT_LVC1_R_N")
	)
	(segment
		(start 22.2758 -81.482692)
		(end 22.2758 -83.08594)
		(width 0.10668)
		(layer "In4.Cu")
		(net "H_CPU1_PROCHOT_LVC1_R_N")
	)
	(segment
		(start 22.2758 -83.08594)
		(end 22.03704 -83.3247)
		(width 0.10668)
		(layer "In4.Cu")
		(net "H_CPU1_PROCHOT_LVC1_R_N")
	)
	(segment
		(start 22.413722 -90.775282)
		(end 21.04771 -90.775282)
		(width 0.10668)
		(layer "In4.Cu")
		(net "H_CPU1_PROCHOT_LVC1_R_N")
	)
	(segment
		(start 22.03704 -83.3247)
		(end 22.03704 -84.6963)
		(width 0.10668)
		(layer "In4.Cu")
		(net "H_CPU1_PROCHOT_LVC1_R_N")
	)
	(segment
		(start 20.535392 -75.01636)
		(end 19.014948 -75.01636)
		(width 0.10668)
		(layer "In4.Cu")
		(net "H_CPU1_PROCHOT_LVC1_R_N")
	)
	(segment
		(start 20.40128 -65.131442)
		(end 20.40128 -67.02552)
		(width 0.10668)
		(layer "In4.Cu")
		(net "H_CPU1_PROCHOT_LVC1_R_N")
	)
	(segment
		(start 21.636228 -80.84312)
		(end 22.2758 -81.482692)
		(width 0.10668)
		(layer "In4.Cu")
		(net "H_CPU1_PROCHOT_LVC1_R_N")
	)
	(segment
		(start 36.654994 -117.117114)
		(end 36.654994 -118.25986)
		(width 0.11684)
		(layer "F.Cu")
		(net "IRQ_SGPIO_N")
	)
	(segment
		(start 33.64738 -105.95102)
		(end 33.64738 -105.57637)
		(width 0.11684)
		(layer "F.Cu")
		(net "IRQ_SGPIO_N")
	)
	(segment
		(start 33.64738 -105.57637)
		(end 33.909 -105.31475)
		(width 0.11684)
		(layer "F.Cu")
		(net "IRQ_SGPIO_N")
	)
	(segment
		(start 33.78835 -108.966)
		(end 34.343594 -109.521244)
		(width 0.11684)
		(layer "F.Cu")
		(net "IRQ_SGPIO_N")
	)
	(segment
		(start 33.909 -105.31475)
		(end 33.909 -103.91394)
		(width 0.11684)
		(layer "F.Cu")
		(net "IRQ_SGPIO_N")
	)
	(segment
		(start 33.33496 -107.494578)
		(end 33.33496 -106.26344)
		(width 0.11684)
		(layer "F.Cu")
		(net "IRQ_SGPIO_N")
	)
	(segment
		(start 33.78835 -108.384594)
		(end 33.64357 -108.239814)
		(width 0.11684)
		(layer "F.Cu")
		(net "IRQ_SGPIO_N")
	)
	(segment
		(start 34.8488 -111.30026)
		(end 36.842192 -113.293652)
		(width 0.11684)
		(layer "F.Cu")
		(net "IRQ_SGPIO_N")
	)
	(segment
		(start 33.33496 -106.26344)
		(end 33.64738 -105.95102)
		(width 0.11684)
		(layer "F.Cu")
		(net "IRQ_SGPIO_N")
	)
	(segment
		(start 34.343594 -109.521244)
		(end 34.616644 -109.521244)
		(width 0.11684)
		(layer "F.Cu")
		(net "IRQ_SGPIO_N")
	)
	(segment
		(start 34.8488 -109.7534)
		(end 34.8488 -111.30026)
		(width 0.11684)
		(layer "F.Cu")
		(net "IRQ_SGPIO_N")
	)
	(segment
		(start 33.78835 -108.966)
		(end 33.78835 -108.384594)
		(width 0.11684)
		(layer "F.Cu")
		(net "IRQ_SGPIO_N")
	)
	(segment
		(start 33.64357 -108.239814)
		(end 33.33496 -107.494578)
		(width 0.11684)
		(layer "F.Cu")
		(net "IRQ_SGPIO_N")
	)
	(segment
		(start 36.842192 -116.929916)
		(end 36.654994 -117.117114)
		(width 0.11684)
		(layer "F.Cu")
		(net "IRQ_SGPIO_N")
	)
	(segment
		(start 34.616644 -109.521244)
		(end 34.8488 -109.7534)
		(width 0.11684)
		(layer "F.Cu")
		(net "IRQ_SGPIO_N")
	)
	(segment
		(start 36.842192 -113.293652)
		(end 36.842192 -116.929916)
		(width 0.11684)
		(layer "F.Cu")
		(net "IRQ_SGPIO_N")
	)
	(via
		(at 24.082248 -76.533248)
		(size 0.6604)
		(drill 0.3302)
		(layers "F.Cu" "B.Cu")
		(net "IRQ_SGPIO_N")
	)
	(via
		(at 34.59226 -40.1574)
		(size 0.508)
		(drill 0.254)
		(layers "F.Cu" "B.Cu")
		(net "IRQ_SGPIO_N")
	)
	(via
		(at 33.909 -103.91394)
		(size 0.508)
		(drill 0.254)
		(layers "F.Cu" "B.Cu")
		(net "IRQ_SGPIO_N")
	)
	(via
		(at 26.6954 -78.5622)
		(size 0.508)
		(drill 0.254)
		(layers "F.Cu" "B.Cu")
		(net "IRQ_SGPIO_N")
	)
	(segment
		(start 13.2588 -83.29295)
		(end 12.82192 -82.85607)
		(width 0.11684)
		(layer "B.Cu")
		(net "IRQ_SGPIO_N")
	)
	(segment
		(start 38.08476 -42.17416)
		(end 37.6174 -41.7068)
		(width 0.11684)
		(layer "B.Cu")
		(net "IRQ_SGPIO_N")
	)
	(segment
		(start 14.351 -75.487276)
		(end 15.949676 -73.8886)
		(width 0.11684)
		(layer "B.Cu")
		(net "IRQ_SGPIO_N")
	)
	(segment
		(start 20.2438 -73.2536)
		(end 20.9042 -73.914)
		(width 0.11684)
		(layer "B.Cu")
		(net "IRQ_SGPIO_N")
	)
	(segment
		(start 15.949676 -73.8886)
		(end 18.4912 -73.8886)
		(width 0.11684)
		(layer "B.Cu")
		(net "IRQ_SGPIO_N")
	)
	(segment
		(start 23.139654 -73.914)
		(end 23.84044 -74.614786)
		(width 0.11684)
		(layer "B.Cu")
		(net "IRQ_SGPIO_N")
	)
	(segment
		(start 23.84044 -74.614786)
		(end 23.84044 -76.29144)
		(width 0.11684)
		(layer "B.Cu")
		(net "IRQ_SGPIO_N")
	)
	(segment
		(start 26.6954 -78.5622)
		(end 24.666448 -76.533248)
		(width 0.11684)
		(layer "B.Cu")
		(net "IRQ_SGPIO_N")
	)
	(segment
		(start 12.82192 -82.85607)
		(end 12.82192 -81.69148)
		(width 0.11684)
		(layer "B.Cu")
		(net "IRQ_SGPIO_N")
	)
	(segment
		(start 12.82192 -81.69148)
		(end 13.48232 -81.03108)
		(width 0.11684)
		(layer "B.Cu")
		(net "IRQ_SGPIO_N")
	)
	(segment
		(start 18.4912 -73.8886)
		(end 19.1262 -73.2536)
		(width 0.11684)
		(layer "B.Cu")
		(net "IRQ_SGPIO_N")
	)
	(segment
		(start 23.84044 -76.29144)
		(end 24.082248 -76.533248)
		(width 0.11684)
		(layer "B.Cu")
		(net "IRQ_SGPIO_N")
	)
	(segment
		(start 41.37279 -42.17416)
		(end 38.08476 -42.17416)
		(width 0.11684)
		(layer "B.Cu")
		(net "IRQ_SGPIO_N")
	)
	(segment
		(start 13.3604 -80.438498)
		(end 13.3604 -78.5622)
		(width 0.11684)
		(layer "B.Cu")
		(net "IRQ_SGPIO_N")
	)
	(segment
		(start 37.6174 -41.7068)
		(end 36.14166 -41.7068)
		(width 0.11684)
		(layer "B.Cu")
		(net "IRQ_SGPIO_N")
	)
	(segment
		(start 41.50995 -42.037)
		(end 41.37279 -42.17416)
		(width 0.11684)
		(layer "B.Cu")
		(net "IRQ_SGPIO_N")
	)
	(segment
		(start 36.14166 -41.7068)
		(end 34.59226 -40.1574)
		(width 0.11684)
		(layer "B.Cu")
		(net "IRQ_SGPIO_N")
	)
	(segment
		(start 19.1262 -73.2536)
		(end 20.2438 -73.2536)
		(width 0.11684)
		(layer "B.Cu")
		(net "IRQ_SGPIO_N")
	)
	(segment
		(start 24.666448 -76.533248)
		(end 24.082248 -76.533248)
		(width 0.11684)
		(layer "B.Cu")
		(net "IRQ_SGPIO_N")
	)
	(segment
		(start 13.48232 -81.03108)
		(end 13.48232 -80.560418)
		(width 0.11684)
		(layer "B.Cu")
		(net "IRQ_SGPIO_N")
	)
	(segment
		(start 13.3604 -78.5622)
		(end 14.351 -77.5716)
		(width 0.11684)
		(layer "B.Cu")
		(net "IRQ_SGPIO_N")
	)
	(segment
		(start 13.48232 -80.560418)
		(end 13.3604 -80.438498)
		(width 0.11684)
		(layer "B.Cu")
		(net "IRQ_SGPIO_N")
	)
	(segment
		(start 20.9042 -73.914)
		(end 23.139654 -73.914)
		(width 0.11684)
		(layer "B.Cu")
		(net "IRQ_SGPIO_N")
	)
	(segment
		(start 14.351 -77.5716)
		(end 14.351 -75.487276)
		(width 0.11684)
		(layer "B.Cu")
		(net "IRQ_SGPIO_N")
	)
	(segment
		(start 34.1249 -40.64)
		(end 34.59226 -40.17264)
		(width 0.10668)
		(layer "In4.Cu")
		(net "IRQ_SGPIO_N")
	)
	(segment
		(start 28.024328 -39.5859)
		(end 28.651708 -38.95852)
		(width 0.10668)
		(layer "In4.Cu")
		(net "IRQ_SGPIO_N")
	)
	(segment
		(start 25.57018 -73.442322)
		(end 25.57018 -71.646034)
		(width 0.10668)
		(layer "In4.Cu")
		(net "IRQ_SGPIO_N")
	)
	(segment
		(start 22.1996 -46.194726)
		(end 23.024846 -44.201842)
		(width 0.10668)
		(layer "In4.Cu")
		(net "IRQ_SGPIO_N")
	)
	(segment
		(start 27.640788 -39.5859)
		(end 28.024328 -39.5859)
		(width 0.10668)
		(layer "In4.Cu")
		(net "IRQ_SGPIO_N")
	)
	(segment
		(start 21.9583 -57.072784)
		(end 21.9583 -51.124104)
		(width 0.10668)
		(layer "In4.Cu")
		(net "IRQ_SGPIO_N")
	)
	(segment
		(start 31.66872 -38.95852)
		(end 33.3502 -40.64)
		(width 0.10668)
		(layer "In4.Cu")
		(net "IRQ_SGPIO_N")
	)
	(segment
		(start 23.024846 -44.201842)
		(end 27.640788 -39.5859)
		(width 0.10668)
		(layer "In4.Cu")
		(net "IRQ_SGPIO_N")
	)
	(segment
		(start 25.59558 -65.63614)
		(end 25.59558 -62.098682)
		(width 0.10668)
		(layer "In4.Cu")
		(net "IRQ_SGPIO_N")
	)
	(segment
		(start 26.37282 -76.49972)
		(end 26.37282 -74.244962)
		(width 0.10668)
		(layer "In4.Cu")
		(net "IRQ_SGPIO_N")
	)
	(segment
		(start 24.7904 -67.426078)
		(end 25.142698 -67.07378)
		(width 0.10668)
		(layer "In4.Cu")
		(net "IRQ_SGPIO_N")
	)
	(segment
		(start 33.3502 -40.64)
		(end 34.1249 -40.64)
		(width 0.10668)
		(layer "In4.Cu")
		(net "IRQ_SGPIO_N")
	)
	(segment
		(start 25.57018 -71.646034)
		(end 24.7904 -70.866254)
		(width 0.10668)
		(layer "In4.Cu")
		(net "IRQ_SGPIO_N")
	)
	(segment
		(start 34.59226 -40.17264)
		(end 34.59226 -40.1574)
		(width 0.10668)
		(layer "In4.Cu")
		(net "IRQ_SGPIO_N")
	)
	(segment
		(start 22.1996 -50.541682)
		(end 22.1996 -46.194726)
		(width 0.10668)
		(layer "In4.Cu")
		(net "IRQ_SGPIO_N")
	)
	(segment
		(start 25.59558 -62.098682)
		(end 24.61514 -61.118242)
		(width 0.10668)
		(layer "In4.Cu")
		(net "IRQ_SGPIO_N")
	)
	(segment
		(start 24.61514 -59.729624)
		(end 21.9583 -57.072784)
		(width 0.10668)
		(layer "In4.Cu")
		(net "IRQ_SGPIO_N")
	)
	(segment
		(start 26.37282 -74.244962)
		(end 25.57018 -73.442322)
		(width 0.10668)
		(layer "In4.Cu")
		(net "IRQ_SGPIO_N")
	)
	(segment
		(start 28.651708 -38.95852)
		(end 31.66872 -38.95852)
		(width 0.10668)
		(layer "In4.Cu")
		(net "IRQ_SGPIO_N")
	)
	(segment
		(start 26.6954 -76.8223)
		(end 26.37282 -76.49972)
		(width 0.10668)
		(layer "In4.Cu")
		(net "IRQ_SGPIO_N")
	)
	(segment
		(start 24.61514 -61.118242)
		(end 24.61514 -59.729624)
		(width 0.10668)
		(layer "In4.Cu")
		(net "IRQ_SGPIO_N")
	)
	(segment
		(start 26.6954 -78.5622)
		(end 26.6954 -76.8223)
		(width 0.10668)
		(layer "In4.Cu")
		(net "IRQ_SGPIO_N")
	)
	(segment
		(start 21.9583 -51.124104)
		(end 22.1996 -50.541682)
		(width 0.10668)
		(layer "In4.Cu")
		(net "IRQ_SGPIO_N")
	)
	(segment
		(start 25.142698 -66.089022)
		(end 25.59558 -65.63614)
		(width 0.10668)
		(layer "In4.Cu")
		(net "IRQ_SGPIO_N")
	)
	(segment
		(start 24.7904 -70.866254)
		(end 24.7904 -67.426078)
		(width 0.10668)
		(layer "In4.Cu")
		(net "IRQ_SGPIO_N")
	)
	(segment
		(start 25.142698 -67.07378)
		(end 25.142698 -66.089022)
		(width 0.10668)
		(layer "In4.Cu")
		(net "IRQ_SGPIO_N")
	)
	(segment
		(start 30.4419 -88.059006)
		(end 28.903168 -86.520274)
		(width 0.10668)
		(layer "In7.Cu")
		(net "IRQ_SGPIO_N")
	)
	(segment
		(start 33.909 -103.91394)
		(end 33.909 -103.2002)
		(width 0.10668)
		(layer "In7.Cu")
		(net "IRQ_SGPIO_N")
	)
	(segment
		(start 26.21026 -80.53578)
		(end 26.21026 -78.74254)
		(width 0.10668)
		(layer "In7.Cu")
		(net "IRQ_SGPIO_N")
	)
	(segment
		(start 26.3906 -78.5622)
		(end 26.6954 -78.5622)
		(width 0.10668)
		(layer "In7.Cu")
		(net "IRQ_SGPIO_N")
	)
	(segment
		(start 34.73958 -98.863404)
		(end 33.22066 -97.344484)
		(width 0.10668)
		(layer "In7.Cu")
		(net "IRQ_SGPIO_N")
	)
	(segment
		(start 26.21026 -78.74254)
		(end 26.3906 -78.5622)
		(width 0.10668)
		(layer "In7.Cu")
		(net "IRQ_SGPIO_N")
	)
	(segment
		(start 33.19526 -102.48646)
		(end 33.19526 -101.4095)
		(width 0.10668)
		(layer "In7.Cu")
		(net "IRQ_SGPIO_N")
	)
	(segment
		(start 32.98698 -96.41586)
		(end 32.37484 -95.80372)
		(width 0.10668)
		(layer "In7.Cu")
		(net "IRQ_SGPIO_N")
	)
	(segment
		(start 31.98114 -92.63634)
		(end 31.98114 -91.7829)
		(width 0.10668)
		(layer "In7.Cu")
		(net "IRQ_SGPIO_N")
	)
	(segment
		(start 33.909 -103.2002)
		(end 33.19526 -102.48646)
		(width 0.10668)
		(layer "In7.Cu")
		(net "IRQ_SGPIO_N")
	)
	(segment
		(start 28.903168 -86.520274)
		(end 28.81757 -86.520274)
		(width 0.10668)
		(layer "In7.Cu")
		(net "IRQ_SGPIO_N")
	)
	(segment
		(start 33.535112 -101.069648)
		(end 33.944052 -101.069648)
		(width 0.10668)
		(layer "In7.Cu")
		(net "IRQ_SGPIO_N")
	)
	(segment
		(start 31.98114 -91.7829)
		(end 30.4419 -90.24366)
		(width 0.10668)
		(layer "In7.Cu")
		(net "IRQ_SGPIO_N")
	)
	(segment
		(start 34.73958 -100.27412)
		(end 34.73958 -98.863404)
		(width 0.10668)
		(layer "In7.Cu")
		(net "IRQ_SGPIO_N")
	)
	(segment
		(start 28.26258 -83.71078)
		(end 27.821128 -83.269328)
		(width 0.10668)
		(layer "In7.Cu")
		(net "IRQ_SGPIO_N")
	)
	(segment
		(start 27.821128 -83.269328)
		(end 27.821128 -82.146648)
		(width 0.10668)
		(layer "In7.Cu")
		(net "IRQ_SGPIO_N")
	)
	(segment
		(start 32.37484 -93.03004)
		(end 31.98114 -92.63634)
		(width 0.10668)
		(layer "In7.Cu")
		(net "IRQ_SGPIO_N")
	)
	(segment
		(start 28.26258 -85.965284)
		(end 28.26258 -83.71078)
		(width 0.10668)
		(layer "In7.Cu")
		(net "IRQ_SGPIO_N")
	)
	(segment
		(start 28.81757 -86.520274)
		(end 28.26258 -85.965284)
		(width 0.10668)
		(layer "In7.Cu")
		(net "IRQ_SGPIO_N")
	)
	(segment
		(start 33.22066 -96.97974)
		(end 32.98698 -96.41586)
		(width 0.10668)
		(layer "In7.Cu")
		(net "IRQ_SGPIO_N")
	)
	(segment
		(start 30.4419 -90.24366)
		(end 30.4419 -88.059006)
		(width 0.10668)
		(layer "In7.Cu")
		(net "IRQ_SGPIO_N")
	)
	(segment
		(start 33.944052 -101.069648)
		(end 34.73958 -100.27412)
		(width 0.10668)
		(layer "In7.Cu")
		(net "IRQ_SGPIO_N")
	)
	(segment
		(start 27.821128 -82.146648)
		(end 26.21026 -80.53578)
		(width 0.10668)
		(layer "In7.Cu")
		(net "IRQ_SGPIO_N")
	)
	(segment
		(start 33.19526 -101.4095)
		(end 33.535112 -101.069648)
		(width 0.10668)
		(layer "In7.Cu")
		(net "IRQ_SGPIO_N")
	)
	(segment
		(start 33.22066 -97.344484)
		(end 33.22066 -96.97974)
		(width 0.10668)
		(layer "In7.Cu")
		(net "IRQ_SGPIO_N")
	)
	(segment
		(start 32.37484 -95.80372)
		(end 32.37484 -93.03004)
		(width 0.10668)
		(layer "In7.Cu")
		(net "IRQ_SGPIO_N")
	)
	(segment
		(start 46.494954 -44.171362)
		(end 46.09973 -43.776138)
		(width 0.11684)
		(layer "F.Cu")
		(net "IRQ_SGPIO_BMC_N")
	)
	(via
		(at 46.09973 -43.776138)
		(size 0.4572)
		(drill 0.254)
		(layers "F.Cu" "B.Cu")
		(net "IRQ_SGPIO_BMC_N")
	)
	(segment
		(start 42.627042 -42.353992)
		(end 42.31005 -42.037)
		(width 0.11684)
		(layer "B.Cu")
		(net "IRQ_SGPIO_BMC_N")
	)
	(segment
		(start 46.09973 -43.776138)
		(end 45.8724 -43.776138)
		(width 0.11684)
		(layer "B.Cu")
		(net "IRQ_SGPIO_BMC_N")
	)
	(segment
		(start 45.138848 -43.364658)
		(end 44.563792 -42.789602)
		(width 0.11684)
		(layer "B.Cu")
		(net "IRQ_SGPIO_BMC_N")
	)
	(segment
		(start 43.512486 -42.353992)
		(end 42.627042 -42.353992)
		(width 0.11684)
		(layer "B.Cu")
		(net "IRQ_SGPIO_BMC_N")
	)
	(segment
		(start 44.563792 -42.789602)
		(end 43.512486 -42.353992)
		(width 0.11684)
		(layer "B.Cu")
		(net "IRQ_SGPIO_BMC_N")
	)
	(segment
		(start 45.8724 -43.776138)
		(end 45.46092 -43.364658)
		(width 0.11684)
		(layer "B.Cu")
		(net "IRQ_SGPIO_BMC_N")
	)
	(segment
		(start 45.46092 -43.364658)
		(end 45.138848 -43.364658)
		(width 0.11684)
		(layer "B.Cu")
		(net "IRQ_SGPIO_BMC_N")
	)
	(segment
		(start 21.336 -86.1568)
		(end 21.859494 -86.680294)
		(width 0.11684)
		(layer "F.Cu")
		(net "IRQ_BMC_PCH_NMI_R_N")
	)
	(segment
		(start 20.701 -86.1568)
		(end 21.336 -86.1568)
		(width 0.11684)
		(layer "F.Cu")
		(net "IRQ_BMC_PCH_NMI_R_N")
	)
	(segment
		(start 21.859494 -86.680294)
		(end 21.859494 -87.587074)
		(width 0.11684)
		(layer "F.Cu")
		(net "IRQ_BMC_PCH_NMI_R_N")
	)
	(segment
		(start 20.0406 -85.4964)
		(end 20.701 -86.1568)
		(width 0.11684)
		(layer "F.Cu")
		(net "IRQ_BMC_PCH_NMI_R_N")
	)
	(via
		(at 20.0406 -85.4964)
		(size 0.508)
		(drill 0.254)
		(layers "F.Cu" "B.Cu")
		(net "IRQ_BMC_PCH_NMI_R_N")
	)
	(segment
		(start 19.431 -84.09305)
		(end 19.812 -84.47405)
		(width 0.11684)
		(layer "B.Cu")
		(net "IRQ_BMC_PCH_NMI_R_N")
	)
	(segment
		(start 19.812 -84.47405)
		(end 19.812 -85.2678)
		(width 0.11684)
		(layer "B.Cu")
		(net "IRQ_BMC_PCH_NMI_R_N")
	)
	(segment
		(start 19.812 -85.2678)
		(end 20.0406 -85.4964)
		(width 0.11684)
		(layer "B.Cu")
		(net "IRQ_BMC_PCH_NMI_R_N")
	)
	(segment
		(start 47.295054 -50.571146)
		(end 46.89983 -50.96637)
		(width 0.11684)
		(layer "F.Cu")
		(net "IRQ_BMC_PCH_NMI_N")
	)
	(via
		(at 48.019716 -100.965)
		(size 0.508)
		(drill 0.254)
		(layers "F.Cu" "B.Cu")
		(net "IRQ_BMC_PCH_NMI_N")
	)
	(via
		(at 17.561306 -105.016808)
		(size 0.508)
		(drill 0.254)
		(layers "F.Cu" "B.Cu")
		(net "IRQ_BMC_PCH_NMI_N")
	)
	(via
		(at 19.5326 -82.042)
		(size 0.508)
		(drill 0.254)
		(layers "F.Cu" "B.Cu")
		(net "IRQ_BMC_PCH_NMI_N")
	)
	(via
		(at 46.89983 -50.96637)
		(size 0.4572)
		(drill 0.254)
		(layers "F.Cu" "B.Cu")
		(net "IRQ_BMC_PCH_NMI_N")
	)
	(segment
		(start 19.755104 -83.29295)
		(end 19.939 -83.109054)
		(width 0.11684)
		(layer "B.Cu")
		(net "IRQ_BMC_PCH_NMI_N")
	)
	(segment
		(start 46.89983 -50.96637)
		(end 47.3964 -51.46294)
		(width 0.11684)
		(layer "B.Cu")
		(net "IRQ_BMC_PCH_NMI_N")
	)
	(segment
		(start 47.3964 -51.46294)
		(end 47.3964 -52.038504)
		(width 0.11684)
		(layer "B.Cu")
		(net "IRQ_BMC_PCH_NMI_N")
	)
	(segment
		(start 47.879 -52.521104)
		(end 47.879 -52.54625)
		(width 0.11684)
		(layer "B.Cu")
		(net "IRQ_BMC_PCH_NMI_N")
	)
	(segment
		(start 19.939 -82.4484)
		(end 19.5326 -82.042)
		(width 0.11684)
		(layer "B.Cu")
		(net "IRQ_BMC_PCH_NMI_N")
	)
	(segment
		(start 47.3964 -52.038504)
		(end 47.879 -52.521104)
		(width 0.11684)
		(layer "B.Cu")
		(net "IRQ_BMC_PCH_NMI_N")
	)
	(segment
		(start 19.431 -83.29295)
		(end 19.755104 -83.29295)
		(width 0.11684)
		(layer "B.Cu")
		(net "IRQ_BMC_PCH_NMI_N")
	)
	(segment
		(start 19.939 -83.109054)
		(end 19.939 -82.4484)
		(width 0.11684)
		(layer "B.Cu")
		(net "IRQ_BMC_PCH_NMI_N")
	)
	(segment
		(start 30.05836 -103.61676)
		(end 29.7942 -103.3526)
		(width 0.08382)
		(layer "In2.Cu")
		(net "IRQ_BMC_PCH_NMI_N")
	)
	(segment
		(start 34.852356 -102.84079)
		(end 33.220152 -102.84079)
		(width 0.08382)
		(layer "In2.Cu")
		(net "IRQ_BMC_PCH_NMI_N")
	)
	(segment
		(start 18.804128 -106.25963)
		(end 17.561306 -105.016808)
		(width 0.08382)
		(layer "In2.Cu")
		(net "IRQ_BMC_PCH_NMI_N")
	)
	(segment
		(start 27.2415 -103.3526)
		(end 26.889456 -103.704644)
		(width 0.08382)
		(layer "In2.Cu")
		(net "IRQ_BMC_PCH_NMI_N")
	)
	(segment
		(start 48.019716 -100.965)
		(end 46.339506 -102.64521)
		(width 0.08382)
		(layer "In2.Cu")
		(net "IRQ_BMC_PCH_NMI_N")
	)
	(segment
		(start 33.220152 -102.84079)
		(end 33.1216 -102.742238)
		(width 0.08382)
		(layer "In2.Cu")
		(net "IRQ_BMC_PCH_NMI_N")
	)
	(segment
		(start 30.826456 -103.61676)
		(end 30.05836 -103.61676)
		(width 0.08382)
		(layer "In2.Cu")
		(net "IRQ_BMC_PCH_NMI_N")
	)
	(segment
		(start 26.889456 -103.704644)
		(end 26.889456 -104.900476)
		(width 0.08382)
		(layer "In2.Cu")
		(net "IRQ_BMC_PCH_NMI_N")
	)
	(segment
		(start 33.1216 -102.742238)
		(end 31.290514 -102.742238)
		(width 0.08382)
		(layer "In2.Cu")
		(net "IRQ_BMC_PCH_NMI_N")
	)
	(segment
		(start 29.7942 -103.3526)
		(end 27.2415 -103.3526)
		(width 0.08382)
		(layer "In2.Cu")
		(net "IRQ_BMC_PCH_NMI_N")
	)
	(segment
		(start 25.530302 -106.25963)
		(end 18.804128 -106.25963)
		(width 0.08382)
		(layer "In2.Cu")
		(net "IRQ_BMC_PCH_NMI_N")
	)
	(segment
		(start 31.0896 -102.943152)
		(end 31.0896 -103.353616)
		(width 0.08382)
		(layer "In2.Cu")
		(net "IRQ_BMC_PCH_NMI_N")
	)
	(segment
		(start 31.0896 -103.353616)
		(end 30.826456 -103.61676)
		(width 0.08382)
		(layer "In2.Cu")
		(net "IRQ_BMC_PCH_NMI_N")
	)
	(segment
		(start 35.047936 -102.64521)
		(end 34.852356 -102.84079)
		(width 0.08382)
		(layer "In2.Cu")
		(net "IRQ_BMC_PCH_NMI_N")
	)
	(segment
		(start 46.339506 -102.64521)
		(end 35.047936 -102.64521)
		(width 0.08382)
		(layer "In2.Cu")
		(net "IRQ_BMC_PCH_NMI_N")
	)
	(segment
		(start 26.889456 -104.900476)
		(end 25.530302 -106.25963)
		(width 0.08382)
		(layer "In2.Cu")
		(net "IRQ_BMC_PCH_NMI_N")
	)
	(segment
		(start 31.290514 -102.742238)
		(end 31.0896 -102.943152)
		(width 0.08382)
		(layer "In2.Cu")
		(net "IRQ_BMC_PCH_NMI_N")
	)
	(segment
		(start 46.541182 -66.463418)
		(end 46.613572 -66.289682)
		(width 0.10668)
		(layer "In4.Cu")
		(net "IRQ_BMC_PCH_NMI_N")
	)
	(segment
		(start 46.659292 -65.646046)
		(end 46.657006 -65.62471)
		(width 0.10668)
		(layer "In4.Cu")
		(net "IRQ_BMC_PCH_NMI_N")
	)
	(segment
		(start 46.654212 -66.19113)
		(end 46.6598 -66.16446)
		(width 0.10668)
		(layer "In4.Cu")
		(net "IRQ_BMC_PCH_NMI_N")
	)
	(segment
		(start 46.1772 -63.8556)
		(end 46.1772 -60.402216)
		(width 0.10668)
		(layer "In4.Cu")
		(net "IRQ_BMC_PCH_NMI_N")
	)
	(segment
		(start 46.782228 -82.556858)
		(end 46.4058 -81.648046)
		(width 0.10668)
		(layer "In4.Cu")
		(net "IRQ_BMC_PCH_NMI_N")
	)
	(segment
		(start 46.6598 -65.653158)
		(end 46.659292 -65.646046)
		(width 0.10668)
		(layer "In4.Cu")
		(net "IRQ_BMC_PCH_NMI_N")
	)
	(segment
		(start 47.28718 -59.26582)
		(end 47.28718 -51.35372)
		(width 0.10668)
		(layer "In4.Cu")
		(net "IRQ_BMC_PCH_NMI_N")
	)
	(segment
		(start 47.4726 -100.417884)
		(end 47.4726 -98.16084)
		(width 0.10668)
		(layer "In4.Cu")
		(net "IRQ_BMC_PCH_NMI_N")
	)
	(segment
		(start 46.426374 -64.4652)
		(end 46.419262 -64.441832)
		(width 0.10668)
		(layer "In4.Cu")
		(net "IRQ_BMC_PCH_NMI_N")
	)
	(segment
		(start 47.266606 -59.31281)
		(end 47.279052 -59.2963)
		(width 0.10668)
		(layer "In4.Cu")
		(net "IRQ_BMC_PCH_NMI_N")
	)
	(segment
		(start 46.416468 -64.433704)
		(end 46.1772 -63.8556)
		(width 0.10668)
		(layer "In4.Cu")
		(net "IRQ_BMC_PCH_NMI_N")
	)
	(segment
		(start 46.652434 -66.195702)
		(end 46.654212 -66.19113)
		(width 0.10668)
		(layer "In4.Cu")
		(net "IRQ_BMC_PCH_NMI_N")
	)
	(segment
		(start 46.0248 -69.671946)
		(end 46.0248 -69.0626)
		(width 0.10668)
		(layer "In4.Cu")
		(net "IRQ_BMC_PCH_NMI_N")
	)
	(segment
		(start 47.284132 -59.284616)
		(end 47.286418 -59.274964)
		(width 0.10668)
		(layer "In4.Cu")
		(net "IRQ_BMC_PCH_NMI_N")
	)
	(segment
		(start 46.4058 -81.648046)
		(end 46.4058 -76.911454)
		(width 0.10668)
		(layer "In4.Cu")
		(net "IRQ_BMC_PCH_NMI_N")
	)
	(segment
		(start 46.419262 -64.441832)
		(end 46.416468 -64.433704)
		(width 0.10668)
		(layer "In4.Cu")
		(net "IRQ_BMC_PCH_NMI_N")
	)
	(segment
		(start 47.4726 -98.16084)
		(end 47.11446 -97.8027)
		(width 0.10668)
		(layer "In4.Cu")
		(net "IRQ_BMC_PCH_NMI_N")
	)
	(segment
		(start 48.019716 -100.965)
		(end 47.4726 -100.417884)
		(width 0.10668)
		(layer "In4.Cu")
		(net "IRQ_BMC_PCH_NMI_N")
	)
	(segment
		(start 47.69612 -94.747334)
		(end 47.69612 -90.099896)
		(width 0.10668)
		(layer "In4.Cu")
		(net "IRQ_BMC_PCH_NMI_N")
	)
	(segment
		(start 47.11446 -95.328994)
		(end 47.69612 -94.747334)
		(width 0.10668)
		(layer "In4.Cu")
		(net "IRQ_BMC_PCH_NMI_N")
	)
	(segment
		(start 46.655736 -65.616328)
		(end 46.428406 -64.47282)
		(width 0.10668)
		(layer "In4.Cu")
		(net "IRQ_BMC_PCH_NMI_N")
	)
	(segment
		(start 47.279052 -59.2963)
		(end 47.284132 -59.284616)
		(width 0.10668)
		(layer "In4.Cu")
		(net "IRQ_BMC_PCH_NMI_N")
	)
	(segment
		(start 47.286418 -59.274964)
		(end 47.28718 -59.26582)
		(width 0.10668)
		(layer "In4.Cu")
		(net "IRQ_BMC_PCH_NMI_N")
	)
	(segment
		(start 46.428406 -64.47282)
		(end 46.426374 -64.4652)
		(width 0.10668)
		(layer "In4.Cu")
		(net "IRQ_BMC_PCH_NMI_N")
	)
	(segment
		(start 46.4058 -76.911454)
		(end 47.196502 -76.120752)
		(width 0.10668)
		(layer "In4.Cu")
		(net "IRQ_BMC_PCH_NMI_N")
	)
	(segment
		(start 46.782228 -86.505288)
		(end 46.782228 -82.556858)
		(width 0.10668)
		(layer "In4.Cu")
		(net "IRQ_BMC_PCH_NMI_N")
	)
	(segment
		(start 47.196502 -70.843648)
		(end 46.0248 -69.671946)
		(width 0.10668)
		(layer "In4.Cu")
		(net "IRQ_BMC_PCH_NMI_N")
	)
	(segment
		(start 46.3042 -67.037204)
		(end 46.54169 -66.463926)
		(width 0.10668)
		(layer "In4.Cu")
		(net "IRQ_BMC_PCH_NMI_N")
	)
	(segment
		(start 46.54169 -66.463926)
		(end 46.541182 -66.463418)
		(width 0.10668)
		(layer "In4.Cu")
		(net "IRQ_BMC_PCH_NMI_N")
	)
	(segment
		(start 47.69612 -90.099896)
		(end 47.14494 -89.548716)
		(width 0.10668)
		(layer "In4.Cu")
		(net "IRQ_BMC_PCH_NMI_N")
	)
	(segment
		(start 46.1772 -60.402216)
		(end 47.266606 -59.31281)
		(width 0.10668)
		(layer "In4.Cu")
		(net "IRQ_BMC_PCH_NMI_N")
	)
	(segment
		(start 47.28718 -51.35372)
		(end 46.89983 -50.96637)
		(width 0.10668)
		(layer "In4.Cu")
		(net "IRQ_BMC_PCH_NMI_N")
	)
	(segment
		(start 46.657006 -65.62471)
		(end 46.655736 -65.616328)
		(width 0.10668)
		(layer "In4.Cu")
		(net "IRQ_BMC_PCH_NMI_N")
	)
	(segment
		(start 46.0248 -69.0626)
		(end 46.3042 -68.7832)
		(width 0.10668)
		(layer "In4.Cu")
		(net "IRQ_BMC_PCH_NMI_N")
	)
	(segment
		(start 46.613572 -66.289682)
		(end 46.652434 -66.195702)
		(width 0.10668)
		(layer "In4.Cu")
		(net "IRQ_BMC_PCH_NMI_N")
	)
	(segment
		(start 47.196502 -76.120752)
		(end 47.196502 -70.843648)
		(width 0.10668)
		(layer "In4.Cu")
		(net "IRQ_BMC_PCH_NMI_N")
	)
	(segment
		(start 47.14494 -89.548716)
		(end 47.14494 -86.868)
		(width 0.10668)
		(layer "In4.Cu")
		(net "IRQ_BMC_PCH_NMI_N")
	)
	(segment
		(start 46.3042 -68.7832)
		(end 46.3042 -67.037204)
		(width 0.10668)
		(layer "In4.Cu")
		(net "IRQ_BMC_PCH_NMI_N")
	)
	(segment
		(start 46.6598 -66.16446)
		(end 46.6598 -65.653158)
		(width 0.10668)
		(layer "In4.Cu")
		(net "IRQ_BMC_PCH_NMI_N")
	)
	(segment
		(start 47.14494 -86.868)
		(end 46.782228 -86.505288)
		(width 0.10668)
		(layer "In4.Cu")
		(net "IRQ_BMC_PCH_NMI_N")
	)
	(segment
		(start 47.11446 -97.8027)
		(end 47.11446 -95.328994)
		(width 0.10668)
		(layer "In4.Cu")
		(net "IRQ_BMC_PCH_NMI_N")
	)
	(segment
		(start 13.848334 -84.909406)
		(end 13.62964 -85.1281)
		(width 0.10668)
		(layer "In7.Cu")
		(net "IRQ_BMC_PCH_NMI_N")
	)
	(segment
		(start 18.9484 -82.3722)
		(end 18.9484 -83.2866)
		(width 0.10668)
		(layer "In7.Cu")
		(net "IRQ_BMC_PCH_NMI_N")
	)
	(segment
		(start 18.9484 -83.2866)
		(end 17.325594 -84.909406)
		(width 0.10668)
		(layer "In7.Cu")
		(net "IRQ_BMC_PCH_NMI_N")
	)
	(segment
		(start 17.21612 -102.35692)
		(end 18.17878 -103.31958)
		(width 0.10668)
		(layer "In7.Cu")
		(net "IRQ_BMC_PCH_NMI_N")
	)
	(segment
		(start 15.34668 -90.706448)
		(end 15.34668 -94.53372)
		(width 0.10668)
		(layer "In7.Cu")
		(net "IRQ_BMC_PCH_NMI_N")
	)
	(segment
		(start 14.4018 -101.142546)
		(end 15.616174 -102.35692)
		(width 0.10668)
		(layer "In7.Cu")
		(net "IRQ_BMC_PCH_NMI_N")
	)
	(segment
		(start 13.62964 -85.1281)
		(end 13.62964 -87.74684)
		(width 0.10668)
		(layer "In7.Cu")
		(net "IRQ_BMC_PCH_NMI_N")
	)
	(segment
		(start 19.2786 -82.042)
		(end 18.9484 -82.3722)
		(width 0.10668)
		(layer "In7.Cu")
		(net "IRQ_BMC_PCH_NMI_N")
	)
	(segment
		(start 15.2908 -90.650568)
		(end 15.34668 -90.706448)
		(width 0.10668)
		(layer "In7.Cu")
		(net "IRQ_BMC_PCH_NMI_N")
	)
	(segment
		(start 18.17878 -104.399334)
		(end 17.561306 -105.016808)
		(width 0.10668)
		(layer "In7.Cu")
		(net "IRQ_BMC_PCH_NMI_N")
	)
	(segment
		(start 19.5326 -82.042)
		(end 19.2786 -82.042)
		(width 0.10668)
		(layer "In7.Cu")
		(net "IRQ_BMC_PCH_NMI_N")
	)
	(segment
		(start 14.91996 -94.96044)
		(end 14.91996 -99.567238)
		(width 0.10668)
		(layer "In7.Cu")
		(net "IRQ_BMC_PCH_NMI_N")
	)
	(segment
		(start 15.616174 -102.35692)
		(end 17.21612 -102.35692)
		(width 0.10668)
		(layer "In7.Cu")
		(net "IRQ_BMC_PCH_NMI_N")
	)
	(segment
		(start 13.62964 -87.74684)
		(end 15.2908 -89.408)
		(width 0.10668)
		(layer "In7.Cu")
		(net "IRQ_BMC_PCH_NMI_N")
	)
	(segment
		(start 15.34668 -94.53372)
		(end 14.91996 -94.96044)
		(width 0.10668)
		(layer "In7.Cu")
		(net "IRQ_BMC_PCH_NMI_N")
	)
	(segment
		(start 17.325594 -84.909406)
		(end 13.848334 -84.909406)
		(width 0.10668)
		(layer "In7.Cu")
		(net "IRQ_BMC_PCH_NMI_N")
	)
	(segment
		(start 14.4018 -100.085398)
		(end 14.4018 -101.142546)
		(width 0.10668)
		(layer "In7.Cu")
		(net "IRQ_BMC_PCH_NMI_N")
	)
	(segment
		(start 18.17878 -103.31958)
		(end 18.17878 -104.399334)
		(width 0.10668)
		(layer "In7.Cu")
		(net "IRQ_BMC_PCH_NMI_N")
	)
	(segment
		(start 14.91996 -99.567238)
		(end 14.4018 -100.085398)
		(width 0.10668)
		(layer "In7.Cu")
		(net "IRQ_BMC_PCH_NMI_N")
	)
	(segment
		(start 15.2908 -89.408)
		(end 15.2908 -90.650568)
		(width 0.10668)
		(layer "In7.Cu")
		(net "IRQ_BMC_PCH_NMI_N")
	)
	(segment
		(start 62.265052 -118.25986)
		(end 62.265052 -116.094764)
		(width 0.11684)
		(layer "F.Cu")
		(net "IRQ_BMC_LPC_SERIRQ_ESPI_GF")
	)
	(segment
		(start 63.62827 -64.70777)
		(end 63.62827 -64.319912)
		(width 0.11684)
		(layer "F.Cu")
		(net "IRQ_BMC_LPC_SERIRQ_ESPI_GF")
	)
	(segment
		(start 62.1538 -115.983512)
		(end 62.1538 -114.3762)
		(width 0.11684)
		(layer "F.Cu")
		(net "IRQ_BMC_LPC_SERIRQ_ESPI_GF")
	)
	(segment
		(start 63.505842 -64.830198)
		(end 63.62827 -64.70777)
		(width 0.11684)
		(layer "F.Cu")
		(net "IRQ_BMC_LPC_SERIRQ_ESPI_GF")
	)
	(segment
		(start 63.815976 -65.37071)
		(end 63.505842 -65.37071)
		(width 0.11684)
		(layer "F.Cu")
		(net "IRQ_BMC_LPC_SERIRQ_ESPI_GF")
	)
	(segment
		(start 63.505842 -65.37071)
		(end 63.505842 -64.830198)
		(width 0.11684)
		(layer "F.Cu")
		(net "IRQ_BMC_LPC_SERIRQ_ESPI_GF")
	)
	(segment
		(start 64.2874 -65.4812)
		(end 63.926466 -65.4812)
		(width 0.11684)
		(layer "F.Cu")
		(net "IRQ_BMC_LPC_SERIRQ_ESPI_GF")
	)
	(segment
		(start 62.1538 -114.3762)
		(end 62.611 -113.919)
		(width 0.11684)
		(layer "F.Cu")
		(net "IRQ_BMC_LPC_SERIRQ_ESPI_GF")
	)
	(segment
		(start 62.265052 -116.094764)
		(end 62.1538 -115.983512)
		(width 0.11684)
		(layer "F.Cu")
		(net "IRQ_BMC_LPC_SERIRQ_ESPI_GF")
	)
	(segment
		(start 63.926466 -65.4812)
		(end 63.815976 -65.37071)
		(width 0.11684)
		(layer "F.Cu")
		(net "IRQ_BMC_LPC_SERIRQ_ESPI_GF")
	)
	(via
		(at 62.611 -113.919)
		(size 0.508)
		(drill 0.254)
		(layers "F.Cu" "B.Cu")
		(net "IRQ_BMC_LPC_SERIRQ_ESPI_GF")
	)
	(via
		(at 64.2874 -65.4812)
		(size 0.508)
		(drill 0.254)
		(layers "F.Cu" "B.Cu")
		(net "IRQ_BMC_LPC_SERIRQ_ESPI_GF")
	)
	(segment
		(start 66.00698 -70.32498)
		(end 65.5574 -69.8754)
		(width 0.10668)
		(layer "In4.Cu")
		(net "IRQ_BMC_LPC_SERIRQ_ESPI_GF")
	)
	(segment
		(start 62.671198 -112.818926)
		(end 62.671198 -112.286542)
		(width 0.10668)
		(layer "In4.Cu")
		(net "IRQ_BMC_LPC_SERIRQ_ESPI_GF")
	)
	(segment
		(start 62.8142 -112.14354)
		(end 62.8142 -112.0902)
		(width 0.10668)
		(layer "In4.Cu")
		(net "IRQ_BMC_LPC_SERIRQ_ESPI_GF")
	)
	(segment
		(start 68.17106 -83.085178)
		(end 68.17106 -77.851)
		(width 0.10668)
		(layer "In4.Cu")
		(net "IRQ_BMC_LPC_SERIRQ_ESPI_GF")
	)
	(segment
		(start 62.611 -113.919)
		(end 62.8142 -113.7158)
		(width 0.10668)
		(layer "In4.Cu")
		(net "IRQ_BMC_LPC_SERIRQ_ESPI_GF")
	)
	(segment
		(start 62.8142 -112.961928)
		(end 62.671198 -112.818926)
		(width 0.10668)
		(layer "In4.Cu")
		(net "IRQ_BMC_LPC_SERIRQ_ESPI_GF")
	)
	(segment
		(start 66.7766 -74.792332)
		(end 67.54622 -74.022712)
		(width 0.10668)
		(layer "In4.Cu")
		(net "IRQ_BMC_LPC_SERIRQ_ESPI_GF")
	)
	(segment
		(start 65.13322 -102.59314)
		(end 65.13322 -89.859612)
		(width 0.10668)
		(layer "In4.Cu")
		(net "IRQ_BMC_LPC_SERIRQ_ESPI_GF")
	)
	(segment
		(start 67.4116 -84.60486)
		(end 67.4116 -83.844638)
		(width 0.10668)
		(layer "In4.Cu")
		(net "IRQ_BMC_LPC_SERIRQ_ESPI_GF")
	)
	(segment
		(start 66.7766 -76.45654)
		(end 66.7766 -74.792332)
		(width 0.10668)
		(layer "In4.Cu")
		(net "IRQ_BMC_LPC_SERIRQ_ESPI_GF")
	)
	(segment
		(start 65.5574 -68.986146)
		(end 64.2874 -67.716146)
		(width 0.10668)
		(layer "In4.Cu")
		(net "IRQ_BMC_LPC_SERIRQ_ESPI_GF")
	)
	(segment
		(start 65.5574 -69.8754)
		(end 65.5574 -68.986146)
		(width 0.10668)
		(layer "In4.Cu")
		(net "IRQ_BMC_LPC_SERIRQ_ESPI_GF")
	)
	(segment
		(start 66.976752 -70.32498)
		(end 66.00698 -70.32498)
		(width 0.10668)
		(layer "In4.Cu")
		(net "IRQ_BMC_LPC_SERIRQ_ESPI_GF")
	)
	(segment
		(start 62.8142 -112.0902)
		(end 65.46088 -109.44352)
		(width 0.10668)
		(layer "In4.Cu")
		(net "IRQ_BMC_LPC_SERIRQ_ESPI_GF")
	)
	(segment
		(start 67.4116 -83.844638)
		(end 68.17106 -83.085178)
		(width 0.10668)
		(layer "In4.Cu")
		(net "IRQ_BMC_LPC_SERIRQ_ESPI_GF")
	)
	(segment
		(start 66.70802 -85.30844)
		(end 67.4116 -84.60486)
		(width 0.10668)
		(layer "In4.Cu")
		(net "IRQ_BMC_LPC_SERIRQ_ESPI_GF")
	)
	(segment
		(start 62.671198 -112.286542)
		(end 62.8142 -112.14354)
		(width 0.10668)
		(layer "In4.Cu")
		(net "IRQ_BMC_LPC_SERIRQ_ESPI_GF")
	)
	(segment
		(start 67.54622 -74.022712)
		(end 67.54622 -70.894448)
		(width 0.10668)
		(layer "In4.Cu")
		(net "IRQ_BMC_LPC_SERIRQ_ESPI_GF")
	)
	(segment
		(start 62.8142 -113.7158)
		(end 62.8142 -112.961928)
		(width 0.10668)
		(layer "In4.Cu")
		(net "IRQ_BMC_LPC_SERIRQ_ESPI_GF")
	)
	(segment
		(start 67.54622 -70.894448)
		(end 66.976752 -70.32498)
		(width 0.10668)
		(layer "In4.Cu")
		(net "IRQ_BMC_LPC_SERIRQ_ESPI_GF")
	)
	(segment
		(start 66.70802 -88.284812)
		(end 66.70802 -85.30844)
		(width 0.10668)
		(layer "In4.Cu")
		(net "IRQ_BMC_LPC_SERIRQ_ESPI_GF")
	)
	(segment
		(start 64.2874 -67.716146)
		(end 64.2874 -65.4812)
		(width 0.10668)
		(layer "In4.Cu")
		(net "IRQ_BMC_LPC_SERIRQ_ESPI_GF")
	)
	(segment
		(start 68.17106 -77.851)
		(end 66.7766 -76.45654)
		(width 0.10668)
		(layer "In4.Cu")
		(net "IRQ_BMC_LPC_SERIRQ_ESPI_GF")
	)
	(segment
		(start 65.13322 -89.859612)
		(end 66.70802 -88.284812)
		(width 0.10668)
		(layer "In4.Cu")
		(net "IRQ_BMC_LPC_SERIRQ_ESPI_GF")
	)
	(segment
		(start 65.46088 -109.44352)
		(end 65.46088 -102.9208)
		(width 0.10668)
		(layer "In4.Cu")
		(net "IRQ_BMC_LPC_SERIRQ_ESPI_GF")
	)
	(segment
		(start 65.46088 -102.9208)
		(end 65.13322 -102.59314)
		(width 0.10668)
		(layer "In4.Cu")
		(net "IRQ_BMC_LPC_SERIRQ_ESPI_GF")
	)
	(segment
		(start 43.171618 -66.176144)
		(end 43.171618 -66.468498)
		(width 0.11684)
		(layer "F.Cu")
		(net "I3C2_SPD_SDA")
	)
	(segment
		(start 43.171618 -66.468498)
		(end 43.584368 -66.881248)
		(width 0.11684)
		(layer "F.Cu")
		(net "I3C2_SPD_SDA")
	)
	(via
		(at 43.584368 -66.881248)
		(size 0.508)
		(drill 0.254)
		(layers "F.Cu" "B.Cu")
		(net "I3C2_SPD_SDA")
	)
	(via
		(at 72.053196 -114.29365)
		(size 0.508)
		(drill 0.254)
		(layers "F.Cu" "B.Cu")
		(net "I3C2_SPD_SDA")
	)
	(via
		(at 70.8406 -107.0356)
		(size 0.508)
		(drill 0.254)
		(layers "F.Cu" "B.Cu")
		(net "I3C2_SPD_SDA")
	)
	(segment
		(start 43.584368 -66.881248)
		(end 43.163236 -66.460116)
		(width 0.11684)
		(layer "B.Cu")
		(net "I3C2_SPD_SDA")
	)
	(segment
		(start 72.053196 -114.29365)
		(end 71.595234 -114.751612)
		(width 0.11684)
		(layer "B.Cu")
		(net "I3C2_SPD_SDA")
	)
	(segment
		(start 71.460106 -117.30482)
		(end 71.460106 -118.460012)
		(width 0.11684)
		(layer "B.Cu")
		(net "I3C2_SPD_SDA")
	)
	(segment
		(start 71.595234 -114.751612)
		(end 71.595234 -116.97843)
		(width 0.11684)
		(layer "B.Cu")
		(net "I3C2_SPD_SDA")
	)
	(segment
		(start 43.163236 -66.460116)
		(end 43.163236 -66.143632)
		(width 0.11684)
		(layer "B.Cu")
		(net "I3C2_SPD_SDA")
	)
	(segment
		(start 71.595234 -116.97843)
		(end 71.460106 -117.30482)
		(width 0.11684)
		(layer "B.Cu")
		(net "I3C2_SPD_SDA")
	)
	(segment
		(start 44.197778 -67.93865)
		(end 45.078396 -67.93865)
		(width 0.10668)
		(layer "In7.Cu")
		(net "I3C2_SPD_SDA")
	)
	(segment
		(start 72.5424 -113.151666)
		(end 72.5424 -113.804446)
		(width 0.10668)
		(layer "In7.Cu")
		(net "I3C2_SPD_SDA")
	)
	(segment
		(start 60.833 -82.761074)
		(end 60.833 -84.027518)
		(width 0.10668)
		(layer "In7.Cu")
		(net "I3C2_SPD_SDA")
	)
	(segment
		(start 56.195722 -76.20127)
		(end 56.44007 -76.20127)
		(width 0.10668)
		(layer "In7.Cu")
		(net "I3C2_SPD_SDA")
	)
	(segment
		(start 52.637436 -72.398636)
		(end 52.637436 -72.642984)
		(width 0.10668)
		(layer "In7.Cu")
		(net "I3C2_SPD_SDA")
	)
	(segment
		(start 55.778908 -75.540108)
		(end 55.778908 -75.784456)
		(width 0.10668)
		(layer "In7.Cu")
		(net "I3C2_SPD_SDA")
	)
	(segment
		(start 71.74992 -112.359186)
		(end 72.5424 -113.151666)
		(width 0.10668)
		(layer "In7.Cu")
		(net "I3C2_SPD_SDA")
	)
	(segment
		(start 59.318398 -81.246472)
		(end 60.833 -82.761074)
		(width 0.10668)
		(layer "In7.Cu")
		(net "I3C2_SPD_SDA")
	)
	(segment
		(start 55.553356 -76.254356)
		(end 55.725822 -76.426822)
		(width 0.10668)
		(layer "In7.Cu")
		(net "I3C2_SPD_SDA")
	)
	(segment
		(start 52.451 -72.2122)
		(end 52.637436 -72.398636)
		(width 0.10668)
		(layer "In7.Cu")
		(net "I3C2_SPD_SDA")
	)
	(segment
		(start 55.362094 -75.367642)
		(end 55.606442 -75.367642)
		(width 0.10668)
		(layer "In7.Cu")
		(net "I3C2_SPD_SDA")
	)
	(segment
		(start 55.553356 -76.010008)
		(end 55.553356 -76.254356)
		(width 0.10668)
		(layer "In7.Cu")
		(net "I3C2_SPD_SDA")
	)
	(segment
		(start 51.3715 -72.04202)
		(end 51.49342 -72.04202)
		(width 0.10668)
		(layer "In7.Cu")
		(net "I3C2_SPD_SDA")
	)
	(segment
		(start 71.1962 -107.0356)
		(end 71.74992 -107.58932)
		(width 0.10668)
		(layer "In7.Cu")
		(net "I3C2_SPD_SDA")
	)
	(segment
		(start 50.45202 -71.12254)
		(end 51.3715 -72.04202)
		(width 0.10668)
		(layer "In7.Cu")
		(net "I3C2_SPD_SDA")
	)
	(segment
		(start 53.471064 -73.476612)
		(end 53.258212 -73.689464)
		(width 0.10668)
		(layer "In7.Cu")
		(net "I3C2_SPD_SDA")
	)
	(segment
		(start 55.606442 -75.367642)
		(end 55.778908 -75.540108)
		(width 0.10668)
		(layer "In7.Cu")
		(net "I3C2_SPD_SDA")
	)
	(segment
		(start 53.887878 -73.893426)
		(end 54.132226 -73.893426)
		(width 0.10668)
		(layer "In7.Cu")
		(net "I3C2_SPD_SDA")
	)
	(segment
		(start 53.258212 -73.933812)
		(end 53.430678 -74.106278)
		(width 0.10668)
		(layer "In7.Cu")
		(net "I3C2_SPD_SDA")
	)
	(segment
		(start 45.078396 -67.93865)
		(end 45.417486 -68.27774)
		(width 0.10668)
		(layer "In7.Cu")
		(net "I3C2_SPD_SDA")
	)
	(segment
		(start 51.49342 -72.04202)
		(end 51.6636 -72.2122)
		(width 0.10668)
		(layer "In7.Cu")
		(net "I3C2_SPD_SDA")
	)
	(segment
		(start 53.430678 -74.106278)
		(end 53.675026 -74.106278)
		(width 0.10668)
		(layer "In7.Cu")
		(net "I3C2_SPD_SDA")
	)
	(segment
		(start 62.025276 -85.367622)
		(end 62.025276 -85.870542)
		(width 0.10668)
		(layer "In7.Cu")
		(net "I3C2_SPD_SDA")
	)
	(segment
		(start 68.50126 -102.257606)
		(end 68.50126 -103.039926)
		(width 0.10668)
		(layer "In7.Cu")
		(net "I3C2_SPD_SDA")
	)
	(segment
		(start 66.31432 -100.070666)
		(end 68.50126 -102.257606)
		(width 0.10668)
		(layer "In7.Cu")
		(net "I3C2_SPD_SDA")
	)
	(segment
		(start 68.50126 -103.039926)
		(end 69.1388 -103.677466)
		(width 0.10668)
		(layer "In7.Cu")
		(net "I3C2_SPD_SDA")
	)
	(segment
		(start 72.5424 -113.804446)
		(end 72.053196 -114.29365)
		(width 0.10668)
		(layer "In7.Cu")
		(net "I3C2_SPD_SDA")
	)
	(segment
		(start 53.471064 -73.232264)
		(end 53.471064 -73.476612)
		(width 0.10668)
		(layer "In7.Cu")
		(net "I3C2_SPD_SDA")
	)
	(segment
		(start 47.4726 -69.2658)
		(end 49.32934 -71.12254)
		(width 0.10668)
		(layer "In7.Cu")
		(net "I3C2_SPD_SDA")
	)
	(segment
		(start 54.94528 -74.950828)
		(end 54.719728 -75.17638)
		(width 0.10668)
		(layer "In7.Cu")
		(net "I3C2_SPD_SDA")
	)
	(segment
		(start 52.841398 -73.27265)
		(end 53.05425 -73.059798)
		(width 0.10668)
		(layer "In7.Cu")
		(net "I3C2_SPD_SDA")
	)
	(segment
		(start 45.417486 -68.27774)
		(end 47.19574 -68.27774)
		(width 0.10668)
		(layer "In7.Cu")
		(net "I3C2_SPD_SDA")
	)
	(segment
		(start 66.31432 -94.359984)
		(end 66.31432 -100.070666)
		(width 0.10668)
		(layer "In7.Cu")
		(net "I3C2_SPD_SDA")
	)
	(segment
		(start 54.892194 -75.593194)
		(end 55.136542 -75.593194)
		(width 0.10668)
		(layer "In7.Cu")
		(net "I3C2_SPD_SDA")
	)
	(segment
		(start 62.025276 -85.870542)
		(end 62.197996 -86.043262)
		(width 0.10668)
		(layer "In7.Cu")
		(net "I3C2_SPD_SDA")
	)
	(segment
		(start 58.749184 -81.246472)
		(end 59.318398 -81.246472)
		(width 0.10668)
		(layer "In7.Cu")
		(net "I3C2_SPD_SDA")
	)
	(segment
		(start 52.424584 -73.100184)
		(end 52.59705 -73.27265)
		(width 0.10668)
		(layer "In7.Cu")
		(net "I3C2_SPD_SDA")
	)
	(segment
		(start 53.298598 -73.059798)
		(end 53.471064 -73.232264)
		(width 0.10668)
		(layer "In7.Cu")
		(net "I3C2_SPD_SDA")
	)
	(segment
		(start 54.132226 -73.893426)
		(end 54.94528 -74.70648)
		(width 0.10668)
		(layer "In7.Cu")
		(net "I3C2_SPD_SDA")
	)
	(segment
		(start 49.32934 -71.12254)
		(end 50.45202 -71.12254)
		(width 0.10668)
		(layer "In7.Cu")
		(net "I3C2_SPD_SDA")
	)
	(segment
		(start 51.6636 -72.2122)
		(end 52.451 -72.2122)
		(width 0.10668)
		(layer "In7.Cu")
		(net "I3C2_SPD_SDA")
	)
	(segment
		(start 52.59705 -73.27265)
		(end 52.841398 -73.27265)
		(width 0.10668)
		(layer "In7.Cu")
		(net "I3C2_SPD_SDA")
	)
	(segment
		(start 60.937394 -84.27974)
		(end 62.025276 -85.367622)
		(width 0.10668)
		(layer "In7.Cu")
		(net "I3C2_SPD_SDA")
	)
	(segment
		(start 55.725822 -76.426822)
		(end 55.97017 -76.426822)
		(width 0.10668)
		(layer "In7.Cu")
		(net "I3C2_SPD_SDA")
	)
	(segment
		(start 71.74992 -107.58932)
		(end 71.74992 -112.359186)
		(width 0.10668)
		(layer "In7.Cu")
		(net "I3C2_SPD_SDA")
	)
	(segment
		(start 70.8406 -106.456734)
		(end 70.8406 -107.0356)
		(width 0.10668)
		(layer "In7.Cu")
		(net "I3C2_SPD_SDA")
	)
	(segment
		(start 62.197996 -90.24366)
		(end 66.31432 -94.359984)
		(width 0.10668)
		(layer "In7.Cu")
		(net "I3C2_SPD_SDA")
	)
	(segment
		(start 52.637436 -72.642984)
		(end 52.424584 -72.855836)
		(width 0.10668)
		(layer "In7.Cu")
		(net "I3C2_SPD_SDA")
	)
	(segment
		(start 60.833 -84.027518)
		(end 60.937394 -84.27974)
		(width 0.10668)
		(layer "In7.Cu")
		(net "I3C2_SPD_SDA")
	)
	(segment
		(start 55.778908 -75.784456)
		(end 55.553356 -76.010008)
		(width 0.10668)
		(layer "In7.Cu")
		(net "I3C2_SPD_SDA")
	)
	(segment
		(start 70.8406 -107.0356)
		(end 71.1962 -107.0356)
		(width 0.10668)
		(layer "In7.Cu")
		(net "I3C2_SPD_SDA")
	)
	(segment
		(start 56.44007 -76.20127)
		(end 56.89092 -76.65212)
		(width 0.10668)
		(layer "In7.Cu")
		(net "I3C2_SPD_SDA")
	)
	(segment
		(start 56.89092 -76.65212)
		(end 56.89092 -79.388208)
		(width 0.10668)
		(layer "In7.Cu")
		(net "I3C2_SPD_SDA")
	)
	(segment
		(start 55.136542 -75.593194)
		(end 55.362094 -75.367642)
		(width 0.10668)
		(layer "In7.Cu")
		(net "I3C2_SPD_SDA")
	)
	(segment
		(start 69.1388 -104.754934)
		(end 70.8406 -106.456734)
		(width 0.10668)
		(layer "In7.Cu")
		(net "I3C2_SPD_SDA")
	)
	(segment
		(start 43.584368 -66.881248)
		(end 43.584368 -67.32524)
		(width 0.10668)
		(layer "In7.Cu")
		(net "I3C2_SPD_SDA")
	)
	(segment
		(start 54.719728 -75.420728)
		(end 54.892194 -75.593194)
		(width 0.10668)
		(layer "In7.Cu")
		(net "I3C2_SPD_SDA")
	)
	(segment
		(start 47.19574 -68.27774)
		(end 47.4726 -68.5546)
		(width 0.10668)
		(layer "In7.Cu")
		(net "I3C2_SPD_SDA")
	)
	(segment
		(start 54.719728 -75.17638)
		(end 54.719728 -75.420728)
		(width 0.10668)
		(layer "In7.Cu")
		(net "I3C2_SPD_SDA")
	)
	(segment
		(start 53.05425 -73.059798)
		(end 53.298598 -73.059798)
		(width 0.10668)
		(layer "In7.Cu")
		(net "I3C2_SPD_SDA")
	)
	(segment
		(start 62.197996 -86.043262)
		(end 62.197996 -90.24366)
		(width 0.10668)
		(layer "In7.Cu")
		(net "I3C2_SPD_SDA")
	)
	(segment
		(start 55.97017 -76.426822)
		(end 56.195722 -76.20127)
		(width 0.10668)
		(layer "In7.Cu")
		(net "I3C2_SPD_SDA")
	)
	(segment
		(start 69.1388 -103.677466)
		(end 69.1388 -104.754934)
		(width 0.10668)
		(layer "In7.Cu")
		(net "I3C2_SPD_SDA")
	)
	(segment
		(start 53.258212 -73.689464)
		(end 53.258212 -73.933812)
		(width 0.10668)
		(layer "In7.Cu")
		(net "I3C2_SPD_SDA")
	)
	(segment
		(start 56.89092 -79.388208)
		(end 58.749184 -81.246472)
		(width 0.10668)
		(layer "In7.Cu")
		(net "I3C2_SPD_SDA")
	)
	(segment
		(start 47.4726 -68.5546)
		(end 47.4726 -69.2658)
		(width 0.10668)
		(layer "In7.Cu")
		(net "I3C2_SPD_SDA")
	)
	(segment
		(start 53.675026 -74.106278)
		(end 53.887878 -73.893426)
		(width 0.10668)
		(layer "In7.Cu")
		(net "I3C2_SPD_SDA")
	)
	(segment
		(start 54.94528 -74.70648)
		(end 54.94528 -74.950828)
		(width 0.10668)
		(layer "In7.Cu")
		(net "I3C2_SPD_SDA")
	)
	(segment
		(start 52.424584 -72.855836)
		(end 52.424584 -73.100184)
		(width 0.10668)
		(layer "In7.Cu")
		(net "I3C2_SPD_SDA")
	)
	(segment
		(start 43.584368 -67.32524)
		(end 44.197778 -67.93865)
		(width 0.10668)
		(layer "In7.Cu")
		(net "I3C2_SPD_SDA")
	)
	(segment
		(start 44.295568 -66.277744)
		(end 44.295568 -66.828416)
		(width 0.11684)
		(layer "F.Cu")
		(net "I3C2_SPD_SCL")
	)
	(segment
		(start 44.295568 -66.828416)
		(end 44.270168 -66.853816)
		(width 0.11684)
		(layer "F.Cu")
		(net "I3C2_SPD_SCL")
	)
	(segment
		(start 44.193968 -66.176144)
		(end 44.295568 -66.277744)
		(width 0.11684)
		(layer "F.Cu")
		(net "I3C2_SPD_SCL")
	)
	(segment
		(start 44.270168 -66.853816)
		(end 44.270168 -66.8782)
		(width 0.11684)
		(layer "F.Cu")
		(net "I3C2_SPD_SCL")
	)
	(via
		(at 44.270168 -66.8782)
		(size 0.508)
		(drill 0.254)
		(layers "F.Cu" "B.Cu")
		(net "I3C2_SPD_SCL")
	)
	(via
		(at 72.06361 -115.003326)
		(size 0.508)
		(drill 0.254)
		(layers "F.Cu" "B.Cu")
		(net "I3C2_SPD_SCL")
	)
	(via
		(at 69.64426 -103.8606)
		(size 0.508)
		(drill 0.254)
		(layers "F.Cu" "B.Cu")
		(net "I3C2_SPD_SCL")
	)
	(segment
		(start 44.270168 -66.853816)
		(end 44.295568 -66.828416)
		(width 0.11684)
		(layer "B.Cu")
		(net "I3C2_SPD_SCL")
	)
	(segment
		(start 44.295568 -66.828416)
		(end 44.295568 -66.244724)
		(width 0.11684)
		(layer "B.Cu")
		(net "I3C2_SPD_SCL")
	)
	(segment
		(start 72.540622 -116.883434)
		(end 72.060054 -117.364002)
		(width 0.11684)
		(layer "B.Cu")
		(net "I3C2_SPD_SCL")
	)
	(segment
		(start 72.06361 -115.003326)
		(end 72.540622 -115.480338)
		(width 0.11684)
		(layer "B.Cu")
		(net "I3C2_SPD_SCL")
	)
	(segment
		(start 72.540622 -115.480338)
		(end 72.540622 -116.883434)
		(width 0.11684)
		(layer "B.Cu")
		(net "I3C2_SPD_SCL")
	)
	(segment
		(start 72.060054 -117.364002)
		(end 72.060054 -118.460012)
		(width 0.11684)
		(layer "B.Cu")
		(net "I3C2_SPD_SCL")
	)
	(segment
		(start 44.295568 -66.244724)
		(end 44.193968 -66.143124)
		(width 0.11684)
		(layer "B.Cu")
		(net "I3C2_SPD_SCL")
	)
	(segment
		(start 44.270168 -66.8782)
		(end 44.270168 -66.853816)
		(width 0.11684)
		(layer "B.Cu")
		(net "I3C2_SPD_SCL")
	)
	(segment
		(start 44.270168 -66.8782)
		(end 44.270168 -66.90868)
		(width 0.10668)
		(layer "In7.Cu")
		(net "I3C2_SPD_SCL")
	)
	(segment
		(start 72.009 -106.07802)
		(end 72.009 -105.41)
		(width 0.10668)
		(layer "In7.Cu")
		(net "I3C2_SPD_SCL")
	)
	(segment
		(start 61.589666 -82.76336)
		(end 61.983366 -83.713574)
		(width 0.10668)
		(layer "In7.Cu")
		(net "I3C2_SPD_SCL")
	)
	(segment
		(start 72.550782 -115.003326)
		(end 72.9996 -114.554508)
		(width 0.10668)
		(layer "In7.Cu")
		(net "I3C2_SPD_SCL")
	)
	(segment
		(start 72.009 -105.41)
		(end 71.85406 -105.25506)
		(width 0.10668)
		(layer "In7.Cu")
		(net "I3C2_SPD_SCL")
	)
	(segment
		(start 68.12026 -101.10724)
		(end 69.03466 -102.02164)
		(width 0.10668)
		(layer "In7.Cu")
		(net "I3C2_SPD_SCL")
	)
	(segment
		(start 62.385956 -84.116164)
		(end 62.385956 -85.720936)
		(width 0.10668)
		(layer "In7.Cu")
		(net "I3C2_SPD_SCL")
	)
	(segment
		(start 72.06361 -115.003326)
		(end 72.550782 -115.003326)
		(width 0.10668)
		(layer "In7.Cu")
		(net "I3C2_SPD_SCL")
	)
	(segment
		(start 68.12026 -99.592384)
		(end 68.12026 -101.10724)
		(width 0.10668)
		(layer "In7.Cu")
		(net "I3C2_SPD_SCL")
	)
	(segment
		(start 54.0512 -72.729598)
		(end 54.0512 -73.273158)
		(width 0.10668)
		(layer "In7.Cu")
		(net "I3C2_SPD_SCL")
	)
	(segment
		(start 44.766738 -67.40525)
		(end 45.30725 -67.40525)
		(width 0.10668)
		(layer "In7.Cu")
		(net "I3C2_SPD_SCL")
	)
	(segment
		(start 47.50054 -67.74434)
		(end 48.006 -68.2498)
		(width 0.10668)
		(layer "In7.Cu")
		(net "I3C2_SPD_SCL")
	)
	(segment
		(start 44.270168 -66.90868)
		(end 44.766738 -67.40525)
		(width 0.10668)
		(layer "In7.Cu")
		(net "I3C2_SPD_SCL")
	)
	(segment
		(start 48.594518 -69.877178)
		(end 50.25009 -69.877178)
		(width 0.10668)
		(layer "In7.Cu")
		(net "I3C2_SPD_SCL")
	)
	(segment
		(start 66.675 -94.210378)
		(end 66.675 -98.147124)
		(width 0.10668)
		(layer "In7.Cu")
		(net "I3C2_SPD_SCL")
	)
	(segment
		(start 58.89879 -80.885792)
		(end 59.712098 -80.885792)
		(width 0.10668)
		(layer "In7.Cu")
		(net "I3C2_SPD_SCL")
	)
	(segment
		(start 72.28332 -112.1283)
		(end 72.28332 -106.35234)
		(width 0.10668)
		(layer "In7.Cu")
		(net "I3C2_SPD_SCL")
	)
	(segment
		(start 51.495452 -71.12254)
		(end 52.444142 -71.12254)
		(width 0.10668)
		(layer "In7.Cu")
		(net "I3C2_SPD_SCL")
	)
	(segment
		(start 66.675 -98.147124)
		(end 68.12026 -99.592384)
		(width 0.10668)
		(layer "In7.Cu")
		(net "I3C2_SPD_SCL")
	)
	(segment
		(start 48.006 -69.28866)
		(end 48.594518 -69.877178)
		(width 0.10668)
		(layer "In7.Cu")
		(net "I3C2_SPD_SCL")
	)
	(segment
		(start 45.30725 -67.40525)
		(end 45.64634 -67.74434)
		(width 0.10668)
		(layer "In7.Cu")
		(net "I3C2_SPD_SCL")
	)
	(segment
		(start 69.64426 -104.750108)
		(end 69.64426 -103.8606)
		(width 0.10668)
		(layer "In7.Cu")
		(net "I3C2_SPD_SCL")
	)
	(segment
		(start 61.983366 -83.713574)
		(end 62.385956 -84.116164)
		(width 0.10668)
		(layer "In7.Cu")
		(net "I3C2_SPD_SCL")
	)
	(segment
		(start 62.385956 -85.720936)
		(end 62.558676 -85.893656)
		(width 0.10668)
		(layer "In7.Cu")
		(net "I3C2_SPD_SCL")
	)
	(segment
		(start 69.64426 -103.66248)
		(end 69.64426 -103.8606)
		(width 0.10668)
		(layer "In7.Cu")
		(net "I3C2_SPD_SCL")
	)
	(segment
		(start 71.85406 -105.25506)
		(end 70.149212 -105.25506)
		(width 0.10668)
		(layer "In7.Cu")
		(net "I3C2_SPD_SCL")
	)
	(segment
		(start 54.0512 -73.273158)
		(end 57.2516 -76.473558)
		(width 0.10668)
		(layer "In7.Cu")
		(net "I3C2_SPD_SCL")
	)
	(segment
		(start 72.9996 -114.554508)
		(end 72.9996 -112.84458)
		(width 0.10668)
		(layer "In7.Cu")
		(net "I3C2_SPD_SCL")
	)
	(segment
		(start 57.2516 -79.238602)
		(end 58.89879 -80.885792)
		(width 0.10668)
		(layer "In7.Cu")
		(net "I3C2_SPD_SCL")
	)
	(segment
		(start 50.25009 -69.877178)
		(end 51.495452 -71.12254)
		(width 0.10668)
		(layer "In7.Cu")
		(net "I3C2_SPD_SCL")
	)
	(segment
		(start 72.28332 -106.35234)
		(end 72.009 -106.07802)
		(width 0.10668)
		(layer "In7.Cu")
		(net "I3C2_SPD_SCL")
	)
	(segment
		(start 69.03466 -102.02164)
		(end 69.03466 -103.05288)
		(width 0.10668)
		(layer "In7.Cu")
		(net "I3C2_SPD_SCL")
	)
	(segment
		(start 70.149212 -105.25506)
		(end 69.64426 -104.750108)
		(width 0.10668)
		(layer "In7.Cu")
		(net "I3C2_SPD_SCL")
	)
	(segment
		(start 69.03466 -103.05288)
		(end 69.64426 -103.66248)
		(width 0.10668)
		(layer "In7.Cu")
		(net "I3C2_SPD_SCL")
	)
	(segment
		(start 48.006 -68.2498)
		(end 48.006 -69.28866)
		(width 0.10668)
		(layer "In7.Cu")
		(net "I3C2_SPD_SCL")
	)
	(segment
		(start 62.558676 -85.893656)
		(end 62.558676 -90.094054)
		(width 0.10668)
		(layer "In7.Cu")
		(net "I3C2_SPD_SCL")
	)
	(segment
		(start 72.9996 -112.84458)
		(end 72.28332 -112.1283)
		(width 0.10668)
		(layer "In7.Cu")
		(net "I3C2_SPD_SCL")
	)
	(segment
		(start 52.444142 -71.12254)
		(end 54.0512 -72.729598)
		(width 0.10668)
		(layer "In7.Cu")
		(net "I3C2_SPD_SCL")
	)
	(segment
		(start 62.558676 -90.094054)
		(end 66.675 -94.210378)
		(width 0.10668)
		(layer "In7.Cu")
		(net "I3C2_SPD_SCL")
	)
	(segment
		(start 45.64634 -67.74434)
		(end 47.50054 -67.74434)
		(width 0.10668)
		(layer "In7.Cu")
		(net "I3C2_SPD_SCL")
	)
	(segment
		(start 59.712098 -80.885792)
		(end 61.589666 -82.76336)
		(width 0.10668)
		(layer "In7.Cu")
		(net "I3C2_SPD_SCL")
	)
	(segment
		(start 57.2516 -76.473558)
		(end 57.2516 -79.238602)
		(width 0.10668)
		(layer "In7.Cu")
		(net "I3C2_SPD_SCL")
	)
	(segment
		(start 40.887142 -64.156844)
		(end 40.887142 -64.766444)
		(width 0.11684)
		(layer "F.Cu")
		(net "I3C1_SPD_SDA")
	)
	(via
		(at 40.887142 -64.766444)
		(size 0.508)
		(drill 0.254)
		(layers "F.Cu" "B.Cu")
		(net "I3C1_SPD_SDA")
	)
	(via
		(at 70.264528 -111.633508)
		(size 0.508)
		(drill 0.254)
		(layers "F.Cu" "B.Cu")
		(net "I3C1_SPD_SDA")
	)
	(via
		(at 68.5038 -104.490266)
		(size 0.508)
		(drill 0.254)
		(layers "F.Cu" "B.Cu")
		(net "I3C1_SPD_SDA")
	)
	(segment
		(start 72.935084 -117.092984)
		(end 72.660002 -117.368066)
		(width 0.11684)
		(layer "B.Cu")
		(net "I3C1_SPD_SDA")
	)
	(segment
		(start 70.264528 -111.633508)
		(end 70.757796 -111.633508)
		(width 0.11684)
		(layer "B.Cu")
		(net "I3C1_SPD_SDA")
	)
	(segment
		(start 72.660002 -117.368066)
		(end 72.660002 -118.460012)
		(width 0.11684)
		(layer "B.Cu")
		(net "I3C1_SPD_SDA")
	)
	(segment
		(start 70.757796 -111.633508)
		(end 72.935084 -113.810796)
		(width 0.11684)
		(layer "B.Cu")
		(net "I3C1_SPD_SDA")
	)
	(segment
		(start 72.935084 -113.810796)
		(end 72.935084 -117.092984)
		(width 0.11684)
		(layer "B.Cu")
		(net "I3C1_SPD_SDA")
	)
	(segment
		(start 40.887142 -64.156844)
		(end 40.887142 -64.766444)
		(width 0.11684)
		(layer "B.Cu")
		(net "I3C1_SPD_SDA")
	)
	(segment
		(start 59.2074 -81.6864)
		(end 60.47232 -82.95132)
		(width 0.10668)
		(layer "In7.Cu")
		(net "I3C1_SPD_SDA")
	)
	(segment
		(start 58.678064 -81.6864)
		(end 59.2074 -81.6864)
		(width 0.10668)
		(layer "In7.Cu")
		(net "I3C1_SPD_SDA")
	)
	(segment
		(start 61.664596 -85.517228)
		(end 61.664596 -86.020148)
		(width 0.10668)
		(layer "In7.Cu")
		(net "I3C1_SPD_SDA")
	)
	(segment
		(start 56.53024 -77.743812)
		(end 56.53024 -79.538576)
		(width 0.10668)
		(layer "In7.Cu")
		(net "I3C1_SPD_SDA")
	)
	(segment
		(start 40.887142 -64.766444)
		(end 42.9768 -66.856102)
		(width 0.10668)
		(layer "In7.Cu")
		(net "I3C1_SPD_SDA")
	)
	(segment
		(start 56.53024 -79.538576)
		(end 58.678064 -81.6864)
		(width 0.10668)
		(layer "In7.Cu")
		(net "I3C1_SPD_SDA")
	)
	(segment
		(start 71.21652 -110.681516)
		(end 70.264528 -111.633508)
		(width 0.10668)
		(layer "In7.Cu")
		(net "I3C1_SPD_SDA")
	)
	(segment
		(start 70.34784 -107.21594)
		(end 71.21652 -108.08462)
		(width 0.10668)
		(layer "In7.Cu")
		(net "I3C1_SPD_SDA")
	)
	(segment
		(start 68.5038 -104.63022)
		(end 70.34784 -106.47426)
		(width 0.10668)
		(layer "In7.Cu")
		(net "I3C1_SPD_SDA")
	)
	(segment
		(start 60.63107 -84.483702)
		(end 61.664596 -85.517228)
		(width 0.10668)
		(layer "In7.Cu")
		(net "I3C1_SPD_SDA")
	)
	(segment
		(start 42.9768 -66.856102)
		(end 42.9768 -67.4116)
		(width 0.10668)
		(layer "In7.Cu")
		(net "I3C1_SPD_SDA")
	)
	(segment
		(start 70.34784 -106.47426)
		(end 70.34784 -107.21594)
		(width 0.10668)
		(layer "In7.Cu")
		(net "I3C1_SPD_SDA")
	)
	(segment
		(start 49.54905 -71.972424)
		(end 49.717198 -72.04202)
		(width 0.10668)
		(layer "In7.Cu")
		(net "I3C1_SPD_SDA")
	)
	(segment
		(start 68.14058 -102.407212)
		(end 68.14058 -103.189532)
		(width 0.10668)
		(layer "In7.Cu")
		(net "I3C1_SPD_SDA")
	)
	(segment
		(start 68.5038 -103.552752)
		(end 68.5038 -104.490266)
		(width 0.10668)
		(layer "In7.Cu")
		(net "I3C1_SPD_SDA")
	)
	(segment
		(start 68.5038 -104.490266)
		(end 68.5038 -104.63022)
		(width 0.10668)
		(layer "In7.Cu")
		(net "I3C1_SPD_SDA")
	)
	(segment
		(start 49.717198 -72.04202)
		(end 50.453798 -72.04202)
		(width 0.10668)
		(layer "In7.Cu")
		(net "I3C1_SPD_SDA")
	)
	(segment
		(start 52.48148 -73.695052)
		(end 56.53024 -77.743812)
		(width 0.10668)
		(layer "In7.Cu")
		(net "I3C1_SPD_SDA")
	)
	(segment
		(start 61.664596 -86.020148)
		(end 61.837316 -86.192868)
		(width 0.10668)
		(layer "In7.Cu")
		(net "I3C1_SPD_SDA")
	)
	(segment
		(start 71.21652 -108.08462)
		(end 71.21652 -110.681516)
		(width 0.10668)
		(layer "In7.Cu")
		(net "I3C1_SPD_SDA")
	)
	(segment
		(start 60.47232 -84.0994)
		(end 60.63107 -84.483702)
		(width 0.10668)
		(layer "In7.Cu")
		(net "I3C1_SPD_SDA")
	)
	(segment
		(start 68.14058 -103.189532)
		(end 68.5038 -103.552752)
		(width 0.10668)
		(layer "In7.Cu")
		(net "I3C1_SPD_SDA")
	)
	(segment
		(start 50.453798 -72.04202)
		(end 52.10683 -73.695052)
		(width 0.10668)
		(layer "In7.Cu")
		(net "I3C1_SPD_SDA")
	)
	(segment
		(start 65.95364 -94.617286)
		(end 65.95364 -100.220272)
		(width 0.10668)
		(layer "In7.Cu")
		(net "I3C1_SPD_SDA")
	)
	(segment
		(start 65.95364 -100.220272)
		(end 68.14058 -102.407212)
		(width 0.10668)
		(layer "In7.Cu")
		(net "I3C1_SPD_SDA")
	)
	(segment
		(start 61.837316 -90.500962)
		(end 65.95364 -94.617286)
		(width 0.10668)
		(layer "In7.Cu")
		(net "I3C1_SPD_SDA")
	)
	(segment
		(start 48.279812 -70.703186)
		(end 49.54905 -71.972424)
		(width 0.10668)
		(layer "In7.Cu")
		(net "I3C1_SPD_SDA")
	)
	(segment
		(start 52.10683 -73.695052)
		(end 52.48148 -73.695052)
		(width 0.10668)
		(layer "In7.Cu")
		(net "I3C1_SPD_SDA")
	)
	(segment
		(start 45.621448 -69.1642)
		(end 46.36897 -69.911722)
		(width 0.10668)
		(layer "In7.Cu")
		(net "I3C1_SPD_SDA")
	)
	(segment
		(start 44.7294 -69.1642)
		(end 45.621448 -69.1642)
		(width 0.10668)
		(layer "In7.Cu")
		(net "I3C1_SPD_SDA")
	)
	(segment
		(start 46.36897 -69.911722)
		(end 48.279812 -70.703186)
		(width 0.10668)
		(layer "In7.Cu")
		(net "I3C1_SPD_SDA")
	)
	(segment
		(start 60.47232 -82.95132)
		(end 60.47232 -84.0994)
		(width 0.10668)
		(layer "In7.Cu")
		(net "I3C1_SPD_SDA")
	)
	(segment
		(start 42.9768 -67.4116)
		(end 44.7294 -69.1642)
		(width 0.10668)
		(layer "In7.Cu")
		(net "I3C1_SPD_SDA")
	)
	(segment
		(start 61.837316 -86.192868)
		(end 61.837316 -90.500962)
		(width 0.10668)
		(layer "In7.Cu")
		(net "I3C1_SPD_SDA")
	)
	(segment
		(start 41.859454 -66.877946)
		(end 41.8592 -66.8782)
		(width 0.11684)
		(layer "F.Cu")
		(net "I3C1_SPD_SCL")
	)
	(segment
		(start 41.859454 -66.176144)
		(end 41.859454 -66.877946)
		(width 0.11684)
		(layer "F.Cu")
		(net "I3C1_SPD_SCL")
	)
	(via
		(at 69.341746 -109.347)
		(size 0.508)
		(drill 0.254)
		(layers "F.Cu" "B.Cu")
		(net "I3C1_SPD_SCL")
	)
	(via
		(at 41.8592 -66.8782)
		(size 0.508)
		(drill 0.254)
		(layers "F.Cu" "B.Cu")
		(net "I3C1_SPD_SCL")
	)
	(segment
		(start 69.341746 -110.3376)
		(end 69.723 -110.718854)
		(width 0.11684)
		(layer "B.Cu")
		(net "I3C1_SPD_SCL")
	)
	(segment
		(start 73.34631 -113.351564)
		(end 73.34631 -117.265196)
		(width 0.11684)
		(layer "B.Cu")
		(net "I3C1_SPD_SCL")
	)
	(segment
		(start 73.34631 -117.265196)
		(end 73.25995 -117.351556)
		(width 0.11684)
		(layer "B.Cu")
		(net "I3C1_SPD_SCL")
	)
	(segment
		(start 69.341746 -109.347)
		(end 69.341746 -110.3376)
		(width 0.11684)
		(layer "B.Cu")
		(net "I3C1_SPD_SCL")
	)
	(segment
		(start 69.723 -110.718854)
		(end 70.7136 -110.718854)
		(width 0.11684)
		(layer "B.Cu")
		(net "I3C1_SPD_SCL")
	)
	(segment
		(start 73.25995 -117.351556)
		(end 73.25995 -118.460012)
		(width 0.11684)
		(layer "B.Cu")
		(net "I3C1_SPD_SCL")
	)
	(segment
		(start 41.8846 -66.8528)
		(end 41.8846 -66.20129)
		(width 0.11684)
		(layer "B.Cu")
		(net "I3C1_SPD_SCL")
	)
	(segment
		(start 41.8592 -66.8782)
		(end 41.8846 -66.8528)
		(width 0.11684)
		(layer "B.Cu")
		(net "I3C1_SPD_SCL")
	)
	(segment
		(start 41.8846 -66.20129)
		(end 41.859454 -66.176144)
		(width 0.11684)
		(layer "B.Cu")
		(net "I3C1_SPD_SCL")
	)
	(segment
		(start 70.7136 -110.718854)
		(end 73.34631 -113.351564)
		(width 0.11684)
		(layer "B.Cu")
		(net "I3C1_SPD_SCL")
	)
	(segment
		(start 48.060864 -71.74611)
		(end 49.644808 -72.4027)
		(width 0.10668)
		(layer "In7.Cu")
		(net "I3C1_SPD_SCL")
	)
	(segment
		(start 59.140598 -82.22742)
		(end 60.11164 -83.198462)
		(width 0.10668)
		(layer "In7.Cu")
		(net "I3C1_SPD_SCL")
	)
	(segment
		(start 61.303916 -86.169754)
		(end 61.476636 -86.342474)
		(width 0.10668)
		(layer "In7.Cu")
		(net "I3C1_SPD_SCL")
	)
	(segment
		(start 49.644808 -72.4027)
		(end 50.29835 -72.4027)
		(width 0.10668)
		(layer "In7.Cu")
		(net "I3C1_SPD_SCL")
	)
	(segment
		(start 47.604172 -71.47687)
		(end 47.841408 -71.714106)
		(width 0.10668)
		(layer "In7.Cu")
		(net "I3C1_SPD_SCL")
	)
	(segment
		(start 52.331874 -74.055732)
		(end 56.16956 -77.893418)
		(width 0.10668)
		(layer "In7.Cu")
		(net "I3C1_SPD_SCL")
	)
	(segment
		(start 47.918878 -71.74611)
		(end 48.060864 -71.74611)
		(width 0.10668)
		(layer "In7.Cu")
		(net "I3C1_SPD_SCL")
	)
	(segment
		(start 56.16956 -77.893418)
		(end 56.16956 -79.688182)
		(width 0.10668)
		(layer "In7.Cu")
		(net "I3C1_SPD_SCL")
	)
	(segment
		(start 70.153784 -109.220762)
		(end 69.467984 -109.220762)
		(width 0.10668)
		(layer "In7.Cu")
		(net "I3C1_SPD_SCL")
	)
	(segment
		(start 70.612 -108.762546)
		(end 70.153784 -109.220762)
		(width 0.10668)
		(layer "In7.Cu")
		(net "I3C1_SPD_SCL")
	)
	(segment
		(start 61.476636 -90.650568)
		(end 65.59296 -94.766892)
		(width 0.10668)
		(layer "In7.Cu")
		(net "I3C1_SPD_SCL")
	)
	(segment
		(start 42.351198 -67.166744)
		(end 42.351198 -67.296284)
		(width 0.10668)
		(layer "In7.Cu")
		(net "I3C1_SPD_SCL")
	)
	(segment
		(start 65.59296 -94.766892)
		(end 65.59296 -100.369878)
		(width 0.10668)
		(layer "In7.Cu")
		(net "I3C1_SPD_SCL")
	)
	(segment
		(start 51.951382 -74.055732)
		(end 52.331874 -74.055732)
		(width 0.10668)
		(layer "In7.Cu")
		(net "I3C1_SPD_SCL")
	)
	(segment
		(start 45.515784 -69.5706)
		(end 46.200314 -70.25513)
		(width 0.10668)
		(layer "In7.Cu")
		(net "I3C1_SPD_SCL")
	)
	(segment
		(start 69.98716 -107.39501)
		(end 70.612 -108.01985)
		(width 0.10668)
		(layer "In7.Cu")
		(net "I3C1_SPD_SCL")
	)
	(segment
		(start 50.29835 -72.4027)
		(end 51.951382 -74.055732)
		(width 0.10668)
		(layer "In7.Cu")
		(net "I3C1_SPD_SCL")
	)
	(segment
		(start 61.476636 -86.342474)
		(end 61.476636 -90.650568)
		(width 0.10668)
		(layer "In7.Cu")
		(net "I3C1_SPD_SCL")
	)
	(segment
		(start 67.7799 -103.339138)
		(end 67.9958 -103.555038)
		(width 0.10668)
		(layer "In7.Cu")
		(net "I3C1_SPD_SCL")
	)
	(segment
		(start 42.351198 -67.296284)
		(end 44.625514 -69.5706)
		(width 0.10668)
		(layer "In7.Cu")
		(net "I3C1_SPD_SCL")
	)
	(segment
		(start 47.841408 -71.714106)
		(end 47.918878 -71.74611)
		(width 0.10668)
		(layer "In7.Cu")
		(net "I3C1_SPD_SCL")
	)
	(segment
		(start 67.9958 -103.555038)
		(end 67.9958 -104.632506)
		(width 0.10668)
		(layer "In7.Cu")
		(net "I3C1_SPD_SCL")
	)
	(segment
		(start 60.11164 -84.171028)
		(end 60.325 -84.687918)
		(width 0.10668)
		(layer "In7.Cu")
		(net "I3C1_SPD_SCL")
	)
	(segment
		(start 41.8592 -66.8782)
		(end 41.91 -66.8782)
		(width 0.10668)
		(layer "In7.Cu")
		(net "I3C1_SPD_SCL")
	)
	(segment
		(start 61.303916 -85.666834)
		(end 61.303916 -86.169754)
		(width 0.10668)
		(layer "In7.Cu")
		(net "I3C1_SPD_SCL")
	)
	(segment
		(start 65.59296 -100.369878)
		(end 67.7799 -102.556818)
		(width 0.10668)
		(layer "In7.Cu")
		(net "I3C1_SPD_SCL")
	)
	(segment
		(start 60.325 -84.687918)
		(end 61.303916 -85.666834)
		(width 0.10668)
		(layer "In7.Cu")
		(net "I3C1_SPD_SCL")
	)
	(segment
		(start 42.07764 -66.893186)
		(end 42.351198 -67.166744)
		(width 0.10668)
		(layer "In7.Cu")
		(net "I3C1_SPD_SCL")
	)
	(segment
		(start 44.625514 -69.5706)
		(end 45.515784 -69.5706)
		(width 0.10668)
		(layer "In7.Cu")
		(net "I3C1_SPD_SCL")
	)
	(segment
		(start 69.467984 -109.220762)
		(end 69.341746 -109.347)
		(width 0.10668)
		(layer "In7.Cu")
		(net "I3C1_SPD_SCL")
	)
	(segment
		(start 67.9958 -104.632506)
		(end 69.98716 -106.623866)
		(width 0.10668)
		(layer "In7.Cu")
		(net "I3C1_SPD_SCL")
	)
	(segment
		(start 41.924986 -66.893186)
		(end 42.07764 -66.893186)
		(width 0.10668)
		(layer "In7.Cu")
		(net "I3C1_SPD_SCL")
	)
	(segment
		(start 67.7799 -102.556818)
		(end 67.7799 -103.339138)
		(width 0.10668)
		(layer "In7.Cu")
		(net "I3C1_SPD_SCL")
	)
	(segment
		(start 60.11164 -83.198462)
		(end 60.11164 -84.171028)
		(width 0.10668)
		(layer "In7.Cu")
		(net "I3C1_SPD_SCL")
	)
	(segment
		(start 58.708798 -82.22742)
		(end 59.140598 -82.22742)
		(width 0.10668)
		(layer "In7.Cu")
		(net "I3C1_SPD_SCL")
	)
	(segment
		(start 56.16956 -79.688182)
		(end 58.708798 -82.22742)
		(width 0.10668)
		(layer "In7.Cu")
		(net "I3C1_SPD_SCL")
	)
	(segment
		(start 46.200314 -70.25513)
		(end 47.416466 -70.759066)
		(width 0.10668)
		(layer "In7.Cu")
		(net "I3C1_SPD_SCL")
	)
	(segment
		(start 41.91 -66.8782)
		(end 41.924986 -66.893186)
		(width 0.10668)
		(layer "In7.Cu")
		(net "I3C1_SPD_SCL")
	)
	(segment
		(start 70.612 -108.01985)
		(end 70.612 -108.762546)
		(width 0.10668)
		(layer "In7.Cu")
		(net "I3C1_SPD_SCL")
	)
	(segment
		(start 69.98716 -106.623866)
		(end 69.98716 -107.39501)
		(width 0.10668)
		(layer "In7.Cu")
		(net "I3C1_SPD_SCL")
	)
	(segment
		(start 47.604172 -70.946772)
		(end 47.604172 -71.47687)
		(width 0.10668)
		(layer "In7.Cu")
		(net "I3C1_SPD_SCL")
	)
	(segment
		(start 47.416466 -70.759066)
		(end 47.604172 -70.946772)
		(width 0.10668)
		(layer "In7.Cu")
		(net "I3C1_SPD_SCL")
	)
	(segment
		(start 30.999938 -94.907862)
		(end 30.999938 -94.55404)
		(width 0.11684)
		(layer "F.Cu")
		(net "FM_THROTTLE_R_N")
	)
	(segment
		(start 29.6926 -98.171)
		(end 30.607 -97.2566)
		(width 0.11684)
		(layer "F.Cu")
		(net "FM_THROTTLE_R_N")
	)
	(segment
		(start 30.607 -97.2566)
		(end 30.607 -95.3008)
		(width 0.11684)
		(layer "F.Cu")
		(net "FM_THROTTLE_R_N")
	)
	(segment
		(start 18.264124 -94.382336)
		(end 18.659348 -93.987112)
		(width 0.11684)
		(layer "F.Cu")
		(net "FM_THROTTLE_R_N")
	)
	(segment
		(start 30.2514 -100.64115)
		(end 29.6926 -100.08235)
		(width 0.11684)
		(layer "F.Cu")
		(net "FM_THROTTLE_R_N")
	)
	(segment
		(start 29.6926 -100.08235)
		(end 29.6926 -98.171)
		(width 0.11684)
		(layer "F.Cu")
		(net "FM_THROTTLE_R_N")
	)
	(segment
		(start 30.607 -95.3008)
		(end 30.999938 -94.907862)
		(width 0.11684)
		(layer "F.Cu")
		(net "FM_THROTTLE_R_N")
	)
	(via
		(at 30.999938 -94.55404)
		(size 0.508)
		(drill 0.254)
		(layers "F.Cu" "B.Cu")
		(net "FM_THROTTLE_R_N")
	)
	(via
		(at 18.264124 -94.382336)
		(size 0.4572)
		(drill 0.254)
		(layers "F.Cu" "B.Cu")
		(net "FM_THROTTLE_R_N")
	)
	(segment
		(start 29.90596 -94.55404)
		(end 29.07792 -95.38208)
		(width 0.08382)
		(layer "In2.Cu")
		(net "FM_THROTTLE_R_N")
	)
	(segment
		(start 27.47772 -95.38208)
		(end 26.10104 -94.0054)
		(width 0.08382)
		(layer "In2.Cu")
		(net "FM_THROTTLE_R_N")
	)
	(segment
		(start 29.07792 -95.38208)
		(end 27.47772 -95.38208)
		(width 0.08382)
		(layer "In2.Cu")
		(net "FM_THROTTLE_R_N")
	)
	(segment
		(start 18.64106 -94.0054)
		(end 18.264124 -94.382336)
		(width 0.08382)
		(layer "In2.Cu")
		(net "FM_THROTTLE_R_N")
	)
	(segment
		(start 26.10104 -94.0054)
		(end 18.64106 -94.0054)
		(width 0.08382)
		(layer "In2.Cu")
		(net "FM_THROTTLE_R_N")
	)
	(segment
		(start 30.999938 -94.55404)
		(end 29.90596 -94.55404)
		(width 0.08382)
		(layer "In2.Cu")
		(net "FM_THROTTLE_R_N")
	)
	(segment
		(start 19.064224 -91.991942)
		(end 19.459448 -92.387166)
		(width 0.11684)
		(layer "F.Cu")
		(net "FM_SLPS3_GF_R_N")
	)
	(via
		(at 19.064224 -91.991942)
		(size 0.4572)
		(drill 0.254)
		(layers "F.Cu" "B.Cu")
		(net "FM_SLPS3_GF_R_N")
	)
	(via
		(at 28.4353 -94.2848)
		(size 0.508)
		(drill 0.254)
		(layers "F.Cu" "B.Cu")
		(net "FM_SLPS3_GF_R_N")
	)
	(segment
		(start 28.4353 -93.77045)
		(end 28.4353 -94.2848)
		(width 0.11684)
		(layer "B.Cu")
		(net "FM_SLPS3_GF_R_N")
	)
	(segment
		(start 29.08935 -93.1164)
		(end 28.4353 -93.77045)
		(width 0.11684)
		(layer "B.Cu")
		(net "FM_SLPS3_GF_R_N")
	)
	(segment
		(start 27.3177 -93.1672)
		(end 28.4353 -94.2848)
		(width 0.08382)
		(layer "In2.Cu")
		(net "FM_SLPS3_GF_R_N")
	)
	(segment
		(start 19.477482 -92.4052)
		(end 21.209 -92.4052)
		(width 0.08382)
		(layer "In2.Cu")
		(net "FM_SLPS3_GF_R_N")
	)
	(segment
		(start 19.064224 -91.991942)
		(end 19.477482 -92.4052)
		(width 0.08382)
		(layer "In2.Cu")
		(net "FM_SLPS3_GF_R_N")
	)
	(segment
		(start 21.209 -92.4052)
		(end 21.971 -93.1672)
		(width 0.08382)
		(layer "In2.Cu")
		(net "FM_SLPS3_GF_R_N")
	)
	(segment
		(start 21.971 -93.1672)
		(end 27.3177 -93.1672)
		(width 0.08382)
		(layer "In2.Cu")
		(net "FM_SLPS3_GF_R_N")
	)
	(segment
		(start 16.664178 -94.382336)
		(end 17.059402 -93.987112)
		(width 0.11684)
		(layer "F.Cu")
		(net "H_CPU0_PROCHOT_LVC1_R_N")
	)
	(via
		(at 16.664178 -94.382336)
		(size 0.4572)
		(drill 0.254)
		(layers "F.Cu" "B.Cu")
		(net "H_CPU0_PROCHOT_LVC1_R_N")
	)
	(segment
		(start 15.18285 -94.6404)
		(end 15.76705 -94.6404)
		(width 0.11684)
		(layer "B.Cu")
		(net "H_CPU0_PROCHOT_LVC1_R_N")
	)
	(segment
		(start 15.76705 -94.6404)
		(end 16.025114 -94.382336)
		(width 0.11684)
		(layer "B.Cu")
		(net "H_CPU0_PROCHOT_LVC1_R_N")
	)
	(segment
		(start 16.025114 -94.382336)
		(end 16.664178 -94.382336)
		(width 0.11684)
		(layer "B.Cu")
		(net "H_CPU0_PROCHOT_LVC1_R_N")
	)
	(segment
		(start 54.494938 -41.771316)
		(end 54.099714 -41.376092)
		(width 0.11684)
		(layer "F.Cu")
		(net "H_CPU0_PROCHOT_LVC1_N")
	)
	(via
		(at 54.099714 -41.376092)
		(size 0.4572)
		(drill 0.254)
		(layers "F.Cu" "B.Cu")
		(net "H_CPU0_PROCHOT_LVC1_N")
	)
	(via
		(at 14.74089 -94.0054)
		(size 0.508)
		(drill 0.254)
		(layers "F.Cu" "B.Cu")
		(net "H_CPU0_PROCHOT_LVC1_N")
	)
	(segment
		(start 14.38275 -94.6404)
		(end 14.38275 -94.36354)
		(width 0.11684)
		(layer "B.Cu")
		(net "H_CPU0_PROCHOT_LVC1_N")
	)
	(segment
		(start 14.38275 -94.36354)
		(end 14.74089 -94.0054)
		(width 0.11684)
		(layer "B.Cu")
		(net "H_CPU0_PROCHOT_LVC1_N")
	)
	(segment
		(start 20.86356 -83.5914)
		(end 20.0914 -82.81924)
		(width 0.10668)
		(layer "In7.Cu")
		(net "H_CPU0_PROCHOT_LVC1_N")
	)
	(segment
		(start 23.0124 -83.0326)
		(end 22.4536 -83.5914)
		(width 0.10668)
		(layer "In7.Cu")
		(net "H_CPU0_PROCHOT_LVC1_N")
	)
	(segment
		(start 20.0914 -82.81924)
		(end 20.0914 -81.8896)
		(width 0.10668)
		(layer "In7.Cu")
		(net "H_CPU0_PROCHOT_LVC1_N")
	)
	(segment
		(start 17.186656 -84.574126)
		(end 13.709396 -84.574126)
		(width 0.10668)
		(layer "In7.Cu")
		(net "H_CPU0_PROCHOT_LVC1_N")
	)
	(segment
		(start 22.09419 -75.10399)
		(end 22.452838 -75.10399)
		(width 0.10668)
		(layer "In7.Cu")
		(net "H_CPU0_PROCHOT_LVC1_N")
	)
	(segment
		(start 23.0124 -75.663552)
		(end 23.0124 -83.0326)
		(width 0.10668)
		(layer "In7.Cu")
		(net "H_CPU0_PROCHOT_LVC1_N")
	)
	(segment
		(start 16.55318 -52.627022)
		(end 16.741902 -52.815744)
		(width 0.10668)
		(layer "In7.Cu")
		(net "H_CPU0_PROCHOT_LVC1_N")
	)
	(segment
		(start 16.544036 -33.304988)
		(end 16.705326 -33.69437)
		(width 0.10668)
		(layer "In7.Cu")
		(net "H_CPU0_PROCHOT_LVC1_N")
	)
	(segment
		(start 60.670948 -22.40534)
		(end 56.424068 -22.40534)
		(width 0.10668)
		(layer "In7.Cu")
		(net "H_CPU0_PROCHOT_LVC1_N")
	)
	(segment
		(start 16.76908 -51.364642)
		(end 16.55318 -51.580542)
		(width 0.10668)
		(layer "In7.Cu")
		(net "H_CPU0_PROCHOT_LVC1_N")
	)
	(segment
		(start 17.03832 -62.302644)
		(end 18.65376 -63.918084)
		(width 0.10668)
		(layer "In7.Cu")
		(net "H_CPU0_PROCHOT_LVC1_N")
	)
	(segment
		(start 19.05 -72.9234)
		(end 19.9136 -72.9234)
		(width 0.10668)
		(layer "In7.Cu")
		(net "H_CPU0_PROCHOT_LVC1_N")
	)
	(segment
		(start 57.69102 -40.73398)
		(end 57.69102 -39.917878)
		(width 0.10668)
		(layer "In7.Cu")
		(net "H_CPU0_PROCHOT_LVC1_N")
	)
	(segment
		(start 17.03832 -59.625992)
		(end 17.03832 -62.302644)
		(width 0.10668)
		(layer "In7.Cu")
		(net "H_CPU0_PROCHOT_LVC1_N")
	)
	(segment
		(start 19.78406 -81.58226)
		(end 18.26514 -81.58226)
		(width 0.10668)
		(layer "In7.Cu")
		(net "H_CPU0_PROCHOT_LVC1_N")
	)
	(segment
		(start 13.709396 -84.574126)
		(end 13.29436 -84.989162)
		(width 0.10668)
		(layer "In7.Cu")
		(net "H_CPU0_PROCHOT_LVC1_N")
	)
	(segment
		(start 16.83512 -33.780984)
		(end 17.11579 -34.061654)
		(width 0.10668)
		(layer "In7.Cu")
		(net "H_CPU0_PROCHOT_LVC1_N")
	)
	(segment
		(start 18.65376 -66.626486)
		(end 17.991836 -67.28841)
		(width 0.10668)
		(layer "In7.Cu")
		(net "H_CPU0_PROCHOT_LVC1_N")
	)
	(segment
		(start 60.45962 -31.10738)
		(end 61.262006 -30.304994)
		(width 0.10668)
		(layer "In7.Cu")
		(net "H_CPU0_PROCHOT_LVC1_N")
	)
	(segment
		(start 16.37792 -58.965592)
		(end 17.03832 -59.625992)
		(width 0.10668)
		(layer "In7.Cu")
		(net "H_CPU0_PROCHOT_LVC1_N")
	)
	(segment
		(start 16.398748 -29.406596)
		(end 16.37792 -29.427424)
		(width 0.10668)
		(layer "In7.Cu")
		(net "H_CPU0_PROCHOT_LVC1_N")
	)
	(segment
		(start 22.452838 -75.10399)
		(end 23.0124 -75.663552)
		(width 0.10668)
		(layer "In7.Cu")
		(net "H_CPU0_PROCHOT_LVC1_N")
	)
	(segment
		(start 48.436784 -19.7612)
		(end 47.819564 -19.14398)
		(width 0.10668)
		(layer "In7.Cu")
		(net "H_CPU0_PROCHOT_LVC1_N")
	)
	(segment
		(start 58.148982 -36.474908)
		(end 60.45962 -34.16427)
		(width 0.10668)
		(layer "In7.Cu")
		(net "H_CPU0_PROCHOT_LVC1_N")
	)
	(segment
		(start 15.456154 -48.69053)
		(end 16.16456 -49.398936)
		(width 0.10668)
		(layer "In7.Cu")
		(net "H_CPU0_PROCHOT_LVC1_N")
	)
	(segment
		(start 16.37792 -32.469582)
		(end 16.544036 -33.304988)
		(width 0.10668)
		(layer "In7.Cu")
		(net "H_CPU0_PROCHOT_LVC1_N")
	)
	(segment
		(start 46.948852 -19.14398)
		(end 45.658532 -17.85366)
		(width 0.10668)
		(layer "In7.Cu")
		(net "H_CPU0_PROCHOT_LVC1_N")
	)
	(segment
		(start 16.54048 -46.138084)
		(end 15.456154 -47.22241)
		(width 0.10668)
		(layer "In7.Cu")
		(net "H_CPU0_PROCHOT_LVC1_N")
	)
	(segment
		(start 58.29554 -39.313358)
		(end 58.29554 -38.389052)
		(width 0.10668)
		(layer "In7.Cu")
		(net "H_CPU0_PROCHOT_LVC1_N")
	)
	(segment
		(start 22.4536 -83.5914)
		(end 20.86356 -83.5914)
		(width 0.10668)
		(layer "In7.Cu")
		(net "H_CPU0_PROCHOT_LVC1_N")
	)
	(segment
		(start 53.779928 -19.7612)
		(end 48.436784 -19.7612)
		(width 0.10668)
		(layer "In7.Cu")
		(net "H_CPU0_PROCHOT_LVC1_N")
	)
	(segment
		(start 60.45962 -34.16427)
		(end 60.45962 -31.10738)
		(width 0.10668)
		(layer "In7.Cu")
		(net "H_CPU0_PROCHOT_LVC1_N")
	)
	(segment
		(start 16.55318 -51.580542)
		(end 16.55318 -52.627022)
		(width 0.10668)
		(layer "In7.Cu")
		(net "H_CPU0_PROCHOT_LVC1_N")
	)
	(segment
		(start 17.0053 -67.712336)
		(end 17.0053 -69.032882)
		(width 0.10668)
		(layer "In7.Cu")
		(net "H_CPU0_PROCHOT_LVC1_N")
	)
	(segment
		(start 18.751042 -72.624442)
		(end 19.05 -72.9234)
		(width 0.10668)
		(layer "In7.Cu")
		(net "H_CPU0_PROCHOT_LVC1_N")
	)
	(segment
		(start 18.034 -83.726782)
		(end 17.186656 -84.574126)
		(width 0.10668)
		(layer "In7.Cu")
		(net "H_CPU0_PROCHOT_LVC1_N")
	)
	(segment
		(start 18.65376 -63.918084)
		(end 18.65376 -66.626486)
		(width 0.10668)
		(layer "In7.Cu")
		(net "H_CPU0_PROCHOT_LVC1_N")
	)
	(segment
		(start 62.133988 -30.035754)
		(end 62.133988 -29.654754)
		(width 0.10668)
		(layer "In7.Cu")
		(net "H_CPU0_PROCHOT_LVC1_N")
	)
	(segment
		(start 18.751042 -70.778624)
		(end 18.751042 -72.624442)
		(width 0.10668)
		(layer "In7.Cu")
		(net "H_CPU0_PROCHOT_LVC1_N")
	)
	(segment
		(start 15.456154 -47.22241)
		(end 15.456154 -48.69053)
		(width 0.10668)
		(layer "In7.Cu")
		(net "H_CPU0_PROCHOT_LVC1_N")
	)
	(segment
		(start 29.454602 -16.68018)
		(end 25.323292 -20.81149)
		(width 0.10668)
		(layer "In7.Cu")
		(net "H_CPU0_PROCHOT_LVC1_N")
	)
	(segment
		(start 16.16456 -50.279554)
		(end 16.76908 -50.884074)
		(width 0.10668)
		(layer "In7.Cu")
		(net "H_CPU0_PROCHOT_LVC1_N")
	)
	(segment
		(start 16.16456 -49.398936)
		(end 16.16456 -50.279554)
		(width 0.10668)
		(layer "In7.Cu")
		(net "H_CPU0_PROCHOT_LVC1_N")
	)
	(segment
		(start 14.491716 -93.756226)
		(end 14.74089 -94.0054)
		(width 0.10668)
		(layer "In7.Cu")
		(net "H_CPU0_PROCHOT_LVC1_N")
	)
	(segment
		(start 62.901322 -25.378918)
		(end 62.901322 -24.635714)
		(width 0.10668)
		(layer "In7.Cu")
		(net "H_CPU0_PROCHOT_LVC1_N")
	)
	(segment
		(start 61.262006 -30.304994)
		(end 61.864748 -30.304994)
		(width 0.10668)
		(layer "In7.Cu")
		(net "H_CPU0_PROCHOT_LVC1_N")
	)
	(segment
		(start 61.864748 -29.385514)
		(end 61.864494 -29.385514)
		(width 0.10668)
		(layer "In7.Cu")
		(net "H_CPU0_PROCHOT_LVC1_N")
	)
	(segment
		(start 45.658532 -17.85366)
		(end 37.376862 -17.85366)
		(width 0.10668)
		(layer "In7.Cu")
		(net "H_CPU0_PROCHOT_LVC1_N")
	)
	(segment
		(start 61.665358 -26.015442)
		(end 61.92266 -25.75814)
		(width 0.10668)
		(layer "In7.Cu")
		(net "H_CPU0_PROCHOT_LVC1_N")
	)
	(segment
		(start 62.901322 -24.635714)
		(end 60.670948 -22.40534)
		(width 0.10668)
		(layer "In7.Cu")
		(net "H_CPU0_PROCHOT_LVC1_N")
	)
	(segment
		(start 54.099714 -41.376092)
		(end 54.490366 -40.98544)
		(width 0.10668)
		(layer "In7.Cu")
		(net "H_CPU0_PROCHOT_LVC1_N")
	)
	(segment
		(start 16.398748 -28.485592)
		(end 16.398748 -29.406596)
		(width 0.10668)
		(layer "In7.Cu")
		(net "H_CPU0_PROCHOT_LVC1_N")
	)
	(segment
		(start 16.54048 -36.302696)
		(end 16.54048 -46.138084)
		(width 0.10668)
		(layer "In7.Cu")
		(net "H_CPU0_PROCHOT_LVC1_N")
	)
	(segment
		(start 20.0914 -81.8896)
		(end 19.78406 -81.58226)
		(width 0.10668)
		(layer "In7.Cu")
		(net "H_CPU0_PROCHOT_LVC1_N")
	)
	(segment
		(start 13.29436 -88.224106)
		(end 14.491716 -89.421462)
		(width 0.10668)
		(layer "In7.Cu")
		(net "H_CPU0_PROCHOT_LVC1_N")
	)
	(segment
		(start 57.43956 -40.98544)
		(end 57.69102 -40.73398)
		(width 0.10668)
		(layer "In7.Cu")
		(net "H_CPU0_PROCHOT_LVC1_N")
	)
	(segment
		(start 54.490366 -40.98544)
		(end 57.43956 -40.98544)
		(width 0.10668)
		(layer "In7.Cu")
		(net "H_CPU0_PROCHOT_LVC1_N")
	)
	(segment
		(start 17.429226 -67.28841)
		(end 17.0053 -67.712336)
		(width 0.10668)
		(layer "In7.Cu")
		(net "H_CPU0_PROCHOT_LVC1_N")
	)
	(segment
		(start 47.819564 -19.14398)
		(end 46.948852 -19.14398)
		(width 0.10668)
		(layer "In7.Cu")
		(net "H_CPU0_PROCHOT_LVC1_N")
	)
	(segment
		(start 18.005552 -20.81149)
		(end 16.0782 -22.738842)
		(width 0.10668)
		(layer "In7.Cu")
		(net "H_CPU0_PROCHOT_LVC1_N")
	)
	(segment
		(start 62.133988 -29.654754)
		(end 61.864748 -29.385514)
		(width 0.10668)
		(layer "In7.Cu")
		(net "H_CPU0_PROCHOT_LVC1_N")
	)
	(segment
		(start 14.491716 -89.421462)
		(end 14.491716 -93.756226)
		(width 0.10668)
		(layer "In7.Cu")
		(net "H_CPU0_PROCHOT_LVC1_N")
	)
	(segment
		(start 17.11579 -35.306762)
		(end 16.83766 -35.584892)
		(width 0.10668)
		(layer "In7.Cu")
		(net "H_CPU0_PROCHOT_LVC1_N")
	)
	(segment
		(start 61.93282 -28.452064)
		(end 61.93282 -26.652474)
		(width 0.10668)
		(layer "In7.Cu")
		(net "H_CPU0_PROCHOT_LVC1_N")
	)
	(segment
		(start 37.376862 -17.85366)
		(end 36.203382 -16.68018)
		(width 0.10668)
		(layer "In7.Cu")
		(net "H_CPU0_PROCHOT_LVC1_N")
	)
	(segment
		(start 13.29436 -84.989162)
		(end 13.29436 -88.224106)
		(width 0.10668)
		(layer "In7.Cu")
		(net "H_CPU0_PROCHOT_LVC1_N")
	)
	(segment
		(start 16.741902 -52.815744)
		(end 16.741902 -57.256426)
		(width 0.10668)
		(layer "In7.Cu")
		(net "H_CPU0_PROCHOT_LVC1_N")
	)
	(segment
		(start 61.93282 -26.652474)
		(end 61.665358 -26.385012)
		(width 0.10668)
		(layer "In7.Cu")
		(net "H_CPU0_PROCHOT_LVC1_N")
	)
	(segment
		(start 61.92266 -25.75814)
		(end 62.5221 -25.75814)
		(width 0.10668)
		(layer "In7.Cu")
		(net "H_CPU0_PROCHOT_LVC1_N")
	)
	(segment
		(start 16.705326 -33.69437)
		(end 16.83512 -33.780984)
		(width 0.10668)
		(layer "In7.Cu")
		(net "H_CPU0_PROCHOT_LVC1_N")
	)
	(segment
		(start 17.0053 -69.032882)
		(end 18.751042 -70.778624)
		(width 0.10668)
		(layer "In7.Cu")
		(net "H_CPU0_PROCHOT_LVC1_N")
	)
	(segment
		(start 58.148982 -38.242494)
		(end 58.148982 -36.474908)
		(width 0.10668)
		(layer "In7.Cu")
		(net "H_CPU0_PROCHOT_LVC1_N")
	)
	(segment
		(start 17.991836 -67.28841)
		(end 17.429226 -67.28841)
		(width 0.10668)
		(layer "In7.Cu")
		(net "H_CPU0_PROCHOT_LVC1_N")
	)
	(segment
		(start 17.11579 -34.061654)
		(end 17.11579 -35.306762)
		(width 0.10668)
		(layer "In7.Cu")
		(net "H_CPU0_PROCHOT_LVC1_N")
	)
	(segment
		(start 61.670184 -28.7147)
		(end 61.93282 -28.452064)
		(width 0.10668)
		(layer "In7.Cu")
		(net "H_CPU0_PROCHOT_LVC1_N")
	)
	(segment
		(start 58.29554 -38.389052)
		(end 58.148982 -38.242494)
		(width 0.10668)
		(layer "In7.Cu")
		(net "H_CPU0_PROCHOT_LVC1_N")
	)
	(segment
		(start 16.76908 -50.884074)
		(end 16.76908 -51.364642)
		(width 0.10668)
		(layer "In7.Cu")
		(net "H_CPU0_PROCHOT_LVC1_N")
	)
	(segment
		(start 61.665358 -26.385012)
		(end 61.665358 -26.015442)
		(width 0.10668)
		(layer "In7.Cu")
		(net "H_CPU0_PROCHOT_LVC1_N")
	)
	(segment
		(start 18.26514 -81.58226)
		(end 18.034 -81.8134)
		(width 0.10668)
		(layer "In7.Cu")
		(net "H_CPU0_PROCHOT_LVC1_N")
	)
	(segment
		(start 36.203382 -16.68018)
		(end 29.454602 -16.68018)
		(width 0.10668)
		(layer "In7.Cu")
		(net "H_CPU0_PROCHOT_LVC1_N")
	)
	(segment
		(start 16.741902 -57.256426)
		(end 16.37792 -57.620408)
		(width 0.10668)
		(layer "In7.Cu")
		(net "H_CPU0_PROCHOT_LVC1_N")
	)
	(segment
		(start 61.864748 -30.304994)
		(end 62.133988 -30.035754)
		(width 0.10668)
		(layer "In7.Cu")
		(net "H_CPU0_PROCHOT_LVC1_N")
	)
	(segment
		(start 16.0782 -22.738842)
		(end 16.0782 -28.165044)
		(width 0.10668)
		(layer "In7.Cu")
		(net "H_CPU0_PROCHOT_LVC1_N")
	)
	(segment
		(start 19.9136 -72.9234)
		(end 22.09419 -75.10399)
		(width 0.10668)
		(layer "In7.Cu")
		(net "H_CPU0_PROCHOT_LVC1_N")
	)
	(segment
		(start 25.323292 -20.81149)
		(end 18.005552 -20.81149)
		(width 0.10668)
		(layer "In7.Cu")
		(net "H_CPU0_PROCHOT_LVC1_N")
	)
	(segment
		(start 16.37792 -29.427424)
		(end 16.37792 -32.469582)
		(width 0.10668)
		(layer "In7.Cu")
		(net "H_CPU0_PROCHOT_LVC1_N")
	)
	(segment
		(start 56.424068 -22.40534)
		(end 53.779928 -19.7612)
		(width 0.10668)
		(layer "In7.Cu")
		(net "H_CPU0_PROCHOT_LVC1_N")
	)
	(segment
		(start 16.83766 -35.584892)
		(end 16.54048 -36.302696)
		(width 0.10668)
		(layer "In7.Cu")
		(net "H_CPU0_PROCHOT_LVC1_N")
	)
	(segment
		(start 16.37792 -57.620408)
		(end 16.37792 -58.965592)
		(width 0.10668)
		(layer "In7.Cu")
		(net "H_CPU0_PROCHOT_LVC1_N")
	)
	(segment
		(start 18.034 -81.8134)
		(end 18.034 -83.726782)
		(width 0.10668)
		(layer "In7.Cu")
		(net "H_CPU0_PROCHOT_LVC1_N")
	)
	(segment
		(start 61.670184 -29.191204)
		(end 61.670184 -28.7147)
		(width 0.10668)
		(layer "In7.Cu")
		(net "H_CPU0_PROCHOT_LVC1_N")
	)
	(segment
		(start 57.69102 -39.917878)
		(end 58.29554 -39.313358)
		(width 0.10668)
		(layer "In7.Cu")
		(net "H_CPU0_PROCHOT_LVC1_N")
	)
	(segment
		(start 16.0782 -28.165044)
		(end 16.398748 -28.485592)
		(width 0.10668)
		(layer "In7.Cu")
		(net "H_CPU0_PROCHOT_LVC1_N")
	)
	(segment
		(start 61.864494 -29.385514)
		(end 61.670184 -29.191204)
		(width 0.10668)
		(layer "In7.Cu")
		(net "H_CPU0_PROCHOT_LVC1_N")
	)
	(segment
		(start 62.5221 -25.75814)
		(end 62.901322 -25.378918)
		(width 0.10668)
		(layer "In7.Cu")
		(net "H_CPU0_PROCHOT_LVC1_N")
	)
	(segment
		(start 33.321244 -46.782482)
		(end 33.166812 -46.62805)
		(width 0.11684)
		(layer "F.Cu")
		(net "RST_PCA9548_SENSOR_R_N")
	)
	(segment
		(start 33.166812 -46.62805)
		(end 32.64535 -46.62805)
		(width 0.11684)
		(layer "F.Cu")
		(net "RST_PCA9548_SENSOR_R_N")
	)
	(segment
		(start 33.7566 -46.80585)
		(end 33.733232 -46.782482)
		(width 0.11684)
		(layer "F.Cu")
		(net "RST_PCA9548_SENSOR_R_N")
	)
	(segment
		(start 31.1912 -48.0822)
		(end 31.1912 -50.712116)
		(width 0.11684)
		(layer "F.Cu")
		(net "RST_PCA9548_SENSOR_R_N")
	)
	(segment
		(start 31.472124 -47.801276)
		(end 31.1912 -48.0822)
		(width 0.11684)
		(layer "F.Cu")
		(net "RST_PCA9548_SENSOR_R_N")
	)
	(segment
		(start 31.1912 -50.712116)
		(end 31.693866 -51.214782)
		(width 0.11684)
		(layer "F.Cu")
		(net "RST_PCA9548_SENSOR_R_N")
	)
	(segment
		(start 46.89983 -50.166524)
		(end 47.295054 -49.7713)
		(width 0.11684)
		(layer "F.Cu")
		(net "RST_PCA9548_SENSOR_R_N")
	)
	(segment
		(start 32.64535 -46.62805)
		(end 31.472124 -47.801276)
		(width 0.11684)
		(layer "F.Cu")
		(net "RST_PCA9548_SENSOR_R_N")
	)
	(segment
		(start 33.733232 -46.782482)
		(end 33.321244 -46.782482)
		(width 0.11684)
		(layer "F.Cu")
		(net "RST_PCA9548_SENSOR_R_N")
	)
	(via
		(at 31.472124 -47.801276)
		(size 0.762)
		(drill 0.381)
		(layers "F.Cu" "B.Cu")
		(net "RST_PCA9548_SENSOR_R_N")
	)
	(via
		(at 46.89983 -50.166524)
		(size 0.4572)
		(drill 0.254)
		(layers "F.Cu" "B.Cu")
		(net "RST_PCA9548_SENSOR_R_N")
	)
	(via
		(at 31.693866 -51.214782)
		(size 0.508)
		(drill 0.254)
		(layers "F.Cu" "B.Cu")
		(net "RST_PCA9548_SENSOR_R_N")
	)
	(segment
		(start 31.693866 -51.214782)
		(end 35.238182 -51.214782)
		(width 0.08382)
		(layer "In2.Cu")
		(net "RST_PCA9548_SENSOR_R_N")
	)
	(segment
		(start 41.81348 -49.75352)
		(end 42.96791 -48.59909)
		(width 0.08382)
		(layer "In2.Cu")
		(net "RST_PCA9548_SENSOR_R_N")
	)
	(segment
		(start 39.2938 -51.4096)
		(end 39.878 -50.8254)
		(width 0.08382)
		(layer "In2.Cu")
		(net "RST_PCA9548_SENSOR_R_N")
	)
	(segment
		(start 39.878 -50.395632)
		(end 40.520112 -49.75352)
		(width 0.08382)
		(layer "In2.Cu")
		(net "RST_PCA9548_SENSOR_R_N")
	)
	(segment
		(start 46.614842 -49.34204)
		(end 46.623986 -49.34204)
		(width 0.08382)
		(layer "In2.Cu")
		(net "RST_PCA9548_SENSOR_R_N")
	)
	(segment
		(start 46.447202 -49.1744)
		(end 46.614842 -49.34204)
		(width 0.08382)
		(layer "In2.Cu")
		(net "RST_PCA9548_SENSOR_R_N")
	)
	(segment
		(start 46.89983 -49.617884)
		(end 46.89983 -50.166524)
		(width 0.08382)
		(layer "In2.Cu")
		(net "RST_PCA9548_SENSOR_R_N")
	)
	(segment
		(start 39.2938 -51.994054)
		(end 39.2938 -51.4096)
		(width 0.08382)
		(layer "In2.Cu")
		(net "RST_PCA9548_SENSOR_R_N")
	)
	(segment
		(start 44.435522 -48.59909)
		(end 45.010832 -49.1744)
		(width 0.08382)
		(layer "In2.Cu")
		(net "RST_PCA9548_SENSOR_R_N")
	)
	(segment
		(start 39.878 -50.8254)
		(end 39.878 -50.395632)
		(width 0.08382)
		(layer "In2.Cu")
		(net "RST_PCA9548_SENSOR_R_N")
	)
	(segment
		(start 35.238182 -51.214782)
		(end 36.2458 -52.2224)
		(width 0.08382)
		(layer "In2.Cu")
		(net "RST_PCA9548_SENSOR_R_N")
	)
	(segment
		(start 42.96791 -48.59909)
		(end 44.435522 -48.59909)
		(width 0.08382)
		(layer "In2.Cu")
		(net "RST_PCA9548_SENSOR_R_N")
	)
	(segment
		(start 45.010832 -49.1744)
		(end 46.447202 -49.1744)
		(width 0.08382)
		(layer "In2.Cu")
		(net "RST_PCA9548_SENSOR_R_N")
	)
	(segment
		(start 46.623986 -49.34204)
		(end 46.89983 -49.617884)
		(width 0.08382)
		(layer "In2.Cu")
		(net "RST_PCA9548_SENSOR_R_N")
	)
	(segment
		(start 39.065454 -52.2224)
		(end 39.2938 -51.994054)
		(width 0.08382)
		(layer "In2.Cu")
		(net "RST_PCA9548_SENSOR_R_N")
	)
	(segment
		(start 40.520112 -49.75352)
		(end 41.81348 -49.75352)
		(width 0.08382)
		(layer "In2.Cu")
		(net "RST_PCA9548_SENSOR_R_N")
	)
	(segment
		(start 36.2458 -52.2224)
		(end 39.065454 -52.2224)
		(width 0.08382)
		(layer "In2.Cu")
		(net "RST_PCA9548_SENSOR_R_N")
	)
	(via
		(at 23.58898 -111.209074)
		(size 0.508)
		(drill 0.254)
		(layers "F.Cu" "B.Cu")
		(net "FM_DBP_CPU_PREQ_GF_R_N")
	)
	(via
		(at 52.978304 -32.755078)
		(size 0.508)
		(drill 0.254)
		(layers "F.Cu" "B.Cu")
		(net "FM_DBP_CPU_PREQ_GF_R_N")
	)
	(via
		(at 24.05634 -110.04804)
		(size 0.6604)
		(drill 0.3302)
		(layers "F.Cu" "B.Cu")
		(net "FM_DBP_CPU_PREQ_GF_R_N")
	)
	(segment
		(start 52.978304 -32.755078)
		(end 52.4764 -33.256982)
		(width 0.11684)
		(layer "B.Cu")
		(net "FM_DBP_CPU_PREQ_GF_R_N")
	)
	(segment
		(start 25.237694 -110.04804)
		(end 28.1559 -112.966246)
		(width 0.11684)
		(layer "B.Cu")
		(net "FM_DBP_CPU_PREQ_GF_R_N")
	)
	(segment
		(start 24.05634 -110.04804)
		(end 23.718774 -110.04804)
		(width 0.11684)
		(layer "B.Cu")
		(net "FM_DBP_CPU_PREQ_GF_R_N")
	)
	(segment
		(start 52.4764 -33.256982)
		(end 52.4764 -34.14395)
		(width 0.11684)
		(layer "B.Cu")
		(net "FM_DBP_CPU_PREQ_GF_R_N")
	)
	(segment
		(start 26.945082 -117.199664)
		(end 26.945082 -118.460012)
		(width 0.11684)
		(layer "B.Cu")
		(net "FM_DBP_CPU_PREQ_GF_R_N")
	)
	(segment
		(start 23.601934 -111.209074)
		(end 23.58898 -111.209074)
		(width 0.11684)
		(layer "B.Cu")
		(net "FM_DBP_CPU_PREQ_GF_R_N")
	)
	(segment
		(start 28.1559 -115.988846)
		(end 26.945082 -117.199664)
		(width 0.11684)
		(layer "B.Cu")
		(net "FM_DBP_CPU_PREQ_GF_R_N")
	)
	(segment
		(start 28.1559 -112.966246)
		(end 28.1559 -115.988846)
		(width 0.11684)
		(layer "B.Cu")
		(net "FM_DBP_CPU_PREQ_GF_R_N")
	)
	(segment
		(start 52.4764 -34.14395)
		(end 52.578 -34.24555)
		(width 0.11684)
		(layer "B.Cu")
		(net "FM_DBP_CPU_PREQ_GF_R_N")
	)
	(segment
		(start 24.05634 -110.04804)
		(end 25.237694 -110.04804)
		(width 0.11684)
		(layer "B.Cu")
		(net "FM_DBP_CPU_PREQ_GF_R_N")
	)
	(segment
		(start 23.601934 -110.16488)
		(end 23.601934 -111.209074)
		(width 0.11684)
		(layer "B.Cu")
		(net "FM_DBP_CPU_PREQ_GF_R_N")
	)
	(segment
		(start 23.718774 -110.04804)
		(end 23.601934 -110.16488)
		(width 0.11684)
		(layer "B.Cu")
		(net "FM_DBP_CPU_PREQ_GF_R_N")
	)
	(segment
		(start 16.740124 -112.20704)
		(end 17.249902 -112.716818)
		(width 0.10668)
		(layer "In4.Cu")
		(net "FM_DBP_CPU_PREQ_GF_R_N")
	)
	(segment
		(start 17.249902 -112.716818)
		(end 19.413728 -112.716818)
		(width 0.10668)
		(layer "In4.Cu")
		(net "FM_DBP_CPU_PREQ_GF_R_N")
	)
	(segment
		(start 15.24 -15.2146)
		(end 13.2588 -17.1958)
		(width 0.10668)
		(layer "In4.Cu")
		(net "FM_DBP_CPU_PREQ_GF_R_N")
	)
	(segment
		(start 2.430272 -88.320626)
		(end 2.430272 -104.462072)
		(width 0.10668)
		(layer "In4.Cu")
		(net "FM_DBP_CPU_PREQ_GF_R_N")
	)
	(segment
		(start 7.6073 -28.99156)
		(end 7.05104 -28.4353)
		(width 0.10668)
		(layer "In4.Cu")
		(net "FM_DBP_CPU_PREQ_GF_R_N")
	)
	(segment
		(start 13.179044 -26.593546)
		(end 11.81989 -27.9527)
		(width 0.10668)
		(layer "In4.Cu")
		(net "FM_DBP_CPU_PREQ_GF_R_N")
	)
	(segment
		(start 5.050536 -28.4353)
		(end 2.328672 -31.157164)
		(width 0.10668)
		(layer "In4.Cu")
		(net "FM_DBP_CPU_PREQ_GF_R_N")
	)
	(segment
		(start 8.626094 -112.20704)
		(end 16.740124 -112.20704)
		(width 0.10668)
		(layer "In4.Cu")
		(net "FM_DBP_CPU_PREQ_GF_R_N")
	)
	(segment
		(start 29.01442 -20.7518)
		(end 28.79598 -20.53336)
		(width 0.10668)
		(layer "In4.Cu")
		(net "FM_DBP_CPU_PREQ_GF_R_N")
	)
	(segment
		(start 28.79598 -20.53336)
		(end 28.79598 -17.01038)
		(width 0.10668)
		(layer "In4.Cu")
		(net "FM_DBP_CPU_PREQ_GF_R_N")
	)
	(segment
		(start 33.274 -25.58288)
		(end 31.13532 -23.4442)
		(width 0.10668)
		(layer "In4.Cu")
		(net "FM_DBP_CPU_PREQ_GF_R_N")
	)
	(segment
		(start 51.834288 -30.892496)
		(end 51.034696 -30.892496)
		(width 0.10668)
		(layer "In4.Cu")
		(net "FM_DBP_CPU_PREQ_GF_R_N")
	)
	(segment
		(start 2.328672 -31.157164)
		(end 2.328672 -77.984858)
		(width 0.10668)
		(layer "In4.Cu")
		(net "FM_DBP_CPU_PREQ_GF_R_N")
	)
	(segment
		(start 19.928586 -112.20196)
		(end 21.474176 -112.20196)
		(width 0.10668)
		(layer "In4.Cu")
		(net "FM_DBP_CPU_PREQ_GF_R_N")
	)
	(segment
		(start 50.287174 -30.144974)
		(end 50.287174 -28.895294)
		(width 0.10668)
		(layer "In4.Cu")
		(net "FM_DBP_CPU_PREQ_GF_R_N")
	)
	(segment
		(start 31.13532 -23.4442)
		(end 29.7942 -23.4442)
		(width 0.10668)
		(layer "In4.Cu")
		(net "FM_DBP_CPU_PREQ_GF_R_N")
	)
	(segment
		(start 6.937502 -107.462574)
		(end 6.937502 -108.234226)
		(width 0.10668)
		(layer "In4.Cu")
		(net "FM_DBP_CPU_PREQ_GF_R_N")
	)
	(segment
		(start 14.0843 -26.275792)
		(end 13.766546 -26.593546)
		(width 0.10668)
		(layer "In4.Cu")
		(net "FM_DBP_CPU_PREQ_GF_R_N")
	)
	(segment
		(start 6.02107 -106.546142)
		(end 6.937502 -107.462574)
		(width 0.10668)
		(layer "In4.Cu")
		(net "FM_DBP_CPU_PREQ_GF_R_N")
	)
	(segment
		(start 27.0002 -15.2146)
		(end 15.24 -15.2146)
		(width 0.10668)
		(layer "In4.Cu")
		(net "FM_DBP_CPU_PREQ_GF_R_N")
	)
	(segment
		(start 12.2936 -21.082)
		(end 14.0843 -22.8727)
		(width 0.10668)
		(layer "In4.Cu")
		(net "FM_DBP_CPU_PREQ_GF_R_N")
	)
	(segment
		(start 4.514342 -106.546142)
		(end 6.02107 -106.546142)
		(width 0.10668)
		(layer "In4.Cu")
		(net "FM_DBP_CPU_PREQ_GF_R_N")
	)
	(segment
		(start 29.01442 -22.66442)
		(end 29.01442 -20.7518)
		(width 0.10668)
		(layer "In4.Cu")
		(net "FM_DBP_CPU_PREQ_GF_R_N")
	)
	(segment
		(start 6.53034 -110.111286)
		(end 8.626094 -112.20704)
		(width 0.10668)
		(layer "In4.Cu")
		(net "FM_DBP_CPU_PREQ_GF_R_N")
	)
	(segment
		(start 6.53034 -108.641388)
		(end 6.53034 -110.111286)
		(width 0.10668)
		(layer "In4.Cu")
		(net "FM_DBP_CPU_PREQ_GF_R_N")
	)
	(segment
		(start 19.413728 -112.716818)
		(end 19.928586 -112.20196)
		(width 0.10668)
		(layer "In4.Cu")
		(net "FM_DBP_CPU_PREQ_GF_R_N")
	)
	(segment
		(start 52.43322 -31.491428)
		(end 51.834288 -30.892496)
		(width 0.10668)
		(layer "In4.Cu")
		(net "FM_DBP_CPU_PREQ_GF_R_N")
	)
	(segment
		(start 29.7942 -23.4442)
		(end 29.01442 -22.66442)
		(width 0.10668)
		(layer "In4.Cu")
		(net "FM_DBP_CPU_PREQ_GF_R_N")
	)
	(segment
		(start 7.05104 -28.4353)
		(end 5.050536 -28.4353)
		(width 0.10668)
		(layer "In4.Cu")
		(net "FM_DBP_CPU_PREQ_GF_R_N")
	)
	(segment
		(start 51.034696 -30.892496)
		(end 50.287174 -30.144974)
		(width 0.10668)
		(layer "In4.Cu")
		(net "FM_DBP_CPU_PREQ_GF_R_N")
	)
	(segment
		(start 43.442636 -25.4762)
		(end 42.94886 -25.4762)
		(width 0.10668)
		(layer "In4.Cu")
		(net "FM_DBP_CPU_PREQ_GF_R_N")
	)
	(segment
		(start 14.0843 -22.8727)
		(end 14.0843 -26.275792)
		(width 0.10668)
		(layer "In4.Cu")
		(net "FM_DBP_CPU_PREQ_GF_R_N")
	)
	(segment
		(start 23.60168 -111.209074)
		(end 23.58898 -111.209074)
		(width 0.10668)
		(layer "In4.Cu")
		(net "FM_DBP_CPU_PREQ_GF_R_N")
	)
	(segment
		(start 12.2936 -17.4244)
		(end 12.2936 -21.082)
		(width 0.10668)
		(layer "In4.Cu")
		(net "FM_DBP_CPU_PREQ_GF_R_N")
	)
	(segment
		(start 5.078476 -80.734662)
		(end 5.078476 -85.672422)
		(width 0.10668)
		(layer "In4.Cu")
		(net "FM_DBP_CPU_PREQ_GF_R_N")
	)
	(segment
		(start 2.328672 -77.984858)
		(end 5.078476 -80.734662)
		(width 0.10668)
		(layer "In4.Cu")
		(net "FM_DBP_CPU_PREQ_GF_R_N")
	)
	(segment
		(start 50.287174 -28.895294)
		(end 48.14062 -26.74874)
		(width 0.10668)
		(layer "In4.Cu")
		(net "FM_DBP_CPU_PREQ_GF_R_N")
	)
	(segment
		(start 5.078476 -85.672422)
		(end 2.430272 -88.320626)
		(width 0.10668)
		(layer "In4.Cu")
		(net "FM_DBP_CPU_PREQ_GF_R_N")
	)
	(segment
		(start 52.978304 -32.755078)
		(end 52.43322 -32.209994)
		(width 0.10668)
		(layer "In4.Cu")
		(net "FM_DBP_CPU_PREQ_GF_R_N")
	)
	(segment
		(start 42.94886 -25.4762)
		(end 42.84218 -25.58288)
		(width 0.10668)
		(layer "In4.Cu")
		(net "FM_DBP_CPU_PREQ_GF_R_N")
	)
	(segment
		(start 13.766546 -26.593546)
		(end 13.179044 -26.593546)
		(width 0.10668)
		(layer "In4.Cu")
		(net "FM_DBP_CPU_PREQ_GF_R_N")
	)
	(segment
		(start 6.937502 -108.234226)
		(end 6.53034 -108.641388)
		(width 0.10668)
		(layer "In4.Cu")
		(net "FM_DBP_CPU_PREQ_GF_R_N")
	)
	(segment
		(start 42.84218 -25.58288)
		(end 33.274 -25.58288)
		(width 0.10668)
		(layer "In4.Cu")
		(net "FM_DBP_CPU_PREQ_GF_R_N")
	)
	(segment
		(start 10.295636 -27.9527)
		(end 9.256776 -28.99156)
		(width 0.10668)
		(layer "In4.Cu")
		(net "FM_DBP_CPU_PREQ_GF_R_N")
	)
	(segment
		(start 2.430272 -104.462072)
		(end 4.514342 -106.546142)
		(width 0.10668)
		(layer "In4.Cu")
		(net "FM_DBP_CPU_PREQ_GF_R_N")
	)
	(segment
		(start 44.715176 -26.74874)
		(end 43.442636 -25.4762)
		(width 0.10668)
		(layer "In4.Cu")
		(net "FM_DBP_CPU_PREQ_GF_R_N")
	)
	(segment
		(start 22.61108 -112.199674)
		(end 23.60168 -111.209074)
		(width 0.10668)
		(layer "In4.Cu")
		(net "FM_DBP_CPU_PREQ_GF_R_N")
	)
	(segment
		(start 52.43322 -32.209994)
		(end 52.43322 -31.491428)
		(width 0.10668)
		(layer "In4.Cu")
		(net "FM_DBP_CPU_PREQ_GF_R_N")
	)
	(segment
		(start 11.81989 -27.9527)
		(end 10.295636 -27.9527)
		(width 0.10668)
		(layer "In4.Cu")
		(net "FM_DBP_CPU_PREQ_GF_R_N")
	)
	(segment
		(start 21.474176 -112.20196)
		(end 22.61108 -112.199674)
		(width 0.10668)
		(layer "In4.Cu")
		(net "FM_DBP_CPU_PREQ_GF_R_N")
	)
	(segment
		(start 9.256776 -28.99156)
		(end 7.6073 -28.99156)
		(width 0.10668)
		(layer "In4.Cu")
		(net "FM_DBP_CPU_PREQ_GF_R_N")
	)
	(segment
		(start 48.14062 -26.74874)
		(end 44.715176 -26.74874)
		(width 0.10668)
		(layer "In4.Cu")
		(net "FM_DBP_CPU_PREQ_GF_R_N")
	)
	(segment
		(start 28.79598 -17.01038)
		(end 27.0002 -15.2146)
		(width 0.10668)
		(layer "In4.Cu")
		(net "FM_DBP_CPU_PREQ_GF_R_N")
	)
	(segment
		(start 12.5222 -17.1958)
		(end 12.2936 -17.4244)
		(width 0.10668)
		(layer "In4.Cu")
		(net "FM_DBP_CPU_PREQ_GF_R_N")
	)
	(segment
		(start 13.2588 -17.1958)
		(end 12.5222 -17.1958)
		(width 0.10668)
		(layer "In4.Cu")
		(net "FM_DBP_CPU_PREQ_GF_R_N")
	)
	(segment
		(start 56.094884 -40.971216)
		(end 56.490108 -40.575992)
		(width 0.11684)
		(layer "F.Cu")
		(net "FM_DBP_BMC_PRDY_R_N")
	)
	(via
		(at 56.490108 -40.575992)
		(size 0.4572)
		(drill 0.254)
		(layers "F.Cu" "B.Cu")
		(net "FM_DBP_BMC_PRDY_R_N")
	)
	(segment
		(start 59.845194 -36.88461)
		(end 59.8932 -36.836604)
		(width 0.11684)
		(layer "B.Cu")
		(net "FM_DBP_BMC_PRDY_R_N")
	)
	(segment
		(start 56.878982 -39.930832)
		(end 56.878982 -39.637716)
		(width 0.11684)
		(layer "B.Cu")
		(net "FM_DBP_BMC_PRDY_R_N")
	)
	(segment
		(start 58.323734 -38.74135)
		(end 58.323734 -37.753036)
		(width 0.11684)
		(layer "B.Cu")
		(net "FM_DBP_BMC_PRDY_R_N")
	)
	(segment
		(start 59.8932 -36.836604)
		(end 60.054998 -36.769548)
		(width 0.11684)
		(layer "B.Cu")
		(net "FM_DBP_BMC_PRDY_R_N")
	)
	(segment
		(start 56.878982 -39.637716)
		(end 57.129172 -39.387526)
		(width 0.11684)
		(layer "B.Cu")
		(net "FM_DBP_BMC_PRDY_R_N")
	)
	(segment
		(start 61.0362 -35.404298)
		(end 61.402722 -35.037776)
		(width 0.11684)
		(layer "B.Cu")
		(net "FM_DBP_BMC_PRDY_R_N")
	)
	(segment
		(start 60.054998 -36.769548)
		(end 61.0362 -35.788346)
		(width 0.11684)
		(layer "B.Cu")
		(net "FM_DBP_BMC_PRDY_R_N")
	)
	(segment
		(start 56.878728 -39.937182)
		(end 56.878728 -39.931086)
		(width 0.11684)
		(layer "B.Cu")
		(net "FM_DBP_BMC_PRDY_R_N")
	)
	(segment
		(start 57.129172 -39.387526)
		(end 57.677558 -39.387526)
		(width 0.11684)
		(layer "B.Cu")
		(net "FM_DBP_BMC_PRDY_R_N")
	)
	(segment
		(start 61.0362 -35.788346)
		(end 61.0362 -35.404298)
		(width 0.11684)
		(layer "B.Cu")
		(net "FM_DBP_BMC_PRDY_R_N")
	)
	(segment
		(start 58.323734 -37.753036)
		(end 58.729626 -37.347144)
		(width 0.11684)
		(layer "B.Cu")
		(net "FM_DBP_BMC_PRDY_R_N")
	)
	(segment
		(start 57.677558 -39.387526)
		(end 58.323734 -38.74135)
		(width 0.11684)
		(layer "B.Cu")
		(net "FM_DBP_BMC_PRDY_R_N")
	)
	(segment
		(start 56.490108 -40.575992)
		(end 56.490108 -40.325802)
		(width 0.11684)
		(layer "B.Cu")
		(net "FM_DBP_BMC_PRDY_R_N")
	)
	(segment
		(start 58.729626 -37.347144)
		(end 59.845194 -36.88461)
		(width 0.11684)
		(layer "B.Cu")
		(net "FM_DBP_BMC_PRDY_R_N")
	)
	(segment
		(start 56.878728 -39.931086)
		(end 56.878982 -39.930832)
		(width 0.11684)
		(layer "B.Cu")
		(net "FM_DBP_BMC_PRDY_R_N")
	)
	(segment
		(start 61.402722 -35.037776)
		(end 61.423804 -35.037776)
		(width 0.11684)
		(layer "B.Cu")
		(net "FM_DBP_BMC_PRDY_R_N")
	)
	(segment
		(start 56.490108 -40.325802)
		(end 56.878728 -39.937182)
		(width 0.11684)
		(layer "B.Cu")
		(net "FM_DBP_BMC_PRDY_R_N")
	)
	(via
		(at 61.595 -32.766)
		(size 0.508)
		(drill 0.254)
		(layers "F.Cu" "B.Cu")
		(net "FM_DBP_BMC_PRDY_N")
	)
	(via
		(at 24.32558 -111.23168)
		(size 0.508)
		(drill 0.254)
		(layers "F.Cu" "B.Cu")
		(net "FM_DBP_BMC_PRDY_N")
	)
	(segment
		(start 27.77744 -113.14684)
		(end 27.77744 -114.7191)
		(width 0.11684)
		(layer "B.Cu")
		(net "FM_DBP_BMC_PRDY_N")
	)
	(segment
		(start 26.345134 -117.355366)
		(end 26.345134 -118.25986)
		(width 0.11684)
		(layer "B.Cu")
		(net "FM_DBP_BMC_PRDY_N")
	)
	(segment
		(start 61.0616 -33.2994)
		(end 61.0616 -33.875472)
		(width 0.11684)
		(layer "B.Cu")
		(net "FM_DBP_BMC_PRDY_N")
	)
	(segment
		(start 24.32558 -111.23168)
		(end 25.86228 -111.23168)
		(width 0.11684)
		(layer "B.Cu")
		(net "FM_DBP_BMC_PRDY_N")
	)
	(segment
		(start 61.0616 -33.875472)
		(end 61.423804 -34.237676)
		(width 0.11684)
		(layer "B.Cu")
		(net "FM_DBP_BMC_PRDY_N")
	)
	(segment
		(start 27.77744 -114.7191)
		(end 26.4668 -116.02974)
		(width 0.11684)
		(layer "B.Cu")
		(net "FM_DBP_BMC_PRDY_N")
	)
	(segment
		(start 26.4668 -117.2337)
		(end 26.345134 -117.355366)
		(width 0.11684)
		(layer "B.Cu")
		(net "FM_DBP_BMC_PRDY_N")
	)
	(segment
		(start 61.595 -32.766)
		(end 61.0616 -33.2994)
		(width 0.11684)
		(layer "B.Cu")
		(net "FM_DBP_BMC_PRDY_N")
	)
	(segment
		(start 26.4668 -116.02974)
		(end 26.4668 -117.2337)
		(width 0.11684)
		(layer "B.Cu")
		(net "FM_DBP_BMC_PRDY_N")
	)
	(segment
		(start 25.86228 -111.23168)
		(end 27.77744 -113.14684)
		(width 0.11684)
		(layer "B.Cu")
		(net "FM_DBP_BMC_PRDY_N")
	)
	(segment
		(start 61.595 -31.642558)
		(end 61.595 -32.766)
		(width 0.10668)
		(layer "In4.Cu")
		(net "FM_DBP_BMC_PRDY_N")
	)
	(segment
		(start 20.27936 -114.48796)
		(end 18.843498 -113.052098)
		(width 0.10668)
		(layer "In4.Cu")
		(net "FM_DBP_BMC_PRDY_N")
	)
	(segment
		(start 39.26459 -23.824946)
		(end 40.465248 -22.624288)
		(width 0.10668)
		(layer "In4.Cu")
		(net "FM_DBP_BMC_PRDY_N")
	)
	(segment
		(start 59.1566 -26.2509)
		(end 59.1566 -27.284172)
		(width 0.10668)
		(layer "In4.Cu")
		(net "FM_DBP_BMC_PRDY_N")
	)
	(segment
		(start 59.74842 -29.091636)
		(end 60.02528 -29.759148)
		(width 0.10668)
		(layer "In4.Cu")
		(net "FM_DBP_BMC_PRDY_N")
	)
	(segment
		(start 26.1874 -14.0208)
		(end 28.7528 -14.0208)
		(width 0.10668)
		(layer "In4.Cu")
		(net "FM_DBP_BMC_PRDY_N")
	)
	(segment
		(start 12.9413 -23.2791)
		(end 12.9413 -23.262336)
		(width 0.10668)
		(layer "In4.Cu")
		(net "FM_DBP_BMC_PRDY_N")
	)
	(segment
		(start 1.759712 -107.957112)
		(end 1.759712 -88.042496)
		(width 0.10668)
		(layer "In4.Cu")
		(net "FM_DBP_BMC_PRDY_N")
	)
	(segment
		(start 23.5204 -112.3188)
		(end 23.5204 -113.11636)
		(width 0.10668)
		(layer "In4.Cu")
		(net "FM_DBP_BMC_PRDY_N")
	)
	(segment
		(start 12.39901 -25.529794)
		(end 12.39901 -24.881078)
		(width 0.10668)
		(layer "In4.Cu")
		(net "FM_DBP_BMC_PRDY_N")
	)
	(segment
		(start 12.94892 -23.28672)
		(end 12.9413 -23.2791)
		(width 0.10668)
		(layer "In4.Cu")
		(net "FM_DBP_BMC_PRDY_N")
	)
	(segment
		(start 31.93542 -19.485864)
		(end 31.93542 -20.77466)
		(width 0.10668)
		(layer "In4.Cu")
		(net "FM_DBP_BMC_PRDY_N")
	)
	(segment
		(start 24.32558 -111.23168)
		(end 24.32558 -111.51362)
		(width 0.10668)
		(layer "In4.Cu")
		(net "FM_DBP_BMC_PRDY_N")
	)
	(segment
		(start 48.971454 -20.8026)
		(end 52.806854 -24.638)
		(width 0.10668)
		(layer "In4.Cu")
		(net "FM_DBP_BMC_PRDY_N")
	)
	(segment
		(start 12.94892 -24.331168)
		(end 12.94892 -23.28672)
		(width 0.10668)
		(layer "In4.Cu")
		(net "FM_DBP_BMC_PRDY_N")
	)
	(segment
		(start 31.93542 -20.77466)
		(end 34.985706 -23.824946)
		(width 0.10668)
		(layer "In4.Cu")
		(net "FM_DBP_BMC_PRDY_N")
	)
	(segment
		(start 1.759712 -88.042496)
		(end 4.407916 -85.394292)
		(width 0.10668)
		(layer "In4.Cu")
		(net "FM_DBP_BMC_PRDY_N")
	)
	(segment
		(start 18.843498 -113.052098)
		(end 17.110964 -113.052098)
		(width 0.10668)
		(layer "In4.Cu")
		(net "FM_DBP_BMC_PRDY_N")
	)
	(segment
		(start 25.908 -13.7414)
		(end 26.1874 -14.0208)
		(width 0.10668)
		(layer "In4.Cu")
		(net "FM_DBP_BMC_PRDY_N")
	)
	(segment
		(start 40.465248 -22.624288)
		(end 43.278552 -22.624288)
		(width 0.10668)
		(layer "In4.Cu")
		(net "FM_DBP_BMC_PRDY_N")
	)
	(segment
		(start 43.89882 -19.190716)
		(end 44.27728 -18.812256)
		(width 0.10668)
		(layer "In4.Cu")
		(net "FM_DBP_BMC_PRDY_N")
	)
	(segment
		(start 11.28776 -21.608796)
		(end 11.28776 -16.554196)
		(width 0.10668)
		(layer "In4.Cu")
		(net "FM_DBP_BMC_PRDY_N")
	)
	(segment
		(start 44.27728 -18.812256)
		(end 45.548296 -18.812256)
		(width 0.10668)
		(layer "In4.Cu")
		(net "FM_DBP_BMC_PRDY_N")
	)
	(segment
		(start 28.7528 -14.0208)
		(end 31.497778 -16.765778)
		(width 0.10668)
		(layer "In4.Cu")
		(net "FM_DBP_BMC_PRDY_N")
	)
	(segment
		(start 59.1566 -27.284172)
		(end 59.74842 -27.875992)
		(width 0.10668)
		(layer "In4.Cu")
		(net "FM_DBP_BMC_PRDY_N")
	)
	(segment
		(start 4.407916 -85.394292)
		(end 4.407916 -81.012792)
		(width 0.10668)
		(layer "In4.Cu")
		(net "FM_DBP_BMC_PRDY_N")
	)
	(segment
		(start 47.53864 -20.8026)
		(end 48.971454 -20.8026)
		(width 0.10668)
		(layer "In4.Cu")
		(net "FM_DBP_BMC_PRDY_N")
	)
	(segment
		(start 11.28776 -16.554196)
		(end 11.9634 -15.878556)
		(width 0.10668)
		(layer "In4.Cu")
		(net "FM_DBP_BMC_PRDY_N")
	)
	(segment
		(start 22.1488 -114.48796)
		(end 20.27936 -114.48796)
		(width 0.10668)
		(layer "In4.Cu")
		(net "FM_DBP_BMC_PRDY_N")
	)
	(segment
		(start 1.658112 -78.262988)
		(end 1.658112 -30.879034)
		(width 0.10668)
		(layer "In4.Cu")
		(net "FM_DBP_BMC_PRDY_N")
	)
	(segment
		(start 45.548296 -18.812256)
		(end 47.53864 -20.8026)
		(width 0.10668)
		(layer "In4.Cu")
		(net "FM_DBP_BMC_PRDY_N")
	)
	(segment
		(start 60.02528 -30.072838)
		(end 61.595 -31.642558)
		(width 0.10668)
		(layer "In4.Cu")
		(net "FM_DBP_BMC_PRDY_N")
	)
	(segment
		(start 11.9634 -15.878556)
		(end 11.9634 -12.8016)
		(width 0.10668)
		(layer "In4.Cu")
		(net "FM_DBP_BMC_PRDY_N")
	)
	(segment
		(start 6.34492 -112.54232)
		(end 1.759712 -107.957112)
		(width 0.10668)
		(layer "In4.Cu")
		(net "FM_DBP_BMC_PRDY_N")
	)
	(segment
		(start 31.497778 -19.048222)
		(end 31.93542 -19.485864)
		(width 0.10668)
		(layer "In4.Cu")
		(net "FM_DBP_BMC_PRDY_N")
	)
	(segment
		(start 60.02528 -29.759148)
		(end 60.02528 -30.072838)
		(width 0.10668)
		(layer "In4.Cu")
		(net "FM_DBP_BMC_PRDY_N")
	)
	(segment
		(start 23.5204 -113.11636)
		(end 22.1488 -114.48796)
		(width 0.10668)
		(layer "In4.Cu")
		(net "FM_DBP_BMC_PRDY_N")
	)
	(segment
		(start 34.985706 -23.824946)
		(end 39.26459 -23.824946)
		(width 0.10668)
		(layer "In4.Cu")
		(net "FM_DBP_BMC_PRDY_N")
	)
	(segment
		(start 59.74842 -27.875992)
		(end 59.74842 -29.091636)
		(width 0.10668)
		(layer "In4.Cu")
		(net "FM_DBP_BMC_PRDY_N")
	)
	(segment
		(start 24.32558 -111.51362)
		(end 23.5204 -112.3188)
		(width 0.10668)
		(layer "In4.Cu")
		(net "FM_DBP_BMC_PRDY_N")
	)
	(segment
		(start 12.39901 -24.881078)
		(end 12.94892 -24.331168)
		(width 0.10668)
		(layer "In4.Cu")
		(net "FM_DBP_BMC_PRDY_N")
	)
	(segment
		(start 12.6238 -12.1412)
		(end 25.019 -12.1412)
		(width 0.10668)
		(layer "In4.Cu")
		(net "FM_DBP_BMC_PRDY_N")
	)
	(segment
		(start 4.772406 -27.76474)
		(end 7.5692 -27.76474)
		(width 0.10668)
		(layer "In4.Cu")
		(net "FM_DBP_BMC_PRDY_N")
	)
	(segment
		(start 4.407916 -81.012792)
		(end 1.658112 -78.262988)
		(width 0.10668)
		(layer "In4.Cu")
		(net "FM_DBP_BMC_PRDY_N")
	)
	(segment
		(start 7.5692 -27.76474)
		(end 9.0043 -26.32964)
		(width 0.10668)
		(layer "In4.Cu")
		(net "FM_DBP_BMC_PRDY_N")
	)
	(segment
		(start 25.908 -13.0302)
		(end 25.908 -13.7414)
		(width 0.10668)
		(layer "In4.Cu")
		(net "FM_DBP_BMC_PRDY_N")
	)
	(segment
		(start 11.9634 -12.8016)
		(end 12.6238 -12.1412)
		(width 0.10668)
		(layer "In4.Cu")
		(net "FM_DBP_BMC_PRDY_N")
	)
	(segment
		(start 16.601186 -112.54232)
		(end 6.34492 -112.54232)
		(width 0.10668)
		(layer "In4.Cu")
		(net "FM_DBP_BMC_PRDY_N")
	)
	(segment
		(start 52.806854 -24.638)
		(end 58.792872 -24.638)
		(width 0.10668)
		(layer "In4.Cu")
		(net "FM_DBP_BMC_PRDY_N")
	)
	(segment
		(start 59.47029 -25.93721)
		(end 59.1566 -26.2509)
		(width 0.10668)
		(layer "In4.Cu")
		(net "FM_DBP_BMC_PRDY_N")
	)
	(segment
		(start 25.019 -12.1412)
		(end 25.908 -13.0302)
		(width 0.10668)
		(layer "In4.Cu")
		(net "FM_DBP_BMC_PRDY_N")
	)
	(segment
		(start 43.89882 -22.00402)
		(end 43.89882 -19.190716)
		(width 0.10668)
		(layer "In4.Cu")
		(net "FM_DBP_BMC_PRDY_N")
	)
	(segment
		(start 58.792872 -24.638)
		(end 59.47029 -25.315418)
		(width 0.10668)
		(layer "In4.Cu")
		(net "FM_DBP_BMC_PRDY_N")
	)
	(segment
		(start 59.47029 -25.315418)
		(end 59.47029 -25.93721)
		(width 0.10668)
		(layer "In4.Cu")
		(net "FM_DBP_BMC_PRDY_N")
	)
	(segment
		(start 17.110964 -113.052098)
		(end 16.601186 -112.54232)
		(width 0.10668)
		(layer "In4.Cu")
		(net "FM_DBP_BMC_PRDY_N")
	)
	(segment
		(start 12.9413 -23.262336)
		(end 11.28776 -21.608796)
		(width 0.10668)
		(layer "In4.Cu")
		(net "FM_DBP_BMC_PRDY_N")
	)
	(segment
		(start 9.0043 -26.32964)
		(end 11.599164 -26.32964)
		(width 0.10668)
		(layer "In4.Cu")
		(net "FM_DBP_BMC_PRDY_N")
	)
	(segment
		(start 43.278552 -22.624288)
		(end 43.89882 -22.00402)
		(width 0.10668)
		(layer "In4.Cu")
		(net "FM_DBP_BMC_PRDY_N")
	)
	(segment
		(start 1.658112 -30.879034)
		(end 4.772406 -27.76474)
		(width 0.10668)
		(layer "In4.Cu")
		(net "FM_DBP_BMC_PRDY_N")
	)
	(segment
		(start 11.599164 -26.32964)
		(end 12.39901 -25.529794)
		(width 0.10668)
		(layer "In4.Cu")
		(net "FM_DBP_BMC_PRDY_N")
	)
	(segment
		(start 31.497778 -16.765778)
		(end 31.497778 -19.048222)
		(width 0.10668)
		(layer "In4.Cu")
		(net "FM_DBP_BMC_PRDY_N")
	)
	(segment
		(start 47.295054 -45.771308)
		(end 46.89983 -45.376084)
		(width 0.11684)
		(layer "F.Cu")
		(net "FM_BMC_MUX_CS_SPI_SEL_0")
	)
	(via
		(at 46.89983 -45.376084)
		(size 0.4572)
		(drill 0.254)
		(layers "F.Cu" "B.Cu")
		(net "FM_BMC_MUX_CS_SPI_SEL_0")
	)
	(via
		(at 41.783 -79.9592)
		(size 0.508)
		(drill 0.254)
		(layers "F.Cu" "B.Cu")
		(net "FM_BMC_MUX_CS_SPI_SEL_0")
	)
	(via
		(at 10.1346 -53.594)
		(size 0.508)
		(drill 0.254)
		(layers "F.Cu" "B.Cu")
		(net "FM_BMC_MUX_CS_SPI_SEL_0")
	)
	(via
		(at 9.9314 -81.6864)
		(size 0.508)
		(drill 0.254)
		(layers "F.Cu" "B.Cu")
		(net "FM_BMC_MUX_CS_SPI_SEL_0")
	)
	(segment
		(start 41.783 -79.3496)
		(end 41.783 -79.9592)
		(width 0.11684)
		(layer "B.Cu")
		(net "FM_BMC_MUX_CS_SPI_SEL_0")
	)
	(segment
		(start 42.2402 -75.47864)
		(end 42.2402 -78.8924)
		(width 0.11684)
		(layer "B.Cu")
		(net "FM_BMC_MUX_CS_SPI_SEL_0")
	)
	(segment
		(start 43.511978 -76.405232)
		(end 43.511978 -75.993244)
		(width 0.11684)
		(layer "B.Cu")
		(net "FM_BMC_MUX_CS_SPI_SEL_0")
	)
	(segment
		(start 42.48404 -75.2348)
		(end 42.2402 -75.47864)
		(width 0.11684)
		(layer "B.Cu")
		(net "FM_BMC_MUX_CS_SPI_SEL_0")
	)
	(segment
		(start 43.511978 -75.993244)
		(end 43.48861 -75.969876)
		(width 0.11684)
		(layer "B.Cu")
		(net "FM_BMC_MUX_CS_SPI_SEL_0")
	)
	(segment
		(start 43.2816 -75.2348)
		(end 42.48404 -75.2348)
		(width 0.11684)
		(layer "B.Cu")
		(net "FM_BMC_MUX_CS_SPI_SEL_0")
	)
	(segment
		(start 43.48861 -75.969876)
		(end 43.48861 -75.44181)
		(width 0.11684)
		(layer "B.Cu")
		(net "FM_BMC_MUX_CS_SPI_SEL_0")
	)
	(segment
		(start 43.48861 -75.44181)
		(end 43.2816 -75.2348)
		(width 0.11684)
		(layer "B.Cu")
		(net "FM_BMC_MUX_CS_SPI_SEL_0")
	)
	(segment
		(start 43.48861 -76.4286)
		(end 43.511978 -76.405232)
		(width 0.11684)
		(layer "B.Cu")
		(net "FM_BMC_MUX_CS_SPI_SEL_0")
	)
	(segment
		(start 42.2402 -78.8924)
		(end 41.783 -79.3496)
		(width 0.11684)
		(layer "B.Cu")
		(net "FM_BMC_MUX_CS_SPI_SEL_0")
	)
	(segment
		(start 23.241 -73.9648)
		(end 24.25954 -74.98334)
		(width 0.08382)
		(layer "In2.Cu")
		(net "FM_BMC_MUX_CS_SPI_SEL_0")
	)
	(segment
		(start 25.40254 -42.29608)
		(end 22.762972 -44.935648)
		(width 0.08382)
		(layer "In2.Cu")
		(net "FM_BMC_MUX_CS_SPI_SEL_0")
	)
	(segment
		(start 37.581586 -79.02956)
		(end 39.252144 -79.02956)
		(width 0.08382)
		(layer "In2.Cu")
		(net "FM_BMC_MUX_CS_SPI_SEL_0")
	)
	(segment
		(start 10.1346 -52.3494)
		(end 10.1346 -53.594)
		(width 0.08382)
		(layer "In2.Cu")
		(net "FM_BMC_MUX_CS_SPI_SEL_0")
	)
	(segment
		(start 40.6146 -46.6852)
		(end 39.0906 -48.2092)
		(width 0.08382)
		(layer "In2.Cu")
		(net "FM_BMC_MUX_CS_SPI_SEL_0")
	)
	(segment
		(start 22.762972 -49.207928)
		(end 21.39061 -50.58029)
		(width 0.08382)
		(layer "In2.Cu")
		(net "FM_BMC_MUX_CS_SPI_SEL_0")
	)
	(segment
		(start 27.571954 -78.5622)
		(end 31.7754 -78.5622)
		(width 0.08382)
		(layer "In2.Cu")
		(net "FM_BMC_MUX_CS_SPI_SEL_0")
	)
	(segment
		(start 24.25954 -75.249786)
		(end 27.571954 -78.5622)
		(width 0.08382)
		(layer "In2.Cu")
		(net "FM_BMC_MUX_CS_SPI_SEL_0")
	)
	(segment
		(start 13.8684 -80.264)
		(end 14.63675 -79.49565)
		(width 0.08382)
		(layer "In2.Cu")
		(net "FM_BMC_MUX_CS_SPI_SEL_0")
	)
	(segment
		(start 22.169374 -73.9648)
		(end 23.241 -73.9648)
		(width 0.08382)
		(layer "In2.Cu")
		(net "FM_BMC_MUX_CS_SPI_SEL_0")
	)
	(segment
		(start 11.22172 -81.6864)
		(end 12.64412 -80.264)
		(width 0.08382)
		(layer "In2.Cu")
		(net "FM_BMC_MUX_CS_SPI_SEL_0")
	)
	(segment
		(start 17.032986 -51.51628)
		(end 16.02994 -51.51628)
		(width 0.08382)
		(layer "In2.Cu")
		(net "FM_BMC_MUX_CS_SPI_SEL_0")
	)
	(segment
		(start 40.31234 -79.51216)
		(end 40.89273 -80.09255)
		(width 0.08382)
		(layer "In2.Cu")
		(net "FM_BMC_MUX_CS_SPI_SEL_0")
	)
	(segment
		(start 15.400782 -50.32629)
		(end 12.15771 -50.32629)
		(width 0.08382)
		(layer "In2.Cu")
		(net "FM_BMC_MUX_CS_SPI_SEL_0")
	)
	(segment
		(start 35.758628 -79.6798)
		(end 36.931346 -79.6798)
		(width 0.08382)
		(layer "In2.Cu")
		(net "FM_BMC_MUX_CS_SPI_SEL_0")
	)
	(segment
		(start 28.617672 -42.29608)
		(end 25.40254 -42.29608)
		(width 0.08382)
		(layer "In2.Cu")
		(net "FM_BMC_MUX_CS_SPI_SEL_0")
	)
	(segment
		(start 45.674026 -45.003974)
		(end 43.9928 -46.6852)
		(width 0.08382)
		(layer "In2.Cu")
		(net "FM_BMC_MUX_CS_SPI_SEL_0")
	)
	(segment
		(start 15.80388 -50.729388)
		(end 15.400782 -50.32629)
		(width 0.08382)
		(layer "In2.Cu")
		(net "FM_BMC_MUX_CS_SPI_SEL_0")
	)
	(segment
		(start 15.80388 -51.29022)
		(end 15.80388 -50.729388)
		(width 0.08382)
		(layer "In2.Cu")
		(net "FM_BMC_MUX_CS_SPI_SEL_0")
	)
	(segment
		(start 15.494 -75.006454)
		(end 17.457674 -73.04278)
		(width 0.08382)
		(layer "In2.Cu")
		(net "FM_BMC_MUX_CS_SPI_SEL_0")
	)
	(segment
		(start 39.0906 -48.2092)
		(end 38.6588 -48.2092)
		(width 0.08382)
		(layer "In2.Cu")
		(net "FM_BMC_MUX_CS_SPI_SEL_0")
	)
	(segment
		(start 24.25954 -74.98334)
		(end 24.25954 -75.249786)
		(width 0.08382)
		(layer "In2.Cu")
		(net "FM_BMC_MUX_CS_SPI_SEL_0")
	)
	(segment
		(start 16.02994 -51.51628)
		(end 15.80388 -51.29022)
		(width 0.08382)
		(layer "In2.Cu")
		(net "FM_BMC_MUX_CS_SPI_SEL_0")
	)
	(segment
		(start 32.09544 -78.88224)
		(end 34.961068 -78.88224)
		(width 0.08382)
		(layer "In2.Cu")
		(net "FM_BMC_MUX_CS_SPI_SEL_0")
	)
	(segment
		(start 22.762972 -44.935648)
		(end 22.762972 -49.207928)
		(width 0.08382)
		(layer "In2.Cu")
		(net "FM_BMC_MUX_CS_SPI_SEL_0")
	)
	(segment
		(start 17.968976 -50.58029)
		(end 17.032986 -51.51628)
		(width 0.08382)
		(layer "In2.Cu")
		(net "FM_BMC_MUX_CS_SPI_SEL_0")
	)
	(segment
		(start 46.89983 -45.376084)
		(end 46.52772 -45.003974)
		(width 0.08382)
		(layer "In2.Cu")
		(net "FM_BMC_MUX_CS_SPI_SEL_0")
	)
	(segment
		(start 38.6588 -48.2092)
		(end 37.929566 -47.479966)
		(width 0.08382)
		(layer "In2.Cu")
		(net "FM_BMC_MUX_CS_SPI_SEL_0")
	)
	(segment
		(start 19.789648 -72.766682)
		(end 20.971256 -72.766682)
		(width 0.08382)
		(layer "In2.Cu")
		(net "FM_BMC_MUX_CS_SPI_SEL_0")
	)
	(segment
		(start 31.7754 -78.5622)
		(end 32.09544 -78.88224)
		(width 0.08382)
		(layer "In2.Cu")
		(net "FM_BMC_MUX_CS_SPI_SEL_0")
	)
	(segment
		(start 31.10992 -44.788328)
		(end 28.617672 -42.29608)
		(width 0.08382)
		(layer "In2.Cu")
		(net "FM_BMC_MUX_CS_SPI_SEL_0")
	)
	(segment
		(start 46.52772 -45.003974)
		(end 45.674026 -45.003974)
		(width 0.08382)
		(layer "In2.Cu")
		(net "FM_BMC_MUX_CS_SPI_SEL_0")
	)
	(segment
		(start 19.123152 -73.04278)
		(end 19.789648 -72.766682)
		(width 0.08382)
		(layer "In2.Cu")
		(net "FM_BMC_MUX_CS_SPI_SEL_0")
	)
	(segment
		(start 31.779464 -47.479966)
		(end 31.10992 -46.810422)
		(width 0.08382)
		(layer "In2.Cu")
		(net "FM_BMC_MUX_CS_SPI_SEL_0")
	)
	(segment
		(start 14.63675 -79.49565)
		(end 15.494 -77.42428)
		(width 0.08382)
		(layer "In2.Cu")
		(net "FM_BMC_MUX_CS_SPI_SEL_0")
	)
	(segment
		(start 12.15771 -50.32629)
		(end 10.1346 -52.3494)
		(width 0.08382)
		(layer "In2.Cu")
		(net "FM_BMC_MUX_CS_SPI_SEL_0")
	)
	(segment
		(start 41.64965 -80.09255)
		(end 41.783 -79.9592)
		(width 0.08382)
		(layer "In2.Cu")
		(net "FM_BMC_MUX_CS_SPI_SEL_0")
	)
	(segment
		(start 39.734744 -79.51216)
		(end 40.31234 -79.51216)
		(width 0.08382)
		(layer "In2.Cu")
		(net "FM_BMC_MUX_CS_SPI_SEL_0")
	)
	(segment
		(start 39.252144 -79.02956)
		(end 39.734744 -79.51216)
		(width 0.08382)
		(layer "In2.Cu")
		(net "FM_BMC_MUX_CS_SPI_SEL_0")
	)
	(segment
		(start 17.457674 -73.04278)
		(end 19.123152 -73.04278)
		(width 0.08382)
		(layer "In2.Cu")
		(net "FM_BMC_MUX_CS_SPI_SEL_0")
	)
	(segment
		(start 37.929566 -47.479966)
		(end 31.779464 -47.479966)
		(width 0.08382)
		(layer "In2.Cu")
		(net "FM_BMC_MUX_CS_SPI_SEL_0")
	)
	(segment
		(start 31.10992 -46.810422)
		(end 31.10992 -44.788328)
		(width 0.08382)
		(layer "In2.Cu")
		(net "FM_BMC_MUX_CS_SPI_SEL_0")
	)
	(segment
		(start 20.971256 -72.766682)
		(end 22.169374 -73.9648)
		(width 0.08382)
		(layer "In2.Cu")
		(net "FM_BMC_MUX_CS_SPI_SEL_0")
	)
	(segment
		(start 9.9314 -81.6864)
		(end 11.22172 -81.6864)
		(width 0.08382)
		(layer "In2.Cu")
		(net "FM_BMC_MUX_CS_SPI_SEL_0")
	)
	(segment
		(start 36.931346 -79.6798)
		(end 37.581586 -79.02956)
		(width 0.08382)
		(layer "In2.Cu")
		(net "FM_BMC_MUX_CS_SPI_SEL_0")
	)
	(segment
		(start 34.961068 -78.88224)
		(end 35.758628 -79.6798)
		(width 0.08382)
		(layer "In2.Cu")
		(net "FM_BMC_MUX_CS_SPI_SEL_0")
	)
	(segment
		(start 12.64412 -80.264)
		(end 13.8684 -80.264)
		(width 0.08382)
		(layer "In2.Cu")
		(net "FM_BMC_MUX_CS_SPI_SEL_0")
	)
	(segment
		(start 15.494 -77.42428)
		(end 15.494 -75.006454)
		(width 0.08382)
		(layer "In2.Cu")
		(net "FM_BMC_MUX_CS_SPI_SEL_0")
	)
	(segment
		(start 21.39061 -50.58029)
		(end 17.968976 -50.58029)
		(width 0.08382)
		(layer "In2.Cu")
		(net "FM_BMC_MUX_CS_SPI_SEL_0")
	)
	(segment
		(start 40.89273 -80.09255)
		(end 41.64965 -80.09255)
		(width 0.08382)
		(layer "In2.Cu")
		(net "FM_BMC_MUX_CS_SPI_SEL_0")
	)
	(segment
		(start 43.9928 -46.6852)
		(end 40.6146 -46.6852)
		(width 0.08382)
		(layer "In2.Cu")
		(net "FM_BMC_MUX_CS_SPI_SEL_0")
	)
	(segment
		(start 12.44727 -56.662066)
		(end 11.046206 -55.261002)
		(width 0.08382)
		(layer "In9.Cu")
		(net "FM_BMC_MUX_CS_SPI_SEL_0")
	)
	(segment
		(start 11.352022 -79.590646)
		(end 11.362182 -79.579978)
		(width 0.08382)
		(layer "In9.Cu")
		(net "FM_BMC_MUX_CS_SPI_SEL_0")
	)
	(segment
		(start 11.362182 -79.579978)
		(end 11.5824 -79.359506)
		(width 0.08382)
		(layer "In9.Cu")
		(net "FM_BMC_MUX_CS_SPI_SEL_0")
	)
	(segment
		(start 10.60069 -81.01711)
		(end 10.60069 -80.341724)
		(width 0.08382)
		(layer "In9.Cu")
		(net "FM_BMC_MUX_CS_SPI_SEL_0")
	)
	(segment
		(start 11.338052 -60.492132)
		(end 12.44727 -59.382914)
		(width 0.08382)
		(layer "In9.Cu")
		(net "FM_BMC_MUX_CS_SPI_SEL_0")
	)
	(segment
		(start 11.5824 -79.359506)
		(end 11.5824 -76.237846)
		(width 0.08382)
		(layer "In9.Cu")
		(net "FM_BMC_MUX_CS_SPI_SEL_0")
	)
	(segment
		(start 9.9314 -81.6864)
		(end 10.60069 -81.01711)
		(width 0.08382)
		(layer "In9.Cu")
		(net "FM_BMC_MUX_CS_SPI_SEL_0")
	)
	(segment
		(start 12.23391 -68.571872)
		(end 11.338052 -67.676014)
		(width 0.08382)
		(layer "In9.Cu")
		(net "FM_BMC_MUX_CS_SPI_SEL_0")
	)
	(segment
		(start 11.046206 -54.505606)
		(end 10.1346 -53.594)
		(width 0.08382)
		(layer "In9.Cu")
		(net "FM_BMC_MUX_CS_SPI_SEL_0")
	)
	(segment
		(start 12.44727 -59.382914)
		(end 12.44727 -56.662066)
		(width 0.08382)
		(layer "In9.Cu")
		(net "FM_BMC_MUX_CS_SPI_SEL_0")
	)
	(segment
		(start 11.046206 -55.261002)
		(end 11.046206 -54.505606)
		(width 0.08382)
		(layer "In9.Cu")
		(net "FM_BMC_MUX_CS_SPI_SEL_0")
	)
	(segment
		(start 11.338052 -67.676014)
		(end 11.338052 -60.492132)
		(width 0.08382)
		(layer "In9.Cu")
		(net "FM_BMC_MUX_CS_SPI_SEL_0")
	)
	(segment
		(start 12.23391 -75.586336)
		(end 12.23391 -68.571872)
		(width 0.08382)
		(layer "In9.Cu")
		(net "FM_BMC_MUX_CS_SPI_SEL_0")
	)
	(segment
		(start 10.60069 -80.341724)
		(end 11.352022 -79.590646)
		(width 0.08382)
		(layer "In9.Cu")
		(net "FM_BMC_MUX_CS_SPI_SEL_0")
	)
	(segment
		(start 11.5824 -76.237846)
		(end 12.23391 -75.586336)
		(width 0.08382)
		(layer "In9.Cu")
		(net "FM_BMC_MUX_CS_SPI_SEL_0")
	)
	(segment
		(start 45.284136 -33.628076)
		(end 45.063156 -33.628076)
		(width 0.11684)
		(layer "F.Cu")
		(net "FM_BMC_DBP_PRESENT_N")
	)
	(segment
		(start 43.656504 -31.769558)
		(end 43.1546 -31.267654)
		(width 0.11684)
		(layer "F.Cu")
		(net "FM_BMC_DBP_PRESENT_N")
	)
	(segment
		(start 44.59732 -33.16224)
		(end 44.02836 -33.16224)
		(width 0.11684)
		(layer "F.Cu")
		(net "FM_BMC_DBP_PRESENT_N")
	)
	(segment
		(start 44.02836 -33.16224)
		(end 43.86834 -33.00222)
		(width 0.11684)
		(layer "F.Cu")
		(net "FM_BMC_DBP_PRESENT_N")
	)
	(segment
		(start 43.1546 -31.267654)
		(end 42.828464 -31.267654)
		(width 0.11684)
		(layer "F.Cu")
		(net "FM_BMC_DBP_PRESENT_N")
	)
	(segment
		(start 45.063156 -33.628076)
		(end 44.59732 -33.16224)
		(width 0.11684)
		(layer "F.Cu")
		(net "FM_BMC_DBP_PRESENT_N")
	)
	(segment
		(start 45.72 -34.22015)
		(end 45.72 -34.06394)
		(width 0.11684)
		(layer "F.Cu")
		(net "FM_BMC_DBP_PRESENT_N")
	)
	(segment
		(start 45.72 -34.06394)
		(end 45.284136 -33.628076)
		(width 0.11684)
		(layer "F.Cu")
		(net "FM_BMC_DBP_PRESENT_N")
	)
	(segment
		(start 43.86834 -33.00222)
		(end 43.86834 -32.28086)
		(width 0.11684)
		(layer "F.Cu")
		(net "FM_BMC_DBP_PRESENT_N")
	)
	(segment
		(start 23.854664 -89.591896)
		(end 23.45944 -89.98712)
		(width 0.11684)
		(layer "F.Cu")
		(net "FM_BMC_DBP_PRESENT_N")
	)
	(segment
		(start 43.86834 -32.28086)
		(end 43.656504 -31.769558)
		(width 0.11684)
		(layer "F.Cu")
		(net "FM_BMC_DBP_PRESENT_N")
	)
	(via
		(at 23.854664 -89.591896)
		(size 0.4572)
		(drill 0.254)
		(layers "F.Cu" "B.Cu")
		(net "FM_BMC_DBP_PRESENT_N")
	)
	(via
		(at 45.284136 -33.628076)
		(size 0.508)
		(drill 0.254)
		(layers "F.Cu" "B.Cu")
		(net "FM_BMC_DBP_PRESENT_N")
	)
	(segment
		(start 29.138118 -36.10102)
		(end 27.329638 -37.9095)
		(width 0.10668)
		(layer "In4.Cu")
		(net "FM_BMC_DBP_PRESENT_N")
	)
	(segment
		(start 22.23262 -72.439784)
		(end 23.554182 -73.761346)
		(width 0.10668)
		(layer "In4.Cu")
		(net "FM_BMC_DBP_PRESENT_N")
	)
	(segment
		(start 45.284136 -33.628076)
		(end 44.79798 -33.14192)
		(width 0.10668)
		(layer "In4.Cu")
		(net "FM_BMC_DBP_PRESENT_N")
	)
	(segment
		(start 35.362642 -30.118558)
		(end 34.80816 -30.67304)
		(width 0.10668)
		(layer "In4.Cu")
		(net "FM_BMC_DBP_PRESENT_N")
	)
	(segment
		(start 42.94632 -30.64002)
		(end 37.11448 -30.64002)
		(width 0.10668)
		(layer "In4.Cu")
		(net "FM_BMC_DBP_PRESENT_N")
	)
	(segment
		(start 20.02282 -58.808366)
		(end 22.64664 -61.432186)
		(width 0.10668)
		(layer "In4.Cu")
		(net "FM_BMC_DBP_PRESENT_N")
	)
	(segment
		(start 19.642328 -49.300384)
		(end 19.642328 -50.589688)
		(width 0.10668)
		(layer "In4.Cu")
		(net "FM_BMC_DBP_PRESENT_N")
	)
	(segment
		(start 23.554182 -77.332078)
		(end 23.49246 -77.3938)
		(width 0.10668)
		(layer "In4.Cu")
		(net "FM_BMC_DBP_PRESENT_N")
	)
	(segment
		(start 20.02282 -50.97018)
		(end 20.02282 -58.808366)
		(width 0.10668)
		(layer "In4.Cu")
		(net "FM_BMC_DBP_PRESENT_N")
	)
	(segment
		(start 33.680146 -32.766)
		(end 33.274254 -32.766)
		(width 0.10668)
		(layer "In4.Cu")
		(net "FM_BMC_DBP_PRESENT_N")
	)
	(segment
		(start 22.94636 -81.760568)
		(end 22.94636 -83.363816)
		(width 0.10668)
		(layer "In4.Cu")
		(net "FM_BMC_DBP_PRESENT_N")
	)
	(segment
		(start 20.24761 -44.63796)
		(end 19.58594 -46.235366)
		(width 0.10668)
		(layer "In4.Cu")
		(net "FM_BMC_DBP_PRESENT_N")
	)
	(segment
		(start 22.94636 -83.363816)
		(end 22.7076 -83.602576)
		(width 0.10668)
		(layer "In4.Cu")
		(net "FM_BMC_DBP_PRESENT_N")
	)
	(segment
		(start 22.23262 -71.806562)
		(end 22.23262 -72.439784)
		(width 0.10668)
		(layer "In4.Cu")
		(net "FM_BMC_DBP_PRESENT_N")
	)
	(segment
		(start 44.79798 -32.49168)
		(end 42.94632 -30.64002)
		(width 0.10668)
		(layer "In4.Cu")
		(net "FM_BMC_DBP_PRESENT_N")
	)
	(segment
		(start 23.9268 -79.61884)
		(end 23.9268 -80.780128)
		(width 0.10668)
		(layer "In4.Cu")
		(net "FM_BMC_DBP_PRESENT_N")
	)
	(segment
		(start 23.471124 -88.418924)
		(end 23.471124 -89.208356)
		(width 0.10668)
		(layer "In4.Cu")
		(net "FM_BMC_DBP_PRESENT_N")
	)
	(segment
		(start 19.642328 -50.589688)
		(end 20.02282 -50.97018)
		(width 0.10668)
		(layer "In4.Cu")
		(net "FM_BMC_DBP_PRESENT_N")
	)
	(segment
		(start 22.7076 -84.418424)
		(end 22.94636 -84.657184)
		(width 0.10668)
		(layer "In4.Cu")
		(net "FM_BMC_DBP_PRESENT_N")
	)
	(segment
		(start 19.58594 -46.89475)
		(end 19.267424 -47.213266)
		(width 0.10668)
		(layer "In4.Cu")
		(net "FM_BMC_DBP_PRESENT_N")
	)
	(segment
		(start 29.939234 -36.10102)
		(end 29.138118 -36.10102)
		(width 0.10668)
		(layer "In4.Cu")
		(net "FM_BMC_DBP_PRESENT_N")
	)
	(segment
		(start 44.79798 -33.14192)
		(end 44.79798 -32.49168)
		(width 0.10668)
		(layer "In4.Cu")
		(net "FM_BMC_DBP_PRESENT_N")
	)
	(segment
		(start 27.329638 -37.9095)
		(end 26.97607 -37.9095)
		(width 0.10668)
		(layer "In4.Cu")
		(net "FM_BMC_DBP_PRESENT_N")
	)
	(segment
		(start 23.49246 -77.3938)
		(end 23.49246 -79.1845)
		(width 0.10668)
		(layer "In4.Cu")
		(net "FM_BMC_DBP_PRESENT_N")
	)
	(segment
		(start 19.23034 -48.888396)
		(end 19.642328 -49.300384)
		(width 0.10668)
		(layer "In4.Cu")
		(net "FM_BMC_DBP_PRESENT_N")
	)
	(segment
		(start 23.554182 -73.761346)
		(end 23.554182 -77.332078)
		(width 0.10668)
		(layer "In4.Cu")
		(net "FM_BMC_DBP_PRESENT_N")
	)
	(segment
		(start 34.80816 -30.67304)
		(end 34.80816 -32.57042)
		(width 0.10668)
		(layer "In4.Cu")
		(net "FM_BMC_DBP_PRESENT_N")
	)
	(segment
		(start 19.267424 -47.213266)
		(end 19.267424 -47.55896)
		(width 0.10668)
		(layer "In4.Cu")
		(net "FM_BMC_DBP_PRESENT_N")
	)
	(segment
		(start 22.7076 -83.602576)
		(end 22.7076 -84.418424)
		(width 0.10668)
		(layer "In4.Cu")
		(net "FM_BMC_DBP_PRESENT_N")
	)
	(segment
		(start 19.23034 -47.596044)
		(end 19.23034 -48.888396)
		(width 0.10668)
		(layer "In4.Cu")
		(net "FM_BMC_DBP_PRESENT_N")
	)
	(segment
		(start 23.64994 -64.572388)
		(end 23.503128 -64.7192)
		(width 0.10668)
		(layer "In4.Cu")
		(net "FM_BMC_DBP_PRESENT_N")
	)
	(segment
		(start 23.64994 -64.01054)
		(end 23.64994 -64.572388)
		(width 0.10668)
		(layer "In4.Cu")
		(net "FM_BMC_DBP_PRESENT_N")
	)
	(segment
		(start 34.80816 -32.57042)
		(end 34.40938 -32.9692)
		(width 0.10668)
		(layer "In4.Cu")
		(net "FM_BMC_DBP_PRESENT_N")
	)
	(segment
		(start 22.64664 -63.00724)
		(end 23.64994 -64.01054)
		(width 0.10668)
		(layer "In4.Cu")
		(net "FM_BMC_DBP_PRESENT_N")
	)
	(segment
		(start 33.274254 -32.766)
		(end 29.939234 -36.10102)
		(width 0.10668)
		(layer "In4.Cu")
		(net "FM_BMC_DBP_PRESENT_N")
	)
	(segment
		(start 22.94636 -87.89416)
		(end 23.471124 -88.418924)
		(width 0.10668)
		(layer "In4.Cu")
		(net "FM_BMC_DBP_PRESENT_N")
	)
	(segment
		(start 19.58594 -46.235366)
		(end 19.58594 -46.89475)
		(width 0.10668)
		(layer "In4.Cu")
		(net "FM_BMC_DBP_PRESENT_N")
	)
	(segment
		(start 26.97607 -37.9095)
		(end 20.24761 -44.63796)
		(width 0.10668)
		(layer "In4.Cu")
		(net "FM_BMC_DBP_PRESENT_N")
	)
	(segment
		(start 23.9268 -80.780128)
		(end 22.94636 -81.760568)
		(width 0.10668)
		(layer "In4.Cu")
		(net "FM_BMC_DBP_PRESENT_N")
	)
	(segment
		(start 19.267424 -47.55896)
		(end 19.23034 -47.596044)
		(width 0.10668)
		(layer "In4.Cu")
		(net "FM_BMC_DBP_PRESENT_N")
	)
	(segment
		(start 34.40938 -32.9692)
		(end 33.883346 -32.9692)
		(width 0.10668)
		(layer "In4.Cu")
		(net "FM_BMC_DBP_PRESENT_N")
	)
	(segment
		(start 22.64664 -61.432186)
		(end 22.64664 -63.00724)
		(width 0.10668)
		(layer "In4.Cu")
		(net "FM_BMC_DBP_PRESENT_N")
	)
	(segment
		(start 22.94636 -84.657184)
		(end 22.94636 -87.89416)
		(width 0.10668)
		(layer "In4.Cu")
		(net "FM_BMC_DBP_PRESENT_N")
	)
	(segment
		(start 33.883346 -32.9692)
		(end 33.680146 -32.766)
		(width 0.10668)
		(layer "In4.Cu")
		(net "FM_BMC_DBP_PRESENT_N")
	)
	(segment
		(start 22.3012 -64.7192)
		(end 21.8694 -65.151)
		(width 0.10668)
		(layer "In4.Cu")
		(net "FM_BMC_DBP_PRESENT_N")
	)
	(segment
		(start 21.6916 -71.265542)
		(end 22.23262 -71.806562)
		(width 0.10668)
		(layer "In4.Cu")
		(net "FM_BMC_DBP_PRESENT_N")
	)
	(segment
		(start 36.593018 -30.118558)
		(end 35.362642 -30.118558)
		(width 0.10668)
		(layer "In4.Cu")
		(net "FM_BMC_DBP_PRESENT_N")
	)
	(segment
		(start 23.503128 -64.7192)
		(end 22.3012 -64.7192)
		(width 0.10668)
		(layer "In4.Cu")
		(net "FM_BMC_DBP_PRESENT_N")
	)
	(segment
		(start 37.11448 -30.64002)
		(end 36.593018 -30.118558)
		(width 0.10668)
		(layer "In4.Cu")
		(net "FM_BMC_DBP_PRESENT_N")
	)
	(segment
		(start 23.49246 -79.1845)
		(end 23.9268 -79.61884)
		(width 0.10668)
		(layer "In4.Cu")
		(net "FM_BMC_DBP_PRESENT_N")
	)
	(segment
		(start 23.471124 -89.208356)
		(end 23.854664 -89.591896)
		(width 0.10668)
		(layer "In4.Cu")
		(net "FM_BMC_DBP_PRESENT_N")
	)
	(segment
		(start 21.8694 -66.624708)
		(end 21.6916 -66.802508)
		(width 0.10668)
		(layer "In4.Cu")
		(net "FM_BMC_DBP_PRESENT_N")
	)
	(segment
		(start 21.6916 -66.802508)
		(end 21.6916 -71.265542)
		(width 0.10668)
		(layer "In4.Cu")
		(net "FM_BMC_DBP_PRESENT_N")
	)
	(segment
		(start 21.8694 -65.151)
		(end 21.8694 -66.624708)
		(width 0.10668)
		(layer "In4.Cu")
		(net "FM_BMC_DBP_PRESENT_N")
	)
	(segment
		(start 20.66417 -95.982282)
		(end 21.059394 -95.587058)
		(width 0.11684)
		(layer "F.Cu")
		(net "FM_BMC_CPU_FBRK_OUT_R_N")
	)
	(via
		(at 10.7188 -110.7186)
		(size 0.508)
		(drill 0.254)
		(layers "F.Cu" "B.Cu")
		(net "FM_BMC_CPU_FBRK_OUT_R_N")
	)
	(via
		(at 27.069796 -71.127112)
		(size 0.508)
		(drill 0.254)
		(layers "F.Cu" "B.Cu")
		(net "FM_BMC_CPU_FBRK_OUT_R_N")
	)
	(via
		(at 9.017 -85.09)
		(size 0.508)
		(drill 0.254)
		(layers "F.Cu" "B.Cu")
		(net "FM_BMC_CPU_FBRK_OUT_R_N")
	)
	(via
		(at 41.1226 -38.227)
		(size 0.508)
		(drill 0.254)
		(layers "F.Cu" "B.Cu")
		(net "FM_BMC_CPU_FBRK_OUT_R_N")
	)
	(via
		(at 20.66417 -95.982282)
		(size 0.4572)
		(drill 0.254)
		(layers "F.Cu" "B.Cu")
		(net "FM_BMC_CPU_FBRK_OUT_R_N")
	)
	(segment
		(start 41.2496 -38.227)
		(end 41.1226 -38.227)
		(width 0.11684)
		(layer "B.Cu")
		(net "FM_BMC_CPU_FBRK_OUT_R_N")
	)
	(segment
		(start 42.164 -38.5064)
		(end 41.529 -38.5064)
		(width 0.11684)
		(layer "B.Cu")
		(net "FM_BMC_CPU_FBRK_OUT_R_N")
	)
	(segment
		(start 41.529 -38.5064)
		(end 41.2496 -38.227)
		(width 0.11684)
		(layer "B.Cu")
		(net "FM_BMC_CPU_FBRK_OUT_R_N")
	)
	(segment
		(start 42.6212 -38.9636)
		(end 42.164 -38.5064)
		(width 0.11684)
		(layer "B.Cu")
		(net "FM_BMC_CPU_FBRK_OUT_R_N")
	)
	(segment
		(start 8.289798 -81.39811)
		(end 7.2136 -82.473546)
		(width 0.08382)
		(layer "In2.Cu")
		(net "FM_BMC_CPU_FBRK_OUT_R_N")
	)
	(segment
		(start 8.611108 -85.09)
		(end 9.017 -85.09)
		(width 0.08382)
		(layer "In2.Cu")
		(net "FM_BMC_CPU_FBRK_OUT_R_N")
	)
	(segment
		(start 7.2136 -82.473546)
		(end 7.2136 -83.692492)
		(width 0.08382)
		(layer "In2.Cu")
		(net "FM_BMC_CPU_FBRK_OUT_R_N")
	)
	(segment
		(start 11.58494 -78.81366)
		(end 11.582146 -78.816454)
		(width 0.08382)
		(layer "In2.Cu")
		(net "FM_BMC_CPU_FBRK_OUT_R_N")
	)
	(segment
		(start 25.934924 -69.99224)
		(end 22.711664 -69.99224)
		(width 0.08382)
		(layer "In2.Cu")
		(net "FM_BMC_CPU_FBRK_OUT_R_N")
	)
	(segment
		(start 22.413214 -69.69379)
		(end 21.387054 -69.69379)
		(width 0.08382)
		(layer "In2.Cu")
		(net "FM_BMC_CPU_FBRK_OUT_R_N")
	)
	(segment
		(start 7.2136 -83.692492)
		(end 8.611108 -85.09)
		(width 0.08382)
		(layer "In2.Cu")
		(net "FM_BMC_CPU_FBRK_OUT_R_N")
	)
	(segment
		(start 8.721344 -81.39811)
		(end 8.289798 -81.39811)
		(width 0.08382)
		(layer "In2.Cu")
		(net "FM_BMC_CPU_FBRK_OUT_R_N")
	)
	(segment
		(start 19.670014 -67.97675)
		(end 15.10665 -67.97675)
		(width 0.08382)
		(layer "In2.Cu")
		(net "FM_BMC_CPU_FBRK_OUT_R_N")
	)
	(segment
		(start 15.10665 -67.97675)
		(end 14.18209 -68.90131)
		(width 0.08382)
		(layer "In2.Cu")
		(net "FM_BMC_CPU_FBRK_OUT_R_N")
	)
	(segment
		(start 11.80592 -77.77988)
		(end 11.58494 -78.00086)
		(width 0.08382)
		(layer "In2.Cu")
		(net "FM_BMC_CPU_FBRK_OUT_R_N")
	)
	(segment
		(start 10.017506 -80.48244)
		(end 9.91616 -80.48244)
		(width 0.08382)
		(layer "In2.Cu")
		(net "FM_BMC_CPU_FBRK_OUT_R_N")
	)
	(segment
		(start 14.18209 -75.808078)
		(end 12.210288 -77.77988)
		(width 0.08382)
		(layer "In2.Cu")
		(net "FM_BMC_CPU_FBRK_OUT_R_N")
	)
	(segment
		(start 14.18209 -68.90131)
		(end 14.18209 -75.808078)
		(width 0.08382)
		(layer "In2.Cu")
		(net "FM_BMC_CPU_FBRK_OUT_R_N")
	)
	(segment
		(start 22.711664 -69.99224)
		(end 22.413214 -69.69379)
		(width 0.08382)
		(layer "In2.Cu")
		(net "FM_BMC_CPU_FBRK_OUT_R_N")
	)
	(segment
		(start 11.582146 -78.816454)
		(end 11.582146 -78.9178)
		(width 0.08382)
		(layer "In2.Cu")
		(net "FM_BMC_CPU_FBRK_OUT_R_N")
	)
	(segment
		(start 11.582146 -78.9178)
		(end 10.017506 -80.48244)
		(width 0.08382)
		(layer "In2.Cu")
		(net "FM_BMC_CPU_FBRK_OUT_R_N")
	)
	(segment
		(start 9.91362 -80.48498)
		(end 9.634474 -80.48498)
		(width 0.08382)
		(layer "In2.Cu")
		(net "FM_BMC_CPU_FBRK_OUT_R_N")
	)
	(segment
		(start 9.91616 -80.48244)
		(end 9.91362 -80.48498)
		(width 0.08382)
		(layer "In2.Cu")
		(net "FM_BMC_CPU_FBRK_OUT_R_N")
	)
	(segment
		(start 21.387054 -69.69379)
		(end 19.670014 -67.97675)
		(width 0.08382)
		(layer "In2.Cu")
		(net "FM_BMC_CPU_FBRK_OUT_R_N")
	)
	(segment
		(start 9.634474 -80.48498)
		(end 8.721344 -81.39811)
		(width 0.08382)
		(layer "In2.Cu")
		(net "FM_BMC_CPU_FBRK_OUT_R_N")
	)
	(segment
		(start 11.58494 -78.00086)
		(end 11.58494 -78.81366)
		(width 0.08382)
		(layer "In2.Cu")
		(net "FM_BMC_CPU_FBRK_OUT_R_N")
	)
	(segment
		(start 12.210288 -77.77988)
		(end 11.80592 -77.77988)
		(width 0.08382)
		(layer "In2.Cu")
		(net "FM_BMC_CPU_FBRK_OUT_R_N")
	)
	(segment
		(start 27.069796 -71.127112)
		(end 25.934924 -69.99224)
		(width 0.08382)
		(layer "In2.Cu")
		(net "FM_BMC_CPU_FBRK_OUT_R_N")
	)
	(segment
		(start 3.94716 -100.143564)
		(end 4.35864 -100.555044)
		(width 0.10668)
		(layer "In4.Cu")
		(net "FM_BMC_CPU_FBRK_OUT_R_N")
	)
	(segment
		(start 31.17342 -41.95826)
		(end 30.607 -42.52468)
		(width 0.10668)
		(layer "In4.Cu")
		(net "FM_BMC_CPU_FBRK_OUT_R_N")
	)
	(segment
		(start 27.36088 -58.40984)
		(end 27.36088 -62.936882)
		(width 0.10668)
		(layer "In4.Cu")
		(net "FM_BMC_CPU_FBRK_OUT_R_N")
	)
	(segment
		(start 4.64312 -102.619556)
		(end 4.64312 -105.252012)
		(width 0.10668)
		(layer "In4.Cu")
		(net "FM_BMC_CPU_FBRK_OUT_R_N")
	)
	(segment
		(start 4.871974 -105.480866)
		(end 6.471666 -105.480866)
		(width 0.10668)
		(layer "In4.Cu")
		(net "FM_BMC_CPU_FBRK_OUT_R_N")
	)
	(segment
		(start 37.762434 -38.354)
		(end 36.89858 -39.217854)
		(width 0.10668)
		(layer "In4.Cu")
		(net "FM_BMC_CPU_FBRK_OUT_R_N")
	)
	(segment
		(start 10.16 -110.1598)
		(end 10.7188 -110.7186)
		(width 0.10668)
		(layer "In4.Cu")
		(net "FM_BMC_CPU_FBRK_OUT_R_N")
	)
	(segment
		(start 29.99359 -55.436516)
		(end 29.752798 -56.017922)
		(width 0.10668)
		(layer "In4.Cu")
		(net "FM_BMC_CPU_FBRK_OUT_R_N")
	)
	(segment
		(start 5.195062 -89.772236)
		(end 4.71932 -90.247978)
		(width 0.10668)
		(layer "In4.Cu")
		(net "FM_BMC_CPU_FBRK_OUT_R_N")
	)
	(segment
		(start 29.752798 -56.017922)
		(end 27.36088 -58.40984)
		(width 0.10668)
		(layer "In4.Cu")
		(net "FM_BMC_CPU_FBRK_OUT_R_N")
	)
	(segment
		(start 4.71932 -90.247978)
		(end 4.71932 -91.60256)
		(width 0.10668)
		(layer "In4.Cu")
		(net "FM_BMC_CPU_FBRK_OUT_R_N")
	)
	(segment
		(start 39.598854 -38.354)
		(end 37.762434 -38.354)
		(width 0.10668)
		(layer "In4.Cu")
		(net "FM_BMC_CPU_FBRK_OUT_R_N")
	)
	(segment
		(start 26.61666 -67.943476)
		(end 26.834084 -68.1609)
		(width 0.10668)
		(layer "In4.Cu")
		(net "FM_BMC_CPU_FBRK_OUT_R_N")
	)
	(segment
		(start 41.1226 -38.227)
		(end 40.93718 -38.04158)
		(width 0.10668)
		(layer "In4.Cu")
		(net "FM_BMC_CPU_FBRK_OUT_R_N")
	)
	(segment
		(start 6.471666 -105.480866)
		(end 8.81888 -107.82808)
		(width 0.10668)
		(layer "In4.Cu")
		(net "FM_BMC_CPU_FBRK_OUT_R_N")
	)
	(segment
		(start 35.578542 -41.34104)
		(end 35.418268 -41.34104)
		(width 0.10668)
		(layer "In4.Cu")
		(net "FM_BMC_CPU_FBRK_OUT_R_N")
	)
	(segment
		(start 4.445 -92.271596)
		(end 3.94716 -92.769436)
		(width 0.10668)
		(layer "In4.Cu")
		(net "FM_BMC_CPU_FBRK_OUT_R_N")
	)
	(segment
		(start 9.652 -85.598)
		(end 9.652 -86.995)
		(width 0.10668)
		(layer "In4.Cu")
		(net "FM_BMC_CPU_FBRK_OUT_R_N")
	)
	(segment
		(start 26.61666 -63.681102)
		(end 26.61666 -67.943476)
		(width 0.10668)
		(layer "In4.Cu")
		(net "FM_BMC_CPU_FBRK_OUT_R_N")
	)
	(segment
		(start 9.271 -85.217)
		(end 9.652 -85.598)
		(width 0.10668)
		(layer "In4.Cu")
		(net "FM_BMC_CPU_FBRK_OUT_R_N")
	)
	(segment
		(start 26.834084 -70.8914)
		(end 27.069796 -71.127112)
		(width 0.10668)
		(layer "In4.Cu")
		(net "FM_BMC_CPU_FBRK_OUT_R_N")
	)
	(segment
		(start 8.81888 -109.42066)
		(end 9.55802 -110.1598)
		(width 0.10668)
		(layer "In4.Cu")
		(net "FM_BMC_CPU_FBRK_OUT_R_N")
	)
	(segment
		(start 4.64312 -105.252012)
		(end 4.871974 -105.480866)
		(width 0.10668)
		(layer "In4.Cu")
		(net "FM_BMC_CPU_FBRK_OUT_R_N")
	)
	(segment
		(start 34.801048 -41.95826)
		(end 31.17342 -41.95826)
		(width 0.10668)
		(layer "In4.Cu")
		(net "FM_BMC_CPU_FBRK_OUT_R_N")
	)
	(segment
		(start 30.1244 -54.77891)
		(end 29.99359 -55.436516)
		(width 0.10668)
		(layer "In4.Cu")
		(net "FM_BMC_CPU_FBRK_OUT_R_N")
	)
	(segment
		(start 4.707636 -91.60256)
		(end 4.445 -91.865196)
		(width 0.10668)
		(layer "In4.Cu")
		(net "FM_BMC_CPU_FBRK_OUT_R_N")
	)
	(segment
		(start 36.89858 -39.217854)
		(end 36.89858 -40.021002)
		(width 0.10668)
		(layer "In4.Cu")
		(net "FM_BMC_CPU_FBRK_OUT_R_N")
	)
	(segment
		(start 8.81888 -107.82808)
		(end 8.81888 -109.42066)
		(width 0.10668)
		(layer "In4.Cu")
		(net "FM_BMC_CPU_FBRK_OUT_R_N")
	)
	(segment
		(start 9.398 -87.249)
		(end 8.9154 -87.249)
		(width 0.10668)
		(layer "In4.Cu")
		(net "FM_BMC_CPU_FBRK_OUT_R_N")
	)
	(segment
		(start 40.93718 -38.04158)
		(end 39.911274 -38.04158)
		(width 0.10668)
		(layer "In4.Cu")
		(net "FM_BMC_CPU_FBRK_OUT_R_N")
	)
	(segment
		(start 27.36088 -62.936882)
		(end 26.61666 -63.681102)
		(width 0.10668)
		(layer "In4.Cu")
		(net "FM_BMC_CPU_FBRK_OUT_R_N")
	)
	(segment
		(start 30.1244 -52.9209)
		(end 30.1244 -54.77891)
		(width 0.10668)
		(layer "In4.Cu")
		(net "FM_BMC_CPU_FBRK_OUT_R_N")
	)
	(segment
		(start 39.911274 -38.04158)
		(end 39.598854 -38.354)
		(width 0.10668)
		(layer "In4.Cu")
		(net "FM_BMC_CPU_FBRK_OUT_R_N")
	)
	(segment
		(start 4.35864 -102.335076)
		(end 4.64312 -102.619556)
		(width 0.10668)
		(layer "In4.Cu")
		(net "FM_BMC_CPU_FBRK_OUT_R_N")
	)
	(segment
		(start 29.70911 -50.33137)
		(end 29.70911 -52.50561)
		(width 0.10668)
		(layer "In4.Cu")
		(net "FM_BMC_CPU_FBRK_OUT_R_N")
	)
	(segment
		(start 4.445 -91.865196)
		(end 4.445 -92.271596)
		(width 0.10668)
		(layer "In4.Cu")
		(net "FM_BMC_CPU_FBRK_OUT_R_N")
	)
	(segment
		(start 29.70911 -52.50561)
		(end 30.1244 -52.9209)
		(width 0.10668)
		(layer "In4.Cu")
		(net "FM_BMC_CPU_FBRK_OUT_R_N")
	)
	(segment
		(start 4.35864 -100.555044)
		(end 4.35864 -102.335076)
		(width 0.10668)
		(layer "In4.Cu")
		(net "FM_BMC_CPU_FBRK_OUT_R_N")
	)
	(segment
		(start 9.144 -85.217)
		(end 9.271 -85.217)
		(width 0.10668)
		(layer "In4.Cu")
		(net "FM_BMC_CPU_FBRK_OUT_R_N")
	)
	(segment
		(start 8.9154 -87.249)
		(end 8.0264 -88.138)
		(width 0.10668)
		(layer "In4.Cu")
		(net "FM_BMC_CPU_FBRK_OUT_R_N")
	)
	(segment
		(start 3.94716 -92.769436)
		(end 3.94716 -100.143564)
		(width 0.10668)
		(layer "In4.Cu")
		(net "FM_BMC_CPU_FBRK_OUT_R_N")
	)
	(segment
		(start 4.71932 -91.60256)
		(end 4.707636 -91.60256)
		(width 0.10668)
		(layer "In4.Cu")
		(net "FM_BMC_CPU_FBRK_OUT_R_N")
	)
	(segment
		(start 6.806946 -89.772236)
		(end 5.195062 -89.772236)
		(width 0.10668)
		(layer "In4.Cu")
		(net "FM_BMC_CPU_FBRK_OUT_R_N")
	)
	(segment
		(start 9.55802 -110.1598)
		(end 10.16 -110.1598)
		(width 0.10668)
		(layer "In4.Cu")
		(net "FM_BMC_CPU_FBRK_OUT_R_N")
	)
	(segment
		(start 30.607 -42.52468)
		(end 30.607 -49.43348)
		(width 0.10668)
		(layer "In4.Cu")
		(net "FM_BMC_CPU_FBRK_OUT_R_N")
	)
	(segment
		(start 8.0264 -88.552782)
		(end 6.806946 -89.772236)
		(width 0.10668)
		(layer "In4.Cu")
		(net "FM_BMC_CPU_FBRK_OUT_R_N")
	)
	(segment
		(start 30.607 -49.43348)
		(end 29.70911 -50.33137)
		(width 0.10668)
		(layer "In4.Cu")
		(net "FM_BMC_CPU_FBRK_OUT_R_N")
	)
	(segment
		(start 9.652 -86.995)
		(end 9.398 -87.249)
		(width 0.10668)
		(layer "In4.Cu")
		(net "FM_BMC_CPU_FBRK_OUT_R_N")
	)
	(segment
		(start 9.017 -85.09)
		(end 9.144 -85.217)
		(width 0.10668)
		(layer "In4.Cu")
		(net "FM_BMC_CPU_FBRK_OUT_R_N")
	)
	(segment
		(start 26.834084 -68.1609)
		(end 26.834084 -70.8914)
		(width 0.10668)
		(layer "In4.Cu")
		(net "FM_BMC_CPU_FBRK_OUT_R_N")
	)
	(segment
		(start 35.418268 -41.34104)
		(end 34.801048 -41.95826)
		(width 0.10668)
		(layer "In4.Cu")
		(net "FM_BMC_CPU_FBRK_OUT_R_N")
	)
	(segment
		(start 8.0264 -88.138)
		(end 8.0264 -88.552782)
		(width 0.10668)
		(layer "In4.Cu")
		(net "FM_BMC_CPU_FBRK_OUT_R_N")
	)
	(segment
		(start 36.89858 -40.021002)
		(end 35.578542 -41.34104)
		(width 0.10668)
		(layer "In4.Cu")
		(net "FM_BMC_CPU_FBRK_OUT_R_N")
	)
	(segment
		(start 17.7546 -96.393)
		(end 17.0434 -96.393)
		(width 0.08382)
		(layer "In9.Cu")
		(net "FM_BMC_CPU_FBRK_OUT_R_N")
	)
	(segment
		(start 16.2814 -96.5454)
		(end 16.2814 -100.711)
		(width 0.08382)
		(layer "In9.Cu")
		(net "FM_BMC_CPU_FBRK_OUT_R_N")
	)
	(segment
		(start 11.0744 -108.79582)
		(end 11.0744 -110.363)
		(width 0.08382)
		(layer "In9.Cu")
		(net "FM_BMC_CPU_FBRK_OUT_R_N")
	)
	(segment
		(start 20.253452 -96.393)
		(end 19.6596 -96.393)
		(width 0.08382)
		(layer "In9.Cu")
		(net "FM_BMC_CPU_FBRK_OUT_R_N")
	)
	(segment
		(start 13.626338 -105.84053)
		(end 11.409426 -105.84053)
		(width 0.08382)
		(layer "In9.Cu")
		(net "FM_BMC_CPU_FBRK_OUT_R_N")
	)
	(segment
		(start 11.409426 -105.84053)
		(end 10.2616 -106.988356)
		(width 0.08382)
		(layer "In9.Cu")
		(net "FM_BMC_CPU_FBRK_OUT_R_N")
	)
	(segment
		(start 11.0744 -110.363)
		(end 10.7188 -110.7186)
		(width 0.08382)
		(layer "In9.Cu")
		(net "FM_BMC_CPU_FBRK_OUT_R_N")
	)
	(segment
		(start 19.4818 -96.2152)
		(end 19.4818 -95.8342)
		(width 0.08382)
		(layer "In9.Cu")
		(net "FM_BMC_CPU_FBRK_OUT_R_N")
	)
	(segment
		(start 19.6596 -96.393)
		(end 19.4818 -96.2152)
		(width 0.08382)
		(layer "In9.Cu")
		(net "FM_BMC_CPU_FBRK_OUT_R_N")
	)
	(segment
		(start 17.8816 -95.7072)
		(end 17.8816 -96.266)
		(width 0.08382)
		(layer "In9.Cu")
		(net "FM_BMC_CPU_FBRK_OUT_R_N")
	)
	(segment
		(start 19.4818 -95.8342)
		(end 19.2024 -95.5548)
		(width 0.08382)
		(layer "In9.Cu")
		(net "FM_BMC_CPU_FBRK_OUT_R_N")
	)
	(segment
		(start 16.5608 -96.266)
		(end 16.2814 -96.5454)
		(width 0.08382)
		(layer "In9.Cu")
		(net "FM_BMC_CPU_FBRK_OUT_R_N")
	)
	(segment
		(start 17.0434 -96.393)
		(end 16.9164 -96.266)
		(width 0.08382)
		(layer "In9.Cu")
		(net "FM_BMC_CPU_FBRK_OUT_R_N")
	)
	(segment
		(start 19.2024 -95.5548)
		(end 18.034 -95.5548)
		(width 0.08382)
		(layer "In9.Cu")
		(net "FM_BMC_CPU_FBRK_OUT_R_N")
	)
	(segment
		(start 20.66417 -95.982282)
		(end 20.253452 -96.393)
		(width 0.08382)
		(layer "In9.Cu")
		(net "FM_BMC_CPU_FBRK_OUT_R_N")
	)
	(segment
		(start 16.2814 -100.711)
		(end 14.4272 -102.5652)
		(width 0.08382)
		(layer "In9.Cu")
		(net "FM_BMC_CPU_FBRK_OUT_R_N")
	)
	(segment
		(start 14.4272 -102.5652)
		(end 14.4272 -105.039668)
		(width 0.08382)
		(layer "In9.Cu")
		(net "FM_BMC_CPU_FBRK_OUT_R_N")
	)
	(segment
		(start 17.8816 -96.266)
		(end 17.7546 -96.393)
		(width 0.08382)
		(layer "In9.Cu")
		(net "FM_BMC_CPU_FBRK_OUT_R_N")
	)
	(segment
		(start 10.2616 -106.988356)
		(end 10.2616 -107.98302)
		(width 0.08382)
		(layer "In9.Cu")
		(net "FM_BMC_CPU_FBRK_OUT_R_N")
	)
	(segment
		(start 10.2616 -107.98302)
		(end 11.0744 -108.79582)
		(width 0.08382)
		(layer "In9.Cu")
		(net "FM_BMC_CPU_FBRK_OUT_R_N")
	)
	(segment
		(start 18.034 -95.5548)
		(end 17.8816 -95.7072)
		(width 0.08382)
		(layer "In9.Cu")
		(net "FM_BMC_CPU_FBRK_OUT_R_N")
	)
	(segment
		(start 16.9164 -96.266)
		(end 16.5608 -96.266)
		(width 0.08382)
		(layer "In9.Cu")
		(net "FM_BMC_CPU_FBRK_OUT_R_N")
	)
	(segment
		(start 14.4272 -105.039668)
		(end 13.626338 -105.84053)
		(width 0.08382)
		(layer "In9.Cu")
		(net "FM_BMC_CPU_FBRK_OUT_R_N")
	)
	(segment
		(start 48.0949 -44.971208)
		(end 47.699676 -44.575984)
		(width 0.11684)
		(layer "F.Cu")
		(net "FM_BMC_CPU_FBRK_OUT_N")
	)
	(via
		(at 40.6146 -39.5224)
		(size 0.508)
		(drill 0.254)
		(layers "F.Cu" "B.Cu")
		(net "FM_BMC_CPU_FBRK_OUT_N")
	)
	(via
		(at 47.699676 -44.575984)
		(size 0.4572)
		(drill 0.254)
		(layers "F.Cu" "B.Cu")
		(net "FM_BMC_CPU_FBRK_OUT_N")
	)
	(segment
		(start 40.6146 -39.3954)
		(end 41.0464 -38.9636)
		(width 0.11684)
		(layer "B.Cu")
		(net "FM_BMC_CPU_FBRK_OUT_N")
	)
	(segment
		(start 41.0464 -38.9636)
		(end 41.8211 -38.9636)
		(width 0.11684)
		(layer "B.Cu")
		(net "FM_BMC_CPU_FBRK_OUT_N")
	)
	(segment
		(start 40.6146 -39.5224)
		(end 40.6146 -39.3954)
		(width 0.11684)
		(layer "B.Cu")
		(net "FM_BMC_CPU_FBRK_OUT_N")
	)
	(segment
		(start 40.9194 -40.6654)
		(end 40.6146 -40.3606)
		(width 0.08382)
		(layer "In9.Cu")
		(net "FM_BMC_CPU_FBRK_OUT_N")
	)
	(segment
		(start 47.29226 -44.9834)
		(end 44.8564 -44.9834)
		(width 0.08382)
		(layer "In9.Cu")
		(net "FM_BMC_CPU_FBRK_OUT_N")
	)
	(segment
		(start 47.699676 -44.575984)
		(end 47.29226 -44.9834)
		(width 0.08382)
		(layer "In9.Cu")
		(net "FM_BMC_CPU_FBRK_OUT_N")
	)
	(segment
		(start 44.8564 -44.9834)
		(end 40.9194 -41.0464)
		(width 0.08382)
		(layer "In9.Cu")
		(net "FM_BMC_CPU_FBRK_OUT_N")
	)
	(segment
		(start 40.6146 -40.3606)
		(end 40.6146 -39.5224)
		(width 0.08382)
		(layer "In9.Cu")
		(net "FM_BMC_CPU_FBRK_OUT_N")
	)
	(segment
		(start 40.9194 -41.0464)
		(end 40.9194 -40.6654)
		(width 0.08382)
		(layer "In9.Cu")
		(net "FM_BMC_CPU_FBRK_OUT_N")
	)
	(segment
		(start 58.7756 -115.551458)
		(end 59.265058 -116.73332)
		(width 0.11684)
		(layer "F.Cu")
		(net "ESPI_LPC_LAD3_IO3")
	)
	(segment
		(start 59.265058 -116.73332)
		(end 59.265058 -118.25986)
		(width 0.11684)
		(layer "F.Cu")
		(net "ESPI_LPC_LAD3_IO3")
	)
	(segment
		(start 58.7756 -114.808)
		(end 58.7756 -115.551458)
		(width 0.11684)
		(layer "F.Cu")
		(net "ESPI_LPC_LAD3_IO3")
	)
	(via
		(at 63.7286 -63.7032)
		(size 0.6604)
		(drill 0.3302)
		(layers "F.Cu" "B.Cu")
		(net "ESPI_LPC_LAD3_IO3")
	)
	(via
		(at 64.28994 -64.746886)
		(size 0.508)
		(drill 0.254)
		(layers "F.Cu" "B.Cu")
		(net "ESPI_LPC_LAD3_IO3")
	)
	(via
		(at 58.7756 -114.808)
		(size 0.508)
		(drill 0.254)
		(layers "F.Cu" "B.Cu")
		(net "ESPI_LPC_LAD3_IO3")
	)
	(segment
		(start 63.967106 -64.423798)
		(end 63.7286 -63.847726)
		(width 0.11684)
		(layer "B.Cu")
		(net "ESPI_LPC_LAD3_IO3")
	)
	(segment
		(start 63.47714 -63.134748)
		(end 63.712598 -63.7032)
		(width 0.11684)
		(layer "B.Cu")
		(net "ESPI_LPC_LAD3_IO3")
	)
	(segment
		(start 63.712598 -63.7032)
		(end 63.7286 -63.7032)
		(width 0.11684)
		(layer "B.Cu")
		(net "ESPI_LPC_LAD3_IO3")
	)
	(segment
		(start 63.47714 -62.555882)
		(end 63.47714 -63.134748)
		(width 0.11684)
		(layer "B.Cu")
		(net "ESPI_LPC_LAD3_IO3")
	)
	(segment
		(start 63.61811 -62.414912)
		(end 63.47714 -62.555882)
		(width 0.11684)
		(layer "B.Cu")
		(net "ESPI_LPC_LAD3_IO3")
	)
	(segment
		(start 63.7286 -63.847726)
		(end 63.7286 -63.7032)
		(width 0.11684)
		(layer "B.Cu")
		(net "ESPI_LPC_LAD3_IO3")
	)
	(segment
		(start 64.28994 -64.746886)
		(end 63.967106 -64.423798)
		(width 0.11684)
		(layer "B.Cu")
		(net "ESPI_LPC_LAD3_IO3")
	)
	(segment
		(start 66.1416 -80.365346)
		(end 66.1416 -78.570836)
		(width 0.10668)
		(layer "In4.Cu")
		(net "ESPI_LPC_LAD3_IO3")
	)
	(segment
		(start 59.2582 -114.70132)
		(end 59.2582 -113.817654)
		(width 0.10668)
		(layer "In4.Cu")
		(net "ESPI_LPC_LAD3_IO3")
	)
	(segment
		(start 67.13474 -71.065136)
		(end 66.806064 -70.73646)
		(width 0.10668)
		(layer "In4.Cu")
		(net "ESPI_LPC_LAD3_IO3")
	)
	(segment
		(start 64.38646 -102.90556)
		(end 64.38646 -100.18649)
		(width 0.10668)
		(layer "In4.Cu")
		(net "ESPI_LPC_LAD3_IO3")
	)
	(segment
		(start 61.002926 -112.71504)
		(end 64.71412 -109.003846)
		(width 0.10668)
		(layer "In4.Cu")
		(net "ESPI_LPC_LAD3_IO3")
	)
	(segment
		(start 63.666116 -65.37071)
		(end 64.28994 -64.746886)
		(width 0.10668)
		(layer "In4.Cu")
		(net "ESPI_LPC_LAD3_IO3")
	)
	(segment
		(start 65.3542 -80.827626)
		(end 65.3542 -80.63611)
		(width 0.10668)
		(layer "In4.Cu")
		(net "ESPI_LPC_LAD3_IO3")
	)
	(segment
		(start 65.024 -69.088)
		(end 63.666116 -67.730116)
		(width 0.10668)
		(layer "In4.Cu")
		(net "ESPI_LPC_LAD3_IO3")
	)
	(segment
		(start 65.3542 -81.752186)
		(end 65.3542 -81.56067)
		(width 0.10668)
		(layer "In4.Cu")
		(net "ESPI_LPC_LAD3_IO3")
	)
	(segment
		(start 64.18072 -85.34908)
		(end 65.776856 -83.752944)
		(width 0.10668)
		(layer "In4.Cu")
		(net "ESPI_LPC_LAD3_IO3")
	)
	(segment
		(start 64.174878 -99.050348)
		(end 63.508382 -99.050348)
		(width 0.10668)
		(layer "In4.Cu")
		(net "ESPI_LPC_LAD3_IO3")
	)
	(segment
		(start 63.666116 -67.730116)
		(end 63.666116 -65.37071)
		(width 0.10668)
		(layer "In4.Cu")
		(net "ESPI_LPC_LAD3_IO3")
	)
	(segment
		(start 64.18072 -88.181688)
		(end 64.18072 -85.34908)
		(width 0.10668)
		(layer "In4.Cu")
		(net "ESPI_LPC_LAD3_IO3")
	)
	(segment
		(start 63.9064 -99.619308)
		(end 64.01308 -99.512628)
		(width 0.10668)
		(layer "In4.Cu")
		(net "ESPI_LPC_LAD3_IO3")
	)
	(segment
		(start 66.1416 -78.570836)
		(end 65.034414 -75.897486)
		(width 0.10668)
		(layer "In4.Cu")
		(net "ESPI_LPC_LAD3_IO3")
	)
	(segment
		(start 65.52438 -74.3331)
		(end 66.653664 -74.3331)
		(width 0.10668)
		(layer "In4.Cu")
		(net "ESPI_LPC_LAD3_IO3")
	)
	(segment
		(start 63.373 -98.72345)
		(end 63.508382 -98.588068)
		(width 0.10668)
		(layer "In4.Cu")
		(net "ESPI_LPC_LAD3_IO3")
	)
	(segment
		(start 66.006218 -81.887568)
		(end 65.489582 -81.887568)
		(width 0.10668)
		(layer "In4.Cu")
		(net "ESPI_LPC_LAD3_IO3")
	)
	(segment
		(start 59.2582 -113.817654)
		(end 59.906662 -113.169192)
		(width 0.10668)
		(layer "In4.Cu")
		(net "ESPI_LPC_LAD3_IO3")
	)
	(segment
		(start 59.15152 -114.808)
		(end 59.2582 -114.70132)
		(width 0.10668)
		(layer "In4.Cu")
		(net "ESPI_LPC_LAD3_IO3")
	)
	(segment
		(start 66.653664 -74.3331)
		(end 67.13474 -73.852024)
		(width 0.10668)
		(layer "In4.Cu")
		(net "ESPI_LPC_LAD3_IO3")
	)
	(segment
		(start 65.034414 -75.897486)
		(end 65.034414 -74.823066)
		(width 0.10668)
		(layer "In4.Cu")
		(net "ESPI_LPC_LAD3_IO3")
	)
	(segment
		(start 65.3542 -81.56067)
		(end 65.489582 -81.425288)
		(width 0.10668)
		(layer "In4.Cu")
		(net "ESPI_LPC_LAD3_IO3")
	)
	(segment
		(start 66.1416 -81.09839)
		(end 66.006218 -80.963008)
		(width 0.10668)
		(layer "In4.Cu")
		(net "ESPI_LPC_LAD3_IO3")
	)
	(segment
		(start 65.489582 -80.963008)
		(end 65.3542 -80.827626)
		(width 0.10668)
		(layer "In4.Cu")
		(net "ESPI_LPC_LAD3_IO3")
	)
	(segment
		(start 64.01308 -99.974908)
		(end 63.9064 -99.868228)
		(width 0.10668)
		(layer "In4.Cu")
		(net "ESPI_LPC_LAD3_IO3")
	)
	(segment
		(start 66.1416 -82.02295)
		(end 66.006218 -81.887568)
		(width 0.10668)
		(layer "In4.Cu")
		(net "ESPI_LPC_LAD3_IO3")
	)
	(segment
		(start 65.489582 -81.425288)
		(end 66.006218 -81.425288)
		(width 0.10668)
		(layer "In4.Cu")
		(net "ESPI_LPC_LAD3_IO3")
	)
	(segment
		(start 63.508382 -98.588068)
		(end 64.174878 -98.588068)
		(width 0.10668)
		(layer "In4.Cu")
		(net "ESPI_LPC_LAD3_IO3")
	)
	(segment
		(start 58.7756 -114.808)
		(end 59.15152 -114.808)
		(width 0.10668)
		(layer "In4.Cu")
		(net "ESPI_LPC_LAD3_IO3")
	)
	(segment
		(start 64.01308 -99.512628)
		(end 64.174878 -99.512628)
		(width 0.10668)
		(layer "In4.Cu")
		(net "ESPI_LPC_LAD3_IO3")
	)
	(segment
		(start 64.71412 -103.23322)
		(end 64.38646 -102.90556)
		(width 0.10668)
		(layer "In4.Cu")
		(net "ESPI_LPC_LAD3_IO3")
	)
	(segment
		(start 65.3542 -80.63611)
		(end 65.489582 -80.500728)
		(width 0.10668)
		(layer "In4.Cu")
		(net "ESPI_LPC_LAD3_IO3")
	)
	(segment
		(start 65.83426 -70.73646)
		(end 65.024 -69.9262)
		(width 0.10668)
		(layer "In4.Cu")
		(net "ESPI_LPC_LAD3_IO3")
	)
	(segment
		(start 66.806064 -70.73646)
		(end 65.83426 -70.73646)
		(width 0.10668)
		(layer "In4.Cu")
		(net "ESPI_LPC_LAD3_IO3")
	)
	(segment
		(start 64.174878 -99.512628)
		(end 64.31026 -99.377246)
		(width 0.10668)
		(layer "In4.Cu")
		(net "ESPI_LPC_LAD3_IO3")
	)
	(segment
		(start 65.489582 -81.887568)
		(end 65.3542 -81.752186)
		(width 0.10668)
		(layer "In4.Cu")
		(net "ESPI_LPC_LAD3_IO3")
	)
	(segment
		(start 65.776856 -83.752944)
		(end 66.1416 -82.658712)
		(width 0.10668)
		(layer "In4.Cu")
		(net "ESPI_LPC_LAD3_IO3")
	)
	(segment
		(start 63.9064 -99.868228)
		(end 63.9064 -99.619308)
		(width 0.10668)
		(layer "In4.Cu")
		(net "ESPI_LPC_LAD3_IO3")
	)
	(segment
		(start 64.31026 -99.377246)
		(end 64.31026 -99.18573)
		(width 0.10668)
		(layer "In4.Cu")
		(net "ESPI_LPC_LAD3_IO3")
	)
	(segment
		(start 65.489582 -80.500728)
		(end 66.006218 -80.500728)
		(width 0.10668)
		(layer "In4.Cu")
		(net "ESPI_LPC_LAD3_IO3")
	)
	(segment
		(start 66.006218 -80.500728)
		(end 66.1416 -80.365346)
		(width 0.10668)
		(layer "In4.Cu")
		(net "ESPI_LPC_LAD3_IO3")
	)
	(segment
		(start 65.034414 -74.823066)
		(end 65.52438 -74.3331)
		(width 0.10668)
		(layer "In4.Cu")
		(net "ESPI_LPC_LAD3_IO3")
	)
	(segment
		(start 64.38646 -89.428828)
		(end 64.2112 -89.005664)
		(width 0.10668)
		(layer "In4.Cu")
		(net "ESPI_LPC_LAD3_IO3")
	)
	(segment
		(start 64.38646 -98.376486)
		(end 64.38646 -89.428828)
		(width 0.10668)
		(layer "In4.Cu")
		(net "ESPI_LPC_LAD3_IO3")
	)
	(segment
		(start 65.024 -69.9262)
		(end 65.024 -69.088)
		(width 0.10668)
		(layer "In4.Cu")
		(net "ESPI_LPC_LAD3_IO3")
	)
	(segment
		(start 63.373 -98.914966)
		(end 63.373 -98.72345)
		(width 0.10668)
		(layer "In4.Cu")
		(net "ESPI_LPC_LAD3_IO3")
	)
	(segment
		(start 64.38646 -100.18649)
		(end 64.174878 -99.974908)
		(width 0.10668)
		(layer "In4.Cu")
		(net "ESPI_LPC_LAD3_IO3")
	)
	(segment
		(start 66.1416 -82.658712)
		(end 66.1416 -82.02295)
		(width 0.10668)
		(layer "In4.Cu")
		(net "ESPI_LPC_LAD3_IO3")
	)
	(segment
		(start 67.13474 -73.852024)
		(end 67.13474 -71.065136)
		(width 0.10668)
		(layer "In4.Cu")
		(net "ESPI_LPC_LAD3_IO3")
	)
	(segment
		(start 64.31026 -99.18573)
		(end 64.174878 -99.050348)
		(width 0.10668)
		(layer "In4.Cu")
		(net "ESPI_LPC_LAD3_IO3")
	)
	(segment
		(start 63.508382 -99.050348)
		(end 63.373 -98.914966)
		(width 0.10668)
		(layer "In4.Cu")
		(net "ESPI_LPC_LAD3_IO3")
	)
	(segment
		(start 64.174878 -98.588068)
		(end 64.38646 -98.376486)
		(width 0.10668)
		(layer "In4.Cu")
		(net "ESPI_LPC_LAD3_IO3")
	)
	(segment
		(start 66.1416 -81.289906)
		(end 66.1416 -81.09839)
		(width 0.10668)
		(layer "In4.Cu")
		(net "ESPI_LPC_LAD3_IO3")
	)
	(segment
		(start 66.006218 -80.963008)
		(end 65.489582 -80.963008)
		(width 0.10668)
		(layer "In4.Cu")
		(net "ESPI_LPC_LAD3_IO3")
	)
	(segment
		(start 64.71412 -109.003846)
		(end 64.71412 -103.23322)
		(width 0.10668)
		(layer "In4.Cu")
		(net "ESPI_LPC_LAD3_IO3")
	)
	(segment
		(start 66.006218 -81.425288)
		(end 66.1416 -81.289906)
		(width 0.10668)
		(layer "In4.Cu")
		(net "ESPI_LPC_LAD3_IO3")
	)
	(segment
		(start 64.2112 -88.212168)
		(end 64.18072 -88.181688)
		(width 0.10668)
		(layer "In4.Cu")
		(net "ESPI_LPC_LAD3_IO3")
	)
	(segment
		(start 64.2112 -89.005664)
		(end 64.2112 -88.212168)
		(width 0.10668)
		(layer "In4.Cu")
		(net "ESPI_LPC_LAD3_IO3")
	)
	(segment
		(start 64.174878 -99.974908)
		(end 64.01308 -99.974908)
		(width 0.10668)
		(layer "In4.Cu")
		(net "ESPI_LPC_LAD3_IO3")
	)
	(segment
		(start 59.906662 -113.169192)
		(end 61.002926 -112.71504)
		(width 0.10668)
		(layer "In4.Cu")
		(net "ESPI_LPC_LAD3_IO3")
	)
	(segment
		(start 59.0804 -114.173)
		(end 59.2455 -114.3381)
		(width 0.11684)
		(layer "F.Cu")
		(net "ESPI_LPC_LAD2_IO2")
	)
	(segment
		(start 59.865006 -116.792248)
		(end 59.865006 -118.25986)
		(width 0.11684)
		(layer "F.Cu")
		(net "ESPI_LPC_LAD2_IO2")
	)
	(segment
		(start 58.7756 -114.173)
		(end 59.0804 -114.173)
		(width 0.11684)
		(layer "F.Cu")
		(net "ESPI_LPC_LAD2_IO2")
	)
	(segment
		(start 59.2455 -114.3381)
		(end 59.2455 -115.296442)
		(width 0.11684)
		(layer "F.Cu")
		(net "ESPI_LPC_LAD2_IO2")
	)
	(segment
		(start 59.2455 -115.296442)
		(end 59.865006 -116.792248)
		(width 0.11684)
		(layer "F.Cu")
		(net "ESPI_LPC_LAD2_IO2")
	)
	(via
		(at 58.7756 -114.173)
		(size 0.508)
		(drill 0.254)
		(layers "F.Cu" "B.Cu")
		(net "ESPI_LPC_LAD2_IO2")
	)
	(via
		(at 62.4586 -77.47)
		(size 0.508)
		(drill 0.254)
		(layers "F.Cu" "B.Cu")
		(net "ESPI_LPC_LAD2_IO2")
	)
	(via
		(at 60.38342 -63.01359)
		(size 0.508)
		(drill 0.254)
		(layers "F.Cu" "B.Cu")
		(net "ESPI_LPC_LAD2_IO2")
	)
	(segment
		(start 60.40247 -62.99454)
		(end 60.40247 -62.413388)
		(width 0.11684)
		(layer "B.Cu")
		(net "ESPI_LPC_LAD2_IO2")
	)
	(segment
		(start 60.40247 -62.413388)
		(end 60.556902 -62.258956)
		(width 0.11684)
		(layer "B.Cu")
		(net "ESPI_LPC_LAD2_IO2")
	)
	(segment
		(start 60.38342 -63.01359)
		(end 60.40247 -62.99454)
		(width 0.11684)
		(layer "B.Cu")
		(net "ESPI_LPC_LAD2_IO2")
	)
	(segment
		(start 60.44438 -83.698588)
		(end 60.44438 -82.026252)
		(width 0.10668)
		(layer "In4.Cu")
		(net "ESPI_LPC_LAD2_IO2")
	)
	(segment
		(start 58.92546 -99.280472)
		(end 58.92546 -98.847148)
		(width 0.10668)
		(layer "In4.Cu")
		(net "ESPI_LPC_LAD2_IO2")
	)
	(segment
		(start 57.63895 -111.474758)
		(end 57.503314 -111.610394)
		(width 0.10668)
		(layer "In4.Cu")
		(net "ESPI_LPC_LAD2_IO2")
	)
	(segment
		(start 58.204354 -104.01173)
		(end 58.39587 -104.01173)
		(width 0.10668)
		(layer "In4.Cu")
		(net "ESPI_LPC_LAD2_IO2")
	)
	(segment
		(start 57.503314 -111.80191)
		(end 58.172096 -112.470692)
		(width 0.10668)
		(layer "In4.Cu")
		(net "ESPI_LPC_LAD2_IO2")
	)
	(segment
		(start 60.6679 -97.709228)
		(end 60.6679 -96.415352)
		(width 0.10668)
		(layer "In4.Cu")
		(net "ESPI_LPC_LAD2_IO2")
	)
	(segment
		(start 60.87872 -96.204532)
		(end 60.87872 -93.347032)
		(width 0.10668)
		(layer "In4.Cu")
		(net "ESPI_LPC_LAD2_IO2")
	)
	(segment
		(start 60.6679 -96.415352)
		(end 60.87872 -96.204532)
		(width 0.10668)
		(layer "In4.Cu")
		(net "ESPI_LPC_LAD2_IO2")
	)
	(segment
		(start 57.090818 -111.38662)
		(end 57.2262 -111.251238)
		(width 0.10668)
		(layer "In4.Cu")
		(net "ESPI_LPC_LAD2_IO2")
	)
	(segment
		(start 57.877456 -104.530144)
		(end 57.877456 -104.338628)
		(width 0.10668)
		(layer "In4.Cu")
		(net "ESPI_LPC_LAD2_IO2")
	)
	(segment
		(start 58.166 -114.06632)
		(end 58.166 -113.321338)
		(width 0.10668)
		(layer "In4.Cu")
		(net "ESPI_LPC_LAD2_IO2")
	)
	(segment
		(start 63.5 -68.2752)
		(end 62.9158 -67.691)
		(width 0.10668)
		(layer "In4.Cu")
		(net "ESPI_LPC_LAD2_IO2")
	)
	(segment
		(start 57.2262 -111.251238)
		(end 57.2262 -111.059722)
		(width 0.10668)
		(layer "In4.Cu")
		(net "ESPI_LPC_LAD2_IO2")
	)
	(segment
		(start 60.44438 -82.026252)
		(end 61.1378 -81.332832)
		(width 0.10668)
		(layer "In4.Cu")
		(net "ESPI_LPC_LAD2_IO2")
	)
	(segment
		(start 62.9666 -73.9902)
		(end 62.9666 -69.2912)
		(width 0.10668)
		(layer "In4.Cu")
		(net "ESPI_LPC_LAD2_IO2")
	)
	(segment
		(start 57.175908 -112.128554)
		(end 56.984646 -112.128554)
		(width 0.10668)
		(layer "In4.Cu")
		(net "ESPI_LPC_LAD2_IO2")
	)
	(segment
		(start 56.84901 -112.26419)
		(end 56.84901 -112.455706)
		(width 0.10668)
		(layer "In4.Cu")
		(net "ESPI_LPC_LAD2_IO2")
	)
	(segment
		(start 58.036206 -112.79759)
		(end 57.844944 -112.79759)
		(width 0.10668)
		(layer "In4.Cu")
		(net "ESPI_LPC_LAD2_IO2")
	)
	(segment
		(start 57.830212 -111.474758)
		(end 57.63895 -111.474758)
		(width 0.10668)
		(layer "In4.Cu")
		(net "ESPI_LPC_LAD2_IO2")
	)
	(segment
		(start 62.738 -78.434692)
		(end 62.738 -77.7494)
		(width 0.10668)
		(layer "In4.Cu")
		(net "ESPI_LPC_LAD2_IO2")
	)
	(segment
		(start 57.2262 -111.059722)
		(end 57.090818 -110.92434)
		(width 0.10668)
		(layer "In4.Cu")
		(net "ESPI_LPC_LAD2_IO2")
	)
	(segment
		(start 58.92546 -98.847148)
		(end 59.238388 -98.53422)
		(width 0.10668)
		(layer "In4.Cu")
		(net "ESPI_LPC_LAD2_IO2")
	)
	(segment
		(start 57.517792 -113.315496)
		(end 57.381902 -113.451386)
		(width 0.10668)
		(layer "In4.Cu")
		(net "ESPI_LPC_LAD2_IO2")
	)
	(segment
		(start 62.4586 -77.47)
		(end 62.4586 -77.1144)
		(width 0.10668)
		(layer "In4.Cu")
		(net "ESPI_LPC_LAD2_IO2")
	)
	(segment
		(start 58.7756 -114.173)
		(end 58.27268 -114.173)
		(width 0.10668)
		(layer "In4.Cu")
		(net "ESPI_LPC_LAD2_IO2")
	)
	(segment
		(start 56.472582 -111.38662)
		(end 57.090818 -111.38662)
		(width 0.10668)
		(layer "In4.Cu")
		(net "ESPI_LPC_LAD2_IO2")
	)
	(segment
		(start 57.888124 -103.6955)
		(end 58.204354 -104.01173)
		(width 0.10668)
		(layer "In4.Cu")
		(net "ESPI_LPC_LAD2_IO2")
	)
	(segment
		(start 58.826146 -112.470692)
		(end 57.830212 -111.474758)
		(width 0.10668)
		(layer "In4.Cu")
		(net "ESPI_LPC_LAD2_IO2")
	)
	(segment
		(start 62.9158 -64.21628)
		(end 62.14872 -63.4492)
		(width 0.10668)
		(layer "In4.Cu")
		(net "ESPI_LPC_LAD2_IO2")
	)
	(segment
		(start 60.747148 -84.35467)
		(end 60.747148 -84.001356)
		(width 0.10668)
		(layer "In4.Cu")
		(net "ESPI_LPC_LAD2_IO2")
	)
	(segment
		(start 60.747148 -84.001356)
		(end 60.44438 -83.698588)
		(width 0.10668)
		(layer "In4.Cu")
		(net "ESPI_LPC_LAD2_IO2")
	)
	(segment
		(start 62.9666 -69.2912)
		(end 63.5 -68.7578)
		(width 0.10668)
		(layer "In4.Cu")
		(net "ESPI_LPC_LAD2_IO2")
	)
	(segment
		(start 57.517792 -113.124488)
		(end 57.517792 -113.315496)
		(width 0.10668)
		(layer "In4.Cu")
		(net "ESPI_LPC_LAD2_IO2")
	)
	(segment
		(start 57.877456 -104.338628)
		(end 57.561226 -104.022398)
		(width 0.10668)
		(layer "In4.Cu")
		(net "ESPI_LPC_LAD2_IO2")
	)
	(segment
		(start 58.166 -113.321338)
		(end 58.826146 -112.6617)
		(width 0.10668)
		(layer "In4.Cu")
		(net "ESPI_LPC_LAD2_IO2")
	)
	(segment
		(start 58.172096 -112.470692)
		(end 58.172096 -112.6617)
		(width 0.10668)
		(layer "In4.Cu")
		(net "ESPI_LPC_LAD2_IO2")
	)
	(segment
		(start 57.844944 -112.79759)
		(end 57.175908 -112.128554)
		(width 0.10668)
		(layer "In4.Cu")
		(net "ESPI_LPC_LAD2_IO2")
	)
	(segment
		(start 56.84901 -112.455706)
		(end 57.517792 -113.124488)
		(width 0.10668)
		(layer "In4.Cu")
		(net "ESPI_LPC_LAD2_IO2")
	)
	(segment
		(start 57.090818 -110.92434)
		(end 56.472582 -110.92434)
		(width 0.10668)
		(layer "In4.Cu")
		(net "ESPI_LPC_LAD2_IO2")
	)
	(segment
		(start 63.246 -74.2696)
		(end 62.9666 -73.9902)
		(width 0.10668)
		(layer "In4.Cu")
		(net "ESPI_LPC_LAD2_IO2")
	)
	(segment
		(start 56.984646 -112.128554)
		(end 56.84901 -112.26419)
		(width 0.10668)
		(layer "In4.Cu")
		(net "ESPI_LPC_LAD2_IO2")
	)
	(segment
		(start 58.9788 -103.4288)
		(end 58.9788 -99.333812)
		(width 0.10668)
		(layer "In4.Cu")
		(net "ESPI_LPC_LAD2_IO2")
	)
	(segment
		(start 59.238388 -98.53422)
		(end 59.842908 -98.53422)
		(width 0.10668)
		(layer "In4.Cu")
		(net "ESPI_LPC_LAD2_IO2")
	)
	(segment
		(start 58.9788 -99.333812)
		(end 58.92546 -99.280472)
		(width 0.10668)
		(layer "In4.Cu")
		(net "ESPI_LPC_LAD2_IO2")
	)
	(segment
		(start 58.172096 -112.6617)
		(end 58.036206 -112.79759)
		(width 0.10668)
		(layer "In4.Cu")
		(net "ESPI_LPC_LAD2_IO2")
	)
	(segment
		(start 57.19064 -113.451386)
		(end 56.3372 -112.597946)
		(width 0.10668)
		(layer "In4.Cu")
		(net "ESPI_LPC_LAD2_IO2")
	)
	(segment
		(start 61.61532 -80.82788)
		(end 61.61532 -79.557372)
		(width 0.10668)
		(layer "In4.Cu")
		(net "ESPI_LPC_LAD2_IO2")
	)
	(segment
		(start 56.3372 -110.788958)
		(end 56.3372 -108.8644)
		(width 0.10668)
		(layer "In4.Cu")
		(net "ESPI_LPC_LAD2_IO2")
	)
	(segment
		(start 62.738 -77.7494)
		(end 62.4586 -77.47)
		(width 0.10668)
		(layer "In4.Cu")
		(net "ESPI_LPC_LAD2_IO2")
	)
	(segment
		(start 61.1378 -81.3054)
		(end 61.61532 -80.82788)
		(width 0.10668)
		(layer "In4.Cu")
		(net "ESPI_LPC_LAD2_IO2")
	)
	(segment
		(start 57.696608 -103.6955)
		(end 57.888124 -103.6955)
		(width 0.10668)
		(layer "In4.Cu")
		(net "ESPI_LPC_LAD2_IO2")
	)
	(segment
		(start 56.6674 -105.7402)
		(end 57.877456 -104.530144)
		(width 0.10668)
		(layer "In4.Cu")
		(net "ESPI_LPC_LAD2_IO2")
	)
	(segment
		(start 58.39587 -104.01173)
		(end 58.9788 -103.4288)
		(width 0.10668)
		(layer "In4.Cu")
		(net "ESPI_LPC_LAD2_IO2")
	)
	(segment
		(start 60.87872 -93.347032)
		(end 61.15812 -92.672154)
		(width 0.10668)
		(layer "In4.Cu")
		(net "ESPI_LPC_LAD2_IO2")
	)
	(segment
		(start 58.27268 -114.173)
		(end 58.166 -114.06632)
		(width 0.10668)
		(layer "In4.Cu")
		(net "ESPI_LPC_LAD2_IO2")
	)
	(segment
		(start 57.561226 -104.022398)
		(end 57.561226 -103.830882)
		(width 0.10668)
		(layer "In4.Cu")
		(net "ESPI_LPC_LAD2_IO2")
	)
	(segment
		(start 56.472582 -110.92434)
		(end 56.3372 -110.788958)
		(width 0.10668)
		(layer "In4.Cu")
		(net "ESPI_LPC_LAD2_IO2")
	)
	(segment
		(start 61.61532 -79.557372)
		(end 62.738 -78.434692)
		(width 0.10668)
		(layer "In4.Cu")
		(net "ESPI_LPC_LAD2_IO2")
	)
	(segment
		(start 62.4586 -77.1144)
		(end 63.246 -76.327)
		(width 0.10668)
		(layer "In4.Cu")
		(net "ESPI_LPC_LAD2_IO2")
	)
	(segment
		(start 57.561226 -103.830882)
		(end 57.696608 -103.6955)
		(width 0.10668)
		(layer "In4.Cu")
		(net "ESPI_LPC_LAD2_IO2")
	)
	(segment
		(start 59.842908 -98.53422)
		(end 60.6679 -97.709228)
		(width 0.10668)
		(layer "In4.Cu")
		(net "ESPI_LPC_LAD2_IO2")
	)
	(segment
		(start 56.6674 -108.5342)
		(end 56.6674 -105.7402)
		(width 0.10668)
		(layer "In4.Cu")
		(net "ESPI_LPC_LAD2_IO2")
	)
	(segment
		(start 57.381902 -113.451386)
		(end 57.19064 -113.451386)
		(width 0.10668)
		(layer "In4.Cu")
		(net "ESPI_LPC_LAD2_IO2")
	)
	(segment
		(start 61.15812 -92.672154)
		(end 61.15812 -84.765642)
		(width 0.10668)
		(layer "In4.Cu")
		(net "ESPI_LPC_LAD2_IO2")
	)
	(segment
		(start 63.5 -68.7578)
		(end 63.5 -68.2752)
		(width 0.10668)
		(layer "In4.Cu")
		(net "ESPI_LPC_LAD2_IO2")
	)
	(segment
		(start 58.826146 -112.6617)
		(end 58.826146 -112.470692)
		(width 0.10668)
		(layer "In4.Cu")
		(net "ESPI_LPC_LAD2_IO2")
	)
	(segment
		(start 57.503314 -111.610394)
		(end 57.503314 -111.80191)
		(width 0.10668)
		(layer "In4.Cu")
		(net "ESPI_LPC_LAD2_IO2")
	)
	(segment
		(start 61.1378 -81.332832)
		(end 61.1378 -81.3054)
		(width 0.10668)
		(layer "In4.Cu")
		(net "ESPI_LPC_LAD2_IO2")
	)
	(segment
		(start 56.3372 -112.597946)
		(end 56.3372 -111.522002)
		(width 0.10668)
		(layer "In4.Cu")
		(net "ESPI_LPC_LAD2_IO2")
	)
	(segment
		(start 62.14872 -63.4492)
		(end 60.81903 -63.4492)
		(width 0.10668)
		(layer "In4.Cu")
		(net "ESPI_LPC_LAD2_IO2")
	)
	(segment
		(start 56.3372 -108.8644)
		(end 56.6674 -108.5342)
		(width 0.10668)
		(layer "In4.Cu")
		(net "ESPI_LPC_LAD2_IO2")
	)
	(segment
		(start 56.3372 -111.522002)
		(end 56.472582 -111.38662)
		(width 0.10668)
		(layer "In4.Cu")
		(net "ESPI_LPC_LAD2_IO2")
	)
	(segment
		(start 60.81903 -63.4492)
		(end 60.38342 -63.01359)
		(width 0.10668)
		(layer "In4.Cu")
		(net "ESPI_LPC_LAD2_IO2")
	)
	(segment
		(start 62.9158 -67.691)
		(end 62.9158 -64.21628)
		(width 0.10668)
		(layer "In4.Cu")
		(net "ESPI_LPC_LAD2_IO2")
	)
	(segment
		(start 61.15812 -84.765642)
		(end 60.747148 -84.35467)
		(width 0.10668)
		(layer "In4.Cu")
		(net "ESPI_LPC_LAD2_IO2")
	)
	(segment
		(start 63.246 -76.327)
		(end 63.246 -74.2696)
		(width 0.10668)
		(layer "In4.Cu")
		(net "ESPI_LPC_LAD2_IO2")
	)
	(segment
		(start 61.01334 -115.1636)
		(end 60.581794 -115.1636)
		(width 0.11684)
		(layer "F.Cu")
		(net "ESPI_LPC_LAD1_IO1")
	)
	(segment
		(start 60.581794 -115.1636)
		(end 60.464954 -115.28044)
		(width 0.11684)
		(layer "F.Cu")
		(net "ESPI_LPC_LAD1_IO1")
	)
	(segment
		(start 60.464954 -115.28044)
		(end 60.464954 -118.25986)
		(width 0.11684)
		(layer "F.Cu")
		(net "ESPI_LPC_LAD1_IO1")
	)
	(via
		(at 61.01334 -115.1636)
		(size 0.508)
		(drill 0.254)
		(layers "F.Cu" "B.Cu")
		(net "ESPI_LPC_LAD1_IO1")
	)
	(via
		(at 66.4972 -63.5762)
		(size 0.6604)
		(drill 0.3302)
		(layers "F.Cu" "B.Cu")
		(net "ESPI_LPC_LAD1_IO1")
	)
	(via
		(at 66.73342 -67.9704)
		(size 0.508)
		(drill 0.254)
		(layers "F.Cu" "B.Cu")
		(net "ESPI_LPC_LAD1_IO1")
	)
	(segment
		(start 66.4972 -63.5762)
		(end 66.4972 -64.8462)
		(width 0.11684)
		(layer "B.Cu")
		(net "ESPI_LPC_LAD1_IO1")
	)
	(segment
		(start 67.056 -67.9704)
		(end 66.73342 -67.9704)
		(width 0.11684)
		(layer "B.Cu")
		(net "ESPI_LPC_LAD1_IO1")
	)
	(segment
		(start 66.847466 -66.568066)
		(end 67.3608 -67.0814)
		(width 0.11684)
		(layer "B.Cu")
		(net "ESPI_LPC_LAD1_IO1")
	)
	(segment
		(start 66.4972 -62.42685)
		(end 66.4972 -63.5762)
		(width 0.11684)
		(layer "B.Cu")
		(net "ESPI_LPC_LAD1_IO1")
	)
	(segment
		(start 67.3608 -67.0814)
		(end 67.3608 -67.6656)
		(width 0.11684)
		(layer "B.Cu")
		(net "ESPI_LPC_LAD1_IO1")
	)
	(segment
		(start 67.3608 -67.6656)
		(end 67.056 -67.9704)
		(width 0.11684)
		(layer "B.Cu")
		(net "ESPI_LPC_LAD1_IO1")
	)
	(segment
		(start 66.4972 -64.8462)
		(end 66.847466 -65.196466)
		(width 0.11684)
		(layer "B.Cu")
		(net "ESPI_LPC_LAD1_IO1")
	)
	(segment
		(start 66.847466 -65.196466)
		(end 66.847466 -66.568066)
		(width 0.11684)
		(layer "B.Cu")
		(net "ESPI_LPC_LAD1_IO1")
	)
	(segment
		(start 68.50888 -77.024484)
		(end 68.50888 -74.454512)
		(width 0.10668)
		(layer "In4.Cu")
		(net "ESPI_LPC_LAD1_IO1")
	)
	(segment
		(start 68.99402 -77.509624)
		(end 68.50888 -77.024484)
		(width 0.10668)
		(layer "In4.Cu")
		(net "ESPI_LPC_LAD1_IO1")
	)
	(segment
		(start 63.743586 -113.52276)
		(end 66.4464 -110.819946)
		(width 0.10668)
		(layer "In4.Cu")
		(net "ESPI_LPC_LAD1_IO1")
	)
	(segment
		(start 67.53098 -88.626188)
		(end 67.53098 -85.651848)
		(width 0.10668)
		(layer "In4.Cu")
		(net "ESPI_LPC_LAD1_IO1")
	)
	(segment
		(start 65.95618 -90.200988)
		(end 67.53098 -88.626188)
		(width 0.10668)
		(layer "In4.Cu")
		(net "ESPI_LPC_LAD1_IO1")
	)
	(segment
		(start 68.23456 -84.367624)
		(end 68.99402 -83.608164)
		(width 0.10668)
		(layer "In4.Cu")
		(net "ESPI_LPC_LAD1_IO1")
	)
	(segment
		(start 67.37858 -69.562472)
		(end 67.37858 -69.144642)
		(width 0.10668)
		(layer "In4.Cu")
		(net "ESPI_LPC_LAD1_IO1")
	)
	(segment
		(start 67.6148 -103.90632)
		(end 65.95618 -102.2477)
		(width 0.10668)
		(layer "In4.Cu")
		(net "ESPI_LPC_LAD1_IO1")
	)
	(segment
		(start 67.53098 -85.651848)
		(end 67.95008 -85.232748)
		(width 0.10668)
		(layer "In4.Cu")
		(net "ESPI_LPC_LAD1_IO1")
	)
	(segment
		(start 67.37858 -69.144642)
		(end 66.7258 -68.491862)
		(width 0.10668)
		(layer "In4.Cu")
		(net "ESPI_LPC_LAD1_IO1")
	)
	(segment
		(start 63.743586 -115.605814)
		(end 63.743586 -113.52276)
		(width 0.10668)
		(layer "In4.Cu")
		(net "ESPI_LPC_LAD1_IO1")
	)
	(segment
		(start 66.3956 -107.771946)
		(end 67.6148 -106.552746)
		(width 0.10668)
		(layer "In4.Cu")
		(net "ESPI_LPC_LAD1_IO1")
	)
	(segment
		(start 68.50888 -74.454512)
		(end 68.36918 -74.314812)
		(width 0.10668)
		(layer "In4.Cu")
		(net "ESPI_LPC_LAD1_IO1")
	)
	(segment
		(start 66.7258 -68.491862)
		(end 66.7258 -67.97802)
		(width 0.10668)
		(layer "In4.Cu")
		(net "ESPI_LPC_LAD1_IO1")
	)
	(segment
		(start 68.23456 -84.946236)
		(end 68.23456 -84.367624)
		(width 0.10668)
		(layer "In4.Cu")
		(net "ESPI_LPC_LAD1_IO1")
	)
	(segment
		(start 67.95008 -85.232748)
		(end 67.95008 -85.230716)
		(width 0.10668)
		(layer "In4.Cu")
		(net "ESPI_LPC_LAD1_IO1")
	)
	(segment
		(start 66.7258 -67.97802)
		(end 66.73342 -67.9704)
		(width 0.10668)
		(layer "In4.Cu")
		(net "ESPI_LPC_LAD1_IO1")
	)
	(segment
		(start 60.58408 -115.1636)
		(end 60.4774 -115.27028)
		(width 0.10668)
		(layer "In4.Cu")
		(net "ESPI_LPC_LAD1_IO1")
	)
	(segment
		(start 63.0174 -116.332)
		(end 63.743586 -115.605814)
		(width 0.10668)
		(layer "In4.Cu")
		(net "ESPI_LPC_LAD1_IO1")
	)
	(segment
		(start 65.95618 -102.2477)
		(end 65.95618 -90.200988)
		(width 0.10668)
		(layer "In4.Cu")
		(net "ESPI_LPC_LAD1_IO1")
	)
	(segment
		(start 68.99402 -83.608164)
		(end 68.99402 -77.509624)
		(width 0.10668)
		(layer "In4.Cu")
		(net "ESPI_LPC_LAD1_IO1")
	)
	(segment
		(start 67.6148 -106.552746)
		(end 67.6148 -103.90632)
		(width 0.10668)
		(layer "In4.Cu")
		(net "ESPI_LPC_LAD1_IO1")
	)
	(segment
		(start 66.3956 -109.906054)
		(end 66.3956 -107.771946)
		(width 0.10668)
		(layer "In4.Cu")
		(net "ESPI_LPC_LAD1_IO1")
	)
	(segment
		(start 66.4464 -109.956854)
		(end 66.3956 -109.906054)
		(width 0.10668)
		(layer "In4.Cu")
		(net "ESPI_LPC_LAD1_IO1")
	)
	(segment
		(start 60.58408 -116.332)
		(end 63.0174 -116.332)
		(width 0.10668)
		(layer "In4.Cu")
		(net "ESPI_LPC_LAD1_IO1")
	)
	(segment
		(start 61.01334 -115.1636)
		(end 60.58408 -115.1636)
		(width 0.10668)
		(layer "In4.Cu")
		(net "ESPI_LPC_LAD1_IO1")
	)
	(segment
		(start 68.36918 -74.314812)
		(end 68.36918 -70.553072)
		(width 0.10668)
		(layer "In4.Cu")
		(net "ESPI_LPC_LAD1_IO1")
	)
	(segment
		(start 67.95008 -85.230716)
		(end 68.23456 -84.946236)
		(width 0.10668)
		(layer "In4.Cu")
		(net "ESPI_LPC_LAD1_IO1")
	)
	(segment
		(start 66.4464 -110.819946)
		(end 66.4464 -109.956854)
		(width 0.10668)
		(layer "In4.Cu")
		(net "ESPI_LPC_LAD1_IO1")
	)
	(segment
		(start 60.4774 -116.22532)
		(end 60.58408 -116.332)
		(width 0.10668)
		(layer "In4.Cu")
		(net "ESPI_LPC_LAD1_IO1")
	)
	(segment
		(start 60.4774 -115.27028)
		(end 60.4774 -116.22532)
		(width 0.10668)
		(layer "In4.Cu")
		(net "ESPI_LPC_LAD1_IO1")
	)
	(segment
		(start 68.36918 -70.553072)
		(end 67.37858 -69.562472)
		(width 0.10668)
		(layer "In4.Cu")
		(net "ESPI_LPC_LAD1_IO1")
	)
	(segment
		(start 60.96254 -115.824)
		(end 60.96254 -116.896134)
		(width 0.11684)
		(layer "F.Cu")
		(net "ESPI_LPC_LAD0_IO0")
	)
	(segment
		(start 60.96254 -116.896134)
		(end 61.064902 -116.998496)
		(width 0.11684)
		(layer "F.Cu")
		(net "ESPI_LPC_LAD0_IO0")
	)
	(segment
		(start 61.064902 -116.998496)
		(end 61.064902 -118.25986)
		(width 0.11684)
		(layer "F.Cu")
		(net "ESPI_LPC_LAD0_IO0")
	)
	(via
		(at 60.96254 -115.824)
		(size 0.508)
		(drill 0.254)
		(layers "F.Cu" "B.Cu")
		(net "ESPI_LPC_LAD0_IO0")
	)
	(via
		(at 65.913 -65.7352)
		(size 0.6604)
		(drill 0.3302)
		(layers "F.Cu" "B.Cu")
		(net "ESPI_LPC_LAD0_IO0")
	)
	(via
		(at 65.913 -66.9798)
		(size 0.508)
		(drill 0.254)
		(layers "F.Cu" "B.Cu")
		(net "ESPI_LPC_LAD0_IO0")
	)
	(segment
		(start 65.913 -66.9798)
		(end 65.913 -65.7352)
		(width 0.11684)
		(layer "B.Cu")
		(net "ESPI_LPC_LAD0_IO0")
	)
	(segment
		(start 65.913 -65.7352)
		(end 64.878458 -64.700658)
		(width 0.11684)
		(layer "B.Cu")
		(net "ESPI_LPC_LAD0_IO0")
	)
	(segment
		(start 64.878458 -62.681866)
		(end 64.634364 -62.437772)
		(width 0.11684)
		(layer "B.Cu")
		(net "ESPI_LPC_LAD0_IO0")
	)
	(segment
		(start 64.878458 -64.700658)
		(end 64.878458 -62.681866)
		(width 0.11684)
		(layer "B.Cu")
		(net "ESPI_LPC_LAD0_IO0")
	)
	(segment
		(start 63.082678 -112.45723)
		(end 63.082678 -112.648238)
		(width 0.10668)
		(layer "In4.Cu")
		(net "ESPI_LPC_LAD0_IO0")
	)
	(segment
		(start 66.9671 -69.315584)
		(end 66.9671 -69.73316)
		(width 0.10668)
		(layer "In4.Cu")
		(net "ESPI_LPC_LAD0_IO0")
	)
	(segment
		(start 64.39027 -111.340646)
		(end 64.758062 -111.708184)
		(width 0.10668)
		(layer "In4.Cu")
		(net "ESPI_LPC_LAD0_IO0")
	)
	(segment
		(start 64.104266 -112.36198)
		(end 64.104266 -112.552988)
		(width 0.10668)
		(layer "In4.Cu")
		(net "ESPI_LPC_LAD0_IO0")
	)
	(segment
		(start 66.5988 -105.078022)
		(end 66.5988 -105.269538)
		(width 0.10668)
		(layer "In4.Cu")
		(net "ESPI_LPC_LAD0_IO0")
	)
	(segment
		(start 65.913 -67.3354)
		(end 66.0146 -67.437)
		(width 0.10668)
		(layer "In4.Cu")
		(net "ESPI_LPC_LAD0_IO0")
	)
	(segment
		(start 66.5988 -106.002582)
		(end 66.5988 -106.194098)
		(width 0.10668)
		(layer "In4.Cu")
		(net "ESPI_LPC_LAD0_IO0")
	)
	(segment
		(start 66.5988 -104.153462)
		(end 66.5988 -104.344978)
		(width 0.10668)
		(layer "In4.Cu")
		(net "ESPI_LPC_LAD0_IO0")
	)
	(segment
		(start 64.39027 -111.149638)
		(end 64.39027 -111.340646)
		(width 0.10668)
		(layer "In4.Cu")
		(net "ESPI_LPC_LAD0_IO0")
	)
	(segment
		(start 62.865 -115.824)
		(end 60.96254 -115.824)
		(width 0.10668)
		(layer "In4.Cu")
		(net "ESPI_LPC_LAD0_IO0")
	)
	(segment
		(start 66.463418 -104.01808)
		(end 66.5988 -104.153462)
		(width 0.10668)
		(layer "In4.Cu")
		(net "ESPI_LPC_LAD0_IO0")
	)
	(segment
		(start 63.246 -115.443)
		(end 62.865 -115.824)
		(width 0.10668)
		(layer "In4.Cu")
		(net "ESPI_LPC_LAD0_IO0")
	)
	(segment
		(start 63.40983 -112.321594)
		(end 63.218314 -112.321594)
		(width 0.10668)
		(layer "In4.Cu")
		(net "ESPI_LPC_LAD0_IO0")
	)
	(segment
		(start 63.082678 -112.648238)
		(end 63.45047 -113.015776)
		(width 0.10668)
		(layer "In4.Cu")
		(net "ESPI_LPC_LAD0_IO0")
	)
	(segment
		(start 63.968376 -112.688878)
		(end 63.777114 -112.688878)
		(width 0.10668)
		(layer "In4.Cu")
		(net "ESPI_LPC_LAD0_IO0")
	)
	(segment
		(start 65.5447 -102.42042)
		(end 65.87236 -102.74808)
		(width 0.10668)
		(layer "In4.Cu")
		(net "ESPI_LPC_LAD0_IO0")
	)
	(segment
		(start 65.94348 -110.13948)
		(end 65.94348 -110.713774)
		(width 0.10668)
		(layer "In4.Cu")
		(net "ESPI_LPC_LAD0_IO0")
	)
	(segment
		(start 68.0974 -83.741006)
		(end 68.0974 -83.922616)
		(width 0.10668)
		(layer "In4.Cu")
		(net "ESPI_LPC_LAD0_IO0")
	)
	(segment
		(start 67.1195 -85.48116)
		(end 67.1195 -88.4555)
		(width 0.10668)
		(layer "In4.Cu")
		(net "ESPI_LPC_LAD0_IO0")
	)
	(segment
		(start 63.736474 -111.803434)
		(end 63.736474 -111.994442)
		(width 0.10668)
		(layer "In4.Cu")
		(net "ESPI_LPC_LAD0_IO0")
	)
	(segment
		(start 65.87236 -103.882698)
		(end 66.007742 -104.01808)
		(width 0.10668)
		(layer "In4.Cu")
		(net "ESPI_LPC_LAD0_IO0")
	)
	(segment
		(start 67.9577 -74.4855)
		(end 68.0974 -74.6252)
		(width 0.10668)
		(layer "In4.Cu")
		(net "ESPI_LPC_LAD0_IO0")
	)
	(segment
		(start 68.0974 -77.195172)
		(end 68.58254 -77.680312)
		(width 0.10668)
		(layer "In4.Cu")
		(net "ESPI_LPC_LAD0_IO0")
	)
	(segment
		(start 65.87236 -106.464862)
		(end 65.87236 -110.06836)
		(width 0.10668)
		(layer "In4.Cu")
		(net "ESPI_LPC_LAD0_IO0")
	)
	(segment
		(start 64.758062 -111.708184)
		(end 64.758062 -111.899192)
		(width 0.10668)
		(layer "In4.Cu")
		(net "ESPI_LPC_LAD0_IO0")
	)
	(segment
		(start 66.5988 -106.194098)
		(end 66.463418 -106.32948)
		(width 0.10668)
		(layer "In4.Cu")
		(net "ESPI_LPC_LAD0_IO0")
	)
	(segment
		(start 65.87236 -102.74808)
		(end 65.87236 -103.882698)
		(width 0.10668)
		(layer "In4.Cu")
		(net "ESPI_LPC_LAD0_IO0")
	)
	(segment
		(start 65.275968 -111.381286)
		(end 65.084706 -111.381286)
		(width 0.10668)
		(layer "In4.Cu")
		(net "ESPI_LPC_LAD0_IO0")
	)
	(segment
		(start 65.94348 -110.713774)
		(end 65.275968 -111.381286)
		(width 0.10668)
		(layer "In4.Cu")
		(net "ESPI_LPC_LAD0_IO0")
	)
	(segment
		(start 67.5386 -85.06206)
		(end 67.1195 -85.48116)
		(width 0.10668)
		(layer "In4.Cu")
		(net "ESPI_LPC_LAD0_IO0")
	)
	(segment
		(start 66.007742 -104.94264)
		(end 66.463418 -104.94264)
		(width 0.10668)
		(layer "In4.Cu")
		(net "ESPI_LPC_LAD0_IO0")
	)
	(segment
		(start 66.0146 -67.437)
		(end 66.0146 -68.363084)
		(width 0.10668)
		(layer "In4.Cu")
		(net "ESPI_LPC_LAD0_IO0")
	)
	(segment
		(start 63.87211 -111.667798)
		(end 63.736474 -111.803434)
		(width 0.10668)
		(layer "In4.Cu")
		(net "ESPI_LPC_LAD0_IO0")
	)
	(segment
		(start 64.758062 -111.899192)
		(end 64.622172 -112.035082)
		(width 0.10668)
		(layer "In4.Cu")
		(net "ESPI_LPC_LAD0_IO0")
	)
	(segment
		(start 64.43091 -112.035082)
		(end 64.063626 -111.667798)
		(width 0.10668)
		(layer "In4.Cu")
		(net "ESPI_LPC_LAD0_IO0")
	)
	(segment
		(start 66.007742 -105.8672)
		(end 66.463418 -105.8672)
		(width 0.10668)
		(layer "In4.Cu")
		(net "ESPI_LPC_LAD0_IO0")
	)
	(segment
		(start 67.82308 -84.196936)
		(end 67.82308 -84.775548)
		(width 0.10668)
		(layer "In4.Cu")
		(net "ESPI_LPC_LAD0_IO0")
	)
	(segment
		(start 66.463418 -104.48036)
		(end 66.007742 -104.48036)
		(width 0.10668)
		(layer "In4.Cu")
		(net "ESPI_LPC_LAD0_IO0")
	)
	(segment
		(start 63.218314 -112.321594)
		(end 63.082678 -112.45723)
		(width 0.10668)
		(layer "In4.Cu")
		(net "ESPI_LPC_LAD0_IO0")
	)
	(segment
		(start 63.45047 -113.015776)
		(end 63.45047 -113.206784)
		(width 0.10668)
		(layer "In4.Cu")
		(net "ESPI_LPC_LAD0_IO0")
	)
	(segment
		(start 66.007742 -105.40492)
		(end 65.87236 -105.540302)
		(width 0.10668)
		(layer "In4.Cu")
		(net "ESPI_LPC_LAD0_IO0")
	)
	(segment
		(start 66.0146 -68.363084)
		(end 66.9671 -69.315584)
		(width 0.10668)
		(layer "In4.Cu")
		(net "ESPI_LPC_LAD0_IO0")
	)
	(segment
		(start 66.9671 -69.73316)
		(end 67.9577 -70.72376)
		(width 0.10668)
		(layer "In4.Cu")
		(net "ESPI_LPC_LAD0_IO0")
	)
	(segment
		(start 68.0974 -74.6252)
		(end 68.0974 -77.195172)
		(width 0.10668)
		(layer "In4.Cu")
		(net "ESPI_LPC_LAD0_IO0")
	)
	(segment
		(start 67.9577 -70.72376)
		(end 67.9577 -74.4855)
		(width 0.10668)
		(layer "In4.Cu")
		(net "ESPI_LPC_LAD0_IO0")
	)
	(segment
		(start 66.007742 -104.01808)
		(end 66.463418 -104.01808)
		(width 0.10668)
		(layer "In4.Cu")
		(net "ESPI_LPC_LAD0_IO0")
	)
	(segment
		(start 65.87236 -105.540302)
		(end 65.87236 -105.731818)
		(width 0.10668)
		(layer "In4.Cu")
		(net "ESPI_LPC_LAD0_IO0")
	)
	(segment
		(start 64.717422 -111.014002)
		(end 64.525906 -111.014002)
		(width 0.10668)
		(layer "In4.Cu")
		(net "ESPI_LPC_LAD0_IO0")
	)
	(segment
		(start 64.622172 -112.035082)
		(end 64.43091 -112.035082)
		(width 0.10668)
		(layer "In4.Cu")
		(net "ESPI_LPC_LAD0_IO0")
	)
	(segment
		(start 67.82308 -84.775548)
		(end 67.5386 -85.060028)
		(width 0.10668)
		(layer "In4.Cu")
		(net "ESPI_LPC_LAD0_IO0")
	)
	(segment
		(start 66.463418 -104.94264)
		(end 66.5988 -105.078022)
		(width 0.10668)
		(layer "In4.Cu")
		(net "ESPI_LPC_LAD0_IO0")
	)
	(segment
		(start 65.87236 -104.615742)
		(end 65.87236 -104.807258)
		(width 0.10668)
		(layer "In4.Cu")
		(net "ESPI_LPC_LAD0_IO0")
	)
	(segment
		(start 66.463418 -105.8672)
		(end 66.5988 -106.002582)
		(width 0.10668)
		(layer "In4.Cu")
		(net "ESPI_LPC_LAD0_IO0")
	)
	(segment
		(start 66.007742 -104.48036)
		(end 65.87236 -104.615742)
		(width 0.10668)
		(layer "In4.Cu")
		(net "ESPI_LPC_LAD0_IO0")
	)
	(segment
		(start 64.063626 -111.667798)
		(end 63.87211 -111.667798)
		(width 0.10668)
		(layer "In4.Cu")
		(net "ESPI_LPC_LAD0_IO0")
	)
	(segment
		(start 65.913 -66.9798)
		(end 65.913 -67.3354)
		(width 0.10668)
		(layer "In4.Cu")
		(net "ESPI_LPC_LAD0_IO0")
	)
	(segment
		(start 68.58254 -83.255866)
		(end 68.0974 -83.741006)
		(width 0.10668)
		(layer "In4.Cu")
		(net "ESPI_LPC_LAD0_IO0")
	)
	(segment
		(start 65.87236 -110.06836)
		(end 65.94348 -110.13948)
		(width 0.10668)
		(layer "In4.Cu")
		(net "ESPI_LPC_LAD0_IO0")
	)
	(segment
		(start 63.777114 -112.688878)
		(end 63.40983 -112.321594)
		(width 0.10668)
		(layer "In4.Cu")
		(net "ESPI_LPC_LAD0_IO0")
	)
	(segment
		(start 66.463418 -105.40492)
		(end 66.007742 -105.40492)
		(width 0.10668)
		(layer "In4.Cu")
		(net "ESPI_LPC_LAD0_IO0")
	)
	(segment
		(start 67.1195 -88.4555)
		(end 65.5447 -90.0303)
		(width 0.10668)
		(layer "In4.Cu")
		(net "ESPI_LPC_LAD0_IO0")
	)
	(segment
		(start 66.5988 -105.269538)
		(end 66.463418 -105.40492)
		(width 0.10668)
		(layer "In4.Cu")
		(net "ESPI_LPC_LAD0_IO0")
	)
	(segment
		(start 68.58254 -77.680312)
		(end 68.58254 -83.255866)
		(width 0.10668)
		(layer "In4.Cu")
		(net "ESPI_LPC_LAD0_IO0")
	)
	(segment
		(start 65.87236 -105.731818)
		(end 66.007742 -105.8672)
		(width 0.10668)
		(layer "In4.Cu")
		(net "ESPI_LPC_LAD0_IO0")
	)
	(segment
		(start 63.45047 -113.206784)
		(end 63.246 -113.411254)
		(width 0.10668)
		(layer "In4.Cu")
		(net "ESPI_LPC_LAD0_IO0")
	)
	(segment
		(start 68.0974 -83.922616)
		(end 67.82308 -84.196936)
		(width 0.10668)
		(layer "In4.Cu")
		(net "ESPI_LPC_LAD0_IO0")
	)
	(segment
		(start 66.5988 -104.344978)
		(end 66.463418 -104.48036)
		(width 0.10668)
		(layer "In4.Cu")
		(net "ESPI_LPC_LAD0_IO0")
	)
	(segment
		(start 66.007742 -106.32948)
		(end 65.87236 -106.464862)
		(width 0.10668)
		(layer "In4.Cu")
		(net "ESPI_LPC_LAD0_IO0")
	)
	(segment
		(start 65.5447 -90.0303)
		(end 65.5447 -102.42042)
		(width 0.10668)
		(layer "In4.Cu")
		(net "ESPI_LPC_LAD0_IO0")
	)
	(segment
		(start 63.246 -113.411254)
		(end 63.246 -115.443)
		(width 0.10668)
		(layer "In4.Cu")
		(net "ESPI_LPC_LAD0_IO0")
	)
	(segment
		(start 67.5386 -85.060028)
		(end 67.5386 -85.06206)
		(width 0.10668)
		(layer "In4.Cu")
		(net "ESPI_LPC_LAD0_IO0")
	)
	(segment
		(start 65.87236 -104.807258)
		(end 66.007742 -104.94264)
		(width 0.10668)
		(layer "In4.Cu")
		(net "ESPI_LPC_LAD0_IO0")
	)
	(segment
		(start 65.084706 -111.381286)
		(end 64.717422 -111.014002)
		(width 0.10668)
		(layer "In4.Cu")
		(net "ESPI_LPC_LAD0_IO0")
	)
	(segment
		(start 64.525906 -111.014002)
		(end 64.39027 -111.149638)
		(width 0.10668)
		(layer "In4.Cu")
		(net "ESPI_LPC_LAD0_IO0")
	)
	(segment
		(start 66.463418 -106.32948)
		(end 66.007742 -106.32948)
		(width 0.10668)
		(layer "In4.Cu")
		(net "ESPI_LPC_LAD0_IO0")
	)
	(segment
		(start 64.104266 -112.552988)
		(end 63.968376 -112.688878)
		(width 0.10668)
		(layer "In4.Cu")
		(net "ESPI_LPC_LAD0_IO0")
	)
	(segment
		(start 63.736474 -111.994442)
		(end 64.104266 -112.36198)
		(width 0.10668)
		(layer "In4.Cu")
		(net "ESPI_LPC_LAD0_IO0")
	)
	(segment
		(start 62.865 -116.2304)
		(end 62.865 -118.25986)
		(width 0.11684)
		(layer "F.Cu")
		(net "ESPI_HOST_LPC_BMC_LFRAME_N")
	)
	(segment
		(start 63.7032 -109.855)
		(end 63.7032 -111.715296)
		(width 0.11684)
		(layer "F.Cu")
		(net "ESPI_HOST_LPC_BMC_LFRAME_N")
	)
	(segment
		(start 64.51854 -109.03966)
		(end 64.51854 -108.404406)
		(width 0.11684)
		(layer "F.Cu")
		(net "ESPI_HOST_LPC_BMC_LFRAME_N")
	)
	(segment
		(start 64.51854 -108.404406)
		(end 64.522096 -108.40085)
		(width 0.11684)
		(layer "F.Cu")
		(net "ESPI_HOST_LPC_BMC_LFRAME_N")
	)
	(segment
		(start 63.1444 -112.274096)
		(end 63.1444 -115.951)
		(width 0.11684)
		(layer "F.Cu")
		(net "ESPI_HOST_LPC_BMC_LFRAME_N")
	)
	(segment
		(start 63.7032 -109.855)
		(end 64.51854 -109.03966)
		(width 0.11684)
		(layer "F.Cu")
		(net "ESPI_HOST_LPC_BMC_LFRAME_N")
	)
	(segment
		(start 63.1444 -115.951)
		(end 62.865 -116.2304)
		(width 0.11684)
		(layer "F.Cu")
		(net "ESPI_HOST_LPC_BMC_LFRAME_N")
	)
	(segment
		(start 64.522096 -108.40085)
		(end 65.5066 -108.40085)
		(width 0.11684)
		(layer "F.Cu")
		(net "ESPI_HOST_LPC_BMC_LFRAME_N")
	)
	(segment
		(start 63.7032 -111.715296)
		(end 63.1444 -112.274096)
		(width 0.11684)
		(layer "F.Cu")
		(net "ESPI_HOST_LPC_BMC_LFRAME_N")
	)
	(via
		(at 63.7032 -109.855)
		(size 0.762)
		(drill 0.381)
		(layers "F.Cu" "B.Cu")
		(net "ESPI_HOST_LPC_BMC_LFRAME_N")
	)
	(segment
		(start 64.657732 -110.87481)
		(end 63.464948 -116.871242)
		(width 0.11684)
		(layer "F.Cu")
		(net "ESPI_HOST_LPC_BMC_CLK")
	)
	(segment
		(start 63.464948 -116.871242)
		(end 63.464948 -118.25986)
		(width 0.11684)
		(layer "F.Cu")
		(net "ESPI_HOST_LPC_BMC_CLK")
	)
	(segment
		(start 64.8208 -110.337092)
		(end 64.657732 -110.87481)
		(width 0.11684)
		(layer "F.Cu")
		(net "ESPI_HOST_LPC_BMC_CLK")
	)
	(segment
		(start 66.32575 -108.40085)
		(end 66.5226 -108.40085)
		(width 0.11684)
		(layer "F.Cu")
		(net "ESPI_HOST_LPC_BMC_CLK")
	)
	(segment
		(start 65.1256 -109.601)
		(end 66.32575 -108.40085)
		(width 0.11684)
		(layer "F.Cu")
		(net "ESPI_HOST_LPC_BMC_CLK")
	)
	(segment
		(start 65.1256 -109.601)
		(end 64.8208 -110.337092)
		(width 0.11684)
		(layer "F.Cu")
		(net "ESPI_HOST_LPC_BMC_CLK")
	)
	(via
		(at 65.1256 -109.601)
		(size 0.762)
		(drill 0.381)
		(layers "F.Cu" "B.Cu")
		(net "ESPI_HOST_LPC_BMC_CLK")
	)
	(segment
		(start 79.16418 -72.43064)
		(end 80.293972 -72.43064)
		(width 0.11684)
		(layer "F.Cu")
		(net "EN_P1V2_AUX_R")
	)
	(segment
		(start 78.365096 -72.43064)
		(end 79.16418 -72.43064)
		(width 0.11684)
		(layer "F.Cu")
		(net "EN_P1V2_AUX_R")
	)
	(segment
		(start 78.347824 -71.396352)
		(end 78.347824 -72.413368)
		(width 0.11684)
		(layer "F.Cu")
		(net "EN_P1V2_AUX_R")
	)
	(segment
		(start 78.347824 -72.413368)
		(end 78.365096 -72.43064)
		(width 0.11684)
		(layer "F.Cu")
		(net "EN_P1V2_AUX_R")
	)
	(segment
		(start 78.347824 -70.3834)
		(end 78.347824 -71.396352)
		(width 0.11684)
		(layer "F.Cu")
		(net "EN_P1V2_AUX_R")
	)
	(via
		(at 79.16418 -72.43064)
		(size 0.508)
		(drill 0.254)
		(layers "F.Cu" "B.Cu")
		(net "EN_P1V2_AUX_R")
	)
	(via
		(at 78.147672 -72.43064)
		(size 0.6604)
		(drill 0.3302)
		(layers "F.Cu" "B.Cu")
		(net "EN_P1V2_AUX_R")
	)
	(segment
		(start 79.16418 -72.43064)
		(end 78.147672 -72.43064)
		(width 0.11684)
		(layer "B.Cu")
		(net "EN_P1V2_AUX_R")
	)
	(segment
		(start 29.845 -69.2404)
		(end 29.508704 -68.904104)
		(width 0.11684)
		(layer "F.Cu")
		(net "EMMC_DT7_R")
	)
	(segment
		(start 30.25013 -71.910194)
		(end 29.27604 -70.936104)
		(width 0.11684)
		(layer "F.Cu")
		(net "EMMC_DT7_R")
	)
	(segment
		(start 30.25013 -73.360534)
		(end 30.25013 -71.910194)
		(width 0.11684)
		(layer "F.Cu")
		(net "EMMC_DT7_R")
	)
	(segment
		(start 29.27604 -70.936104)
		(end 29.845 -70.367144)
		(width 0.11684)
		(layer "F.Cu")
		(net "EMMC_DT7_R")
	)
	(segment
		(start 29.508704 -68.904104)
		(end 29.27604 -68.904104)
		(width 0.11684)
		(layer "F.Cu")
		(net "EMMC_DT7_R")
	)
	(segment
		(start 29.845 -70.367144)
		(end 29.845 -69.2404)
		(width 0.11684)
		(layer "F.Cu")
		(net "EMMC_DT7_R")
	)
	(segment
		(start 31.0769 -69.3547)
		(end 31.0769 -70.278244)
		(width 0.11684)
		(layer "F.Cu")
		(net "EMMC_DT6_R")
	)
	(segment
		(start 30.626304 -68.904104)
		(end 31.0769 -69.3547)
		(width 0.11684)
		(layer "F.Cu")
		(net "EMMC_DT6_R")
	)
	(segment
		(start 31.0769 -70.278244)
		(end 30.41904 -70.936104)
		(width 0.11684)
		(layer "F.Cu")
		(net "EMMC_DT6_R")
	)
	(segment
		(start 30.41904 -68.904104)
		(end 30.626304 -68.904104)
		(width 0.11684)
		(layer "F.Cu")
		(net "EMMC_DT6_R")
	)
	(segment
		(start 30.41904 -70.936104)
		(end 30.750002 -71.267066)
		(width 0.11684)
		(layer "F.Cu")
		(net "EMMC_DT6_R")
	)
	(segment
		(start 30.750002 -71.267066)
		(end 30.750002 -73.360534)
		(width 0.11684)
		(layer "F.Cu")
		(net "EMMC_DT6_R")
	)
	(segment
		(start 32.24022 -69.27342)
		(end 32.24022 -70.257924)
		(width 0.11684)
		(layer "F.Cu")
		(net "EMMC_DT5_R")
	)
	(segment
		(start 31.250128 -73.360534)
		(end 31.250128 -71.248016)
		(width 0.11684)
		(layer "F.Cu")
		(net "EMMC_DT5_R")
	)
	(segment
		(start 31.870904 -68.904104)
		(end 32.24022 -69.27342)
		(width 0.11684)
		(layer "F.Cu")
		(net "EMMC_DT5_R")
	)
	(segment
		(start 31.56204 -68.904104)
		(end 31.870904 -68.904104)
		(width 0.11684)
		(layer "F.Cu")
		(net "EMMC_DT5_R")
	)
	(segment
		(start 31.250128 -71.248016)
		(end 31.56204 -70.936104)
		(width 0.11684)
		(layer "F.Cu")
		(net "EMMC_DT5_R")
	)
	(segment
		(start 32.24022 -70.257924)
		(end 31.56204 -70.936104)
		(width 0.11684)
		(layer "F.Cu")
		(net "EMMC_DT5_R")
	)
	(segment
		(start 32.746696 -68.904104)
		(end 32.70504 -68.904104)
		(width 0.11684)
		(layer "F.Cu")
		(net "EMMC_DT4_R")
	)
	(segment
		(start 31.75 -71.891144)
		(end 31.75 -73.360534)
		(width 0.11684)
		(layer "F.Cu")
		(net "EMMC_DT4_R")
	)
	(segment
		(start 33.16986 -70.471284)
		(end 33.16986 -69.327268)
		(width 0.11684)
		(layer "F.Cu")
		(net "EMMC_DT4_R")
	)
	(segment
		(start 32.70504 -70.936104)
		(end 31.75 -71.891144)
		(width 0.11684)
		(layer "F.Cu")
		(net "EMMC_DT4_R")
	)
	(segment
		(start 33.16986 -69.327268)
		(end 32.746696 -68.904104)
		(width 0.11684)
		(layer "F.Cu")
		(net "EMMC_DT4_R")
	)
	(segment
		(start 32.70504 -70.936104)
		(end 33.16986 -70.471284)
		(width 0.11684)
		(layer "F.Cu")
		(net "EMMC_DT4_R")
	)
	(segment
		(start 31.983172 -83.281774)
		(end 31.983172 -83.416902)
		(width 0.11684)
		(layer "F.Cu")
		(net "EMMC_DT3_R")
	)
	(segment
		(start 32.999172 -83.416902)
		(end 31.983172 -83.416902)
		(width 0.11684)
		(layer "F.Cu")
		(net "EMMC_DT3_R")
	)
	(segment
		(start 32.500062 -82.764884)
		(end 31.983172 -83.281774)
		(width 0.11684)
		(layer "F.Cu")
		(net "EMMC_DT3_R")
	)
	(segment
		(start 32.500062 -80.910176)
		(end 32.500062 -82.764884)
		(width 0.11684)
		(layer "F.Cu")
		(net "EMMC_DT3_R")
	)
	(segment
		(start 35.031172 -83.416902)
		(end 34.015172 -83.416902)
		(width 0.11684)
		(layer "F.Cu")
		(net "EMMC_DT2_R")
	)
	(segment
		(start 34.015172 -83.416902)
		(end 34.015172 -82.706718)
		(width 0.11684)
		(layer "F.Cu")
		(net "EMMC_DT2_R")
	)
	(segment
		(start 34.015172 -82.706718)
		(end 33.50006 -82.191606)
		(width 0.11684)
		(layer "F.Cu")
		(net "EMMC_DT2_R")
	)
	(segment
		(start 33.50006 -82.191606)
		(end 33.50006 -80.910176)
		(width 0.11684)
		(layer "F.Cu")
		(net "EMMC_DT2_R")
	)
	(segment
		(start 36.3982 -82.3214)
		(end 34.2392 -82.3214)
		(width 0.11684)
		(layer "F.Cu")
		(net "EMMC_DT1_R")
	)
	(segment
		(start 37.063172 -82.986372)
		(end 36.3982 -82.3214)
		(width 0.11684)
		(layer "F.Cu")
		(net "EMMC_DT1_R")
	)
	(segment
		(start 36.047172 -83.416902)
		(end 37.063172 -83.416902)
		(width 0.11684)
		(layer "F.Cu")
		(net "EMMC_DT1_R")
	)
	(segment
		(start 37.063172 -83.416902)
		(end 37.063172 -82.986372)
		(width 0.11684)
		(layer "F.Cu")
		(net "EMMC_DT1_R")
	)
	(segment
		(start 34.2392 -82.3214)
		(end 33.999932 -82.082132)
		(width 0.11684)
		(layer "F.Cu")
		(net "EMMC_DT1_R")
	)
	(segment
		(start 33.999932 -82.082132)
		(end 33.999932 -80.910176)
		(width 0.11684)
		(layer "F.Cu")
		(net "EMMC_DT1_R")
	)
	(segment
		(start 34.99993 -80.910176)
		(end 34.99993 -81.78673)
		(width 0.11684)
		(layer "F.Cu")
		(net "EMMC_DT0_R")
	)
	(segment
		(start 36.57727 -81.915)
		(end 38.079172 -83.416902)
		(width 0.11684)
		(layer "F.Cu")
		(net "EMMC_DT0_R")
	)
	(segment
		(start 38.079172 -83.416902)
		(end 39.095172 -83.416902)
		(width 0.11684)
		(layer "F.Cu")
		(net "EMMC_DT0_R")
	)
	(segment
		(start 34.99993 -81.78673)
		(end 35.1282 -81.915)
		(width 0.11684)
		(layer "F.Cu")
		(net "EMMC_DT0_R")
	)
	(segment
		(start 35.1282 -81.915)
		(end 36.57727 -81.915)
		(width 0.11684)
		(layer "F.Cu")
		(net "EMMC_DT0_R")
	)
	(segment
		(start 31.554166 -81.895696)
		(end 31.716726 -81.895696)
		(width 0.11684)
		(layer "F.Cu")
		(net "EMMC_CMD_R")
	)
	(segment
		(start 30.967172 -82.48269)
		(end 31.554166 -81.895696)
		(width 0.11684)
		(layer "F.Cu")
		(net "EMMC_CMD_R")
	)
	(segment
		(start 31.773622 -81.8388)
		(end 31.7754 -81.8388)
		(width 0.11684)
		(layer "F.Cu")
		(net "EMMC_CMD_R")
	)
	(segment
		(start 29.951172 -83.416902)
		(end 30.967172 -83.416902)
		(width 0.11684)
		(layer "F.Cu")
		(net "EMMC_CMD_R")
	)
	(segment
		(start 31.999936 -81.614264)
		(end 31.999936 -80.910176)
		(width 0.11684)
		(layer "F.Cu")
		(net "EMMC_CMD_R")
	)
	(segment
		(start 30.967172 -83.416902)
		(end 30.967172 -82.48269)
		(width 0.11684)
		(layer "F.Cu")
		(net "EMMC_CMD_R")
	)
	(segment
		(start 31.7754 -81.8388)
		(end 31.999936 -81.614264)
		(width 0.11684)
		(layer "F.Cu")
		(net "EMMC_CMD_R")
	)
	(segment
		(start 31.716726 -81.895696)
		(end 31.773622 -81.8388)
		(width 0.11684)
		(layer "F.Cu")
		(net "EMMC_CMD_R")
	)
	(segment
		(start 29.374084 -82.182716)
		(end 30.440884 -82.182716)
		(width 0.11684)
		(layer "F.Cu")
		(net "EMMC_CLK_R")
	)
	(segment
		(start 28.935172 -82.621628)
		(end 29.374084 -82.182716)
		(width 0.11684)
		(layer "F.Cu")
		(net "EMMC_CLK_R")
	)
	(segment
		(start 30.440884 -82.182716)
		(end 30.999938 -81.623662)
		(width 0.11684)
		(layer "F.Cu")
		(net "EMMC_CLK_R")
	)
	(segment
		(start 30.999938 -81.623662)
		(end 30.999938 -80.910176)
		(width 0.11684)
		(layer "F.Cu")
		(net "EMMC_CLK_R")
	)
	(segment
		(start 28.935172 -83.416902)
		(end 28.935172 -82.621628)
		(width 0.11684)
		(layer "F.Cu")
		(net "EMMC_CLK_R")
	)
	(segment
		(start 47.295054 -39.37127)
		(end 46.89983 -38.976046)
		(width 0.11684)
		(layer "F.Cu")
		(net "BMC_EMMC_WP_N")
	)
	(via
		(at 46.89983 -38.976046)
		(size 0.4572)
		(drill 0.254)
		(layers "F.Cu" "B.Cu")
		(net "BMC_EMMC_WP_N")
	)
	(via
		(at 72.621394 -71.010526)
		(size 0.762)
		(drill 0.254)
		(layers "F.Cu" "B.Cu")
		(net "BMC_EMMC_WP_N")
	)
	(segment
		(start 72.621394 -71.647558)
		(end 72.621394 -71.010526)
		(width 0.11684)
		(layer "B.Cu")
		(net "BMC_EMMC_WP_N")
	)
	(segment
		(start 72.621394 -71.010526)
		(end 72.621394 -69.976238)
		(width 0.11684)
		(layer "B.Cu")
		(net "BMC_EMMC_WP_N")
	)
	(segment
		(start 74.84872 -57.239916)
		(end 72.263 -54.654196)
		(width 0.10668)
		(layer "In4.Cu")
		(net "BMC_EMMC_WP_N")
	)
	(segment
		(start 48.6156 -39.7256)
		(end 48.249586 -39.359586)
		(width 0.10668)
		(layer "In4.Cu")
		(net "BMC_EMMC_WP_N")
	)
	(segment
		(start 56.0832 -48.407574)
		(end 55.858664 -48.183038)
		(width 0.10668)
		(layer "In4.Cu")
		(net "BMC_EMMC_WP_N")
	)
	(segment
		(start 55.1942 -47.930054)
		(end 55.1942 -46.863)
		(width 0.10668)
		(layer "In4.Cu")
		(net "BMC_EMMC_WP_N")
	)
	(segment
		(start 73.23836 -70.39356)
		(end 73.64984 -70.39356)
		(width 0.10668)
		(layer "In4.Cu")
		(net "BMC_EMMC_WP_N")
	)
	(segment
		(start 56.728106 -49.46396)
		(end 56.0832 -48.819054)
		(width 0.10668)
		(layer "In4.Cu")
		(net "BMC_EMMC_WP_N")
	)
	(segment
		(start 51.308 -42.8244)
		(end 51.054 -42.5704)
		(width 0.10668)
		(layer "In4.Cu")
		(net "BMC_EMMC_WP_N")
	)
	(segment
		(start 50.7238 -42.5704)
		(end 50.5206 -42.3672)
		(width 0.10668)
		(layer "In4.Cu")
		(net "BMC_EMMC_WP_N")
	)
	(segment
		(start 49.896522 -40.168576)
		(end 49.453546 -39.7256)
		(width 0.10668)
		(layer "In4.Cu")
		(net "BMC_EMMC_WP_N")
	)
	(segment
		(start 66.65722 -49.7078)
		(end 61.0616 -49.7078)
		(width 0.10668)
		(layer "In4.Cu")
		(net "BMC_EMMC_WP_N")
	)
	(segment
		(start 50.516282 -40.432482)
		(end 50.252376 -40.168576)
		(width 0.10668)
		(layer "In4.Cu")
		(net "BMC_EMMC_WP_N")
	)
	(segment
		(start 74.84872 -69.19468)
		(end 74.84872 -57.239916)
		(width 0.10668)
		(layer "In4.Cu")
		(net "BMC_EMMC_WP_N")
	)
	(segment
		(start 60.81776 -49.46396)
		(end 56.728106 -49.46396)
		(width 0.10668)
		(layer "In4.Cu")
		(net "BMC_EMMC_WP_N")
	)
	(segment
		(start 61.0616 -49.7078)
		(end 60.81776 -49.46396)
		(width 0.10668)
		(layer "In4.Cu")
		(net "BMC_EMMC_WP_N")
	)
	(segment
		(start 71.693024 -52.96408)
		(end 69.69506 -50.966116)
		(width 0.10668)
		(layer "In4.Cu")
		(net "BMC_EMMC_WP_N")
	)
	(segment
		(start 48.249586 -39.359586)
		(end 47.28337 -39.359586)
		(width 0.10668)
		(layer "In4.Cu")
		(net "BMC_EMMC_WP_N")
	)
	(segment
		(start 50.5206 -42.3672)
		(end 50.5206 -42.33926)
		(width 0.10668)
		(layer "In4.Cu")
		(net "BMC_EMMC_WP_N")
	)
	(segment
		(start 50.516282 -42.334942)
		(end 50.516282 -40.432482)
		(width 0.10668)
		(layer "In4.Cu")
		(net "BMC_EMMC_WP_N")
	)
	(segment
		(start 73.64984 -70.39356)
		(end 74.84872 -69.19468)
		(width 0.10668)
		(layer "In4.Cu")
		(net "BMC_EMMC_WP_N")
	)
	(segment
		(start 71.9582 -52.96408)
		(end 71.693024 -52.96408)
		(width 0.10668)
		(layer "In4.Cu")
		(net "BMC_EMMC_WP_N")
	)
	(segment
		(start 55.447184 -48.183038)
		(end 55.1942 -47.930054)
		(width 0.10668)
		(layer "In4.Cu")
		(net "BMC_EMMC_WP_N")
	)
	(segment
		(start 51.308 -43.2816)
		(end 51.308 -42.8244)
		(width 0.10668)
		(layer "In4.Cu")
		(net "BMC_EMMC_WP_N")
	)
	(segment
		(start 72.263 -53.26888)
		(end 71.9582 -52.96408)
		(width 0.10668)
		(layer "In4.Cu")
		(net "BMC_EMMC_WP_N")
	)
	(segment
		(start 55.858664 -48.183038)
		(end 55.447184 -48.183038)
		(width 0.10668)
		(layer "In4.Cu")
		(net "BMC_EMMC_WP_N")
	)
	(segment
		(start 54.67604 -46.34484)
		(end 54.67604 -45.76572)
		(width 0.10668)
		(layer "In4.Cu")
		(net "BMC_EMMC_WP_N")
	)
	(segment
		(start 51.054 -42.5704)
		(end 50.7238 -42.5704)
		(width 0.10668)
		(layer "In4.Cu")
		(net "BMC_EMMC_WP_N")
	)
	(segment
		(start 49.453546 -39.7256)
		(end 48.6156 -39.7256)
		(width 0.10668)
		(layer "In4.Cu")
		(net "BMC_EMMC_WP_N")
	)
	(segment
		(start 54.67604 -45.76572)
		(end 53.683408 -44.773088)
		(width 0.10668)
		(layer "In4.Cu")
		(net "BMC_EMMC_WP_N")
	)
	(segment
		(start 52.979828 -43.7134)
		(end 51.7398 -43.7134)
		(width 0.10668)
		(layer "In4.Cu")
		(net "BMC_EMMC_WP_N")
	)
	(segment
		(start 51.7398 -43.7134)
		(end 51.308 -43.2816)
		(width 0.10668)
		(layer "In4.Cu")
		(net "BMC_EMMC_WP_N")
	)
	(segment
		(start 72.263 -54.654196)
		(end 72.263 -53.26888)
		(width 0.10668)
		(layer "In4.Cu")
		(net "BMC_EMMC_WP_N")
	)
	(segment
		(start 50.252376 -40.168576)
		(end 49.896522 -40.168576)
		(width 0.10668)
		(layer "In4.Cu")
		(net "BMC_EMMC_WP_N")
	)
	(segment
		(start 56.0832 -48.819054)
		(end 56.0832 -48.407574)
		(width 0.10668)
		(layer "In4.Cu")
		(net "BMC_EMMC_WP_N")
	)
	(segment
		(start 53.683408 -44.773088)
		(end 53.683408 -44.41698)
		(width 0.10668)
		(layer "In4.Cu")
		(net "BMC_EMMC_WP_N")
	)
	(segment
		(start 47.28337 -39.359586)
		(end 46.89983 -38.976046)
		(width 0.10668)
		(layer "In4.Cu")
		(net "BMC_EMMC_WP_N")
	)
	(segment
		(start 53.683408 -44.41698)
		(end 52.979828 -43.7134)
		(width 0.10668)
		(layer "In4.Cu")
		(net "BMC_EMMC_WP_N")
	)
	(segment
		(start 50.5206 -42.33926)
		(end 50.516282 -42.334942)
		(width 0.10668)
		(layer "In4.Cu")
		(net "BMC_EMMC_WP_N")
	)
	(segment
		(start 69.69506 -50.966116)
		(end 66.65722 -49.7078)
		(width 0.10668)
		(layer "In4.Cu")
		(net "BMC_EMMC_WP_N")
	)
	(segment
		(start 55.1942 -46.863)
		(end 54.67604 -46.34484)
		(width 0.10668)
		(layer "In4.Cu")
		(net "BMC_EMMC_WP_N")
	)
	(segment
		(start 72.621394 -71.010526)
		(end 73.23836 -70.39356)
		(width 0.10668)
		(layer "In4.Cu")
		(net "BMC_EMMC_WP_N")
	)
	(segment
		(start 38.177724 -76.740766)
		(end 38.17747 -76.740766)
		(width 0.11684)
		(layer "F.Cu")
		(net "BMC_EMMC_RST_N")
	)
	(segment
		(start 64.1096 -71.24319)
		(end 64.469772 -71.603362)
		(width 0.11684)
		(layer "F.Cu")
		(net "BMC_EMMC_RST_N")
	)
	(segment
		(start 64.770762 -71.603362)
		(end 65.532 -72.3646)
		(width 0.11684)
		(layer "F.Cu")
		(net "BMC_EMMC_RST_N")
	)
	(segment
		(start 33.749996 -71.431404)
		(end 33.749996 -73.360534)
		(width 0.11684)
		(layer "F.Cu")
		(net "BMC_EMMC_RST_N")
	)
	(segment
		(start 34.10204 -69.83476)
		(end 33.849818 -70.086982)
		(width 0.11684)
		(layer "F.Cu")
		(net "BMC_EMMC_RST_N")
	)
	(segment
		(start 38.17747 -76.740766)
		(end 38.174422 -76.737718)
		(width 0.11684)
		(layer "F.Cu")
		(net "BMC_EMMC_RST_N")
	)
	(segment
		(start 34.5186 -76.962)
		(end 37.95649 -76.962)
		(width 0.11684)
		(layer "F.Cu")
		(net "BMC_EMMC_RST_N")
	)
	(segment
		(start 64.469772 -71.603362)
		(end 64.770762 -71.603362)
		(width 0.11684)
		(layer "F.Cu")
		(net "BMC_EMMC_RST_N")
	)
	(segment
		(start 33.849818 -70.086982)
		(end 33.849818 -71.331582)
		(width 0.11684)
		(layer "F.Cu")
		(net "BMC_EMMC_RST_N")
	)
	(segment
		(start 33.749996 -73.360534)
		(end 33.749996 -76.193396)
		(width 0.11684)
		(layer "F.Cu")
		(net "BMC_EMMC_RST_N")
	)
	(segment
		(start 33.749996 -76.193396)
		(end 34.5186 -76.962)
		(width 0.11684)
		(layer "F.Cu")
		(net "BMC_EMMC_RST_N")
	)
	(segment
		(start 34.10204 -69.17309)
		(end 34.10204 -69.83476)
		(width 0.11684)
		(layer "F.Cu")
		(net "BMC_EMMC_RST_N")
	)
	(segment
		(start 33.849818 -71.331582)
		(end 33.749996 -71.431404)
		(width 0.11684)
		(layer "F.Cu")
		(net "BMC_EMMC_RST_N")
	)
	(segment
		(start 37.95649 -76.962)
		(end 38.177724 -76.740766)
		(width 0.11684)
		(layer "F.Cu")
		(net "BMC_EMMC_RST_N")
	)
	(segment
		(start 33.782 -68.85305)
		(end 34.10204 -69.17309)
		(width 0.11684)
		(layer "F.Cu")
		(net "BMC_EMMC_RST_N")
	)
	(via
		(at 61.618368 -83.993482)
		(size 0.508)
		(drill 0.254)
		(layers "F.Cu" "B.Cu")
		(net "BMC_EMMC_RST_N")
	)
	(via
		(at 65.532 -72.3646)
		(size 0.508)
		(drill 0.254)
		(layers "F.Cu" "B.Cu")
		(net "BMC_EMMC_RST_N")
	)
	(via
		(at 62.484 -84.8106)
		(size 0.6604)
		(drill 0.3302)
		(layers "F.Cu" "B.Cu")
		(net "BMC_EMMC_RST_N")
	)
	(via
		(at 38.174422 -76.737718)
		(size 0.508)
		(drill 0.254)
		(layers "F.Cu" "B.Cu")
		(net "BMC_EMMC_RST_N")
	)
	(via
		(at 67.6402 -78.105)
		(size 0.508)
		(drill 0.254)
		(layers "F.Cu" "B.Cu")
		(net "BMC_EMMC_RST_N")
	)
	(segment
		(start 62.484 -84.8106)
		(end 63.3984 -84.8106)
		(width 0.11684)
		(layer "B.Cu")
		(net "BMC_EMMC_RST_N")
	)
	(segment
		(start 61.618368 -83.993482)
		(end 62.435486 -84.8106)
		(width 0.11684)
		(layer "B.Cu")
		(net "BMC_EMMC_RST_N")
	)
	(segment
		(start 64.64808 -83.56092)
		(end 67.16268 -83.56092)
		(width 0.11684)
		(layer "B.Cu")
		(net "BMC_EMMC_RST_N")
	)
	(segment
		(start 67.8688 -78.3336)
		(end 67.6402 -78.105)
		(width 0.11684)
		(layer "B.Cu")
		(net "BMC_EMMC_RST_N")
	)
	(segment
		(start 67.16268 -83.56092)
		(end 67.8688 -82.8548)
		(width 0.11684)
		(layer "B.Cu")
		(net "BMC_EMMC_RST_N")
	)
	(segment
		(start 67.8688 -82.8548)
		(end 67.8688 -78.3336)
		(width 0.11684)
		(layer "B.Cu")
		(net "BMC_EMMC_RST_N")
	)
	(segment
		(start 62.435486 -84.8106)
		(end 62.484 -84.8106)
		(width 0.11684)
		(layer "B.Cu")
		(net "BMC_EMMC_RST_N")
	)
	(segment
		(start 63.3984 -84.8106)
		(end 64.64808 -83.56092)
		(width 0.11684)
		(layer "B.Cu")
		(net "BMC_EMMC_RST_N")
	)
	(segment
		(start 42.645838 -75.30846)
		(end 44.377102 -75.30846)
		(width 0.08382)
		(layer "In2.Cu")
		(net "BMC_EMMC_RST_N")
	)
	(segment
		(start 60.367672 -78.448408)
		(end 60.719462 -78.800198)
		(width 0.08382)
		(layer "In2.Cu")
		(net "BMC_EMMC_RST_N")
	)
	(segment
		(start 47.85995 -76.58735)
		(end 48.0822 -76.8096)
		(width 0.08382)
		(layer "In2.Cu")
		(net "BMC_EMMC_RST_N")
	)
	(segment
		(start 48.0822 -76.8096)
		(end 50.744628 -76.8096)
		(width 0.08382)
		(layer "In2.Cu")
		(net "BMC_EMMC_RST_N")
	)
	(segment
		(start 60.719462 -78.800198)
		(end 60.719462 -79.210916)
		(width 0.08382)
		(layer "In2.Cu")
		(net "BMC_EMMC_RST_N")
	)
	(segment
		(start 60.845446 -79.3369)
		(end 61.59754 -79.3369)
		(width 0.08382)
		(layer "In2.Cu")
		(net "BMC_EMMC_RST_N")
	)
	(segment
		(start 59.869832 -78.448408)
		(end 60.367672 -78.448408)
		(width 0.08382)
		(layer "In2.Cu")
		(net "BMC_EMMC_RST_N")
	)
	(segment
		(start 40.543734 -75.991466)
		(end 41.962832 -75.991466)
		(width 0.08382)
		(layer "In2.Cu")
		(net "BMC_EMMC_RST_N")
	)
	(segment
		(start 41.962832 -75.991466)
		(end 42.645838 -75.30846)
		(width 0.08382)
		(layer "In2.Cu")
		(net "BMC_EMMC_RST_N")
	)
	(segment
		(start 53.70703 -76.944728)
		(end 53.70703 -76.833984)
		(width 0.08382)
		(layer "In2.Cu")
		(net "BMC_EMMC_RST_N")
	)
	(segment
		(start 59.610498 -78.707742)
		(end 59.869832 -78.448408)
		(width 0.08382)
		(layer "In2.Cu")
		(net "BMC_EMMC_RST_N")
	)
	(segment
		(start 54.76494 -76.44638)
		(end 57.026302 -78.707742)
		(width 0.08382)
		(layer "In2.Cu")
		(net "BMC_EMMC_RST_N")
	)
	(segment
		(start 64.81318 -78.54442)
		(end 65.4558 -77.9018)
		(width 0.08382)
		(layer "In2.Cu")
		(net "BMC_EMMC_RST_N")
	)
	(segment
		(start 62.39002 -78.54442)
		(end 64.81318 -78.54442)
		(width 0.08382)
		(layer "In2.Cu")
		(net "BMC_EMMC_RST_N")
	)
	(segment
		(start 53.078888 -77.57287)
		(end 53.70703 -76.944728)
		(width 0.08382)
		(layer "In2.Cu")
		(net "BMC_EMMC_RST_N")
	)
	(segment
		(start 45.86732 -76.58735)
		(end 47.85995 -76.58735)
		(width 0.08382)
		(layer "In2.Cu")
		(net "BMC_EMMC_RST_N")
	)
	(segment
		(start 51.507898 -77.57287)
		(end 53.078888 -77.57287)
		(width 0.08382)
		(layer "In2.Cu")
		(net "BMC_EMMC_RST_N")
	)
	(segment
		(start 61.59754 -79.3369)
		(end 62.39002 -78.54442)
		(width 0.08382)
		(layer "In2.Cu")
		(net "BMC_EMMC_RST_N")
	)
	(segment
		(start 65.4558 -77.9018)
		(end 67.437 -77.9018)
		(width 0.08382)
		(layer "In2.Cu")
		(net "BMC_EMMC_RST_N")
	)
	(segment
		(start 44.377102 -75.30846)
		(end 45.506894 -76.438252)
		(width 0.08382)
		(layer "In2.Cu")
		(net "BMC_EMMC_RST_N")
	)
	(segment
		(start 45.632116 -76.490068)
		(end 45.86732 -76.58735)
		(width 0.08382)
		(layer "In2.Cu")
		(net "BMC_EMMC_RST_N")
	)
	(segment
		(start 45.506894 -76.438252)
		(end 45.632116 -76.490068)
		(width 0.08382)
		(layer "In2.Cu")
		(net "BMC_EMMC_RST_N")
	)
	(segment
		(start 60.719462 -79.210916)
		(end 60.845446 -79.3369)
		(width 0.08382)
		(layer "In2.Cu")
		(net "BMC_EMMC_RST_N")
	)
	(segment
		(start 54.094634 -76.44638)
		(end 54.76494 -76.44638)
		(width 0.08382)
		(layer "In2.Cu")
		(net "BMC_EMMC_RST_N")
	)
	(segment
		(start 50.744628 -76.8096)
		(end 51.507898 -77.57287)
		(width 0.08382)
		(layer "In2.Cu")
		(net "BMC_EMMC_RST_N")
	)
	(segment
		(start 67.437 -77.9018)
		(end 67.6402 -78.105)
		(width 0.08382)
		(layer "In2.Cu")
		(net "BMC_EMMC_RST_N")
	)
	(segment
		(start 39.797482 -76.737718)
		(end 40.543734 -75.991466)
		(width 0.08382)
		(layer "In2.Cu")
		(net "BMC_EMMC_RST_N")
	)
	(segment
		(start 53.70703 -76.833984)
		(end 54.094634 -76.44638)
		(width 0.08382)
		(layer "In2.Cu")
		(net "BMC_EMMC_RST_N")
	)
	(segment
		(start 38.174422 -76.737718)
		(end 39.797482 -76.737718)
		(width 0.08382)
		(layer "In2.Cu")
		(net "BMC_EMMC_RST_N")
	)
	(segment
		(start 57.026302 -78.707742)
		(end 59.610498 -78.707742)
		(width 0.08382)
		(layer "In2.Cu")
		(net "BMC_EMMC_RST_N")
	)
	(segment
		(start 63.68034 -78.557374)
		(end 63.68034 -74.5744)
		(width 0.10668)
		(layer "In4.Cu")
		(net "BMC_EMMC_RST_N")
	)
	(segment
		(start 61.618368 -83.993482)
		(end 61.6458 -83.993482)
		(width 0.10668)
		(layer "In4.Cu")
		(net "BMC_EMMC_RST_N")
	)
	(segment
		(start 62.3316 -79.906114)
		(end 63.68034 -78.557374)
		(width 0.10668)
		(layer "In4.Cu")
		(net "BMC_EMMC_RST_N")
	)
	(segment
		(start 63.68034 -74.5744)
		(end 64.81064 -73.4441)
		(width 0.10668)
		(layer "In4.Cu")
		(net "BMC_EMMC_RST_N")
	)
	(segment
		(start 61.6458 -83.993482)
		(end 61.6458 -83.705192)
		(width 0.10668)
		(layer "In4.Cu")
		(net "BMC_EMMC_RST_N")
	)
	(segment
		(start 64.81064 -73.4441)
		(end 65.532 -72.3646)
		(width 0.10668)
		(layer "In4.Cu")
		(net "BMC_EMMC_RST_N")
	)
	(segment
		(start 61.6458 -83.705192)
		(end 62.3316 -83.019392)
		(width 0.10668)
		(layer "In4.Cu")
		(net "BMC_EMMC_RST_N")
	)
	(segment
		(start 62.3316 -83.019392)
		(end 62.3316 -79.906114)
		(width 0.10668)
		(layer "In4.Cu")
		(net "BMC_EMMC_RST_N")
	)
	(segment
		(start 49.6951 -42.571162)
		(end 49.299876 -42.175938)
		(width 0.11684)
		(layer "F.Cu")
		(net "BMC_EMMC_DT7")
	)
	(segment
		(start 29.27604 -70.136004)
		(end 29.21 -70.069964)
		(width 0.11684)
		(layer "F.Cu")
		(net "BMC_EMMC_DT7")
	)
	(segment
		(start 29.21 -70.069964)
		(end 29.21 -69.5198)
		(width 0.11684)
		(layer "F.Cu")
		(net "BMC_EMMC_DT7")
	)
	(via
		(at 73.644506 -78.50124)
		(size 0.508)
		(drill 0.254)
		(layers "F.Cu" "B.Cu")
		(net "BMC_EMMC_DT7")
	)
	(via
		(at 29.21 -69.5198)
		(size 0.508)
		(drill 0.254)
		(layers "F.Cu" "B.Cu")
		(net "BMC_EMMC_DT7")
	)
	(via
		(at 49.299876 -42.175938)
		(size 0.4572)
		(drill 0.254)
		(layers "F.Cu" "B.Cu")
		(net "BMC_EMMC_DT7")
	)
	(segment
		(start 63.899034 -76.950824)
		(end 64.085978 -77.137768)
		(width 0.08382)
		(layer "In2.Cu")
		(net "BMC_EMMC_DT7")
	)
	(segment
		(start 64.085978 -77.137768)
		(end 68.85178 -77.137768)
		(width 0.08382)
		(layer "In2.Cu")
		(net "BMC_EMMC_DT7")
	)
	(segment
		(start 41.096946 -69.85)
		(end 43.812206 -72.56526)
		(width 0.08382)
		(layer "In2.Cu")
		(net "BMC_EMMC_DT7")
	)
	(segment
		(start 54.398672 -74.06386)
		(end 56.284622 -75.94981)
		(width 0.08382)
		(layer "In2.Cu")
		(net "BMC_EMMC_DT7")
	)
	(segment
		(start 35.009582 -72.33158)
		(end 37.491162 -69.85)
		(width 0.08382)
		(layer "In2.Cu")
		(net "BMC_EMMC_DT7")
	)
	(segment
		(start 52.046124 -74.06386)
		(end 54.398672 -74.06386)
		(width 0.08382)
		(layer "In2.Cu")
		(net "BMC_EMMC_DT7")
	)
	(segment
		(start 69.789548 -76.2)
		(end 70.5612 -76.2)
		(width 0.08382)
		(layer "In2.Cu")
		(net "BMC_EMMC_DT7")
	)
	(segment
		(start 29.21 -69.5198)
		(end 32.02178 -72.33158)
		(width 0.08382)
		(layer "In2.Cu")
		(net "BMC_EMMC_DT7")
	)
	(segment
		(start 56.284622 -75.94981)
		(end 60.55741 -75.94981)
		(width 0.08382)
		(layer "In2.Cu")
		(net "BMC_EMMC_DT7")
	)
	(segment
		(start 72.86244 -78.50124)
		(end 73.644506 -78.50124)
		(width 0.08382)
		(layer "In2.Cu")
		(net "BMC_EMMC_DT7")
	)
	(segment
		(start 43.812206 -72.56526)
		(end 50.547524 -72.56526)
		(width 0.08382)
		(layer "In2.Cu")
		(net "BMC_EMMC_DT7")
	)
	(segment
		(start 32.02178 -72.33158)
		(end 35.009582 -72.33158)
		(width 0.08382)
		(layer "In2.Cu")
		(net "BMC_EMMC_DT7")
	)
	(segment
		(start 61.558424 -76.950824)
		(end 63.899034 -76.950824)
		(width 0.08382)
		(layer "In2.Cu")
		(net "BMC_EMMC_DT7")
	)
	(segment
		(start 70.5612 -76.2)
		(end 72.86244 -78.50124)
		(width 0.08382)
		(layer "In2.Cu")
		(net "BMC_EMMC_DT7")
	)
	(segment
		(start 68.85178 -77.137768)
		(end 69.789548 -76.2)
		(width 0.08382)
		(layer "In2.Cu")
		(net "BMC_EMMC_DT7")
	)
	(segment
		(start 50.547524 -72.56526)
		(end 52.046124 -74.06386)
		(width 0.08382)
		(layer "In2.Cu")
		(net "BMC_EMMC_DT7")
	)
	(segment
		(start 37.491162 -69.85)
		(end 41.096946 -69.85)
		(width 0.08382)
		(layer "In2.Cu")
		(net "BMC_EMMC_DT7")
	)
	(segment
		(start 60.55741 -75.94981)
		(end 61.558424 -76.950824)
		(width 0.08382)
		(layer "In2.Cu")
		(net "BMC_EMMC_DT7")
	)
	(segment
		(start 71.6788 -54.8894)
		(end 71.6788 -53.7972)
		(width 0.10668)
		(layer "In4.Cu")
		(net "BMC_EMMC_DT7")
	)
	(segment
		(start 71.6788 -53.7972)
		(end 69.742812 -51.861212)
		(width 0.10668)
		(layer "In4.Cu")
		(net "BMC_EMMC_DT7")
	)
	(segment
		(start 51.858672 -44.192444)
		(end 51.629564 -44.192444)
		(width 0.10668)
		(layer "In4.Cu")
		(net "BMC_EMMC_DT7")
	)
	(segment
		(start 73.0758 -77.1398)
		(end 72.7456 -77.1398)
		(width 0.10668)
		(layer "In4.Cu")
		(net "BMC_EMMC_DT7")
	)
	(segment
		(start 52.116228 -44.45)
		(end 51.858672 -44.192444)
		(width 0.10668)
		(layer "In4.Cu")
		(net "BMC_EMMC_DT7")
	)
	(segment
		(start 51.17592 -43.7388)
		(end 50.2158 -43.7388)
		(width 0.10668)
		(layer "In4.Cu")
		(net "BMC_EMMC_DT7")
	)
	(segment
		(start 71.19874 -71.2724)
		(end 71.19874 -70.0278)
		(width 0.10668)
		(layer "In4.Cu")
		(net "BMC_EMMC_DT7")
	)
	(segment
		(start 74.2696 -57.4802)
		(end 71.6788 -54.8894)
		(width 0.10668)
		(layer "In4.Cu")
		(net "BMC_EMMC_DT7")
	)
	(segment
		(start 49.9364 -42.976546)
		(end 49.507902 -42.548048)
		(width 0.10668)
		(layer "In4.Cu")
		(net "BMC_EMMC_DT7")
	)
	(segment
		(start 52.116228 -45.535088)
		(end 52.116228 -44.45)
		(width 0.10668)
		(layer "In4.Cu")
		(net "BMC_EMMC_DT7")
	)
	(segment
		(start 69.742812 -51.861212)
		(end 68.529962 -51.3588)
		(width 0.10668)
		(layer "In4.Cu")
		(net "BMC_EMMC_DT7")
	)
	(segment
		(start 68.529962 -51.3588)
		(end 61.0108 -51.3588)
		(width 0.10668)
		(layer "In4.Cu")
		(net "BMC_EMMC_DT7")
	)
	(segment
		(start 71.19874 -70.0278)
		(end 71.4121 -69.81444)
		(width 0.10668)
		(layer "In4.Cu")
		(net "BMC_EMMC_DT7")
	)
	(segment
		(start 49.507902 -42.383964)
		(end 49.299876 -42.175938)
		(width 0.10668)
		(layer "In4.Cu")
		(net "BMC_EMMC_DT7")
	)
	(segment
		(start 50.2158 -43.7388)
		(end 49.9364 -43.4594)
		(width 0.10668)
		(layer "In4.Cu")
		(net "BMC_EMMC_DT7")
	)
	(segment
		(start 72.4408 -72.51446)
		(end 71.19874 -71.2724)
		(width 0.10668)
		(layer "In4.Cu")
		(net "BMC_EMMC_DT7")
	)
	(segment
		(start 52.658772 -45.79239)
		(end 52.37353 -45.79239)
		(width 0.10668)
		(layer "In4.Cu")
		(net "BMC_EMMC_DT7")
	)
	(segment
		(start 57.131204 -50.559462)
		(end 57.121806 -50.550064)
		(width 0.10668)
		(layer "In4.Cu")
		(net "BMC_EMMC_DT7")
	)
	(segment
		(start 71.4121 -69.81444)
		(end 73.284588 -69.81444)
		(width 0.10668)
		(layer "In4.Cu")
		(net "BMC_EMMC_DT7")
	)
	(segment
		(start 74.2696 -68.829428)
		(end 74.2696 -57.4802)
		(width 0.10668)
		(layer "In4.Cu")
		(net "BMC_EMMC_DT7")
	)
	(segment
		(start 60.202064 -50.550064)
		(end 57.45861 -50.550064)
		(width 0.10668)
		(layer "In4.Cu")
		(net "BMC_EMMC_DT7")
	)
	(segment
		(start 73.644506 -78.50124)
		(end 73.644506 -77.708506)
		(width 0.10668)
		(layer "In4.Cu")
		(net "BMC_EMMC_DT7")
	)
	(segment
		(start 57.121806 -50.550064)
		(end 55.531258 -50.550064)
		(width 0.10668)
		(layer "In4.Cu")
		(net "BMC_EMMC_DT7")
	)
	(segment
		(start 57.45861 -50.550064)
		(end 57.449212 -50.559462)
		(width 0.10668)
		(layer "In4.Cu")
		(net "BMC_EMMC_DT7")
	)
	(segment
		(start 72.4408 -76.835)
		(end 72.4408 -72.51446)
		(width 0.10668)
		(layer "In4.Cu")
		(net "BMC_EMMC_DT7")
	)
	(segment
		(start 55.245 -50.263806)
		(end 55.245 -49.243996)
		(width 0.10668)
		(layer "In4.Cu")
		(net "BMC_EMMC_DT7")
	)
	(segment
		(start 55.245 -49.243996)
		(end 53.716174 -47.71517)
		(width 0.10668)
		(layer "In4.Cu")
		(net "BMC_EMMC_DT7")
	)
	(segment
		(start 73.284588 -69.81444)
		(end 74.2696 -68.829428)
		(width 0.10668)
		(layer "In4.Cu")
		(net "BMC_EMMC_DT7")
	)
	(segment
		(start 49.507902 -42.548048)
		(end 49.507902 -42.383964)
		(width 0.10668)
		(layer "In4.Cu")
		(net "BMC_EMMC_DT7")
	)
	(segment
		(start 51.629564 -44.192444)
		(end 51.17592 -43.7388)
		(width 0.10668)
		(layer "In4.Cu")
		(net "BMC_EMMC_DT7")
	)
	(segment
		(start 73.644506 -77.708506)
		(end 73.0758 -77.1398)
		(width 0.10668)
		(layer "In4.Cu")
		(net "BMC_EMMC_DT7")
	)
	(segment
		(start 72.7456 -77.1398)
		(end 72.4408 -76.835)
		(width 0.10668)
		(layer "In4.Cu")
		(net "BMC_EMMC_DT7")
	)
	(segment
		(start 61.0108 -51.3588)
		(end 60.202064 -50.550064)
		(width 0.10668)
		(layer "In4.Cu")
		(net "BMC_EMMC_DT7")
	)
	(segment
		(start 52.883308 -46.301914)
		(end 52.883308 -46.016926)
		(width 0.10668)
		(layer "In4.Cu")
		(net "BMC_EMMC_DT7")
	)
	(segment
		(start 52.883308 -46.016926)
		(end 52.658772 -45.79239)
		(width 0.10668)
		(layer "In4.Cu")
		(net "BMC_EMMC_DT7")
	)
	(segment
		(start 53.716174 -47.71517)
		(end 53.716174 -46.849792)
		(width 0.10668)
		(layer "In4.Cu")
		(net "BMC_EMMC_DT7")
	)
	(segment
		(start 53.173884 -46.59249)
		(end 52.883308 -46.301914)
		(width 0.10668)
		(layer "In4.Cu")
		(net "BMC_EMMC_DT7")
	)
	(segment
		(start 49.9364 -43.4594)
		(end 49.9364 -42.976546)
		(width 0.10668)
		(layer "In4.Cu")
		(net "BMC_EMMC_DT7")
	)
	(segment
		(start 55.531258 -50.550064)
		(end 55.245 -50.263806)
		(width 0.10668)
		(layer "In4.Cu")
		(net "BMC_EMMC_DT7")
	)
	(segment
		(start 52.37353 -45.79239)
		(end 52.116228 -45.535088)
		(width 0.10668)
		(layer "In4.Cu")
		(net "BMC_EMMC_DT7")
	)
	(segment
		(start 53.716174 -46.849792)
		(end 53.458872 -46.59249)
		(width 0.10668)
		(layer "In4.Cu")
		(net "BMC_EMMC_DT7")
	)
	(segment
		(start 57.449212 -50.559462)
		(end 57.131204 -50.559462)
		(width 0.10668)
		(layer "In4.Cu")
		(net "BMC_EMMC_DT7")
	)
	(segment
		(start 53.458872 -46.59249)
		(end 53.173884 -46.59249)
		(width 0.10668)
		(layer "In4.Cu")
		(net "BMC_EMMC_DT7")
	)
	(segment
		(start 48.895 -38.837616)
		(end 48.8696 -38.812216)
		(width 0.11684)
		(layer "F.Cu")
		(net "BMC_EMMC_DT6")
	)
	(segment
		(start 30.41904 -70.136004)
		(end 30.49778 -70.057264)
		(width 0.11684)
		(layer "F.Cu")
		(net "BMC_EMMC_DT6")
	)
	(segment
		(start 30.49778 -70.057264)
		(end 30.49778 -69.5198)
		(width 0.11684)
		(layer "F.Cu")
		(net "BMC_EMMC_DT6")
	)
	(segment
		(start 48.895 -39.37127)
		(end 48.895 -38.837616)
		(width 0.11684)
		(layer "F.Cu")
		(net "BMC_EMMC_DT6")
	)
	(via
		(at 73.026778 -76.605384)
		(size 0.508)
		(drill 0.254)
		(layers "F.Cu" "B.Cu")
		(net "BMC_EMMC_DT6")
	)
	(via
		(at 30.49778 -69.5198)
		(size 0.508)
		(drill 0.254)
		(layers "F.Cu" "B.Cu")
		(net "BMC_EMMC_DT6")
	)
	(via
		(at 48.8696 -38.812216)
		(size 0.4572)
		(drill 0.254)
		(layers "F.Cu" "B.Cu")
		(net "BMC_EMMC_DT6")
	)
	(segment
		(start 54.503066 -73.8124)
		(end 56.389016 -75.69835)
		(width 0.08382)
		(layer "In2.Cu")
		(net "BMC_EMMC_DT6")
	)
	(segment
		(start 70.529196 -75.3618)
		(end 70.775576 -75.3618)
		(width 0.08382)
		(layer "In2.Cu")
		(net "BMC_EMMC_DT6")
	)
	(segment
		(start 64.190372 -76.886308)
		(end 67.690746 -76.886308)
		(width 0.08382)
		(layer "In2.Cu")
		(net "BMC_EMMC_DT6")
	)
	(segment
		(start 69.586856 -75.3618)
		(end 69.760846 -75.53579)
		(width 0.08382)
		(layer "In2.Cu")
		(net "BMC_EMMC_DT6")
	)
	(segment
		(start 69.166486 -75.74788)
		(end 69.166486 -75.53579)
		(width 0.08382)
		(layer "In2.Cu")
		(net "BMC_EMMC_DT6")
	)
	(segment
		(start 69.166486 -75.53579)
		(end 69.340476 -75.3618)
		(width 0.08382)
		(layer "In2.Cu")
		(net "BMC_EMMC_DT6")
	)
	(segment
		(start 34.905188 -72.08012)
		(end 37.386768 -69.59854)
		(width 0.08382)
		(layer "In2.Cu")
		(net "BMC_EMMC_DT6")
	)
	(segment
		(start 71.890382 -75.92187)
		(end 72.573896 -76.605384)
		(width 0.08382)
		(layer "In2.Cu")
		(net "BMC_EMMC_DT6")
	)
	(segment
		(start 52.150772 -73.8124)
		(end 54.503066 -73.8124)
		(width 0.08382)
		(layer "In2.Cu")
		(net "BMC_EMMC_DT6")
	)
	(segment
		(start 72.573896 -76.605384)
		(end 73.026778 -76.605384)
		(width 0.08382)
		(layer "In2.Cu")
		(net "BMC_EMMC_DT6")
	)
	(segment
		(start 70.949566 -75.53579)
		(end 70.949566 -75.74788)
		(width 0.08382)
		(layer "In2.Cu")
		(net "BMC_EMMC_DT6")
	)
	(segment
		(start 61.662818 -76.699364)
		(end 64.003428 -76.699364)
		(width 0.08382)
		(layer "In2.Cu")
		(net "BMC_EMMC_DT6")
	)
	(segment
		(start 69.760846 -75.53579)
		(end 69.760846 -75.74788)
		(width 0.08382)
		(layer "In2.Cu")
		(net "BMC_EMMC_DT6")
	)
	(segment
		(start 69.934836 -75.92187)
		(end 70.181216 -75.92187)
		(width 0.08382)
		(layer "In2.Cu")
		(net "BMC_EMMC_DT6")
	)
	(segment
		(start 60.661804 -75.69835)
		(end 61.662818 -76.699364)
		(width 0.08382)
		(layer "In2.Cu")
		(net "BMC_EMMC_DT6")
	)
	(segment
		(start 70.181216 -75.92187)
		(end 70.355206 -75.74788)
		(width 0.08382)
		(layer "In2.Cu")
		(net "BMC_EMMC_DT6")
	)
	(segment
		(start 43.88485 -72.28205)
		(end 50.620422 -72.28205)
		(width 0.08382)
		(layer "In2.Cu")
		(net "BMC_EMMC_DT6")
	)
	(segment
		(start 30.49778 -69.5198)
		(end 30.49778 -70.14718)
		(width 0.08382)
		(layer "In2.Cu")
		(net "BMC_EMMC_DT6")
	)
	(segment
		(start 37.386768 -69.59854)
		(end 41.20134 -69.59854)
		(width 0.08382)
		(layer "In2.Cu")
		(net "BMC_EMMC_DT6")
	)
	(segment
		(start 41.20134 -69.59854)
		(end 43.88485 -72.28205)
		(width 0.08382)
		(layer "In2.Cu")
		(net "BMC_EMMC_DT6")
	)
	(segment
		(start 70.775576 -75.3618)
		(end 70.949566 -75.53579)
		(width 0.08382)
		(layer "In2.Cu")
		(net "BMC_EMMC_DT6")
	)
	(segment
		(start 69.340476 -75.3618)
		(end 69.586856 -75.3618)
		(width 0.08382)
		(layer "In2.Cu")
		(net "BMC_EMMC_DT6")
	)
	(segment
		(start 50.620422 -72.28205)
		(end 52.150772 -73.8124)
		(width 0.08382)
		(layer "In2.Cu")
		(net "BMC_EMMC_DT6")
	)
	(segment
		(start 30.49778 -70.14718)
		(end 32.43072 -72.08012)
		(width 0.08382)
		(layer "In2.Cu")
		(net "BMC_EMMC_DT6")
	)
	(segment
		(start 67.690746 -76.886308)
		(end 68.655184 -75.92187)
		(width 0.08382)
		(layer "In2.Cu")
		(net "BMC_EMMC_DT6")
	)
	(segment
		(start 70.355206 -75.53579)
		(end 70.529196 -75.3618)
		(width 0.08382)
		(layer "In2.Cu")
		(net "BMC_EMMC_DT6")
	)
	(segment
		(start 70.949566 -75.74788)
		(end 71.123556 -75.92187)
		(width 0.08382)
		(layer "In2.Cu")
		(net "BMC_EMMC_DT6")
	)
	(segment
		(start 64.003428 -76.699364)
		(end 64.190372 -76.886308)
		(width 0.08382)
		(layer "In2.Cu")
		(net "BMC_EMMC_DT6")
	)
	(segment
		(start 71.123556 -75.92187)
		(end 71.890382 -75.92187)
		(width 0.08382)
		(layer "In2.Cu")
		(net "BMC_EMMC_DT6")
	)
	(segment
		(start 32.43072 -72.08012)
		(end 34.905188 -72.08012)
		(width 0.08382)
		(layer "In2.Cu")
		(net "BMC_EMMC_DT6")
	)
	(segment
		(start 70.355206 -75.74788)
		(end 70.355206 -75.53579)
		(width 0.08382)
		(layer "In2.Cu")
		(net "BMC_EMMC_DT6")
	)
	(segment
		(start 68.992496 -75.92187)
		(end 69.166486 -75.74788)
		(width 0.08382)
		(layer "In2.Cu")
		(net "BMC_EMMC_DT6")
	)
	(segment
		(start 69.760846 -75.74788)
		(end 69.934836 -75.92187)
		(width 0.08382)
		(layer "In2.Cu")
		(net "BMC_EMMC_DT6")
	)
	(segment
		(start 68.655184 -75.92187)
		(end 68.992496 -75.92187)
		(width 0.08382)
		(layer "In2.Cu")
		(net "BMC_EMMC_DT6")
	)
	(segment
		(start 56.389016 -75.69835)
		(end 60.661804 -75.69835)
		(width 0.08382)
		(layer "In2.Cu")
		(net "BMC_EMMC_DT6")
	)
	(segment
		(start 70.056756 -50.422556)
		(end 66.736976 -49.0474)
		(width 0.10668)
		(layer "In4.Cu")
		(net "BMC_EMMC_DT6")
	)
	(segment
		(start 54.111398 -43.951398)
		(end 53.6956 -43.5356)
		(width 0.10668)
		(layer "In4.Cu")
		(net "BMC_EMMC_DT6")
	)
	(segment
		(start 51.093116 -39.426896)
		(end 49.609756 -38.812216)
		(width 0.10668)
		(layer "In4.Cu")
		(net "BMC_EMMC_DT6")
	)
	(segment
		(start 74.510138 -75.094084)
		(end 74.448416 -75.032362)
		(width 0.10668)
		(layer "In4.Cu")
		(net "BMC_EMMC_DT6")
	)
	(segment
		(start 74.448416 -75.032362)
		(end 74.448416 -74.777092)
		(width 0.10668)
		(layer "In4.Cu")
		(net "BMC_EMMC_DT6")
	)
	(segment
		(start 75.4888 -56.97474)
		(end 73.8632 -55.34914)
		(width 0.10668)
		(layer "In4.Cu")
		(net "BMC_EMMC_DT6")
	)
	(segment
		(start 74.885042 -74.59599)
		(end 74.946764 -74.657458)
		(width 0.10668)
		(layer "In4.Cu")
		(net "BMC_EMMC_DT6")
	)
	(segment
		(start 75.202288 -74.657458)
		(end 76.3778 -73.481946)
		(width 0.10668)
		(layer "In4.Cu")
		(net "BMC_EMMC_DT6")
	)
	(segment
		(start 56.906668 -47.935134)
		(end 56.906668 -47.889668)
		(width 0.10668)
		(layer "In4.Cu")
		(net "BMC_EMMC_DT6")
	)
	(segment
		(start 73.8632 -53.213)
		(end 72.9742 -52.324)
		(width 0.10668)
		(layer "In4.Cu")
		(net "BMC_EMMC_DT6")
	)
	(segment
		(start 75.847448 -73.04278)
		(end 75.1332 -72.328532)
		(width 0.10668)
		(layer "In4.Cu")
		(net "BMC_EMMC_DT6")
	)
	(segment
		(start 72.9742 -52.324)
		(end 71.9582 -52.324)
		(width 0.10668)
		(layer "In4.Cu")
		(net "BMC_EMMC_DT6")
	)
	(segment
		(start 75.4888 -69.9008)
		(end 75.4888 -56.97474)
		(width 0.10668)
		(layer "In4.Cu")
		(net "BMC_EMMC_DT6")
	)
	(segment
		(start 75.1332 -72.328532)
		(end 75.1332 -70.75932)
		(width 0.10668)
		(layer "In4.Cu")
		(net "BMC_EMMC_DT6")
	)
	(segment
		(start 52.2986 -42.5704)
		(end 52.0954 -42.3672)
		(width 0.10668)
		(layer "In4.Cu")
		(net "BMC_EMMC_DT6")
	)
	(segment
		(start 74.629518 -74.59599)
		(end 74.885042 -74.59599)
		(width 0.10668)
		(layer "In4.Cu")
		(net "BMC_EMMC_DT6")
	)
	(segment
		(start 57.673748 -48.70196)
		(end 57.673748 -48.416972)
		(width 0.10668)
		(layer "In4.Cu")
		(net "BMC_EMMC_DT6")
	)
	(segment
		(start 53.6956 -43.5356)
		(end 53.6956 -42.828972)
		(width 0.10668)
		(layer "In4.Cu")
		(net "BMC_EMMC_DT6")
	)
	(segment
		(start 73.026778 -76.605384)
		(end 73.737216 -76.605384)
		(width 0.10668)
		(layer "In4.Cu")
		(net "BMC_EMMC_DT6")
	)
	(segment
		(start 73.8632 -55.34914)
		(end 73.8632 -53.213)
		(width 0.10668)
		(layer "In4.Cu")
		(net "BMC_EMMC_DT6")
	)
	(segment
		(start 76.196952 -73.04278)
		(end 75.847448 -73.04278)
		(width 0.10668)
		(layer "In4.Cu")
		(net "BMC_EMMC_DT6")
	)
	(segment
		(start 76.3778 -73.481946)
		(end 76.3778 -73.223628)
		(width 0.10668)
		(layer "In4.Cu")
		(net "BMC_EMMC_DT6")
	)
	(segment
		(start 55.0926 -45.593)
		(end 54.111398 -44.611798)
		(width 0.10668)
		(layer "In4.Cu")
		(net "BMC_EMMC_DT6")
	)
	(segment
		(start 57.449212 -48.192436)
		(end 57.16397 -48.192436)
		(width 0.10668)
		(layer "In4.Cu")
		(net "BMC_EMMC_DT6")
	)
	(segment
		(start 76.3778 -73.223628)
		(end 76.196952 -73.04278)
		(width 0.10668)
		(layer "In4.Cu")
		(net "BMC_EMMC_DT6")
	)
	(segment
		(start 74.510138 -75.832462)
		(end 74.510138 -75.094084)
		(width 0.10668)
		(layer "In4.Cu")
		(net "BMC_EMMC_DT6")
	)
	(segment
		(start 74.448416 -74.777092)
		(end 74.629518 -74.59599)
		(width 0.10668)
		(layer "In4.Cu")
		(net "BMC_EMMC_DT6")
	)
	(segment
		(start 49.609756 -38.812216)
		(end 48.8696 -38.812216)
		(width 0.10668)
		(layer "In4.Cu")
		(net "BMC_EMMC_DT6")
	)
	(segment
		(start 57.16397 -48.192436)
		(end 56.906668 -47.935134)
		(width 0.10668)
		(layer "In4.Cu")
		(net "BMC_EMMC_DT6")
	)
	(segment
		(start 56.906668 -47.889668)
		(end 55.0926 -46.0756)
		(width 0.10668)
		(layer "In4.Cu")
		(net "BMC_EMMC_DT6")
	)
	(segment
		(start 57.673748 -48.416972)
		(end 57.449212 -48.192436)
		(width 0.10668)
		(layer "In4.Cu")
		(net "BMC_EMMC_DT6")
	)
	(segment
		(start 53.6956 -42.828972)
		(end 53.437028 -42.5704)
		(width 0.10668)
		(layer "In4.Cu")
		(net "BMC_EMMC_DT6")
	)
	(segment
		(start 55.0926 -46.0756)
		(end 55.0926 -45.593)
		(width 0.10668)
		(layer "In4.Cu")
		(net "BMC_EMMC_DT6")
	)
	(segment
		(start 53.437028 -42.5704)
		(end 52.2986 -42.5704)
		(width 0.10668)
		(layer "In4.Cu")
		(net "BMC_EMMC_DT6")
	)
	(segment
		(start 54.111398 -44.611798)
		(end 54.111398 -43.951398)
		(width 0.10668)
		(layer "In4.Cu")
		(net "BMC_EMMC_DT6")
	)
	(segment
		(start 66.736976 -49.0474)
		(end 58.019188 -49.0474)
		(width 0.10668)
		(layer "In4.Cu")
		(net "BMC_EMMC_DT6")
	)
	(segment
		(start 71.9582 -52.324)
		(end 70.056756 -50.422556)
		(width 0.10668)
		(layer "In4.Cu")
		(net "BMC_EMMC_DT6")
	)
	(segment
		(start 52.0954 -40.42918)
		(end 51.093116 -39.426896)
		(width 0.10668)
		(layer "In4.Cu")
		(net "BMC_EMMC_DT6")
	)
	(segment
		(start 75.1332 -70.75932)
		(end 75.4888 -69.9008)
		(width 0.10668)
		(layer "In4.Cu")
		(net "BMC_EMMC_DT6")
	)
	(segment
		(start 74.946764 -74.657458)
		(end 75.202288 -74.657458)
		(width 0.10668)
		(layer "In4.Cu")
		(net "BMC_EMMC_DT6")
	)
	(segment
		(start 73.737216 -76.605384)
		(end 74.510138 -75.832462)
		(width 0.10668)
		(layer "In4.Cu")
		(net "BMC_EMMC_DT6")
	)
	(segment
		(start 52.0954 -42.3672)
		(end 52.0954 -40.42918)
		(width 0.10668)
		(layer "In4.Cu")
		(net "BMC_EMMC_DT6")
	)
	(segment
		(start 58.019188 -49.0474)
		(end 57.673748 -48.70196)
		(width 0.10668)
		(layer "In4.Cu")
		(net "BMC_EMMC_DT6")
	)
	(segment
		(start 32.2072 -67.1068)
		(end 31.958026 -67.708018)
		(width 0.11684)
		(layer "F.Cu")
		(net "BMC_EMMC_DT5")
	)
	(segment
		(start 48.0949 -39.37127)
		(end 47.699676 -38.976046)
		(width 0.11684)
		(layer "F.Cu")
		(net "BMC_EMMC_DT5")
	)
	(segment
		(start 33.665414 -66.98996)
		(end 32.32404 -66.98996)
		(width 0.11684)
		(layer "F.Cu")
		(net "BMC_EMMC_DT5")
	)
	(segment
		(start 32.32404 -66.98996)
		(end 32.2072 -67.1068)
		(width 0.11684)
		(layer "F.Cu")
		(net "BMC_EMMC_DT5")
	)
	(segment
		(start 31.958026 -67.708018)
		(end 31.56204 -68.104004)
		(width 0.11684)
		(layer "F.Cu")
		(net "BMC_EMMC_DT5")
	)
	(segment
		(start 35.3568 -69.46646)
		(end 34.801556 -68.126102)
		(width 0.11684)
		(layer "F.Cu")
		(net "BMC_EMMC_DT5")
	)
	(segment
		(start 34.801556 -68.126102)
		(end 33.665414 -66.98996)
		(width 0.11684)
		(layer "F.Cu")
		(net "BMC_EMMC_DT5")
	)
	(segment
		(start 34.819082 -70.612254)
		(end 35.3568 -70.074536)
		(width 0.11684)
		(layer "F.Cu")
		(net "BMC_EMMC_DT5")
	)
	(segment
		(start 35.3568 -70.074536)
		(end 35.3568 -69.46646)
		(width 0.11684)
		(layer "F.Cu")
		(net "BMC_EMMC_DT5")
	)
	(segment
		(start 34.819082 -70.62343)
		(end 34.819082 -70.612254)
		(width 0.11684)
		(layer "F.Cu")
		(net "BMC_EMMC_DT5")
	)
	(via
		(at 47.699676 -38.976046)
		(size 0.4572)
		(drill 0.254)
		(layers "F.Cu" "B.Cu")
		(net "BMC_EMMC_DT5")
	)
	(via
		(at 34.819082 -70.62343)
		(size 0.508)
		(drill 0.254)
		(layers "F.Cu" "B.Cu")
		(net "BMC_EMMC_DT5")
	)
	(via
		(at 73.914 -75.6158)
		(size 0.508)
		(drill 0.254)
		(layers "F.Cu" "B.Cu")
		(net "BMC_EMMC_DT5")
	)
	(segment
		(start 53.848 -73.279)
		(end 54.681374 -73.279)
		(width 0.08382)
		(layer "In2.Cu")
		(net "BMC_EMMC_DT5")
	)
	(segment
		(start 35.631374 -70.642226)
		(end 37.17798 -69.09562)
		(width 0.08382)
		(layer "In2.Cu")
		(net "BMC_EMMC_DT5")
	)
	(segment
		(start 44.2722 -70.9168)
		(end 44.89831 -70.29069)
		(width 0.08382)
		(layer "In2.Cu")
		(net "BMC_EMMC_DT5")
	)
	(segment
		(start 68.059808 -73.2028)
		(end 69.168518 -74.31151)
		(width 0.08382)
		(layer "In2.Cu")
		(net "BMC_EMMC_DT5")
	)
	(segment
		(start 48.5648 -70.6628)
		(end 49.022 -71.12)
		(width 0.08382)
		(layer "In2.Cu")
		(net "BMC_EMMC_DT5")
	)
	(segment
		(start 73.495916 -75.6158)
		(end 73.914 -75.6158)
		(width 0.08382)
		(layer "In2.Cu")
		(net "BMC_EMMC_DT5")
	)
	(segment
		(start 51.917092 -72.07631)
		(end 52.64531 -72.07631)
		(width 0.08382)
		(layer "In2.Cu")
		(net "BMC_EMMC_DT5")
	)
	(segment
		(start 56.597804 -75.19543)
		(end 60.846716 -75.19543)
		(width 0.08382)
		(layer "In2.Cu")
		(net "BMC_EMMC_DT5")
	)
	(segment
		(start 72.191626 -74.31151)
		(end 73.495916 -75.6158)
		(width 0.08382)
		(layer "In2.Cu")
		(net "BMC_EMMC_DT5")
	)
	(segment
		(start 41.410128 -69.09562)
		(end 43.231308 -70.9168)
		(width 0.08382)
		(layer "In2.Cu")
		(net "BMC_EMMC_DT5")
	)
	(segment
		(start 49.022 -71.12)
		(end 50.960782 -71.12)
		(width 0.08382)
		(layer "In2.Cu")
		(net "BMC_EMMC_DT5")
	)
	(segment
		(start 60.846716 -75.19543)
		(end 62.356746 -73.6854)
		(width 0.08382)
		(layer "In2.Cu")
		(net "BMC_EMMC_DT5")
	)
	(segment
		(start 62.356746 -73.6854)
		(end 65.729612 -73.6854)
		(width 0.08382)
		(layer "In2.Cu")
		(net "BMC_EMMC_DT5")
	)
	(segment
		(start 54.681374 -73.279)
		(end 56.597804 -75.19543)
		(width 0.08382)
		(layer "In2.Cu")
		(net "BMC_EMMC_DT5")
	)
	(segment
		(start 34.837878 -70.642226)
		(end 35.631374 -70.642226)
		(width 0.08382)
		(layer "In2.Cu")
		(net "BMC_EMMC_DT5")
	)
	(segment
		(start 46.6344 -70.6628)
		(end 48.5648 -70.6628)
		(width 0.08382)
		(layer "In2.Cu")
		(net "BMC_EMMC_DT5")
	)
	(segment
		(start 34.819082 -70.62343)
		(end 34.837878 -70.642226)
		(width 0.08382)
		(layer "In2.Cu")
		(net "BMC_EMMC_DT5")
	)
	(segment
		(start 37.17798 -69.09562)
		(end 41.410128 -69.09562)
		(width 0.08382)
		(layer "In2.Cu")
		(net "BMC_EMMC_DT5")
	)
	(segment
		(start 50.960782 -71.12)
		(end 51.917092 -72.07631)
		(width 0.08382)
		(layer "In2.Cu")
		(net "BMC_EMMC_DT5")
	)
	(segment
		(start 52.64531 -72.07631)
		(end 53.848 -73.279)
		(width 0.08382)
		(layer "In2.Cu")
		(net "BMC_EMMC_DT5")
	)
	(segment
		(start 44.89831 -70.29069)
		(end 46.26229 -70.29069)
		(width 0.08382)
		(layer "In2.Cu")
		(net "BMC_EMMC_DT5")
	)
	(segment
		(start 46.26229 -70.29069)
		(end 46.6344 -70.6628)
		(width 0.08382)
		(layer "In2.Cu")
		(net "BMC_EMMC_DT5")
	)
	(segment
		(start 69.168518 -74.31151)
		(end 72.191626 -74.31151)
		(width 0.08382)
		(layer "In2.Cu")
		(net "BMC_EMMC_DT5")
	)
	(segment
		(start 66.212212 -73.2028)
		(end 68.059808 -73.2028)
		(width 0.08382)
		(layer "In2.Cu")
		(net "BMC_EMMC_DT5")
	)
	(segment
		(start 65.729612 -73.6854)
		(end 66.212212 -73.2028)
		(width 0.08382)
		(layer "In2.Cu")
		(net "BMC_EMMC_DT5")
	)
	(segment
		(start 43.231308 -70.9168)
		(end 44.2722 -70.9168)
		(width 0.08382)
		(layer "In2.Cu")
		(net "BMC_EMMC_DT5")
	)
	(segment
		(start 49.991518 -39.2938)
		(end 50.279808 -39.41318)
		(width 0.10668)
		(layer "In4.Cu")
		(net "BMC_EMMC_DT5")
	)
	(segment
		(start 47.699676 -38.976046)
		(end 48.348646 -38.976046)
		(width 0.10668)
		(layer "In4.Cu")
		(net "BMC_EMMC_DT5")
	)
	(segment
		(start 50.279808 -39.41318)
		(end 51.308 -40.441372)
		(width 0.10668)
		(layer "In4.Cu")
		(net "BMC_EMMC_DT5")
	)
	(segment
		(start 72.73036 -52.64404)
		(end 73.086976 -53.000656)
		(width 0.10668)
		(layer "In4.Cu")
		(net "BMC_EMMC_DT5")
	)
	(segment
		(start 74.190352 -74.22769)
		(end 73.914 -75.6158)
		(width 0.10668)
		(layer "In4.Cu")
		(net "BMC_EMMC_DT5")
	)
	(segment
		(start 73.086976 -55.025544)
		(end 75.16876 -57.107328)
		(width 0.10668)
		(layer "In4.Cu")
		(net "BMC_EMMC_DT5")
	)
	(segment
		(start 52.116228 -43.135042)
		(end 52.415186 -43.434)
		(width 0.10668)
		(layer "In4.Cu")
		(net "BMC_EMMC_DT5")
	)
	(segment
		(start 53.903118 -44.167044)
		(end 53.903118 -44.698158)
		(width 0.10668)
		(layer "In4.Cu")
		(net "BMC_EMMC_DT5")
	)
	(segment
		(start 57.38368 -49.25568)
		(end 61.00064 -49.25568)
		(width 0.10668)
		(layer "In4.Cu")
		(net "BMC_EMMC_DT5")
	)
	(segment
		(start 69.875654 -50.694082)
		(end 71.825612 -52.64404)
		(width 0.10668)
		(layer "In4.Cu")
		(net "BMC_EMMC_DT5")
	)
	(segment
		(start 75.16876 -69.61124)
		(end 74.6252 -70.923658)
		(width 0.10668)
		(layer "In4.Cu")
		(net "BMC_EMMC_DT5")
	)
	(segment
		(start 52.415186 -43.434)
		(end 53.170074 -43.434)
		(width 0.10668)
		(layer "In4.Cu")
		(net "BMC_EMMC_DT5")
	)
	(segment
		(start 73.086976 -53.000656)
		(end 73.086976 -55.025544)
		(width 0.10668)
		(layer "In4.Cu")
		(net "BMC_EMMC_DT5")
	)
	(segment
		(start 51.932078 -42.559478)
		(end 52.116228 -42.743628)
		(width 0.10668)
		(layer "In4.Cu")
		(net "BMC_EMMC_DT5")
	)
	(segment
		(start 56.873648 -48.227488)
		(end 56.873648 -48.745648)
		(width 0.10668)
		(layer "In4.Cu")
		(net "BMC_EMMC_DT5")
	)
	(segment
		(start 74.6252 -70.923658)
		(end 74.6252 -73.177654)
		(width 0.10668)
		(layer "In4.Cu")
		(net "BMC_EMMC_DT5")
	)
	(segment
		(start 56.873648 -48.745648)
		(end 57.38368 -49.25568)
		(width 0.10668)
		(layer "In4.Cu")
		(net "BMC_EMMC_DT5")
	)
	(segment
		(start 53.170074 -43.434)
		(end 53.903118 -44.167044)
		(width 0.10668)
		(layer "In4.Cu")
		(net "BMC_EMMC_DT5")
	)
	(segment
		(start 71.825612 -52.64404)
		(end 72.73036 -52.64404)
		(width 0.10668)
		(layer "In4.Cu")
		(net "BMC_EMMC_DT5")
	)
	(segment
		(start 53.903118 -44.698158)
		(end 54.88432 -45.67936)
		(width 0.10668)
		(layer "In4.Cu")
		(net "BMC_EMMC_DT5")
	)
	(segment
		(start 61.00064 -49.25568)
		(end 61.12256 -49.3776)
		(width 0.10668)
		(layer "In4.Cu")
		(net "BMC_EMMC_DT5")
	)
	(segment
		(start 52.116228 -42.743628)
		(end 52.116228 -43.135042)
		(width 0.10668)
		(layer "In4.Cu")
		(net "BMC_EMMC_DT5")
	)
	(segment
		(start 75.16876 -57.107328)
		(end 75.16876 -69.61124)
		(width 0.10668)
		(layer "In4.Cu")
		(net "BMC_EMMC_DT5")
	)
	(segment
		(start 61.12256 -49.3776)
		(end 66.697352 -49.3776)
		(width 0.10668)
		(layer "In4.Cu")
		(net "BMC_EMMC_DT5")
	)
	(segment
		(start 74.6252 -73.177654)
		(end 74.190352 -74.22769)
		(width 0.10668)
		(layer "In4.Cu")
		(net "BMC_EMMC_DT5")
	)
	(segment
		(start 54.88432 -46.23816)
		(end 56.873648 -48.227488)
		(width 0.10668)
		(layer "In4.Cu")
		(net "BMC_EMMC_DT5")
	)
	(segment
		(start 48.6664 -39.2938)
		(end 49.991518 -39.2938)
		(width 0.10668)
		(layer "In4.Cu")
		(net "BMC_EMMC_DT5")
	)
	(segment
		(start 48.348646 -38.976046)
		(end 48.6664 -39.2938)
		(width 0.10668)
		(layer "In4.Cu")
		(net "BMC_EMMC_DT5")
	)
	(segment
		(start 54.88432 -45.67936)
		(end 54.88432 -46.23816)
		(width 0.10668)
		(layer "In4.Cu")
		(net "BMC_EMMC_DT5")
	)
	(segment
		(start 51.308 -42.342054)
		(end 51.525424 -42.559478)
		(width 0.10668)
		(layer "In4.Cu")
		(net "BMC_EMMC_DT5")
	)
	(segment
		(start 51.525424 -42.559478)
		(end 51.932078 -42.559478)
		(width 0.10668)
		(layer "In4.Cu")
		(net "BMC_EMMC_DT5")
	)
	(segment
		(start 66.697352 -49.3776)
		(end 69.875654 -50.694082)
		(width 0.10668)
		(layer "In4.Cu")
		(net "BMC_EMMC_DT5")
	)
	(segment
		(start 51.308 -40.441372)
		(end 51.308 -42.342054)
		(width 0.10668)
		(layer "In4.Cu")
		(net "BMC_EMMC_DT5")
	)
	(segment
		(start 48.895 -40.971216)
		(end 48.499776 -40.575992)
		(width 0.11684)
		(layer "F.Cu")
		(net "BMC_EMMC_DT4")
	)
	(segment
		(start 32.70504 -70.136004)
		(end 32.70504 -69.520054)
		(width 0.11684)
		(layer "F.Cu")
		(net "BMC_EMMC_DT4")
	)
	(via
		(at 72.9107 -77.6859)
		(size 0.508)
		(drill 0.254)
		(layers "F.Cu" "B.Cu")
		(net "BMC_EMMC_DT4")
	)
	(via
		(at 48.499776 -40.575992)
		(size 0.4572)
		(drill 0.254)
		(layers "F.Cu" "B.Cu")
		(net "BMC_EMMC_DT4")
	)
	(via
		(at 32.70504 -69.520054)
		(size 0.508)
		(drill 0.254)
		(layers "F.Cu" "B.Cu")
		(net "BMC_EMMC_DT4")
	)
	(segment
		(start 68.846954 -74.3458)
		(end 69.064124 -74.56297)
		(width 0.08382)
		(layer "In2.Cu")
		(net "BMC_EMMC_DT4")
	)
	(segment
		(start 32.70504 -69.520054)
		(end 32.70504 -71.338694)
		(width 0.08382)
		(layer "In2.Cu")
		(net "BMC_EMMC_DT4")
	)
	(segment
		(start 72.1741 -75.43292)
		(end 72.1741 -75.678792)
		(width 0.08382)
		(layer "In2.Cu")
		(net "BMC_EMMC_DT4")
	)
	(segment
		(start 64.699642 -74.3458)
		(end 68.846954 -74.3458)
		(width 0.08382)
		(layer "In2.Cu")
		(net "BMC_EMMC_DT4")
	)
	(segment
		(start 51.515518 -72.03059)
		(end 51.812698 -72.32777)
		(width 0.08382)
		(layer "In2.Cu")
		(net "BMC_EMMC_DT4")
	)
	(segment
		(start 73.644506 -76.120244)
		(end 73.644506 -76.952094)
		(width 0.08382)
		(layer "In2.Cu")
		(net "BMC_EMMC_DT4")
	)
	(segment
		(start 64.105282 -75.3364)
		(end 64.351662 -75.3364)
		(width 0.08382)
		(layer "In2.Cu")
		(net "BMC_EMMC_DT4")
	)
	(segment
		(start 63.931292 -74.51979)
		(end 63.931292 -75.16241)
		(width 0.08382)
		(layer "In2.Cu")
		(net "BMC_EMMC_DT4")
	)
	(segment
		(start 72.348598 -75.85329)
		(end 72.59447 -75.85329)
		(width 0.08382)
		(layer "In2.Cu")
		(net "BMC_EMMC_DT4")
	)
	(segment
		(start 41.305734 -69.34708)
		(end 43.989244 -72.03059)
		(width 0.08382)
		(layer "In2.Cu")
		(net "BMC_EMMC_DT4")
	)
	(segment
		(start 37.282374 -69.34708)
		(end 41.305734 -69.34708)
		(width 0.08382)
		(layer "In2.Cu")
		(net "BMC_EMMC_DT4")
	)
	(segment
		(start 73.10882 -75.584558)
		(end 73.644506 -76.120244)
		(width 0.08382)
		(layer "In2.Cu")
		(net "BMC_EMMC_DT4")
	)
	(segment
		(start 63.757302 -74.3458)
		(end 63.931292 -74.51979)
		(width 0.08382)
		(layer "In2.Cu")
		(net "BMC_EMMC_DT4")
	)
	(segment
		(start 64.351662 -75.3364)
		(end 64.525652 -75.16241)
		(width 0.08382)
		(layer "In2.Cu")
		(net "BMC_EMMC_DT4")
	)
	(segment
		(start 62.23 -74.168)
		(end 63.1952 -74.168)
		(width 0.08382)
		(layer "In2.Cu")
		(net "BMC_EMMC_DT4")
	)
	(segment
		(start 72.442578 -75.164188)
		(end 72.1741 -75.43292)
		(width 0.08382)
		(layer "In2.Cu")
		(net "BMC_EMMC_DT4")
	)
	(segment
		(start 73.644506 -76.952094)
		(end 72.9107 -77.6859)
		(width 0.08382)
		(layer "In2.Cu")
		(net "BMC_EMMC_DT4")
	)
	(segment
		(start 54.57698 -73.53046)
		(end 56.49341 -75.44689)
		(width 0.08382)
		(layer "In2.Cu")
		(net "BMC_EMMC_DT4")
	)
	(segment
		(start 34.800794 -71.82866)
		(end 37.282374 -69.34708)
		(width 0.08382)
		(layer "In2.Cu")
		(net "BMC_EMMC_DT4")
	)
	(segment
		(start 69.064124 -74.56297)
		(end 72.087232 -74.56297)
		(width 0.08382)
		(layer "In2.Cu")
		(net "BMC_EMMC_DT4")
	)
	(segment
		(start 52.540916 -72.32777)
		(end 53.743606 -73.53046)
		(width 0.08382)
		(layer "In2.Cu")
		(net "BMC_EMMC_DT4")
	)
	(segment
		(start 33.195006 -71.82866)
		(end 34.800794 -71.82866)
		(width 0.08382)
		(layer "In2.Cu")
		(net "BMC_EMMC_DT4")
	)
	(segment
		(start 53.743606 -73.53046)
		(end 54.57698 -73.53046)
		(width 0.08382)
		(layer "In2.Cu")
		(net "BMC_EMMC_DT4")
	)
	(segment
		(start 72.862948 -75.584558)
		(end 73.10882 -75.584558)
		(width 0.08382)
		(layer "In2.Cu")
		(net "BMC_EMMC_DT4")
	)
	(segment
		(start 56.49341 -75.44689)
		(end 60.95111 -75.44689)
		(width 0.08382)
		(layer "In2.Cu")
		(net "BMC_EMMC_DT4")
	)
	(segment
		(start 64.525652 -75.16241)
		(end 64.525652 -74.51979)
		(width 0.08382)
		(layer "In2.Cu")
		(net "BMC_EMMC_DT4")
	)
	(segment
		(start 43.989244 -72.03059)
		(end 51.515518 -72.03059)
		(width 0.08382)
		(layer "In2.Cu")
		(net "BMC_EMMC_DT4")
	)
	(segment
		(start 32.70504 -71.338694)
		(end 33.195006 -71.82866)
		(width 0.08382)
		(layer "In2.Cu")
		(net "BMC_EMMC_DT4")
	)
	(segment
		(start 60.95111 -75.44689)
		(end 62.23 -74.168)
		(width 0.08382)
		(layer "In2.Cu")
		(net "BMC_EMMC_DT4")
	)
	(segment
		(start 64.525652 -74.51979)
		(end 64.699642 -74.3458)
		(width 0.08382)
		(layer "In2.Cu")
		(net "BMC_EMMC_DT4")
	)
	(segment
		(start 72.442578 -74.918316)
		(end 72.442578 -75.164188)
		(width 0.08382)
		(layer "In2.Cu")
		(net "BMC_EMMC_DT4")
	)
	(segment
		(start 72.59447 -75.85329)
		(end 72.862948 -75.584558)
		(width 0.08382)
		(layer "In2.Cu")
		(net "BMC_EMMC_DT4")
	)
	(segment
		(start 63.931292 -75.16241)
		(end 64.105282 -75.3364)
		(width 0.08382)
		(layer "In2.Cu")
		(net "BMC_EMMC_DT4")
	)
	(segment
		(start 51.812698 -72.32777)
		(end 52.540916 -72.32777)
		(width 0.08382)
		(layer "In2.Cu")
		(net "BMC_EMMC_DT4")
	)
	(segment
		(start 63.1952 -74.168)
		(end 63.373 -74.3458)
		(width 0.08382)
		(layer "In2.Cu")
		(net "BMC_EMMC_DT4")
	)
	(segment
		(start 63.373 -74.3458)
		(end 63.757302 -74.3458)
		(width 0.08382)
		(layer "In2.Cu")
		(net "BMC_EMMC_DT4")
	)
	(segment
		(start 72.087232 -74.56297)
		(end 72.442578 -74.918316)
		(width 0.08382)
		(layer "In2.Cu")
		(net "BMC_EMMC_DT4")
	)
	(segment
		(start 72.1741 -75.678792)
		(end 72.348598 -75.85329)
		(width 0.08382)
		(layer "In2.Cu")
		(net "BMC_EMMC_DT4")
	)
	(segment
		(start 60.6425 -54.1528)
		(end 59.39028 -54.1528)
		(width 0.10668)
		(layer "In4.Cu")
		(net "BMC_EMMC_DT4")
	)
	(segment
		(start 50.864262 -43.99788)
		(end 49.779174 -43.99788)
		(width 0.10668)
		(layer "In4.Cu")
		(net "BMC_EMMC_DT4")
	)
	(segment
		(start 71.1327 -69.4944)
		(end 73.152 -69.4944)
		(width 0.10668)
		(layer "In4.Cu")
		(net "BMC_EMMC_DT4")
	)
	(segment
		(start 61.1124 -54.6227)
		(end 60.6425 -54.1528)
		(width 0.10668)
		(layer "In4.Cu")
		(net "BMC_EMMC_DT4")
	)
	(segment
		(start 48.883316 -40.959532)
		(end 48.499776 -40.575992)
		(width 0.10668)
		(layer "In4.Cu")
		(net "BMC_EMMC_DT4")
	)
	(segment
		(start 51.8414 -46.2026)
		(end 51.8414 -45.6438)
		(width 0.10668)
		(layer "In4.Cu")
		(net "BMC_EMMC_DT4")
	)
	(segment
		(start 65.2907 -54.6227)
		(end 61.1124 -54.6227)
		(width 0.10668)
		(layer "In4.Cu")
		(net "BMC_EMMC_DT4")
	)
	(segment
		(start 48.883316 -42.253408)
		(end 48.883316 -40.959532)
		(width 0.10668)
		(layer "In4.Cu")
		(net "BMC_EMMC_DT4")
	)
	(segment
		(start 48.916336 -42.286428)
		(end 48.883316 -42.253408)
		(width 0.10668)
		(layer "In4.Cu")
		(net "BMC_EMMC_DT4")
	)
	(segment
		(start 69.69506 -63.52286)
		(end 67.434968 -61.262768)
		(width 0.10668)
		(layer "In4.Cu")
		(net "BMC_EMMC_DT4")
	)
	(segment
		(start 58.33491 -51.34991)
		(end 55.51551 -51.34991)
		(width 0.10668)
		(layer "In4.Cu")
		(net "BMC_EMMC_DT4")
	)
	(segment
		(start 73.69556 -68.95084)
		(end 73.69556 -67.52336)
		(width 0.10668)
		(layer "In4.Cu")
		(net "BMC_EMMC_DT4")
	)
	(segment
		(start 58.4962 -52.0954)
		(end 58.4962 -51.5112)
		(width 0.10668)
		(layer "In4.Cu")
		(net "BMC_EMMC_DT4")
	)
	(segment
		(start 66.2178 -55.5498)
		(end 65.2907 -54.6227)
		(width 0.10668)
		(layer "In4.Cu")
		(net "BMC_EMMC_DT4")
	)
	(segment
		(start 73.152 -69.4944)
		(end 73.69556 -68.95084)
		(width 0.10668)
		(layer "In4.Cu")
		(net "BMC_EMMC_DT4")
	)
	(segment
		(start 59.2836 -54.04612)
		(end 59.2836 -52.8828)
		(width 0.10668)
		(layer "In4.Cu")
		(net "BMC_EMMC_DT4")
	)
	(segment
		(start 72.9107 -77.6859)
		(end 72.5805 -77.6859)
		(width 0.10668)
		(layer "In4.Cu")
		(net "BMC_EMMC_DT4")
	)
	(segment
		(start 73.69556 -67.52336)
		(end 70.51294 -64.34074)
		(width 0.10668)
		(layer "In4.Cu")
		(net "BMC_EMMC_DT4")
	)
	(segment
		(start 51.8414 -45.6438)
		(end 51.316128 -45.118528)
		(width 0.10668)
		(layer "In4.Cu")
		(net "BMC_EMMC_DT4")
	)
	(segment
		(start 54.9656 -49.3268)
		(end 51.8414 -46.2026)
		(width 0.10668)
		(layer "In4.Cu")
		(net "BMC_EMMC_DT4")
	)
	(segment
		(start 67.147694 -60.569094)
		(end 66.2178 -59.6392)
		(width 0.10668)
		(layer "In4.Cu")
		(net "BMC_EMMC_DT4")
	)
	(segment
		(start 51.316128 -44.449746)
		(end 50.864262 -43.99788)
		(width 0.10668)
		(layer "In4.Cu")
		(net "BMC_EMMC_DT4")
	)
	(segment
		(start 69.9643 -64.34074)
		(end 69.69506 -64.0715)
		(width 0.10668)
		(layer "In4.Cu")
		(net "BMC_EMMC_DT4")
	)
	(segment
		(start 69.69506 -64.0715)
		(end 69.69506 -63.52286)
		(width 0.10668)
		(layer "In4.Cu")
		(net "BMC_EMMC_DT4")
	)
	(segment
		(start 48.916336 -43.135042)
		(end 48.916336 -42.286428)
		(width 0.10668)
		(layer "In4.Cu")
		(net "BMC_EMMC_DT4")
	)
	(segment
		(start 67.434968 -61.262768)
		(end 67.147694 -60.569094)
		(width 0.10668)
		(layer "In4.Cu")
		(net "BMC_EMMC_DT4")
	)
	(segment
		(start 59.39028 -54.1528)
		(end 59.2836 -54.04612)
		(width 0.10668)
		(layer "In4.Cu")
		(net "BMC_EMMC_DT4")
	)
	(segment
		(start 72.5805 -77.6859)
		(end 72.0852 -77.1906)
		(width 0.10668)
		(layer "In4.Cu")
		(net "BMC_EMMC_DT4")
	)
	(segment
		(start 55.51551 -51.34991)
		(end 54.9656 -50.8)
		(width 0.10668)
		(layer "In4.Cu")
		(net "BMC_EMMC_DT4")
	)
	(segment
		(start 70.8787 -71.404988)
		(end 70.8787 -69.7484)
		(width 0.10668)
		(layer "In4.Cu")
		(net "BMC_EMMC_DT4")
	)
	(segment
		(start 59.2836 -52.8828)
		(end 58.4962 -52.0954)
		(width 0.10668)
		(layer "In4.Cu")
		(net "BMC_EMMC_DT4")
	)
	(segment
		(start 49.779174 -43.99788)
		(end 48.916336 -43.135042)
		(width 0.10668)
		(layer "In4.Cu")
		(net "BMC_EMMC_DT4")
	)
	(segment
		(start 54.9656 -50.8)
		(end 54.9656 -49.3268)
		(width 0.10668)
		(layer "In4.Cu")
		(net "BMC_EMMC_DT4")
	)
	(segment
		(start 70.51294 -64.34074)
		(end 69.9643 -64.34074)
		(width 0.10668)
		(layer "In4.Cu")
		(net "BMC_EMMC_DT4")
	)
	(segment
		(start 72.0852 -72.611488)
		(end 70.8787 -71.404988)
		(width 0.10668)
		(layer "In4.Cu")
		(net "BMC_EMMC_DT4")
	)
	(segment
		(start 51.316128 -45.118528)
		(end 51.316128 -44.449746)
		(width 0.10668)
		(layer "In4.Cu")
		(net "BMC_EMMC_DT4")
	)
	(segment
		(start 72.0852 -77.1906)
		(end 72.0852 -72.611488)
		(width 0.10668)
		(layer "In4.Cu")
		(net "BMC_EMMC_DT4")
	)
	(segment
		(start 58.4962 -51.5112)
		(end 58.33491 -51.34991)
		(width 0.10668)
		(layer "In4.Cu")
		(net "BMC_EMMC_DT4")
	)
	(segment
		(start 66.2178 -59.6392)
		(end 66.2178 -55.5498)
		(width 0.10668)
		(layer "In4.Cu")
		(net "BMC_EMMC_DT4")
	)
	(segment
		(start 70.8787 -69.7484)
		(end 71.1327 -69.4944)
		(width 0.10668)
		(layer "In4.Cu")
		(net "BMC_EMMC_DT4")
	)
	(segment
		(start 45.704506 -39.37127)
		(end 45.695108 -39.37127)
		(width 0.11684)
		(layer "F.Cu")
		(net "BMC_EMMC_DT3")
	)
	(segment
		(start 32.999172 -84.217002)
		(end 33.64357 -84.8614)
		(width 0.11684)
		(layer "F.Cu")
		(net "BMC_EMMC_DT3")
	)
	(segment
		(start 46.09973 -38.976046)
		(end 45.704506 -39.37127)
		(width 0.11684)
		(layer "F.Cu")
		(net "BMC_EMMC_DT3")
	)
	(segment
		(start 33.64357 -84.8614)
		(end 33.8582 -84.8614)
		(width 0.11684)
		(layer "F.Cu")
		(net "BMC_EMMC_DT3")
	)
	(via
		(at 33.8582 -84.8614)
		(size 0.508)
		(drill 0.254)
		(layers "F.Cu" "B.Cu")
		(net "BMC_EMMC_DT3")
	)
	(via
		(at 46.09973 -38.976046)
		(size 0.4572)
		(drill 0.254)
		(layers "F.Cu" "B.Cu")
		(net "BMC_EMMC_DT3")
	)
	(via
		(at 59.69 -85.1662)
		(size 0.508)
		(drill 0.254)
		(layers "F.Cu" "B.Cu")
		(net "BMC_EMMC_DT3")
	)
	(segment
		(start 59.69 -85.6234)
		(end 59.69 -85.1662)
		(width 0.08382)
		(layer "In2.Cu")
		(net "BMC_EMMC_DT3")
	)
	(segment
		(start 49.426114 -85.31606)
		(end 51.301142 -85.31606)
		(width 0.08382)
		(layer "In2.Cu")
		(net "BMC_EMMC_DT3")
	)
	(segment
		(start 58.610246 -85.839554)
		(end 58.610246 -85.8393)
		(width 0.08382)
		(layer "In2.Cu")
		(net "BMC_EMMC_DT3")
	)
	(segment
		(start 47.680626 -84.787232)
		(end 48.897286 -84.787232)
		(width 0.08382)
		(layer "In2.Cu")
		(net "BMC_EMMC_DT3")
	)
	(segment
		(start 51.301142 -85.31606)
		(end 52.139342 -86.15426)
		(width 0.08382)
		(layer "In2.Cu")
		(net "BMC_EMMC_DT3")
	)
	(segment
		(start 33.8582 -84.8614)
		(end 33.909 -84.8614)
		(width 0.08382)
		(layer "In2.Cu")
		(net "BMC_EMMC_DT3")
	)
	(segment
		(start 59.41314 -85.90026)
		(end 59.69 -85.6234)
		(width 0.08382)
		(layer "In2.Cu")
		(net "BMC_EMMC_DT3")
	)
	(segment
		(start 35.90671 -86.85911)
		(end 36.712906 -86.85911)
		(width 0.08382)
		(layer "In2.Cu")
		(net "BMC_EMMC_DT3")
	)
	(segment
		(start 33.909 -84.8614)
		(end 35.90671 -86.85911)
		(width 0.08382)
		(layer "In2.Cu")
		(net "BMC_EMMC_DT3")
	)
	(segment
		(start 55.577994 -86.15426)
		(end 55.600854 -86.1314)
		(width 0.08382)
		(layer "In2.Cu")
		(net "BMC_EMMC_DT3")
	)
	(segment
		(start 55.626508 -86.1314)
		(end 56.829198 -84.92871)
		(width 0.08382)
		(layer "In2.Cu")
		(net "BMC_EMMC_DT3")
	)
	(segment
		(start 48.897286 -84.787232)
		(end 49.426114 -85.31606)
		(width 0.08382)
		(layer "In2.Cu")
		(net "BMC_EMMC_DT3")
	)
	(segment
		(start 44.2468 -88.2142)
		(end 45.12183 -87.33917)
		(width 0.08382)
		(layer "In2.Cu")
		(net "BMC_EMMC_DT3")
	)
	(segment
		(start 52.139342 -86.15426)
		(end 55.577994 -86.15426)
		(width 0.08382)
		(layer "In2.Cu")
		(net "BMC_EMMC_DT3")
	)
	(segment
		(start 56.829198 -84.92871)
		(end 57.699402 -84.92871)
		(width 0.08382)
		(layer "In2.Cu")
		(net "BMC_EMMC_DT3")
	)
	(segment
		(start 45.12183 -87.33917)
		(end 45.12183 -86.52891)
		(width 0.08382)
		(layer "In2.Cu")
		(net "BMC_EMMC_DT3")
	)
	(segment
		(start 58.610246 -85.8393)
		(end 58.671206 -85.90026)
		(width 0.08382)
		(layer "In2.Cu")
		(net "BMC_EMMC_DT3")
	)
	(segment
		(start 38.067996 -88.2142)
		(end 44.2468 -88.2142)
		(width 0.08382)
		(layer "In2.Cu")
		(net "BMC_EMMC_DT3")
	)
	(segment
		(start 45.12183 -86.52891)
		(end 45.780706 -85.870034)
		(width 0.08382)
		(layer "In2.Cu")
		(net "BMC_EMMC_DT3")
	)
	(segment
		(start 46.597824 -85.870034)
		(end 47.680626 -84.787232)
		(width 0.08382)
		(layer "In2.Cu")
		(net "BMC_EMMC_DT3")
	)
	(segment
		(start 57.699402 -84.92871)
		(end 58.610246 -85.839554)
		(width 0.08382)
		(layer "In2.Cu")
		(net "BMC_EMMC_DT3")
	)
	(segment
		(start 55.600854 -86.1314)
		(end 55.626508 -86.1314)
		(width 0.08382)
		(layer "In2.Cu")
		(net "BMC_EMMC_DT3")
	)
	(segment
		(start 45.780706 -85.870034)
		(end 46.597824 -85.870034)
		(width 0.08382)
		(layer "In2.Cu")
		(net "BMC_EMMC_DT3")
	)
	(segment
		(start 36.712906 -86.85911)
		(end 38.067996 -88.2142)
		(width 0.08382)
		(layer "In2.Cu")
		(net "BMC_EMMC_DT3")
	)
	(segment
		(start 58.671206 -85.90026)
		(end 59.41314 -85.90026)
		(width 0.08382)
		(layer "In2.Cu")
		(net "BMC_EMMC_DT3")
	)
	(segment
		(start 59.6646 -63.1952)
		(end 59.6646 -62.0268)
		(width 0.10668)
		(layer "In4.Cu")
		(net "BMC_EMMC_DT3")
	)
	(segment
		(start 45.835824 -45.759624)
		(end 43.4594 -43.3832)
		(width 0.10668)
		(layer "In4.Cu")
		(net "BMC_EMMC_DT3")
	)
	(segment
		(start 58.7248 -61.087)
		(end 58.7248 -60.5282)
		(width 0.10668)
		(layer "In4.Cu")
		(net "BMC_EMMC_DT3")
	)
	(segment
		(start 55.609744 -55.1434)
		(end 55.4736 -55.1434)
		(width 0.10668)
		(layer "In4.Cu")
		(net "BMC_EMMC_DT3")
	)
	(segment
		(start 61.699648 -67.069208)
		(end 61.5188 -66.88836)
		(width 0.10668)
		(layer "In4.Cu")
		(net "BMC_EMMC_DT3")
	)
	(segment
		(start 62.5094 -72.41921)
		(end 62.5094 -72.163686)
		(width 0.10668)
		(layer "In4.Cu")
		(net "BMC_EMMC_DT3")
	)
	(segment
		(start 61.979048 -72.600058)
		(end 62.328552 -72.600058)
		(width 0.10668)
		(layer "In4.Cu")
		(net "BMC_EMMC_DT3")
	)
	(segment
		(start 60.8838 -79.706724)
		(end 60.8838 -77.8764)
		(width 0.10668)
		(layer "In4.Cu")
		(net "BMC_EMMC_DT3")
	)
	(segment
		(start 56.3372 -56.9722)
		(end 56.106568 -56.741568)
		(width 0.10668)
		(layer "In4.Cu")
		(net "BMC_EMMC_DT3")
	)
	(segment
		(start 60.099448 -75.28814)
		(end 59.9186 -75.107292)
		(width 0.10668)
		(layer "In4.Cu")
		(net "BMC_EMMC_DT3")
	)
	(segment
		(start 61.5188 -69.7992)
		(end 62.2808 -69.0372)
		(width 0.10668)
		(layer "In4.Cu")
		(net "BMC_EMMC_DT3")
	)
	(segment
		(start 61.7982 -76.962)
		(end 61.7982 -76.703428)
		(width 0.10668)
		(layer "In4.Cu")
		(net "BMC_EMMC_DT3")
	)
	(segment
		(start 50.4952 -48.361854)
		(end 50.317146 -48.1838)
		(width 0.10668)
		(layer "In4.Cu")
		(net "BMC_EMMC_DT3")
	)
	(segment
		(start 59.309 -58.293)
		(end 59.309 -57.2262)
		(width 0.10668)
		(layer "In4.Cu")
		(net "BMC_EMMC_DT3")
	)
	(segment
		(start 62.2808 -66.27114)
		(end 62.2808 -64.516)
		(width 0.10668)
		(layer "In4.Cu")
		(net "BMC_EMMC_DT3")
	)
	(segment
		(start 43.4594 -43.3832)
		(end 43.4594 -42.674032)
		(width 0.10668)
		(layer "In4.Cu")
		(net "BMC_EMMC_DT3")
	)
	(segment
		(start 62.2808 -69.0372)
		(end 62.2808 -67.250056)
		(width 0.10668)
		(layer "In4.Cu")
		(net "BMC_EMMC_DT3")
	)
	(segment
		(start 47.1678 -46.5836)
		(end 46.736 -46.5836)
		(width 0.10668)
		(layer "In4.Cu")
		(net "BMC_EMMC_DT3")
	)
	(segment
		(start 60.099448 -74.67092)
		(end 61.617352 -74.67092)
		(width 0.10668)
		(layer "In4.Cu")
		(net "BMC_EMMC_DT3")
	)
	(segment
		(start 51.7906 -51.8668)
		(end 51.4096 -51.8668)
		(width 0.10668)
		(layer "In4.Cu")
		(net "BMC_EMMC_DT3")
	)
	(segment
		(start 61.617352 -75.28814)
		(end 60.099448 -75.28814)
		(width 0.10668)
		(layer "In4.Cu")
		(net "BMC_EMMC_DT3")
	)
	(segment
		(start 61.5188 -66.88836)
		(end 61.5188 -66.632836)
		(width 0.10668)
		(layer "In4.Cu")
		(net "BMC_EMMC_DT3")
	)
	(segment
		(start 48.0568 -48.1838)
		(end 47.2948 -47.4218)
		(width 0.10668)
		(layer "In4.Cu")
		(net "BMC_EMMC_DT3")
	)
	(segment
		(start 47.2948 -46.7106)
		(end 47.1678 -46.5836)
		(width 0.10668)
		(layer "In4.Cu")
		(net "BMC_EMMC_DT3")
	)
	(segment
		(start 61.979048 -71.982838)
		(end 61.7982 -71.80199)
		(width 0.10668)
		(layer "In4.Cu")
		(net "BMC_EMMC_DT3")
	)
	(segment
		(start 61.7982 -71.028814)
		(end 61.5188 -70.354444)
		(width 0.10668)
		(layer "In4.Cu")
		(net "BMC_EMMC_DT3")
	)
	(segment
		(start 61.7982 -71.80199)
		(end 61.7982 -71.028814)
		(width 0.10668)
		(layer "In4.Cu")
		(net "BMC_EMMC_DT3")
	)
	(segment
		(start 61.7982 -74.234548)
		(end 61.617352 -74.0537)
		(width 0.10668)
		(layer "In4.Cu")
		(net "BMC_EMMC_DT3")
	)
	(segment
		(start 61.7982 -73.255632)
		(end 61.7982 -72.780906)
		(width 0.10668)
		(layer "In4.Cu")
		(net "BMC_EMMC_DT3")
	)
	(segment
		(start 62.2808 -64.516)
		(end 61.6712 -63.9064)
		(width 0.10668)
		(layer "In4.Cu")
		(net "BMC_EMMC_DT3")
	)
	(segment
		(start 61.699648 -66.451988)
		(end 62.099952 -66.451988)
		(width 0.10668)
		(layer "In4.Cu")
		(net "BMC_EMMC_DT3")
	)
	(segment
		(start 51.4096 -51.8668)
		(end 50.9016 -51.3588)
		(width 0.10668)
		(layer "In4.Cu")
		(net "BMC_EMMC_DT3")
	)
	(segment
		(start 58.3946 -60.198)
		(end 58.3946 -58.9026)
		(width 0.10668)
		(layer "In4.Cu")
		(net "BMC_EMMC_DT3")
	)
	(segment
		(start 61.7982 -72.780906)
		(end 61.979048 -72.600058)
		(width 0.10668)
		(layer "In4.Cu")
		(net "BMC_EMMC_DT3")
	)
	(segment
		(start 62.099952 -67.069208)
		(end 61.699648 -67.069208)
		(width 0.10668)
		(layer "In4.Cu")
		(net "BMC_EMMC_DT3")
	)
	(segment
		(start 45.6946 -39.381176)
		(end 46.09973 -38.976046)
		(width 0.10668)
		(layer "In4.Cu")
		(net "BMC_EMMC_DT3")
	)
	(segment
		(start 56.106568 -55.640224)
		(end 55.609744 -55.1434)
		(width 0.10668)
		(layer "In4.Cu")
		(net "BMC_EMMC_DT3")
	)
	(segment
		(start 50.9016 -51.3588)
		(end 50.9016 -49.6062)
		(width 0.10668)
		(layer "In4.Cu")
		(net "BMC_EMMC_DT3")
	)
	(segment
		(start 59.9186 -76.086208)
		(end 60.099448 -75.90536)
		(width 0.10668)
		(layer "In4.Cu")
		(net "BMC_EMMC_DT3")
	)
	(segment
		(start 55.4736 -55.1434)
		(end 54.483254 -54.153054)
		(width 0.10668)
		(layer "In4.Cu")
		(net "BMC_EMMC_DT3")
	)
	(segment
		(start 58.7248 -58.5724)
		(end 59.0296 -58.5724)
		(width 0.10668)
		(layer "In4.Cu")
		(net "BMC_EMMC_DT3")
	)
	(segment
		(start 61.5188 -66.632836)
		(end 61.699648 -66.451988)
		(width 0.10668)
		(layer "In4.Cu")
		(net "BMC_EMMC_DT3")
	)
	(segment
		(start 46.5074 -46.355)
		(end 46.5074 -45.974)
		(width 0.10668)
		(layer "In4.Cu")
		(net "BMC_EMMC_DT3")
	)
	(segment
		(start 61.5188 -70.354444)
		(end 61.5188 -69.7992)
		(width 0.10668)
		(layer "In4.Cu")
		(net "BMC_EMMC_DT3")
	)
	(segment
		(start 46.293024 -45.759624)
		(end 45.835824 -45.759624)
		(width 0.10668)
		(layer "In4.Cu")
		(net "BMC_EMMC_DT3")
	)
	(segment
		(start 60.099448 -75.90536)
		(end 61.617352 -75.90536)
		(width 0.10668)
		(layer "In4.Cu")
		(net "BMC_EMMC_DT3")
	)
	(segment
		(start 52.0954 -52.832)
		(end 52.0954 -52.1716)
		(width 0.10668)
		(layer "In4.Cu")
		(net "BMC_EMMC_DT3")
	)
	(segment
		(start 56.106568 -56.741568)
		(end 56.106568 -55.640224)
		(width 0.10668)
		(layer "In4.Cu")
		(net "BMC_EMMC_DT3")
	)
	(segment
		(start 62.328552 -72.600058)
		(end 62.5094 -72.41921)
		(width 0.10668)
		(layer "In4.Cu")
		(net "BMC_EMMC_DT3")
	)
	(segment
		(start 54.483254 -54.007512)
		(end 54.247542 -53.7718)
		(width 0.10668)
		(layer "In4.Cu")
		(net "BMC_EMMC_DT3")
	)
	(segment
		(start 59.5757 -80.5053)
		(end 60.10148 -79.97952)
		(width 0.10668)
		(layer "In4.Cu")
		(net "BMC_EMMC_DT3")
	)
	(segment
		(start 61.617352 -75.90536)
		(end 61.7982 -75.724512)
		(width 0.10668)
		(layer "In4.Cu")
		(net "BMC_EMMC_DT3")
	)
	(segment
		(start 52.0954 -52.1716)
		(end 51.7906 -51.8668)
		(width 0.10668)
		(layer "In4.Cu")
		(net "BMC_EMMC_DT3")
	)
	(segment
		(start 60.099448 -76.52258)
		(end 59.9186 -76.341732)
		(width 0.10668)
		(layer "In4.Cu")
		(net "BMC_EMMC_DT3")
	)
	(segment
		(start 61.7982 -75.468988)
		(end 61.617352 -75.28814)
		(width 0.10668)
		(layer "In4.Cu")
		(net "BMC_EMMC_DT3")
	)
	(segment
		(start 45.494448 -40.992552)
		(end 45.6946 -40.7924)
		(width 0.10668)
		(layer "In4.Cu")
		(net "BMC_EMMC_DT3")
	)
	(segment
		(start 59.055 -56.9722)
		(end 56.3372 -56.9722)
		(width 0.10668)
		(layer "In4.Cu")
		(net "BMC_EMMC_DT3")
	)
	(segment
		(start 59.6646 -62.0268)
		(end 58.7248 -61.087)
		(width 0.10668)
		(layer "In4.Cu")
		(net "BMC_EMMC_DT3")
	)
	(segment
		(start 61.7982 -76.703428)
		(end 61.617352 -76.52258)
		(width 0.10668)
		(layer "In4.Cu")
		(net "BMC_EMMC_DT3")
	)
	(segment
		(start 59.9186 -76.341732)
		(end 59.9186 -76.086208)
		(width 0.10668)
		(layer "In4.Cu")
		(net "BMC_EMMC_DT3")
	)
	(segment
		(start 60.099448 -74.0537)
		(end 59.9186 -73.872852)
		(width 0.10668)
		(layer "In4.Cu")
		(net "BMC_EMMC_DT3")
	)
	(segment
		(start 59.9186 -73.872852)
		(end 59.9186 -73.617328)
		(width 0.10668)
		(layer "In4.Cu")
		(net "BMC_EMMC_DT3")
	)
	(segment
		(start 54.247542 -53.7718)
		(end 53.0352 -53.7718)
		(width 0.10668)
		(layer "In4.Cu")
		(net "BMC_EMMC_DT3")
	)
	(segment
		(start 60.611004 -79.97952)
		(end 60.8838 -79.706724)
		(width 0.10668)
		(layer "In4.Cu")
		(net "BMC_EMMC_DT3")
	)
	(segment
		(start 58.3946 -58.9026)
		(end 58.7248 -58.5724)
		(width 0.10668)
		(layer "In4.Cu")
		(net "BMC_EMMC_DT3")
	)
	(segment
		(start 59.9186 -74.851768)
		(end 60.099448 -74.67092)
		(width 0.10668)
		(layer "In4.Cu")
		(net "BMC_EMMC_DT3")
	)
	(segment
		(start 62.5094 -72.163686)
		(end 62.328552 -71.982838)
		(width 0.10668)
		(layer "In4.Cu")
		(net "BMC_EMMC_DT3")
	)
	(segment
		(start 61.617352 -76.52258)
		(end 60.099448 -76.52258)
		(width 0.10668)
		(layer "In4.Cu")
		(net "BMC_EMMC_DT3")
	)
	(segment
		(start 59.9186 -75.107292)
		(end 59.9186 -74.851768)
		(width 0.10668)
		(layer "In4.Cu")
		(net "BMC_EMMC_DT3")
	)
	(segment
		(start 62.328552 -71.982838)
		(end 61.979048 -71.982838)
		(width 0.10668)
		(layer "In4.Cu")
		(net "BMC_EMMC_DT3")
	)
	(segment
		(start 61.617352 -73.43648)
		(end 61.7982 -73.255632)
		(width 0.10668)
		(layer "In4.Cu")
		(net "BMC_EMMC_DT3")
	)
	(segment
		(start 43.4594 -42.674032)
		(end 45.14088 -40.992552)
		(width 0.10668)
		(layer "In4.Cu")
		(net "BMC_EMMC_DT3")
	)
	(segment
		(start 60.099448 -73.43648)
		(end 61.617352 -73.43648)
		(width 0.10668)
		(layer "In4.Cu")
		(net "BMC_EMMC_DT3")
	)
	(segment
		(start 60.3758 -63.9064)
		(end 59.6646 -63.1952)
		(width 0.10668)
		(layer "In4.Cu")
		(net "BMC_EMMC_DT3")
	)
	(segment
		(start 54.483254 -54.153054)
		(end 54.483254 -54.007512)
		(width 0.10668)
		(layer "In4.Cu")
		(net "BMC_EMMC_DT3")
	)
	(segment
		(start 59.309 -57.2262)
		(end 59.055 -56.9722)
		(width 0.10668)
		(layer "In4.Cu")
		(net "BMC_EMMC_DT3")
	)
	(segment
		(start 62.2808 -67.250056)
		(end 62.099952 -67.069208)
		(width 0.10668)
		(layer "In4.Cu")
		(net "BMC_EMMC_DT3")
	)
	(segment
		(start 53.0352 -53.7718)
		(end 52.0954 -52.832)
		(width 0.10668)
		(layer "In4.Cu")
		(net "BMC_EMMC_DT3")
	)
	(segment
		(start 59.5757 -85.0519)
		(end 59.5757 -80.5053)
		(width 0.10668)
		(layer "In4.Cu")
		(net "BMC_EMMC_DT3")
	)
	(segment
		(start 61.617352 -74.67092)
		(end 61.7982 -74.490072)
		(width 0.10668)
		(layer "In4.Cu")
		(net "BMC_EMMC_DT3")
	)
	(segment
		(start 60.10148 -79.97952)
		(end 60.611004 -79.97952)
		(width 0.10668)
		(layer "In4.Cu")
		(net "BMC_EMMC_DT3")
	)
	(segment
		(start 50.4952 -49.1998)
		(end 50.4952 -48.361854)
		(width 0.10668)
		(layer "In4.Cu")
		(net "BMC_EMMC_DT3")
	)
	(segment
		(start 50.9016 -49.6062)
		(end 50.4952 -49.1998)
		(width 0.10668)
		(layer "In4.Cu")
		(net "BMC_EMMC_DT3")
	)
	(segment
		(start 60.8838 -77.8764)
		(end 61.7982 -76.962)
		(width 0.10668)
		(layer "In4.Cu")
		(net "BMC_EMMC_DT3")
	)
	(segment
		(start 46.736 -46.5836)
		(end 46.5074 -46.355)
		(width 0.10668)
		(layer "In4.Cu")
		(net "BMC_EMMC_DT3")
	)
	(segment
		(start 47.2948 -47.4218)
		(end 47.2948 -46.7106)
		(width 0.10668)
		(layer "In4.Cu")
		(net "BMC_EMMC_DT3")
	)
	(segment
		(start 59.0296 -58.5724)
		(end 59.309 -58.293)
		(width 0.10668)
		(layer "In4.Cu")
		(net "BMC_EMMC_DT3")
	)
	(segment
		(start 45.14088 -40.992552)
		(end 45.494448 -40.992552)
		(width 0.10668)
		(layer "In4.Cu")
		(net "BMC_EMMC_DT3")
	)
	(segment
		(start 59.69 -85.1662)
		(end 59.5757 -85.0519)
		(width 0.10668)
		(layer "In4.Cu")
		(net "BMC_EMMC_DT3")
	)
	(segment
		(start 50.317146 -48.1838)
		(end 48.0568 -48.1838)
		(width 0.10668)
		(layer "In4.Cu")
		(net "BMC_EMMC_DT3")
	)
	(segment
		(start 45.6946 -40.7924)
		(end 45.6946 -39.381176)
		(width 0.10668)
		(layer "In4.Cu")
		(net "BMC_EMMC_DT3")
	)
	(segment
		(start 58.7248 -60.5282)
		(end 58.3946 -60.198)
		(width 0.10668)
		(layer "In4.Cu")
		(net "BMC_EMMC_DT3")
	)
	(segment
		(start 62.099952 -66.451988)
		(end 62.2808 -66.27114)
		(width 0.10668)
		(layer "In4.Cu")
		(net "BMC_EMMC_DT3")
	)
	(segment
		(start 59.9186 -73.617328)
		(end 60.099448 -73.43648)
		(width 0.10668)
		(layer "In4.Cu")
		(net "BMC_EMMC_DT3")
	)
	(segment
		(start 46.5074 -45.974)
		(end 46.293024 -45.759624)
		(width 0.10668)
		(layer "In4.Cu")
		(net "BMC_EMMC_DT3")
	)
	(segment
		(start 61.617352 -74.0537)
		(end 60.099448 -74.0537)
		(width 0.10668)
		(layer "In4.Cu")
		(net "BMC_EMMC_DT3")
	)
	(segment
		(start 61.7982 -74.490072)
		(end 61.7982 -74.234548)
		(width 0.10668)
		(layer "In4.Cu")
		(net "BMC_EMMC_DT3")
	)
	(segment
		(start 61.7982 -75.724512)
		(end 61.7982 -75.468988)
		(width 0.10668)
		(layer "In4.Cu")
		(net "BMC_EMMC_DT3")
	)
	(segment
		(start 61.6712 -63.9064)
		(end 60.3758 -63.9064)
		(width 0.10668)
		(layer "In4.Cu")
		(net "BMC_EMMC_DT3")
	)
	(segment
		(start 34.102802 -84.217002)
		(end 34.5694 -84.6836)
		(width 0.11684)
		(layer "F.Cu")
		(net "BMC_EMMC_DT2")
	)
	(segment
		(start 34.5694 -84.6836)
		(end 34.5694 -84.836)
		(width 0.11684)
		(layer "F.Cu")
		(net "BMC_EMMC_DT2")
	)
	(segment
		(start 34.015172 -84.217002)
		(end 34.102802 -84.217002)
		(width 0.11684)
		(layer "F.Cu")
		(net "BMC_EMMC_DT2")
	)
	(segment
		(start 48.499776 -41.376092)
		(end 48.0949 -40.971216)
		(width 0.11684)
		(layer "F.Cu")
		(net "BMC_EMMC_DT2")
	)
	(via
		(at 48.499776 -41.376092)
		(size 0.4572)
		(drill 0.254)
		(layers "F.Cu" "B.Cu")
		(net "BMC_EMMC_DT2")
	)
	(via
		(at 73.66 -85.2424)
		(size 0.508)
		(drill 0.254)
		(layers "F.Cu" "B.Cu")
		(net "BMC_EMMC_DT2")
	)
	(via
		(at 34.5694 -84.836)
		(size 0.508)
		(drill 0.254)
		(layers "F.Cu" "B.Cu")
		(net "BMC_EMMC_DT2")
	)
	(segment
		(start 44.87037 -86.424516)
		(end 45.676312 -85.618574)
		(width 0.08382)
		(layer "In2.Cu")
		(net "BMC_EMMC_DT2")
	)
	(segment
		(start 52.38369 -84.989162)
		(end 51.97983 -85.393022)
		(width 0.08382)
		(layer "In2.Cu")
		(net "BMC_EMMC_DT2")
	)
	(segment
		(start 55.88254 -85.49386)
		(end 55.88254 -85.247988)
		(width 0.08382)
		(layer "In2.Cu")
		(net "BMC_EMMC_DT2")
	)
	(segment
		(start 41.967912 -87.9094)
		(end 42.214292 -87.9094)
		(width 0.08382)
		(layer "In2.Cu")
		(net "BMC_EMMC_DT2")
	)
	(segment
		(start 73.13422 -84.71662)
		(end 73.66 -85.2424)
		(width 0.08382)
		(layer "In2.Cu")
		(net "BMC_EMMC_DT2")
	)
	(segment
		(start 41.619932 -87.1474)
		(end 41.793922 -87.32139)
		(width 0.08382)
		(layer "In2.Cu")
		(net "BMC_EMMC_DT2")
	)
	(segment
		(start 52.885848 -85.72881)
		(end 52.885848 -85.41639)
		(width 0.08382)
		(layer "In2.Cu")
		(net "BMC_EMMC_DT2")
	)
	(segment
		(start 56.040782 -84.56549)
		(end 56.30291 -84.827618)
		(width 0.08382)
		(layer "In2.Cu")
		(net "BMC_EMMC_DT2")
	)
	(segment
		(start 56.548782 -84.827618)
		(end 56.905906 -84.470494)
		(width 0.08382)
		(layer "In2.Cu")
		(net "BMC_EMMC_DT2")
	)
	(segment
		(start 42.982642 -87.32139)
		(end 42.982642 -87.73541)
		(width 0.08382)
		(layer "In2.Cu")
		(net "BMC_EMMC_DT2")
	)
	(segment
		(start 52.38369 -84.74329)
		(end 52.38369 -84.989162)
		(width 0.08382)
		(layer "In2.Cu")
		(net "BMC_EMMC_DT2")
	)
	(segment
		(start 56.905906 -84.470494)
		(end 58.253122 -84.470494)
		(width 0.08382)
		(layer "In2.Cu")
		(net "BMC_EMMC_DT2")
	)
	(segment
		(start 41.025572 -87.9094)
		(end 41.199562 -87.73541)
		(width 0.08382)
		(layer "In2.Cu")
		(net "BMC_EMMC_DT2")
	)
	(segment
		(start 42.388282 -87.32139)
		(end 42.562272 -87.1474)
		(width 0.08382)
		(layer "In2.Cu")
		(net "BMC_EMMC_DT2")
	)
	(segment
		(start 36.34105 -86.60765)
		(end 36.8173 -86.60765)
		(width 0.08382)
		(layer "In2.Cu")
		(net "BMC_EMMC_DT2")
	)
	(segment
		(start 52.885848 -85.41639)
		(end 53.059838 -85.2424)
		(width 0.08382)
		(layer "In2.Cu")
		(net "BMC_EMMC_DT2")
	)
	(segment
		(start 55.595012 -84.739988)
		(end 55.76951 -84.56549)
		(width 0.08382)
		(layer "In2.Cu")
		(net "BMC_EMMC_DT2")
	)
	(segment
		(start 69.540374 -85.54212)
		(end 70.795388 -85.54212)
		(width 0.08382)
		(layer "In2.Cu")
		(net "BMC_EMMC_DT2")
	)
	(segment
		(start 38.11905 -87.9094)
		(end 41.025572 -87.9094)
		(width 0.08382)
		(layer "In2.Cu")
		(net "BMC_EMMC_DT2")
	)
	(segment
		(start 43.156632 -87.9094)
		(end 44.1198 -87.9094)
		(width 0.08382)
		(layer "In2.Cu")
		(net "BMC_EMMC_DT2")
	)
	(segment
		(start 34.5694 -84.836)
		(end 36.34105 -86.60765)
		(width 0.08382)
		(layer "In2.Cu")
		(net "BMC_EMMC_DT2")
	)
	(segment
		(start 36.8173 -86.60765)
		(end 38.11905 -87.9094)
		(width 0.08382)
		(layer "In2.Cu")
		(net "BMC_EMMC_DT2")
	)
	(segment
		(start 55.4736 -85.9028)
		(end 55.88254 -85.49386)
		(width 0.08382)
		(layer "In2.Cu")
		(net "BMC_EMMC_DT2")
	)
	(segment
		(start 46.49343 -85.618574)
		(end 47.576232 -84.535772)
		(width 0.08382)
		(layer "In2.Cu")
		(net "BMC_EMMC_DT2")
	)
	(segment
		(start 49.00168 -84.535772)
		(end 49.43856 -84.972652)
		(width 0.08382)
		(layer "In2.Cu")
		(net "BMC_EMMC_DT2")
	)
	(segment
		(start 52.209192 -84.568792)
		(end 52.38369 -84.74329)
		(width 0.08382)
		(layer "In2.Cu")
		(net "BMC_EMMC_DT2")
	)
	(segment
		(start 53.654198 -85.9028)
		(end 55.4736 -85.9028)
		(width 0.08382)
		(layer "In2.Cu")
		(net "BMC_EMMC_DT2")
	)
	(segment
		(start 52.243736 -85.9028)
		(end 52.711858 -85.9028)
		(width 0.08382)
		(layer "In2.Cu")
		(net "BMC_EMMC_DT2")
	)
	(segment
		(start 70.795388 -85.54212)
		(end 71.620888 -84.71662)
		(width 0.08382)
		(layer "In2.Cu")
		(net "BMC_EMMC_DT2")
	)
	(segment
		(start 42.982642 -87.73541)
		(end 43.156632 -87.9094)
		(width 0.08382)
		(layer "In2.Cu")
		(net "BMC_EMMC_DT2")
	)
	(segment
		(start 58.617866 -84.10575)
		(end 59.15025 -84.10575)
		(width 0.08382)
		(layer "In2.Cu")
		(net "BMC_EMMC_DT2")
	)
	(segment
		(start 45.676312 -85.618574)
		(end 46.49343 -85.618574)
		(width 0.08382)
		(layer "In2.Cu")
		(net "BMC_EMMC_DT2")
	)
	(segment
		(start 41.373552 -87.1474)
		(end 41.619932 -87.1474)
		(width 0.08382)
		(layer "In2.Cu")
		(net "BMC_EMMC_DT2")
	)
	(segment
		(start 55.76951 -84.56549)
		(end 56.040782 -84.56549)
		(width 0.08382)
		(layer "In2.Cu")
		(net "BMC_EMMC_DT2")
	)
	(segment
		(start 58.253122 -84.470494)
		(end 58.617866 -84.10575)
		(width 0.08382)
		(layer "In2.Cu")
		(net "BMC_EMMC_DT2")
	)
	(segment
		(start 49.43856 -84.972652)
		(end 51.55946 -84.972652)
		(width 0.08382)
		(layer "In2.Cu")
		(net "BMC_EMMC_DT2")
	)
	(segment
		(start 52.711858 -85.9028)
		(end 52.885848 -85.72881)
		(width 0.08382)
		(layer "In2.Cu")
		(net "BMC_EMMC_DT2")
	)
	(segment
		(start 67.896994 -83.89874)
		(end 69.540374 -85.54212)
		(width 0.08382)
		(layer "In2.Cu")
		(net "BMC_EMMC_DT2")
	)
	(segment
		(start 44.87037 -87.15883)
		(end 44.87037 -86.424516)
		(width 0.08382)
		(layer "In2.Cu")
		(net "BMC_EMMC_DT2")
	)
	(segment
		(start 62.479682 -85.6488)
		(end 64.229742 -83.89874)
		(width 0.08382)
		(layer "In2.Cu")
		(net "BMC_EMMC_DT2")
	)
	(segment
		(start 42.214292 -87.9094)
		(end 42.388282 -87.73541)
		(width 0.08382)
		(layer "In2.Cu")
		(net "BMC_EMMC_DT2")
	)
	(segment
		(start 47.576232 -84.535772)
		(end 49.00168 -84.535772)
		(width 0.08382)
		(layer "In2.Cu")
		(net "BMC_EMMC_DT2")
	)
	(segment
		(start 55.595012 -84.96046)
		(end 55.595012 -84.739988)
		(width 0.08382)
		(layer "In2.Cu")
		(net "BMC_EMMC_DT2")
	)
	(segment
		(start 51.96332 -84.568792)
		(end 52.209192 -84.568792)
		(width 0.08382)
		(layer "In2.Cu")
		(net "BMC_EMMC_DT2")
	)
	(segment
		(start 41.793922 -87.73541)
		(end 41.967912 -87.9094)
		(width 0.08382)
		(layer "In2.Cu")
		(net "BMC_EMMC_DT2")
	)
	(segment
		(start 51.97983 -85.393022)
		(end 51.97983 -85.638894)
		(width 0.08382)
		(layer "In2.Cu")
		(net "BMC_EMMC_DT2")
	)
	(segment
		(start 41.793922 -87.32139)
		(end 41.793922 -87.73541)
		(width 0.08382)
		(layer "In2.Cu")
		(net "BMC_EMMC_DT2")
	)
	(segment
		(start 42.562272 -87.1474)
		(end 42.808652 -87.1474)
		(width 0.08382)
		(layer "In2.Cu")
		(net "BMC_EMMC_DT2")
	)
	(segment
		(start 61.040772 -85.6488)
		(end 62.479682 -85.6488)
		(width 0.08382)
		(layer "In2.Cu")
		(net "BMC_EMMC_DT2")
	)
	(segment
		(start 53.480208 -85.72881)
		(end 53.654198 -85.9028)
		(width 0.08382)
		(layer "In2.Cu")
		(net "BMC_EMMC_DT2")
	)
	(segment
		(start 42.808652 -87.1474)
		(end 42.982642 -87.32139)
		(width 0.08382)
		(layer "In2.Cu")
		(net "BMC_EMMC_DT2")
	)
	(segment
		(start 55.88254 -85.247988)
		(end 55.595012 -84.96046)
		(width 0.08382)
		(layer "In2.Cu")
		(net "BMC_EMMC_DT2")
	)
	(segment
		(start 41.199562 -87.73541)
		(end 41.199562 -87.32139)
		(width 0.08382)
		(layer "In2.Cu")
		(net "BMC_EMMC_DT2")
	)
	(segment
		(start 53.306218 -85.2424)
		(end 53.480208 -85.41639)
		(width 0.08382)
		(layer "In2.Cu")
		(net "BMC_EMMC_DT2")
	)
	(segment
		(start 59.694318 -84.302346)
		(end 61.040772 -85.6488)
		(width 0.08382)
		(layer "In2.Cu")
		(net "BMC_EMMC_DT2")
	)
	(segment
		(start 64.229742 -83.89874)
		(end 67.896994 -83.89874)
		(width 0.08382)
		(layer "In2.Cu")
		(net "BMC_EMMC_DT2")
	)
	(segment
		(start 51.55946 -84.972652)
		(end 51.96332 -84.568792)
		(width 0.08382)
		(layer "In2.Cu")
		(net "BMC_EMMC_DT2")
	)
	(segment
		(start 44.1198 -87.9094)
		(end 44.87037 -87.15883)
		(width 0.08382)
		(layer "In2.Cu")
		(net "BMC_EMMC_DT2")
	)
	(segment
		(start 56.30291 -84.827618)
		(end 56.548782 -84.827618)
		(width 0.08382)
		(layer "In2.Cu")
		(net "BMC_EMMC_DT2")
	)
	(segment
		(start 53.059838 -85.2424)
		(end 53.306218 -85.2424)
		(width 0.08382)
		(layer "In2.Cu")
		(net "BMC_EMMC_DT2")
	)
	(segment
		(start 71.620888 -84.71662)
		(end 73.13422 -84.71662)
		(width 0.08382)
		(layer "In2.Cu")
		(net "BMC_EMMC_DT2")
	)
	(segment
		(start 51.97983 -85.638894)
		(end 52.243736 -85.9028)
		(width 0.08382)
		(layer "In2.Cu")
		(net "BMC_EMMC_DT2")
	)
	(segment
		(start 53.480208 -85.41639)
		(end 53.480208 -85.72881)
		(width 0.08382)
		(layer "In2.Cu")
		(net "BMC_EMMC_DT2")
	)
	(segment
		(start 42.388282 -87.73541)
		(end 42.388282 -87.32139)
		(width 0.08382)
		(layer "In2.Cu")
		(net "BMC_EMMC_DT2")
	)
	(segment
		(start 59.15025 -84.10575)
		(end 59.346846 -84.302346)
		(width 0.08382)
		(layer "In2.Cu")
		(net "BMC_EMMC_DT2")
	)
	(segment
		(start 59.346846 -84.302346)
		(end 59.694318 -84.302346)
		(width 0.08382)
		(layer "In2.Cu")
		(net "BMC_EMMC_DT2")
	)
	(segment
		(start 41.199562 -87.32139)
		(end 41.373552 -87.1474)
		(width 0.08382)
		(layer "In2.Cu")
		(net "BMC_EMMC_DT2")
	)
	(segment
		(start 47.540672 -43.359578)
		(end 47.85868 -43.359578)
		(width 0.10668)
		(layer "In4.Cu")
		(net "BMC_EMMC_DT2")
	)
	(segment
		(start 70.485 -73.2917)
		(end 70.485 -76.457048)
		(width 0.10668)
		(layer "In4.Cu")
		(net "BMC_EMMC_DT2")
	)
	(segment
		(start 63.037212 -60.827666)
		(end 65.50152 -60.827666)
		(width 0.10668)
		(layer "In4.Cu")
		(net "BMC_EMMC_DT2")
	)
	(segment
		(start 47.85868 -43.359578)
		(end 48.083216 -43.584114)
		(width 0.10668)
		(layer "In4.Cu")
		(net "BMC_EMMC_DT2")
	)
	(segment
		(start 73.914 -81.37906)
		(end 74.041 -81.50606)
		(width 0.10668)
		(layer "In4.Cu")
		(net "BMC_EMMC_DT2")
	)
	(segment
		(start 70.79234 -76.764388)
		(end 70.79234 -77.01534)
		(width 0.10668)
		(layer "In4.Cu")
		(net "BMC_EMMC_DT2")
	)
	(segment
		(start 47.2948 -43.1292)
		(end 47.5234 -43.3578)
		(width 0.10668)
		(layer "In4.Cu")
		(net "BMC_EMMC_DT2")
	)
	(segment
		(start 47.2948 -42.03827)
		(end 47.2948 -43.1292)
		(width 0.10668)
		(layer "In4.Cu")
		(net "BMC_EMMC_DT2")
	)
	(segment
		(start 48.083216 -43.584114)
		(end 48.083216 -43.935142)
		(width 0.10668)
		(layer "In4.Cu")
		(net "BMC_EMMC_DT2")
	)
	(segment
		(start 54.54904 -49.69764)
		(end 54.54904 -51.27244)
		(width 0.10668)
		(layer "In4.Cu")
		(net "BMC_EMMC_DT2")
	)
	(segment
		(start 70.79234 -77.01534)
		(end 72.2122 -78.4352)
		(width 0.10668)
		(layer "In4.Cu")
		(net "BMC_EMMC_DT2")
	)
	(segment
		(start 47.3964 -41.93667)
		(end 47.2948 -42.03827)
		(width 0.10668)
		(layer "In4.Cu")
		(net "BMC_EMMC_DT2")
	)
	(segment
		(start 74.2188 -83.872832)
		(end 74.2188 -84.6836)
		(width 0.10668)
		(layer "In4.Cu")
		(net "BMC_EMMC_DT2")
	)
	(segment
		(start 65.50152 -60.827666)
		(end 67.310508 -62.636654)
		(width 0.10668)
		(layer "In4.Cu")
		(net "BMC_EMMC_DT2")
	)
	(segment
		(start 60.9346 -55.1688)
		(end 61.6458 -55.1688)
		(width 0.10668)
		(layer "In4.Cu")
		(net "BMC_EMMC_DT2")
	)
	(segment
		(start 55.0418 -51.7652)
		(end 55.0418 -52.0954)
		(width 0.10668)
		(layer "In4.Cu")
		(net "BMC_EMMC_DT2")
	)
	(segment
		(start 62.3824 -57.6834)
		(end 63.2968 -58.5978)
		(width 0.10668)
		(layer "In4.Cu")
		(net "BMC_EMMC_DT2")
	)
	(segment
		(start 48.499776 -41.376092)
		(end 48.311308 -41.376092)
		(width 0.10668)
		(layer "In4.Cu")
		(net "BMC_EMMC_DT2")
	)
	(segment
		(start 70.47611 -73.214738)
		(end 70.47611 -73.28281)
		(width 0.10668)
		(layer "In4.Cu")
		(net "BMC_EMMC_DT2")
	)
	(segment
		(start 48.2854 -44.1706)
		(end 48.7934 -44.1706)
		(width 0.10668)
		(layer "In4.Cu")
		(net "BMC_EMMC_DT2")
	)
	(segment
		(start 67.310508 -62.636654)
		(end 67.631056 -63.410592)
		(width 0.10668)
		(layer "In4.Cu")
		(net "BMC_EMMC_DT2")
	)
	(segment
		(start 47.9044 -41.783)
		(end 47.5488 -41.783)
		(width 0.10668)
		(layer "In4.Cu")
		(net "BMC_EMMC_DT2")
	)
	(segment
		(start 70.23862 -66.018156)
		(end 70.23862 -72.977248)
		(width 0.10668)
		(layer "In4.Cu")
		(net "BMC_EMMC_DT2")
	)
	(segment
		(start 48.083216 -43.935142)
		(end 48.0822 -43.936158)
		(width 0.10668)
		(layer "In4.Cu")
		(net "BMC_EMMC_DT2")
	)
	(segment
		(start 62.8396 -60.630054)
		(end 63.037212 -60.827666)
		(width 0.10668)
		(layer "In4.Cu")
		(net "BMC_EMMC_DT2")
	)
	(segment
		(start 55.0418 -52.0954)
		(end 55.306722 -52.360322)
		(width 0.10668)
		(layer "In4.Cu")
		(net "BMC_EMMC_DT2")
	)
	(segment
		(start 59.309 -54.8132)
		(end 60.579 -54.8132)
		(width 0.10668)
		(layer "In4.Cu")
		(net "BMC_EMMC_DT2")
	)
	(segment
		(start 55.93969 -52.95011)
		(end 57.923176 -53.7718)
		(width 0.10668)
		(layer "In4.Cu")
		(net "BMC_EMMC_DT2")
	)
	(segment
		(start 50.611024 -45.759624)
		(end 54.54904 -49.69764)
		(width 0.10668)
		(layer "In4.Cu")
		(net "BMC_EMMC_DT2")
	)
	(segment
		(start 61.6458 -55.1688)
		(end 62.3824 -55.9054)
		(width 0.10668)
		(layer "In4.Cu")
		(net "BMC_EMMC_DT2")
	)
	(segment
		(start 55.531258 -52.95011)
		(end 55.93969 -52.95011)
		(width 0.10668)
		(layer "In4.Cu")
		(net "BMC_EMMC_DT2")
	)
	(segment
		(start 49.1236 -44.942506)
		(end 49.940718 -45.759624)
		(width 0.10668)
		(layer "In4.Cu")
		(net "BMC_EMMC_DT2")
	)
	(segment
		(start 58.2676 -53.7718)
		(end 59.309 -54.8132)
		(width 0.10668)
		(layer "In4.Cu")
		(net "BMC_EMMC_DT2")
	)
	(segment
		(start 60.579 -54.8132)
		(end 60.9346 -55.1688)
		(width 0.10668)
		(layer "In4.Cu")
		(net "BMC_EMMC_DT2")
	)
	(segment
		(start 72.2122 -80.139286)
		(end 73.451974 -81.37906)
		(width 0.10668)
		(layer "In4.Cu")
		(net "BMC_EMMC_DT2")
	)
	(segment
		(start 67.631056 -63.410592)
		(end 70.23862 -66.018156)
		(width 0.10668)
		(layer "In4.Cu")
		(net "BMC_EMMC_DT2")
	)
	(segment
		(start 74.2188 -84.6836)
		(end 73.66 -85.2424)
		(width 0.10668)
		(layer "In4.Cu")
		(net "BMC_EMMC_DT2")
	)
	(segment
		(start 55.306722 -52.725574)
		(end 55.531258 -52.95011)
		(width 0.10668)
		(layer "In4.Cu")
		(net "BMC_EMMC_DT2")
	)
	(segment
		(start 55.306722 -52.360322)
		(end 55.306722 -52.725574)
		(width 0.10668)
		(layer "In4.Cu")
		(net "BMC_EMMC_DT2")
	)
	(segment
		(start 47.538894 -43.3578)
		(end 47.540672 -43.359578)
		(width 0.10668)
		(layer "In4.Cu")
		(net "BMC_EMMC_DT2")
	)
	(segment
		(start 47.3964 -41.9354)
		(end 47.3964 -41.93667)
		(width 0.10668)
		(layer "In4.Cu")
		(net "BMC_EMMC_DT2")
	)
	(segment
		(start 62.8396 -59.9186)
		(end 62.8396 -60.630054)
		(width 0.10668)
		(layer "In4.Cu")
		(net "BMC_EMMC_DT2")
	)
	(segment
		(start 74.041 -81.50606)
		(end 74.041 -83.695032)
		(width 0.10668)
		(layer "In4.Cu")
		(net "BMC_EMMC_DT2")
	)
	(segment
		(start 48.311308 -41.376092)
		(end 47.9044 -41.783)
		(width 0.10668)
		(layer "In4.Cu")
		(net "BMC_EMMC_DT2")
	)
	(segment
		(start 49.940718 -45.759624)
		(end 50.611024 -45.759624)
		(width 0.10668)
		(layer "In4.Cu")
		(net "BMC_EMMC_DT2")
	)
	(segment
		(start 54.54904 -51.27244)
		(end 55.0418 -51.7652)
		(width 0.10668)
		(layer "In4.Cu")
		(net "BMC_EMMC_DT2")
	)
	(segment
		(start 48.0822 -43.9674)
		(end 48.2854 -44.1706)
		(width 0.10668)
		(layer "In4.Cu")
		(net "BMC_EMMC_DT2")
	)
	(segment
		(start 57.923176 -53.7718)
		(end 58.2676 -53.7718)
		(width 0.10668)
		(layer "In4.Cu")
		(net "BMC_EMMC_DT2")
	)
	(segment
		(start 49.1236 -44.5008)
		(end 49.1236 -44.942506)
		(width 0.10668)
		(layer "In4.Cu")
		(net "BMC_EMMC_DT2")
	)
	(segment
		(start 70.485 -76.457048)
		(end 70.79234 -76.764388)
		(width 0.10668)
		(layer "In4.Cu")
		(net "BMC_EMMC_DT2")
	)
	(segment
		(start 48.0822 -43.936158)
		(end 48.0822 -43.9674)
		(width 0.10668)
		(layer "In4.Cu")
		(net "BMC_EMMC_DT2")
	)
	(segment
		(start 47.5234 -43.3578)
		(end 47.538894 -43.3578)
		(width 0.10668)
		(layer "In4.Cu")
		(net "BMC_EMMC_DT2")
	)
	(segment
		(start 74.041 -83.695032)
		(end 74.2188 -83.872832)
		(width 0.10668)
		(layer "In4.Cu")
		(net "BMC_EMMC_DT2")
	)
	(segment
		(start 47.5488 -41.783)
		(end 47.3964 -41.9354)
		(width 0.10668)
		(layer "In4.Cu")
		(net "BMC_EMMC_DT2")
	)
	(segment
		(start 63.2968 -58.5978)
		(end 63.2968 -59.4614)
		(width 0.10668)
		(layer "In4.Cu")
		(net "BMC_EMMC_DT2")
	)
	(segment
		(start 70.23862 -72.977248)
		(end 70.47611 -73.214738)
		(width 0.10668)
		(layer "In4.Cu")
		(net "BMC_EMMC_DT2")
	)
	(segment
		(start 72.2122 -78.4352)
		(end 72.2122 -80.139286)
		(width 0.10668)
		(layer "In4.Cu")
		(net "BMC_EMMC_DT2")
	)
	(segment
		(start 62.3824 -55.9054)
		(end 62.3824 -57.6834)
		(width 0.10668)
		(layer "In4.Cu")
		(net "BMC_EMMC_DT2")
	)
	(segment
		(start 48.7934 -44.1706)
		(end 49.1236 -44.5008)
		(width 0.10668)
		(layer "In4.Cu")
		(net "BMC_EMMC_DT2")
	)
	(segment
		(start 73.451974 -81.37906)
		(end 73.914 -81.37906)
		(width 0.10668)
		(layer "In4.Cu")
		(net "BMC_EMMC_DT2")
	)
	(segment
		(start 70.47611 -73.28281)
		(end 70.485 -73.2917)
		(width 0.10668)
		(layer "In4.Cu")
		(net "BMC_EMMC_DT2")
	)
	(segment
		(start 63.2968 -59.4614)
		(end 62.8396 -59.9186)
		(width 0.10668)
		(layer "In4.Cu")
		(net "BMC_EMMC_DT2")
	)
	(segment
		(start 37.063172 -84.217002)
		(end 37.063172 -84.552028)
		(width 0.11684)
		(layer "F.Cu")
		(net "BMC_EMMC_DT1")
	)
	(segment
		(start 37.063172 -84.552028)
		(end 36.7538 -84.8614)
		(width 0.11684)
		(layer "F.Cu")
		(net "BMC_EMMC_DT1")
	)
	(segment
		(start 47.295054 -40.971216)
		(end 46.89983 -40.575992)
		(width 0.11684)
		(layer "F.Cu")
		(net "BMC_EMMC_DT1")
	)
	(via
		(at 46.89983 -40.575992)
		(size 0.4572)
		(drill 0.254)
		(layers "F.Cu" "B.Cu")
		(net "BMC_EMMC_DT1")
	)
	(via
		(at 36.7538 -84.8614)
		(size 0.508)
		(drill 0.254)
		(layers "F.Cu" "B.Cu")
		(net "BMC_EMMC_DT1")
	)
	(via
		(at 72.738488 -82.999072)
		(size 0.508)
		(drill 0.254)
		(layers "F.Cu" "B.Cu")
		(net "BMC_EMMC_DT1")
	)
	(segment
		(start 72.626728 -82.999072)
		(end 71.751952 -83.873848)
		(width 0.08382)
		(layer "In2.Cu")
		(net "BMC_EMMC_DT1")
	)
	(segment
		(start 59.359038 -83.60283)
		(end 58.409078 -83.60283)
		(width 0.08382)
		(layer "In2.Cu")
		(net "BMC_EMMC_DT1")
	)
	(segment
		(start 68.17106 -83.39582)
		(end 64.020954 -83.39582)
		(width 0.08382)
		(layer "In2.Cu")
		(net "BMC_EMMC_DT1")
	)
	(segment
		(start 72.738488 -82.999072)
		(end 72.626728 -82.999072)
		(width 0.08382)
		(layer "In2.Cu")
		(net "BMC_EMMC_DT1")
	)
	(segment
		(start 59.903106 -83.799426)
		(end 59.555634 -83.799426)
		(width 0.08382)
		(layer "In2.Cu")
		(net "BMC_EMMC_DT1")
	)
	(segment
		(start 46.538896 -84.8614)
		(end 36.7538 -84.8614)
		(width 0.08382)
		(layer "In2.Cu")
		(net "BMC_EMMC_DT1")
	)
	(segment
		(start 71.08571 -84.54009)
		(end 70.5866 -85.0392)
		(width 0.08382)
		(layer "In2.Cu")
		(net "BMC_EMMC_DT1")
	)
	(segment
		(start 51.517804 -84.3026)
		(end 49.480216 -84.3026)
		(width 0.08382)
		(layer "In2.Cu")
		(net "BMC_EMMC_DT1")
	)
	(segment
		(start 70.83298 -83.44662)
		(end 70.658482 -83.621118)
		(width 0.08382)
		(layer "In2.Cu")
		(net "BMC_EMMC_DT1")
	)
	(segment
		(start 49.210468 -84.032852)
		(end 47.367444 -84.032852)
		(width 0.08382)
		(layer "In2.Cu")
		(net "BMC_EMMC_DT1")
	)
	(segment
		(start 70.5866 -85.0392)
		(end 69.81444 -85.0392)
		(width 0.08382)
		(layer "In2.Cu")
		(net "BMC_EMMC_DT1")
	)
	(segment
		(start 56.638952 -84.02574)
		(end 54.789832 -84.02574)
		(width 0.08382)
		(layer "In2.Cu")
		(net "BMC_EMMC_DT1")
	)
	(segment
		(start 62.270894 -85.14588)
		(end 61.24956 -85.14588)
		(width 0.08382)
		(layer "In2.Cu")
		(net "BMC_EMMC_DT1")
	)
	(segment
		(start 71.50608 -83.873848)
		(end 71.078852 -83.44662)
		(width 0.08382)
		(layer "In2.Cu")
		(net "BMC_EMMC_DT1")
	)
	(segment
		(start 58.044334 -83.967574)
		(end 56.697118 -83.967574)
		(width 0.08382)
		(layer "In2.Cu")
		(net "BMC_EMMC_DT1")
	)
	(segment
		(start 59.555634 -83.799426)
		(end 59.359038 -83.60283)
		(width 0.08382)
		(layer "In2.Cu")
		(net "BMC_EMMC_DT1")
	)
	(segment
		(start 71.078852 -83.44662)
		(end 70.83298 -83.44662)
		(width 0.08382)
		(layer "In2.Cu")
		(net "BMC_EMMC_DT1")
	)
	(segment
		(start 58.409078 -83.60283)
		(end 58.044334 -83.967574)
		(width 0.08382)
		(layer "In2.Cu")
		(net "BMC_EMMC_DT1")
	)
	(segment
		(start 47.367444 -84.032852)
		(end 46.538896 -84.8614)
		(width 0.08382)
		(layer "In2.Cu")
		(net "BMC_EMMC_DT1")
	)
	(segment
		(start 64.020954 -83.39582)
		(end 62.270894 -85.14588)
		(width 0.08382)
		(layer "In2.Cu")
		(net "BMC_EMMC_DT1")
	)
	(segment
		(start 70.658482 -83.621118)
		(end 70.658482 -83.86699)
		(width 0.08382)
		(layer "In2.Cu")
		(net "BMC_EMMC_DT1")
	)
	(segment
		(start 70.658482 -83.86699)
		(end 71.08571 -84.294218)
		(width 0.08382)
		(layer "In2.Cu")
		(net "BMC_EMMC_DT1")
	)
	(segment
		(start 51.851814 -83.96859)
		(end 51.517804 -84.3026)
		(width 0.08382)
		(layer "In2.Cu")
		(net "BMC_EMMC_DT1")
	)
	(segment
		(start 71.751952 -83.873848)
		(end 71.50608 -83.873848)
		(width 0.08382)
		(layer "In2.Cu")
		(net "BMC_EMMC_DT1")
	)
	(segment
		(start 49.480216 -84.3026)
		(end 49.210468 -84.032852)
		(width 0.08382)
		(layer "In2.Cu")
		(net "BMC_EMMC_DT1")
	)
	(segment
		(start 54.789832 -84.02574)
		(end 54.732682 -83.96859)
		(width 0.08382)
		(layer "In2.Cu")
		(net "BMC_EMMC_DT1")
	)
	(segment
		(start 54.732682 -83.96859)
		(end 51.851814 -83.96859)
		(width 0.08382)
		(layer "In2.Cu")
		(net "BMC_EMMC_DT1")
	)
	(segment
		(start 69.81444 -85.0392)
		(end 68.17106 -83.39582)
		(width 0.08382)
		(layer "In2.Cu")
		(net "BMC_EMMC_DT1")
	)
	(segment
		(start 61.24956 -85.14588)
		(end 59.903106 -83.799426)
		(width 0.08382)
		(layer "In2.Cu")
		(net "BMC_EMMC_DT1")
	)
	(segment
		(start 71.08571 -84.294218)
		(end 71.08571 -84.54009)
		(width 0.08382)
		(layer "In2.Cu")
		(net "BMC_EMMC_DT1")
	)
	(segment
		(start 56.697118 -83.967574)
		(end 56.638952 -84.02574)
		(width 0.08382)
		(layer "In2.Cu")
		(net "BMC_EMMC_DT1")
	)
	(segment
		(start 46.4312 -40.9702)
		(end 46.825408 -40.575992)
		(width 0.10668)
		(layer "In4.Cu")
		(net "BMC_EMMC_DT1")
	)
	(segment
		(start 52.07 -51.562)
		(end 51.562 -51.562)
		(width 0.10668)
		(layer "In4.Cu")
		(net "BMC_EMMC_DT1")
	)
	(segment
		(start 45.683424 -44.41698)
		(end 45.458888 -44.192444)
		(width 0.10668)
		(layer "In4.Cu")
		(net "BMC_EMMC_DT1")
	)
	(segment
		(start 47.28337 -46.302168)
		(end 47.28337 -46.016926)
		(width 0.10668)
		(layer "In4.Cu")
		(net "BMC_EMMC_DT1")
	)
	(segment
		(start 54.483254 -53.492654)
		(end 54.483254 -53.207412)
		(width 0.10668)
		(layer "In4.Cu")
		(net "BMC_EMMC_DT1")
	)
	(segment
		(start 64.028828 -63.5254)
		(end 63.692786 -63.189358)
		(width 0.10668)
		(layer "In4.Cu")
		(net "BMC_EMMC_DT1")
	)
	(segment
		(start 45.683424 -41.590976)
		(end 45.683424 -41.217088)
		(width 0.10668)
		(layer "In4.Cu")
		(net "BMC_EMMC_DT1")
	)
	(segment
		(start 70.81647 -80.271366)
		(end 69.4055 -78.860396)
		(width 0.10668)
		(layer "In4.Cu")
		(net "BMC_EMMC_DT1")
	)
	(segment
		(start 47.540672 -46.55947)
		(end 47.28337 -46.302168)
		(width 0.10668)
		(layer "In4.Cu")
		(net "BMC_EMMC_DT1")
	)
	(segment
		(start 48.352202 -47.371)
		(end 48.116236 -47.135034)
		(width 0.10668)
		(layer "In4.Cu")
		(net "BMC_EMMC_DT1")
	)
	(segment
		(start 61.425836 -62.357)
		(end 59.8932 -60.824364)
		(width 0.10668)
		(layer "In4.Cu")
		(net "BMC_EMMC_DT1")
	)
	(segment
		(start 68.78066 -70.382384)
		(end 67.79006 -69.391784)
		(width 0.10668)
		(layer "In4.Cu")
		(net "BMC_EMMC_DT1")
	)
	(segment
		(start 60.3504 -58.5216)
		(end 60.3504 -57.8866)
		(width 0.10668)
		(layer "In4.Cu")
		(net "BMC_EMMC_DT1")
	)
	(segment
		(start 54.483254 -53.207412)
		(end 54.234842 -52.959)
		(width 0.10668)
		(layer "In4.Cu")
		(net "BMC_EMMC_DT1")
	)
	(segment
		(start 69.09308 -77.026516)
		(end 69.09308 -74.456544)
		(width 0.10668)
		(layer "In4.Cu")
		(net "BMC_EMMC_DT1")
	)
	(segment
		(start 67.79006 -68.973954)
		(end 67.2084 -68.392294)
		(width 0.10668)
		(layer "In4.Cu")
		(net "BMC_EMMC_DT1")
	)
	(segment
		(start 52.9082 -52.832)
		(end 52.9082 -52.4002)
		(width 0.10668)
		(layer "In4.Cu")
		(net "BMC_EMMC_DT1")
	)
	(segment
		(start 56.2864 -54.8894)
		(end 55.5498 -54.8894)
		(width 0.10668)
		(layer "In4.Cu")
		(net "BMC_EMMC_DT1")
	)
	(segment
		(start 67.79006 -69.391784)
		(end 67.79006 -68.973954)
		(width 0.10668)
		(layer "In4.Cu")
		(net "BMC_EMMC_DT1")
	)
	(segment
		(start 45.683424 -41.217088)
		(end 45.930312 -40.9702)
		(width 0.10668)
		(layer "In4.Cu")
		(net "BMC_EMMC_DT1")
	)
	(segment
		(start 66.444114 -66.1416)
		(end 66.039746 -66.1416)
		(width 0.10668)
		(layer "In4.Cu")
		(net "BMC_EMMC_DT1")
	)
	(segment
		(start 48.116236 -46.820836)
		(end 47.85487 -46.55947)
		(width 0.10668)
		(layer "In4.Cu")
		(net "BMC_EMMC_DT1")
	)
	(segment
		(start 46.70679 -45.79239)
		(end 46.48327 -45.56887)
		(width 0.10668)
		(layer "In4.Cu")
		(net "BMC_EMMC_DT1")
	)
	(segment
		(start 72.60082 -82.861404)
		(end 71.583804 -82.861404)
		(width 0.10668)
		(layer "In4.Cu")
		(net "BMC_EMMC_DT1")
	)
	(segment
		(start 60.10656 -56.42356)
		(end 59.866022 -56.183022)
		(width 0.10668)
		(layer "In4.Cu")
		(net "BMC_EMMC_DT1")
	)
	(segment
		(start 67.3608 -67.8942)
		(end 67.3608 -67.058286)
		(width 0.10668)
		(layer "In4.Cu")
		(net "BMC_EMMC_DT1")
	)
	(segment
		(start 49.4792 -47.371)
		(end 48.352202 -47.371)
		(width 0.10668)
		(layer "In4.Cu")
		(net "BMC_EMMC_DT1")
	)
	(segment
		(start 68.78066 -74.144124)
		(end 68.78066 -70.382384)
		(width 0.10668)
		(layer "In4.Cu")
		(net "BMC_EMMC_DT1")
	)
	(segment
		(start 67.2084 -68.0466)
		(end 67.3608 -67.8942)
		(width 0.10668)
		(layer "In4.Cu")
		(net "BMC_EMMC_DT1")
	)
	(segment
		(start 56.8833 -55.9689)
		(end 56.8833 -55.4863)
		(width 0.10668)
		(layer "In4.Cu")
		(net "BMC_EMMC_DT1")
	)
	(segment
		(start 46.825408 -40.575992)
		(end 46.89983 -40.575992)
		(width 0.10668)
		(layer "In4.Cu")
		(net "BMC_EMMC_DT1")
	)
	(segment
		(start 55.5498 -54.8894)
		(end 55.0418 -54.3814)
		(width 0.10668)
		(layer "In4.Cu")
		(net "BMC_EMMC_DT1")
	)
	(segment
		(start 63.398908 -62.357)
		(end 61.425836 -62.357)
		(width 0.10668)
		(layer "In4.Cu")
		(net "BMC_EMMC_DT1")
	)
	(segment
		(start 59.8932 -60.824364)
		(end 59.8932 -58.9788)
		(width 0.10668)
		(layer "In4.Cu")
		(net "BMC_EMMC_DT1")
	)
	(segment
		(start 45.899324 -44.959524)
		(end 45.683424 -44.743624)
		(width 0.10668)
		(layer "In4.Cu")
		(net "BMC_EMMC_DT1")
	)
	(segment
		(start 47.058834 -45.79239)
		(end 46.70679 -45.79239)
		(width 0.10668)
		(layer "In4.Cu")
		(net "BMC_EMMC_DT1")
	)
	(segment
		(start 63.692786 -63.189358)
		(end 63.692786 -62.650878)
		(width 0.10668)
		(layer "In4.Cu")
		(net "BMC_EMMC_DT1")
	)
	(segment
		(start 55.0418 -54.0512)
		(end 54.483254 -53.492654)
		(width 0.10668)
		(layer "In4.Cu")
		(net "BMC_EMMC_DT1")
	)
	(segment
		(start 59.8932 -58.9788)
		(end 60.3504 -58.5216)
		(width 0.10668)
		(layer "In4.Cu")
		(net "BMC_EMMC_DT1")
	)
	(segment
		(start 50.0126 -47.9044)
		(end 49.4792 -47.371)
		(width 0.10668)
		(layer "In4.Cu")
		(net "BMC_EMMC_DT1")
	)
	(segment
		(start 52.9082 -52.4002)
		(end 52.07 -51.562)
		(width 0.10668)
		(layer "In4.Cu")
		(net "BMC_EMMC_DT1")
	)
	(segment
		(start 45.173646 -44.192444)
		(end 44.916344 -43.935142)
		(width 0.10668)
		(layer "In4.Cu")
		(net "BMC_EMMC_DT1")
	)
	(segment
		(start 44.916344 -42.358056)
		(end 45.683424 -41.590976)
		(width 0.10668)
		(layer "In4.Cu")
		(net "BMC_EMMC_DT1")
	)
	(segment
		(start 64.3128 -63.5254)
		(end 64.028828 -63.5254)
		(width 0.10668)
		(layer "In4.Cu")
		(net "BMC_EMMC_DT1")
	)
	(segment
		(start 46.48327 -45.21708)
		(end 46.225714 -44.959524)
		(width 0.10668)
		(layer "In4.Cu")
		(net "BMC_EMMC_DT1")
	)
	(segment
		(start 51.562 -51.562)
		(end 51.308 -51.308)
		(width 0.10668)
		(layer "In4.Cu")
		(net "BMC_EMMC_DT1")
	)
	(segment
		(start 45.458888 -44.192444)
		(end 45.173646 -44.192444)
		(width 0.10668)
		(layer "In4.Cu")
		(net "BMC_EMMC_DT1")
	)
	(segment
		(start 51.308 -48.133)
		(end 51.0794 -47.9044)
		(width 0.10668)
		(layer "In4.Cu")
		(net "BMC_EMMC_DT1")
	)
	(segment
		(start 47.85487 -46.55947)
		(end 47.540672 -46.55947)
		(width 0.10668)
		(layer "In4.Cu")
		(net "BMC_EMMC_DT1")
	)
	(segment
		(start 57.097422 -56.183022)
		(end 56.8833 -55.9689)
		(width 0.10668)
		(layer "In4.Cu")
		(net "BMC_EMMC_DT1")
	)
	(segment
		(start 67.2084 -68.392294)
		(end 67.2084 -68.0466)
		(width 0.10668)
		(layer "In4.Cu")
		(net "BMC_EMMC_DT1")
	)
	(segment
		(start 60.3504 -57.8866)
		(end 60.10656 -57.64276)
		(width 0.10668)
		(layer "In4.Cu")
		(net "BMC_EMMC_DT1")
	)
	(segment
		(start 54.234842 -52.959)
		(end 53.0352 -52.959)
		(width 0.10668)
		(layer "In4.Cu")
		(net "BMC_EMMC_DT1")
	)
	(segment
		(start 66.039746 -66.1416)
		(end 64.8462 -64.948054)
		(width 0.10668)
		(layer "In4.Cu")
		(net "BMC_EMMC_DT1")
	)
	(segment
		(start 45.683424 -44.743624)
		(end 45.683424 -44.41698)
		(width 0.10668)
		(layer "In4.Cu")
		(net "BMC_EMMC_DT1")
	)
	(segment
		(start 53.0352 -52.959)
		(end 52.9082 -52.832)
		(width 0.10668)
		(layer "In4.Cu")
		(net "BMC_EMMC_DT1")
	)
	(segment
		(start 59.866022 -56.183022)
		(end 57.097422 -56.183022)
		(width 0.10668)
		(layer "In4.Cu")
		(net "BMC_EMMC_DT1")
	)
	(segment
		(start 69.4055 -77.338936)
		(end 69.09308 -77.026516)
		(width 0.10668)
		(layer "In4.Cu")
		(net "BMC_EMMC_DT1")
	)
	(segment
		(start 45.930312 -40.9702)
		(end 46.4312 -40.9702)
		(width 0.10668)
		(layer "In4.Cu")
		(net "BMC_EMMC_DT1")
	)
	(segment
		(start 46.225714 -44.959524)
		(end 45.899324 -44.959524)
		(width 0.10668)
		(layer "In4.Cu")
		(net "BMC_EMMC_DT1")
	)
	(segment
		(start 60.10656 -57.64276)
		(end 60.10656 -56.42356)
		(width 0.10668)
		(layer "In4.Cu")
		(net "BMC_EMMC_DT1")
	)
	(segment
		(start 51.0794 -47.9044)
		(end 50.0126 -47.9044)
		(width 0.10668)
		(layer "In4.Cu")
		(net "BMC_EMMC_DT1")
	)
	(segment
		(start 51.308 -51.308)
		(end 51.308 -48.133)
		(width 0.10668)
		(layer "In4.Cu")
		(net "BMC_EMMC_DT1")
	)
	(segment
		(start 44.916344 -43.935142)
		(end 44.916344 -42.358056)
		(width 0.10668)
		(layer "In4.Cu")
		(net "BMC_EMMC_DT1")
	)
	(segment
		(start 67.3608 -67.058286)
		(end 66.444114 -66.1416)
		(width 0.10668)
		(layer "In4.Cu")
		(net "BMC_EMMC_DT1")
	)
	(segment
		(start 63.692786 -62.650878)
		(end 63.398908 -62.357)
		(width 0.10668)
		(layer "In4.Cu")
		(net "BMC_EMMC_DT1")
	)
	(segment
		(start 70.81647 -82.09407)
		(end 70.81647 -80.271366)
		(width 0.10668)
		(layer "In4.Cu")
		(net "BMC_EMMC_DT1")
	)
	(segment
		(start 71.583804 -82.861404)
		(end 70.81647 -82.09407)
		(width 0.10668)
		(layer "In4.Cu")
		(net "BMC_EMMC_DT1")
	)
	(segment
		(start 46.48327 -45.56887)
		(end 46.48327 -45.21708)
		(width 0.10668)
		(layer "In4.Cu")
		(net "BMC_EMMC_DT1")
	)
	(segment
		(start 64.8462 -64.0588)
		(end 64.3128 -63.5254)
		(width 0.10668)
		(layer "In4.Cu")
		(net "BMC_EMMC_DT1")
	)
	(segment
		(start 69.4055 -78.860396)
		(end 69.4055 -77.338936)
		(width 0.10668)
		(layer "In4.Cu")
		(net "BMC_EMMC_DT1")
	)
	(segment
		(start 69.09308 -74.456544)
		(end 68.78066 -74.144124)
		(width 0.10668)
		(layer "In4.Cu")
		(net "BMC_EMMC_DT1")
	)
	(segment
		(start 56.8833 -55.4863)
		(end 56.2864 -54.8894)
		(width 0.10668)
		(layer "In4.Cu")
		(net "BMC_EMMC_DT1")
	)
	(segment
		(start 48.116236 -47.135034)
		(end 48.116236 -46.820836)
		(width 0.10668)
		(layer "In4.Cu")
		(net "BMC_EMMC_DT1")
	)
	(segment
		(start 55.0418 -54.3814)
		(end 55.0418 -54.0512)
		(width 0.10668)
		(layer "In4.Cu")
		(net "BMC_EMMC_DT1")
	)
	(segment
		(start 47.28337 -46.016926)
		(end 47.058834 -45.79239)
		(width 0.10668)
		(layer "In4.Cu")
		(net "BMC_EMMC_DT1")
	)
	(segment
		(start 72.738488 -82.999072)
		(end 72.60082 -82.861404)
		(width 0.10668)
		(layer "In4.Cu")
		(net "BMC_EMMC_DT1")
	)
	(segment
		(start 64.8462 -64.948054)
		(end 64.8462 -64.0588)
		(width 0.10668)
		(layer "In4.Cu")
		(net "BMC_EMMC_DT1")
	)
	(segment
		(start 38.079172 -84.217002)
		(end 37.855398 -84.217002)
		(width 0.11684)
		(layer "F.Cu")
		(net "BMC_EMMC_DT0")
	)
	(segment
		(start 47.295054 -41.771316)
		(end 46.89983 -41.376092)
		(width 0.11684)
		(layer "F.Cu")
		(net "BMC_EMMC_DT0")
	)
	(segment
		(start 37.4904 -84.8106)
		(end 36.7792 -85.5218)
		(width 0.11684)
		(layer "F.Cu")
		(net "BMC_EMMC_DT0")
	)
	(segment
		(start 37.855398 -84.217002)
		(end 37.4904 -84.582)
		(width 0.11684)
		(layer "F.Cu")
		(net "BMC_EMMC_DT0")
	)
	(segment
		(start 37.4904 -84.582)
		(end 37.4904 -84.8106)
		(width 0.11684)
		(layer "F.Cu")
		(net "BMC_EMMC_DT0")
	)
	(via
		(at 36.7792 -85.5218)
		(size 0.508)
		(drill 0.254)
		(layers "F.Cu" "B.Cu")
		(net "BMC_EMMC_DT0")
	)
	(via
		(at 46.89983 -41.376092)
		(size 0.4572)
		(drill 0.254)
		(layers "F.Cu" "B.Cu")
		(net "BMC_EMMC_DT0")
	)
	(via
		(at 73.5584 -81.852262)
		(size 0.508)
		(drill 0.254)
		(layers "F.Cu" "B.Cu")
		(net "BMC_EMMC_DT0")
	)
	(segment
		(start 51.956208 -84.22005)
		(end 54.628288 -84.22005)
		(width 0.08382)
		(layer "In2.Cu")
		(net "BMC_EMMC_DT0")
	)
	(segment
		(start 62.375288 -85.39734)
		(end 64.125348 -83.64728)
		(width 0.08382)
		(layer "In2.Cu")
		(net "BMC_EMMC_DT0")
	)
	(segment
		(start 44.327064 -85.86851)
		(end 44.82846 -85.367114)
		(width 0.08382)
		(layer "In2.Cu")
		(net "BMC_EMMC_DT0")
	)
	(segment
		(start 54.628288 -84.22005)
		(end 54.685438 -84.2772)
		(width 0.08382)
		(layer "In2.Cu")
		(net "BMC_EMMC_DT0")
	)
	(segment
		(start 73.5584 -83.4644)
		(end 73.5584 -81.852262)
		(width 0.08382)
		(layer "In2.Cu")
		(net "BMC_EMMC_DT0")
	)
	(segment
		(start 59.254644 -83.85429)
		(end 59.45124 -84.050886)
		(width 0.08382)
		(layer "In2.Cu")
		(net "BMC_EMMC_DT0")
	)
	(segment
		(start 46.389036 -85.367114)
		(end 47.471838 -84.284312)
		(width 0.08382)
		(layer "In2.Cu")
		(net "BMC_EMMC_DT0")
	)
	(segment
		(start 58.513472 -83.85429)
		(end 59.254644 -83.85429)
		(width 0.08382)
		(layer "In2.Cu")
		(net "BMC_EMMC_DT0")
	)
	(segment
		(start 49.106074 -84.284312)
		(end 49.378362 -84.5566)
		(width 0.08382)
		(layer "In2.Cu")
		(net "BMC_EMMC_DT0")
	)
	(segment
		(start 61.145166 -85.39734)
		(end 62.375288 -85.39734)
		(width 0.08382)
		(layer "In2.Cu")
		(net "BMC_EMMC_DT0")
	)
	(segment
		(start 37.12591 -85.86851)
		(end 44.327064 -85.86851)
		(width 0.08382)
		(layer "In2.Cu")
		(net "BMC_EMMC_DT0")
	)
	(segment
		(start 69.710046 -85.29066)
		(end 70.690994 -85.29066)
		(width 0.08382)
		(layer "In2.Cu")
		(net "BMC_EMMC_DT0")
	)
	(segment
		(start 70.690994 -85.29066)
		(end 72.390254 -83.5914)
		(width 0.08382)
		(layer "In2.Cu")
		(net "BMC_EMMC_DT0")
	)
	(segment
		(start 56.743346 -84.2772)
		(end 56.801512 -84.219034)
		(width 0.08382)
		(layer "In2.Cu")
		(net "BMC_EMMC_DT0")
	)
	(segment
		(start 44.82846 -85.367114)
		(end 46.389036 -85.367114)
		(width 0.08382)
		(layer "In2.Cu")
		(net "BMC_EMMC_DT0")
	)
	(segment
		(start 47.471838 -84.284312)
		(end 49.106074 -84.284312)
		(width 0.08382)
		(layer "In2.Cu")
		(net "BMC_EMMC_DT0")
	)
	(segment
		(start 72.390254 -83.5914)
		(end 73.4314 -83.5914)
		(width 0.08382)
		(layer "In2.Cu")
		(net "BMC_EMMC_DT0")
	)
	(segment
		(start 49.378362 -84.5566)
		(end 51.619658 -84.5566)
		(width 0.08382)
		(layer "In2.Cu")
		(net "BMC_EMMC_DT0")
	)
	(segment
		(start 51.619658 -84.5566)
		(end 51.956208 -84.22005)
		(width 0.08382)
		(layer "In2.Cu")
		(net "BMC_EMMC_DT0")
	)
	(segment
		(start 68.066666 -83.64728)
		(end 69.710046 -85.29066)
		(width 0.08382)
		(layer "In2.Cu")
		(net "BMC_EMMC_DT0")
	)
	(segment
		(start 58.148728 -84.219034)
		(end 58.513472 -83.85429)
		(width 0.08382)
		(layer "In2.Cu")
		(net "BMC_EMMC_DT0")
	)
	(segment
		(start 56.801512 -84.219034)
		(end 58.148728 -84.219034)
		(width 0.08382)
		(layer "In2.Cu")
		(net "BMC_EMMC_DT0")
	)
	(segment
		(start 36.7792 -85.5218)
		(end 37.12591 -85.86851)
		(width 0.08382)
		(layer "In2.Cu")
		(net "BMC_EMMC_DT0")
	)
	(segment
		(start 73.4314 -83.5914)
		(end 73.5584 -83.4644)
		(width 0.08382)
		(layer "In2.Cu")
		(net "BMC_EMMC_DT0")
	)
	(segment
		(start 54.685438 -84.2772)
		(end 56.743346 -84.2772)
		(width 0.08382)
		(layer "In2.Cu")
		(net "BMC_EMMC_DT0")
	)
	(segment
		(start 59.798712 -84.050886)
		(end 61.145166 -85.39734)
		(width 0.08382)
		(layer "In2.Cu")
		(net "BMC_EMMC_DT0")
	)
	(segment
		(start 64.125348 -83.64728)
		(end 68.066666 -83.64728)
		(width 0.08382)
		(layer "In2.Cu")
		(net "BMC_EMMC_DT0")
	)
	(segment
		(start 59.45124 -84.050886)
		(end 59.798712 -84.050886)
		(width 0.08382)
		(layer "In2.Cu")
		(net "BMC_EMMC_DT0")
	)
	(segment
		(start 66.088514 -63.80226)
		(end 65.52946 -63.80226)
		(width 0.10668)
		(layer "In4.Cu")
		(net "BMC_EMMC_DT0")
	)
	(segment
		(start 72.604884 -82.094832)
		(end 71.13651 -80.626458)
		(width 0.10668)
		(layer "In4.Cu")
		(net "BMC_EMMC_DT0")
	)
	(segment
		(start 69.72554 -77.206348)
		(end 69.41312 -76.893928)
		(width 0.10668)
		(layer "In4.Cu")
		(net "BMC_EMMC_DT0")
	)
	(segment
		(start 50.0126 -47.5488)
		(end 49.5046 -47.0408)
		(width 0.10668)
		(layer "In4.Cu")
		(net "BMC_EMMC_DT0")
	)
	(segment
		(start 45.71619 -42.016934)
		(end 45.940726 -41.792398)
		(width 0.10668)
		(layer "In4.Cu")
		(net "BMC_EMMC_DT0")
	)
	(segment
		(start 45.973492 -44.192444)
		(end 45.71619 -43.935142)
		(width 0.10668)
		(layer "In4.Cu")
		(net "BMC_EMMC_DT0")
	)
	(segment
		(start 49.5046 -47.0408)
		(end 49.276 -47.0408)
		(width 0.10668)
		(layer "In4.Cu")
		(net "BMC_EMMC_DT0")
	)
	(segment
		(start 47.54499 -45.79239)
		(end 47.316136 -45.563536)
		(width 0.10668)
		(layer "In4.Cu")
		(net "BMC_EMMC_DT0")
	)
	(segment
		(start 54.483254 -52.400454)
		(end 54.23281 -52.15001)
		(width 0.10668)
		(layer "In4.Cu")
		(net "BMC_EMMC_DT0")
	)
	(segment
		(start 64.77 -63.0428)
		(end 64.77 -62.611)
		(width 0.10668)
		(layer "In4.Cu")
		(net "BMC_EMMC_DT0")
	)
	(segment
		(start 52.083208 -48.3616)
		(end 51.270408 -47.5488)
		(width 0.10668)
		(layer "In4.Cu")
		(net "BMC_EMMC_DT0")
	)
	(segment
		(start 51.270408 -47.5488)
		(end 50.0126 -47.5488)
		(width 0.10668)
		(layer "In4.Cu")
		(net "BMC_EMMC_DT0")
	)
	(segment
		(start 48.31207 -46.55947)
		(end 48.083216 -46.330616)
		(width 0.10668)
		(layer "In4.Cu")
		(net "BMC_EMMC_DT0")
	)
	(segment
		(start 55.306722 -54.32552)
		(end 55.306722 -53.960522)
		(width 0.10668)
		(layer "In4.Cu")
		(net "BMC_EMMC_DT0")
	)
	(segment
		(start 54.23281 -52.15001)
		(end 53.87721 -52.15001)
		(width 0.10668)
		(layer "In4.Cu")
		(net "BMC_EMMC_DT0")
	)
	(segment
		(start 52.083208 -50.000408)
		(end 52.083208 -48.3616)
		(width 0.10668)
		(layer "In4.Cu")
		(net "BMC_EMMC_DT0")
	)
	(segment
		(start 49.276 -47.0408)
		(end 48.79467 -46.55947)
		(width 0.10668)
		(layer "In4.Cu")
		(net "BMC_EMMC_DT0")
	)
	(segment
		(start 47.316136 -45.249846)
		(end 47.058834 -44.992544)
		(width 0.10668)
		(layer "In4.Cu")
		(net "BMC_EMMC_DT0")
	)
	(segment
		(start 60.8838 -58.6232)
		(end 60.8838 -56.3372)
		(width 0.10668)
		(layer "In4.Cu")
		(net "BMC_EMMC_DT0")
	)
	(segment
		(start 48.083216 -46.016926)
		(end 47.85868 -45.79239)
		(width 0.10668)
		(layer "In4.Cu")
		(net "BMC_EMMC_DT0")
	)
	(segment
		(start 48.083216 -46.330616)
		(end 48.083216 -46.016926)
		(width 0.10668)
		(layer "In4.Cu")
		(net "BMC_EMMC_DT0")
	)
	(segment
		(start 46.51629 -44.408344)
		(end 46.30039 -44.192444)
		(width 0.10668)
		(layer "In4.Cu")
		(net "BMC_EMMC_DT0")
	)
	(segment
		(start 71.13651 -80.138778)
		(end 69.72554 -78.727808)
		(width 0.10668)
		(layer "In4.Cu")
		(net "BMC_EMMC_DT0")
	)
	(segment
		(start 54.691534 -53.345334)
		(end 54.691534 -52.786788)
		(width 0.10668)
		(layer "In4.Cu")
		(net "BMC_EMMC_DT0")
	)
	(segment
		(start 60.8838 -56.3372)
		(end 60.696602 -56.150002)
		(width 0.10668)
		(layer "In4.Cu")
		(net "BMC_EMMC_DT0")
	)
	(segment
		(start 46.770798 -44.992544)
		(end 46.51629 -44.738036)
		(width 0.10668)
		(layer "In4.Cu")
		(net "BMC_EMMC_DT0")
	)
	(segment
		(start 54.483254 -52.578508)
		(end 54.483254 -52.400454)
		(width 0.10668)
		(layer "In4.Cu")
		(net "BMC_EMMC_DT0")
	)
	(segment
		(start 71.13651 -80.626458)
		(end 71.13651 -80.138778)
		(width 0.10668)
		(layer "In4.Cu")
		(net "BMC_EMMC_DT0")
	)
	(segment
		(start 60.198 -59.309)
		(end 60.8838 -58.6232)
		(width 0.10668)
		(layer "In4.Cu")
		(net "BMC_EMMC_DT0")
	)
	(segment
		(start 52.916328 -51.189128)
		(end 52.916328 -50.833528)
		(width 0.10668)
		(layer "In4.Cu")
		(net "BMC_EMMC_DT0")
	)
	(segment
		(start 46.51629 -44.738036)
		(end 46.51629 -44.408344)
		(width 0.10668)
		(layer "In4.Cu")
		(net "BMC_EMMC_DT0")
	)
	(segment
		(start 52.916328 -50.833528)
		(end 52.083208 -50.000408)
		(width 0.10668)
		(layer "In4.Cu")
		(net "BMC_EMMC_DT0")
	)
	(segment
		(start 64.77 -62.611)
		(end 64.1096 -61.9506)
		(width 0.10668)
		(layer "In4.Cu")
		(net "BMC_EMMC_DT0")
	)
	(segment
		(start 47.058834 -44.992544)
		(end 46.770798 -44.992544)
		(width 0.10668)
		(layer "In4.Cu")
		(net "BMC_EMMC_DT0")
	)
	(segment
		(start 54.691534 -52.786788)
		(end 54.483254 -52.578508)
		(width 0.10668)
		(layer "In4.Cu")
		(net "BMC_EMMC_DT0")
	)
	(segment
		(start 47.85868 -45.79239)
		(end 47.54499 -45.79239)
		(width 0.10668)
		(layer "In4.Cu")
		(net "BMC_EMMC_DT0")
	)
	(segment
		(start 69.17182 -66.885566)
		(end 66.088514 -63.80226)
		(width 0.10668)
		(layer "In4.Cu")
		(net "BMC_EMMC_DT0")
	)
	(segment
		(start 55.531258 -54.550056)
		(end 55.306722 -54.32552)
		(width 0.10668)
		(layer "In4.Cu")
		(net "BMC_EMMC_DT0")
	)
	(segment
		(start 69.17182 -74.082656)
		(end 69.17182 -66.885566)
		(width 0.10668)
		(layer "In4.Cu")
		(net "BMC_EMMC_DT0")
	)
	(segment
		(start 73.31583 -82.094832)
		(end 72.604884 -82.094832)
		(width 0.10668)
		(layer "In4.Cu")
		(net "BMC_EMMC_DT0")
	)
	(segment
		(start 64.1096 -61.9506)
		(end 61.4934 -61.9506)
		(width 0.10668)
		(layer "In4.Cu")
		(net "BMC_EMMC_DT0")
	)
	(segment
		(start 60.10656 -55.925466)
		(end 60.10656 -55.635906)
		(width 0.10668)
		(layer "In4.Cu")
		(net "BMC_EMMC_DT0")
	)
	(segment
		(start 46.371002 -41.792398)
		(end 46.787308 -41.376092)
		(width 0.10668)
		(layer "In4.Cu")
		(net "BMC_EMMC_DT0")
	)
	(segment
		(start 69.41312 -76.893928)
		(end 69.41312 -74.323956)
		(width 0.10668)
		(layer "In4.Cu")
		(net "BMC_EMMC_DT0")
	)
	(segment
		(start 55.306722 -53.960522)
		(end 54.691534 -53.345334)
		(width 0.10668)
		(layer "In4.Cu")
		(net "BMC_EMMC_DT0")
	)
	(segment
		(start 61.4934 -61.9506)
		(end 60.198 -60.6552)
		(width 0.10668)
		(layer "In4.Cu")
		(net "BMC_EMMC_DT0")
	)
	(segment
		(start 60.198 -60.6552)
		(end 60.198 -59.309)
		(width 0.10668)
		(layer "In4.Cu")
		(net "BMC_EMMC_DT0")
	)
	(segment
		(start 48.79467 -46.55947)
		(end 48.31207 -46.55947)
		(width 0.10668)
		(layer "In4.Cu")
		(net "BMC_EMMC_DT0")
	)
	(segment
		(start 69.41312 -74.323956)
		(end 69.17182 -74.082656)
		(width 0.10668)
		(layer "In4.Cu")
		(net "BMC_EMMC_DT0")
	)
	(segment
		(start 60.10656 -55.635906)
		(end 59.842654 -55.372)
		(width 0.10668)
		(layer "In4.Cu")
		(net "BMC_EMMC_DT0")
	)
	(segment
		(start 46.30039 -44.192444)
		(end 45.973492 -44.192444)
		(width 0.10668)
		(layer "In4.Cu")
		(net "BMC_EMMC_DT0")
	)
	(segment
		(start 47.316136 -45.563536)
		(end 47.316136 -45.249846)
		(width 0.10668)
		(layer "In4.Cu")
		(net "BMC_EMMC_DT0")
	)
	(segment
		(start 60.331096 -56.150002)
		(end 60.10656 -55.925466)
		(width 0.10668)
		(layer "In4.Cu")
		(net "BMC_EMMC_DT0")
	)
	(segment
		(start 46.787308 -41.376092)
		(end 46.89983 -41.376092)
		(width 0.10668)
		(layer "In4.Cu")
		(net "BMC_EMMC_DT0")
	)
	(segment
		(start 69.72554 -78.727808)
		(end 69.72554 -77.206348)
		(width 0.10668)
		(layer "In4.Cu")
		(net "BMC_EMMC_DT0")
	)
	(segment
		(start 45.940726 -41.792398)
		(end 46.371002 -41.792398)
		(width 0.10668)
		(layer "In4.Cu")
		(net "BMC_EMMC_DT0")
	)
	(segment
		(start 59.842654 -55.372)
		(end 57.4548 -55.372)
		(width 0.10668)
		(layer "In4.Cu")
		(net "BMC_EMMC_DT0")
	)
	(segment
		(start 65.52946 -63.80226)
		(end 64.77 -63.0428)
		(width 0.10668)
		(layer "In4.Cu")
		(net "BMC_EMMC_DT0")
	)
	(segment
		(start 56.632856 -54.550056)
		(end 55.531258 -54.550056)
		(width 0.10668)
		(layer "In4.Cu")
		(net "BMC_EMMC_DT0")
	)
	(segment
		(start 73.5584 -81.852262)
		(end 73.31583 -82.094832)
		(width 0.10668)
		(layer "In4.Cu")
		(net "BMC_EMMC_DT0")
	)
	(segment
		(start 53.87721 -52.15001)
		(end 52.916328 -51.189128)
		(width 0.10668)
		(layer "In4.Cu")
		(net "BMC_EMMC_DT0")
	)
	(segment
		(start 57.4548 -55.372)
		(end 56.632856 -54.550056)
		(width 0.10668)
		(layer "In4.Cu")
		(net "BMC_EMMC_DT0")
	)
	(segment
		(start 45.71619 -43.935142)
		(end 45.71619 -42.016934)
		(width 0.10668)
		(layer "In4.Cu")
		(net "BMC_EMMC_DT0")
	)
	(segment
		(start 60.696602 -56.150002)
		(end 60.331096 -56.150002)
		(width 0.10668)
		(layer "In4.Cu")
		(net "BMC_EMMC_DT0")
	)
	(segment
		(start 31.135066 -85.400896)
		(end 31.9786 -85.7504)
		(width 0.11684)
		(layer "F.Cu")
		(net "BMC_EMMC_CMD")
	)
	(segment
		(start 29.951172 -84.217002)
		(end 31.135066 -85.400896)
		(width 0.11684)
		(layer "F.Cu")
		(net "BMC_EMMC_CMD")
	)
	(segment
		(start 48.0949 -42.571162)
		(end 47.699676 -42.175938)
		(width 0.11684)
		(layer "F.Cu")
		(net "BMC_EMMC_CMD")
	)
	(via
		(at 31.9786 -85.7504)
		(size 0.508)
		(drill 0.254)
		(layers "F.Cu" "B.Cu")
		(net "BMC_EMMC_CMD")
	)
	(via
		(at 73.69048 -86.19998)
		(size 0.762)
		(drill 0.254)
		(layers "F.Cu" "B.Cu")
		(net "BMC_EMMC_CMD")
	)
	(via
		(at 47.699676 -42.175938)
		(size 0.4572)
		(drill 0.254)
		(layers "F.Cu" "B.Cu")
		(net "BMC_EMMC_CMD")
	)
	(segment
		(start 38.857682 -89.35974)
		(end 43.711114 -89.35974)
		(width 0.08382)
		(layer "In2.Cu")
		(net "BMC_EMMC_CMD")
	)
	(segment
		(start 57.05983 -85.18017)
		(end 57.54497 -85.18017)
		(width 0.08382)
		(layer "In2.Cu")
		(net "BMC_EMMC_CMD")
	)
	(segment
		(start 34.248344 -87.11057)
		(end 36.608512 -87.11057)
		(width 0.08382)
		(layer "In2.Cu")
		(net "BMC_EMMC_CMD")
	)
	(segment
		(start 45.37329 -87.697564)
		(end 45.37329 -86.633304)
		(width 0.08382)
		(layer "In2.Cu")
		(net "BMC_EMMC_CMD")
	)
	(segment
		(start 32.888174 -85.7504)
		(end 34.248344 -87.11057)
		(width 0.08382)
		(layer "In2.Cu")
		(net "BMC_EMMC_CMD")
	)
	(segment
		(start 62.332616 -86.15172)
		(end 64.334136 -84.1502)
		(width 0.08382)
		(layer "In2.Cu")
		(net "BMC_EMMC_CMD")
	)
	(segment
		(start 58.51652 -86.15172)
		(end 62.332616 -86.15172)
		(width 0.08382)
		(layer "In2.Cu")
		(net "BMC_EMMC_CMD")
	)
	(segment
		(start 64.334136 -84.1502)
		(end 67.640454 -84.1502)
		(width 0.08382)
		(layer "In2.Cu")
		(net "BMC_EMMC_CMD")
	)
	(segment
		(start 47.78502 -85.038692)
		(end 48.792892 -85.038692)
		(width 0.08382)
		(layer "In2.Cu")
		(net "BMC_EMMC_CMD")
	)
	(segment
		(start 45.8851 -86.121494)
		(end 46.702218 -86.121494)
		(width 0.08382)
		(layer "In2.Cu")
		(net "BMC_EMMC_CMD")
	)
	(segment
		(start 57.54497 -85.18017)
		(end 58.51652 -86.15172)
		(width 0.08382)
		(layer "In2.Cu")
		(net "BMC_EMMC_CMD")
	)
	(segment
		(start 46.702218 -86.121494)
		(end 47.78502 -85.038692)
		(width 0.08382)
		(layer "In2.Cu")
		(net "BMC_EMMC_CMD")
	)
	(segment
		(start 48.792892 -85.038692)
		(end 49.32172 -85.56752)
		(width 0.08382)
		(layer "In2.Cu")
		(net "BMC_EMMC_CMD")
	)
	(segment
		(start 36.608512 -87.11057)
		(end 38.857682 -89.35974)
		(width 0.08382)
		(layer "In2.Cu")
		(net "BMC_EMMC_CMD")
	)
	(segment
		(start 52.040028 -86.4108)
		(end 55.8292 -86.4108)
		(width 0.08382)
		(layer "In2.Cu")
		(net "BMC_EMMC_CMD")
	)
	(segment
		(start 55.8292 -86.4108)
		(end 57.05983 -85.18017)
		(width 0.08382)
		(layer "In2.Cu")
		(net "BMC_EMMC_CMD")
	)
	(segment
		(start 31.9786 -85.7504)
		(end 32.888174 -85.7504)
		(width 0.08382)
		(layer "In2.Cu")
		(net "BMC_EMMC_CMD")
	)
	(segment
		(start 45.37329 -86.633304)
		(end 45.8851 -86.121494)
		(width 0.08382)
		(layer "In2.Cu")
		(net "BMC_EMMC_CMD")
	)
	(segment
		(start 73.54316 -86.05266)
		(end 73.69048 -86.19998)
		(width 0.08382)
		(layer "In2.Cu")
		(net "BMC_EMMC_CMD")
	)
	(segment
		(start 67.640454 -84.1502)
		(end 69.542914 -86.05266)
		(width 0.08382)
		(layer "In2.Cu")
		(net "BMC_EMMC_CMD")
	)
	(segment
		(start 49.32172 -85.56752)
		(end 51.196748 -85.56752)
		(width 0.08382)
		(layer "In2.Cu")
		(net "BMC_EMMC_CMD")
	)
	(segment
		(start 69.542914 -86.05266)
		(end 73.54316 -86.05266)
		(width 0.08382)
		(layer "In2.Cu")
		(net "BMC_EMMC_CMD")
	)
	(segment
		(start 43.711114 -89.35974)
		(end 45.37329 -87.697564)
		(width 0.08382)
		(layer "In2.Cu")
		(net "BMC_EMMC_CMD")
	)
	(segment
		(start 51.196748 -85.56752)
		(end 52.040028 -86.4108)
		(width 0.08382)
		(layer "In2.Cu")
		(net "BMC_EMMC_CMD")
	)
	(segment
		(start 70.8152 -73.1012)
		(end 70.55866 -72.84466)
		(width 0.10668)
		(layer "In4.Cu")
		(net "BMC_EMMC_CMD")
	)
	(segment
		(start 66.876422 -60.750958)
		(end 65.89776 -59.771788)
		(width 0.10668)
		(layer "In4.Cu")
		(net "BMC_EMMC_CMD")
	)
	(segment
		(start 59.309 -54.4576)
		(end 58.4962 -53.6448)
		(width 0.10668)
		(layer "In4.Cu")
		(net "BMC_EMMC_CMD")
	)
	(segment
		(start 70.8152 -76.33462)
		(end 70.8152 -73.1012)
		(width 0.10668)
		(layer "In4.Cu")
		(net "BMC_EMMC_CMD")
	)
	(segment
		(start 48.116236 -42.299636)
		(end 47.992538 -42.175938)
		(width 0.10668)
		(layer "In4.Cu")
		(net "BMC_EMMC_CMD")
	)
	(segment
		(start 55.306722 -51.471322)
		(end 54.75732 -50.92192)
		(width 0.10668)
		(layer "In4.Cu")
		(net "BMC_EMMC_CMD")
	)
	(segment
		(start 55.5498 -52.1716)
		(end 55.306722 -51.928522)
		(width 0.10668)
		(layer "In4.Cu")
		(net "BMC_EMMC_CMD")
	)
	(segment
		(start 50.877724 -44.959524)
		(end 49.940718 -44.959524)
		(width 0.10668)
		(layer "In4.Cu")
		(net "BMC_EMMC_CMD")
	)
	(segment
		(start 65.104772 -54.8894)
		(end 61.0362 -54.8894)
		(width 0.10668)
		(layer "In4.Cu")
		(net "BMC_EMMC_CMD")
	)
	(segment
		(start 73.576942 -81.0514)
		(end 72.53224 -80.006698)
		(width 0.10668)
		(layer "In4.Cu")
		(net "BMC_EMMC_CMD")
	)
	(segment
		(start 74.59472 -85.29574)
		(end 74.59472 -81.60512)
		(width 0.10668)
		(layer "In4.Cu")
		(net "BMC_EMMC_CMD")
	)
	(segment
		(start 60.6044 -54.4576)
		(end 59.309 -54.4576)
		(width 0.10668)
		(layer "In4.Cu")
		(net "BMC_EMMC_CMD")
	)
	(segment
		(start 49.4284 -44.0182)
		(end 48.769778 -43.359578)
		(width 0.10668)
		(layer "In4.Cu")
		(net "BMC_EMMC_CMD")
	)
	(segment
		(start 72.53224 -78.302612)
		(end 71.11238 -76.882752)
		(width 0.10668)
		(layer "In4.Cu")
		(net "BMC_EMMC_CMD")
	)
	(segment
		(start 48.769778 -43.359578)
		(end 48.340772 -43.359578)
		(width 0.10668)
		(layer "In4.Cu")
		(net "BMC_EMMC_CMD")
	)
	(segment
		(start 73.69048 -86.19998)
		(end 74.59472 -85.29574)
		(width 0.10668)
		(layer "In4.Cu")
		(net "BMC_EMMC_CMD")
	)
	(segment
		(start 48.116236 -43.135042)
		(end 48.116236 -42.299636)
		(width 0.10668)
		(layer "In4.Cu")
		(net "BMC_EMMC_CMD")
	)
	(segment
		(start 71.11238 -76.882752)
		(end 71.11238 -76.6318)
		(width 0.10668)
		(layer "In4.Cu")
		(net "BMC_EMMC_CMD")
	)
	(segment
		(start 47.992538 -42.175938)
		(end 47.699676 -42.175938)
		(width 0.10668)
		(layer "In4.Cu")
		(net "BMC_EMMC_CMD")
	)
	(segment
		(start 55.306722 -51.928522)
		(end 55.306722 -51.471322)
		(width 0.10668)
		(layer "In4.Cu")
		(net "BMC_EMMC_CMD")
	)
	(segment
		(start 65.89776 -59.771788)
		(end 65.89776 -55.682388)
		(width 0.10668)
		(layer "In4.Cu")
		(net "BMC_EMMC_CMD")
	)
	(segment
		(start 49.940718 -44.959524)
		(end 49.4284 -44.447206)
		(width 0.10668)
		(layer "In4.Cu")
		(net "BMC_EMMC_CMD")
	)
	(segment
		(start 54.75732 -50.92192)
		(end 54.75732 -49.49952)
		(width 0.10668)
		(layer "In4.Cu")
		(net "BMC_EMMC_CMD")
	)
	(segment
		(start 49.4284 -44.447206)
		(end 49.4284 -44.0182)
		(width 0.10668)
		(layer "In4.Cu")
		(net "BMC_EMMC_CMD")
	)
	(segment
		(start 65.89776 -55.682388)
		(end 65.104772 -54.8894)
		(width 0.10668)
		(layer "In4.Cu")
		(net "BMC_EMMC_CMD")
	)
	(segment
		(start 51.107848 -45.189648)
		(end 50.877724 -44.959524)
		(width 0.10668)
		(layer "In4.Cu")
		(net "BMC_EMMC_CMD")
	)
	(segment
		(start 54.75732 -49.49952)
		(end 51.107848 -45.850048)
		(width 0.10668)
		(layer "In4.Cu")
		(net "BMC_EMMC_CMD")
	)
	(segment
		(start 48.340772 -43.359578)
		(end 48.116236 -43.135042)
		(width 0.10668)
		(layer "In4.Cu")
		(net "BMC_EMMC_CMD")
	)
	(segment
		(start 74.59472 -81.60512)
		(end 74.041 -81.0514)
		(width 0.10668)
		(layer "In4.Cu")
		(net "BMC_EMMC_CMD")
	)
	(segment
		(start 71.11238 -76.6318)
		(end 70.8152 -76.33462)
		(width 0.10668)
		(layer "In4.Cu")
		(net "BMC_EMMC_CMD")
	)
	(segment
		(start 74.041 -81.0514)
		(end 73.576942 -81.0514)
		(width 0.10668)
		(layer "In4.Cu")
		(net "BMC_EMMC_CMD")
	)
	(segment
		(start 70.55866 -65.885314)
		(end 67.902582 -63.229236)
		(width 0.10668)
		(layer "In4.Cu")
		(net "BMC_EMMC_CMD")
	)
	(segment
		(start 61.0362 -54.8894)
		(end 60.6044 -54.4576)
		(width 0.10668)
		(layer "In4.Cu")
		(net "BMC_EMMC_CMD")
	)
	(segment
		(start 51.107848 -45.850048)
		(end 51.107848 -45.189648)
		(width 0.10668)
		(layer "In4.Cu")
		(net "BMC_EMMC_CMD")
	)
	(segment
		(start 70.55866 -72.84466)
		(end 70.55866 -65.885314)
		(width 0.10668)
		(layer "In4.Cu")
		(net "BMC_EMMC_CMD")
	)
	(segment
		(start 58.4962 -53.6448)
		(end 58.4962 -52.8066)
		(width 0.10668)
		(layer "In4.Cu")
		(net "BMC_EMMC_CMD")
	)
	(segment
		(start 72.53224 -80.006698)
		(end 72.53224 -78.302612)
		(width 0.10668)
		(layer "In4.Cu")
		(net "BMC_EMMC_CMD")
	)
	(segment
		(start 57.8612 -52.1716)
		(end 55.5498 -52.1716)
		(width 0.10668)
		(layer "In4.Cu")
		(net "BMC_EMMC_CMD")
	)
	(segment
		(start 67.902582 -63.229236)
		(end 66.876422 -60.750958)
		(width 0.10668)
		(layer "In4.Cu")
		(net "BMC_EMMC_CMD")
	)
	(segment
		(start 58.4962 -52.8066)
		(end 57.8612 -52.1716)
		(width 0.10668)
		(layer "In4.Cu")
		(net "BMC_EMMC_CMD")
	)
	(segment
		(start 27.14371 -82.112866)
		(end 27.140408 -82.116168)
		(width 0.11684)
		(layer "F.Cu")
		(net "BMC_EMMC_CLK")
	)
	(segment
		(start 28.350972 -82.859372)
		(end 27.604466 -82.112866)
		(width 0.11684)
		(layer "F.Cu")
		(net "BMC_EMMC_CLK")
	)
	(segment
		(start 48.0949 -41.771316)
		(end 47.699676 -41.376092)
		(width 0.11684)
		(layer "F.Cu")
		(net "BMC_EMMC_CLK")
	)
	(segment
		(start 28.935172 -84.217002)
		(end 28.590748 -84.217002)
		(width 0.11684)
		(layer "F.Cu")
		(net "BMC_EMMC_CLK")
	)
	(segment
		(start 27.604466 -82.112866)
		(end 27.14371 -82.112866)
		(width 0.11684)
		(layer "F.Cu")
		(net "BMC_EMMC_CLK")
	)
	(segment
		(start 28.590748 -84.217002)
		(end 28.350972 -83.977226)
		(width 0.11684)
		(layer "F.Cu")
		(net "BMC_EMMC_CLK")
	)
	(segment
		(start 28.350972 -83.977226)
		(end 28.350972 -82.859372)
		(width 0.11684)
		(layer "F.Cu")
		(net "BMC_EMMC_CLK")
	)
	(via
		(at 27.140408 -82.116168)
		(size 0.508)
		(drill 0.254)
		(layers "F.Cu" "B.Cu")
		(net "BMC_EMMC_CLK")
	)
	(via
		(at 47.699676 -41.376092)
		(size 0.4572)
		(drill 0.254)
		(layers "F.Cu" "B.Cu")
		(net "BMC_EMMC_CLK")
	)
	(via
		(at 72.738488 -81.4578)
		(size 0.762)
		(drill 0.254)
		(layers "F.Cu" "B.Cu")
		(net "BMC_EMMC_CLK")
	)
	(segment
		(start 63.982346 -81.4578)
		(end 62.68466 -82.755486)
		(width 0.08382)
		(layer "In2.Cu")
		(net "BMC_EMMC_CLK")
	)
	(segment
		(start 45.65523 -81.301844)
		(end 45.063664 -81.89341)
		(width 0.08382)
		(layer "In2.Cu")
		(net "BMC_EMMC_CLK")
	)
	(segment
		(start 49.100994 -82.4357)
		(end 47.967138 -81.301844)
		(width 0.08382)
		(layer "In2.Cu")
		(net "BMC_EMMC_CLK")
	)
	(segment
		(start 72.738488 -81.4578)
		(end 67.537838 -81.4578)
		(width 0.08382)
		(layer "In2.Cu")
		(net "BMC_EMMC_CLK")
	)
	(segment
		(start 67.537838 -81.4578)
		(end 67.394328 -81.60131)
		(width 0.08382)
		(layer "In2.Cu")
		(net "BMC_EMMC_CLK")
	)
	(segment
		(start 59.98845 -82.755486)
		(end 59.122564 -81.8896)
		(width 0.08382)
		(layer "In2.Cu")
		(net "BMC_EMMC_CLK")
	)
	(segment
		(start 51.43881 -82.4357)
		(end 49.100994 -82.4357)
		(width 0.08382)
		(layer "In2.Cu")
		(net "BMC_EMMC_CLK")
	)
	(segment
		(start 67.394328 -81.60131)
		(end 67.022472 -81.60131)
		(width 0.08382)
		(layer "In2.Cu")
		(net "BMC_EMMC_CLK")
	)
	(segment
		(start 39.074344 -81.10474)
		(end 39.015924 -81.04632)
		(width 0.08382)
		(layer "In2.Cu")
		(net "BMC_EMMC_CLK")
	)
	(segment
		(start 52.74183 -81.13268)
		(end 51.43881 -82.4357)
		(width 0.08382)
		(layer "In2.Cu")
		(net "BMC_EMMC_CLK")
	)
	(segment
		(start 67.022472 -81.60131)
		(end 66.878962 -81.4578)
		(width 0.08382)
		(layer "In2.Cu")
		(net "BMC_EMMC_CLK")
	)
	(segment
		(start 53.799486 -81.13268)
		(end 52.74183 -81.13268)
		(width 0.08382)
		(layer "In2.Cu")
		(net "BMC_EMMC_CLK")
	)
	(segment
		(start 47.967138 -81.301844)
		(end 45.65523 -81.301844)
		(width 0.08382)
		(layer "In2.Cu")
		(net "BMC_EMMC_CLK")
	)
	(segment
		(start 38.932358 -81.04632)
		(end 38.663626 -81.315052)
		(width 0.08382)
		(layer "In2.Cu")
		(net "BMC_EMMC_CLK")
	)
	(segment
		(start 34.939224 -81.20634)
		(end 28.050236 -81.20634)
		(width 0.08382)
		(layer "In2.Cu")
		(net "BMC_EMMC_CLK")
	)
	(segment
		(start 62.68466 -82.755486)
		(end 59.98845 -82.755486)
		(width 0.08382)
		(layer "In2.Cu")
		(net "BMC_EMMC_CLK")
	)
	(segment
		(start 40.338248 -81.89341)
		(end 39.549578 -81.10474)
		(width 0.08382)
		(layer "In2.Cu")
		(net "BMC_EMMC_CLK")
	)
	(segment
		(start 54.001416 -81.33461)
		(end 53.799486 -81.13268)
		(width 0.08382)
		(layer "In2.Cu")
		(net "BMC_EMMC_CLK")
	)
	(segment
		(start 28.050236 -81.20634)
		(end 27.140408 -82.116168)
		(width 0.08382)
		(layer "In2.Cu")
		(net "BMC_EMMC_CLK")
	)
	(segment
		(start 35.048444 -81.31556)
		(end 34.939224 -81.20634)
		(width 0.08382)
		(layer "In2.Cu")
		(net "BMC_EMMC_CLK")
	)
	(segment
		(start 37.595302 -81.31556)
		(end 35.048444 -81.31556)
		(width 0.08382)
		(layer "In2.Cu")
		(net "BMC_EMMC_CLK")
	)
	(segment
		(start 37.685218 -81.315052)
		(end 37.640514 -81.270348)
		(width 0.08382)
		(layer "In2.Cu")
		(net "BMC_EMMC_CLK")
	)
	(segment
		(start 59.122564 -81.8896)
		(end 56.2864 -81.8896)
		(width 0.08382)
		(layer "In2.Cu")
		(net "BMC_EMMC_CLK")
	)
	(segment
		(start 45.063664 -81.89341)
		(end 40.338248 -81.89341)
		(width 0.08382)
		(layer "In2.Cu")
		(net "BMC_EMMC_CLK")
	)
	(segment
		(start 39.549578 -81.10474)
		(end 39.074344 -81.10474)
		(width 0.08382)
		(layer "In2.Cu")
		(net "BMC_EMMC_CLK")
	)
	(segment
		(start 66.878962 -81.4578)
		(end 63.982346 -81.4578)
		(width 0.08382)
		(layer "In2.Cu")
		(net "BMC_EMMC_CLK")
	)
	(segment
		(start 38.663626 -81.315052)
		(end 37.685218 -81.315052)
		(width 0.08382)
		(layer "In2.Cu")
		(net "BMC_EMMC_CLK")
	)
	(segment
		(start 39.015924 -81.04632)
		(end 38.932358 -81.04632)
		(width 0.08382)
		(layer "In2.Cu")
		(net "BMC_EMMC_CLK")
	)
	(segment
		(start 55.73141 -81.33461)
		(end 54.001416 -81.33461)
		(width 0.08382)
		(layer "In2.Cu")
		(net "BMC_EMMC_CLK")
	)
	(segment
		(start 37.640514 -81.270348)
		(end 37.595302 -81.31556)
		(width 0.08382)
		(layer "In2.Cu")
		(net "BMC_EMMC_CLK")
	)
	(segment
		(start 56.2864 -81.8896)
		(end 55.73141 -81.33461)
		(width 0.08382)
		(layer "In2.Cu")
		(net "BMC_EMMC_CLK")
	)
	(segment
		(start 47.06239 -44.196)
		(end 47.058834 -44.192444)
		(width 0.10668)
		(layer "In4.Cu")
		(net "BMC_EMMC_CLK")
	)
	(segment
		(start 71.66991 -80.389222)
		(end 71.66991 -79.917798)
		(width 0.10668)
		(layer "In4.Cu")
		(net "BMC_EMMC_CLK")
	)
	(segment
		(start 61.6966 -59.1566)
		(end 61.6966 -56.29656)
		(width 0.10668)
		(layer "In4.Cu")
		(net "BMC_EMMC_CLK")
	)
	(segment
		(start 60.56376 -55.16372)
		(end 59.07532 -55.16372)
		(width 0.10668)
		(layer "In4.Cu")
		(net "BMC_EMMC_CLK")
	)
	(segment
		(start 47.058834 -44.192444)
		(end 46.732444 -44.192444)
		(width 0.10668)
		(layer "In4.Cu")
		(net "BMC_EMMC_CLK")
	)
	(segment
		(start 48.083216 -45.543216)
		(end 48.083216 -45.21708)
		(width 0.10668)
		(layer "In4.Cu")
		(net "BMC_EMMC_CLK")
	)
	(segment
		(start 47.8282 -44.9834)
		(end 47.5742 -44.9834)
		(width 0.10668)
		(layer "In4.Cu")
		(net "BMC_EMMC_CLK")
	)
	(segment
		(start 47.85868 -44.992544)
		(end 47.837344 -44.992544)
		(width 0.10668)
		(layer "In4.Cu")
		(net "BMC_EMMC_CLK")
	)
	(segment
		(start 52.197 -48.1076)
		(end 50.6222 -46.5328)
		(width 0.10668)
		(layer "In4.Cu")
		(net "BMC_EMMC_CLK")
	)
	(segment
		(start 52.578 -48.1076)
		(end 52.197 -48.1076)
		(width 0.10668)
		(layer "In4.Cu")
		(net "BMC_EMMC_CLK")
	)
	(segment
		(start 47.574708 -41.376092)
		(end 47.699676 -41.376092)
		(width 0.10668)
		(layer "In4.Cu")
		(net "BMC_EMMC_CLK")
	)
	(segment
		(start 72.738488 -81.4578)
		(end 71.66991 -80.389222)
		(width 0.10668)
		(layer "In4.Cu")
		(net "BMC_EMMC_CLK")
	)
	(segment
		(start 47.550324 -44.959524)
		(end 47.540672 -44.959524)
		(width 0.10668)
		(layer "In4.Cu")
		(net "BMC_EMMC_CLK")
	)
	(segment
		(start 46.732444 -44.192444)
		(end 46.5074 -43.9674)
		(width 0.10668)
		(layer "In4.Cu")
		(net "BMC_EMMC_CLK")
	)
	(segment
		(start 56.721756 -53.749956)
		(end 55.477156 -53.749956)
		(width 0.10668)
		(layer "In4.Cu")
		(net "BMC_EMMC_CLK")
	)
	(segment
		(start 48.083216 -45.21708)
		(end 47.85868 -44.992544)
		(width 0.10668)
		(layer "In4.Cu")
		(net "BMC_EMMC_CLK")
	)
	(segment
		(start 69.70522 -73.2663)
		(end 69.70522 -66.239136)
		(width 0.10668)
		(layer "In4.Cu")
		(net "BMC_EMMC_CLK")
	)
	(segment
		(start 70.25894 -76.985368)
		(end 69.9516 -76.678028)
		(width 0.10668)
		(layer "In4.Cu")
		(net "BMC_EMMC_CLK")
	)
	(segment
		(start 46.5074 -42.025824)
		(end 46.740826 -41.792398)
		(width 0.10668)
		(layer "In4.Cu")
		(net "BMC_EMMC_CLK")
	)
	(segment
		(start 62.4078 -59.52998)
		(end 62.30112 -59.4233)
		(width 0.10668)
		(layer "In4.Cu")
		(net "BMC_EMMC_CLK")
	)
	(segment
		(start 66.698114 -62.778894)
		(end 65.33642 -61.4172)
		(width 0.10668)
		(layer "In4.Cu")
		(net "BMC_EMMC_CLK")
	)
	(segment
		(start 53.716174 -49.245774)
		(end 52.578 -48.1076)
		(width 0.10668)
		(layer "In4.Cu")
		(net "BMC_EMMC_CLK")
	)
	(segment
		(start 47.158402 -41.792398)
		(end 47.574708 -41.376092)
		(width 0.10668)
		(layer "In4.Cu")
		(net "BMC_EMMC_CLK")
	)
	(segment
		(start 59.07532 -55.16372)
		(end 58.4708 -54.5592)
		(width 0.10668)
		(layer "In4.Cu")
		(net "BMC_EMMC_CLK")
	)
	(segment
		(start 54.7624 -51.8668)
		(end 54.24551 -51.34991)
		(width 0.10668)
		(layer "In4.Cu")
		(net "BMC_EMMC_CLK")
	)
	(segment
		(start 61.9633 -59.4233)
		(end 61.6966 -59.1566)
		(width 0.10668)
		(layer "In4.Cu")
		(net "BMC_EMMC_CLK")
	)
	(segment
		(start 48.68799 -45.8216)
		(end 48.65878 -45.79239)
		(width 0.10668)
		(layer "In4.Cu")
		(net "BMC_EMMC_CLK")
	)
	(segment
		(start 62.30112 -59.4233)
		(end 61.9633 -59.4233)
		(width 0.10668)
		(layer "In4.Cu")
		(net "BMC_EMMC_CLK")
	)
	(segment
		(start 63.119 -61.4172)
		(end 62.4078 -60.706)
		(width 0.10668)
		(layer "In4.Cu")
		(net "BMC_EMMC_CLK")
	)
	(segment
		(start 69.9516 -73.51268)
		(end 69.70522 -73.2663)
		(width 0.10668)
		(layer "In4.Cu")
		(net "BMC_EMMC_CLK")
	)
	(segment
		(start 47.540672 -44.959524)
		(end 47.28337 -44.702222)
		(width 0.10668)
		(layer "In4.Cu")
		(net "BMC_EMMC_CLK")
	)
	(segment
		(start 71.66991 -79.917798)
		(end 70.25894 -78.506828)
		(width 0.10668)
		(layer "In4.Cu")
		(net "BMC_EMMC_CLK")
	)
	(segment
		(start 69.9516 -76.678028)
		(end 69.9516 -73.51268)
		(width 0.10668)
		(layer "In4.Cu")
		(net "BMC_EMMC_CLK")
	)
	(segment
		(start 54.7624 -52.4764)
		(end 54.7624 -51.8668)
		(width 0.10668)
		(layer "In4.Cu")
		(net "BMC_EMMC_CLK")
	)
	(segment
		(start 47.11192 -44.196)
		(end 47.06239 -44.196)
		(width 0.10668)
		(layer "In4.Cu")
		(net "BMC_EMMC_CLK")
	)
	(segment
		(start 57.531 -54.5592)
		(end 56.721756 -53.749956)
		(width 0.10668)
		(layer "In4.Cu")
		(net "BMC_EMMC_CLK")
	)
	(segment
		(start 67.178428 -63.712344)
		(end 67.018154 -63.55207)
		(width 0.10668)
		(layer "In4.Cu")
		(net "BMC_EMMC_CLK")
	)
	(segment
		(start 50.6222 -46.5328)
		(end 49.403 -46.5328)
		(width 0.10668)
		(layer "In4.Cu")
		(net "BMC_EMMC_CLK")
	)
	(segment
		(start 70.25894 -78.506828)
		(end 70.25894 -76.985368)
		(width 0.10668)
		(layer "In4.Cu")
		(net "BMC_EMMC_CLK")
	)
	(segment
		(start 67.178682 -63.712852)
		(end 67.178428 -63.712344)
		(width 0.10668)
		(layer "In4.Cu")
		(net "BMC_EMMC_CLK")
	)
	(segment
		(start 47.837344 -44.992544)
		(end 47.8282 -44.9834)
		(width 0.10668)
		(layer "In4.Cu")
		(net "BMC_EMMC_CLK")
	)
	(segment
		(start 53.94071 -51.34991)
		(end 53.716174 -51.125374)
		(width 0.10668)
		(layer "In4.Cu")
		(net "BMC_EMMC_CLK")
	)
	(segment
		(start 47.5742 -44.9834)
		(end 47.550324 -44.959524)
		(width 0.10668)
		(layer "In4.Cu")
		(net "BMC_EMMC_CLK")
	)
	(segment
		(start 49.403 -46.5328)
		(end 48.6918 -45.8216)
		(width 0.10668)
		(layer "In4.Cu")
		(net "BMC_EMMC_CLK")
	)
	(segment
		(start 54.991 -52.705)
		(end 54.7624 -52.4764)
		(width 0.10668)
		(layer "In4.Cu")
		(net "BMC_EMMC_CLK")
	)
	(segment
		(start 62.4078 -60.706)
		(end 62.4078 -59.52998)
		(width 0.10668)
		(layer "In4.Cu")
		(net "BMC_EMMC_CLK")
	)
	(segment
		(start 48.6918 -45.8216)
		(end 48.68799 -45.8216)
		(width 0.10668)
		(layer "In4.Cu")
		(net "BMC_EMMC_CLK")
	)
	(segment
		(start 65.33642 -61.4172)
		(end 63.119 -61.4172)
		(width 0.10668)
		(layer "In4.Cu")
		(net "BMC_EMMC_CLK")
	)
	(segment
		(start 58.4708 -54.5592)
		(end 57.531 -54.5592)
		(width 0.10668)
		(layer "In4.Cu")
		(net "BMC_EMMC_CLK")
	)
	(segment
		(start 67.018154 -63.55207)
		(end 66.698114 -62.778894)
		(width 0.10668)
		(layer "In4.Cu")
		(net "BMC_EMMC_CLK")
	)
	(segment
		(start 69.70522 -66.239136)
		(end 67.178682 -63.712852)
		(width 0.10668)
		(layer "In4.Cu")
		(net "BMC_EMMC_CLK")
	)
	(segment
		(start 46.740826 -41.792398)
		(end 47.158402 -41.792398)
		(width 0.10668)
		(layer "In4.Cu")
		(net "BMC_EMMC_CLK")
	)
	(segment
		(start 46.5074 -43.9674)
		(end 46.5074 -42.025824)
		(width 0.10668)
		(layer "In4.Cu")
		(net "BMC_EMMC_CLK")
	)
	(segment
		(start 54.991 -53.2638)
		(end 54.991 -52.705)
		(width 0.10668)
		(layer "In4.Cu")
		(net "BMC_EMMC_CLK")
	)
	(segment
		(start 48.33239 -45.79239)
		(end 48.083216 -45.543216)
		(width 0.10668)
		(layer "In4.Cu")
		(net "BMC_EMMC_CLK")
	)
	(segment
		(start 47.28337 -44.702222)
		(end 47.28337 -44.36745)
		(width 0.10668)
		(layer "In4.Cu")
		(net "BMC_EMMC_CLK")
	)
	(segment
		(start 54.24551 -51.34991)
		(end 53.94071 -51.34991)
		(width 0.10668)
		(layer "In4.Cu")
		(net "BMC_EMMC_CLK")
	)
	(segment
		(start 61.6966 -56.29656)
		(end 60.56376 -55.16372)
		(width 0.10668)
		(layer "In4.Cu")
		(net "BMC_EMMC_CLK")
	)
	(segment
		(start 55.477156 -53.749956)
		(end 54.991 -53.2638)
		(width 0.10668)
		(layer "In4.Cu")
		(net "BMC_EMMC_CLK")
	)
	(segment
		(start 47.28337 -44.36745)
		(end 47.11192 -44.196)
		(width 0.10668)
		(layer "In4.Cu")
		(net "BMC_EMMC_CLK")
	)
	(segment
		(start 48.65878 -45.79239)
		(end 48.33239 -45.79239)
		(width 0.10668)
		(layer "In4.Cu")
		(net "BMC_EMMC_CLK")
	)
	(segment
		(start 53.716174 -51.125374)
		(end 53.716174 -49.245774)
		(width 0.10668)
		(layer "In4.Cu")
		(net "BMC_EMMC_CLK")
	)
	(segment
		(start 46.89983 -39.776146)
		(end 46.494954 -39.37127)
		(width 0.11684)
		(layer "F.Cu")
		(net "BMC_EMMC_CD_N")
	)
	(via
		(at 71.859394 -71.010526)
		(size 0.508)
		(drill 0.254)
		(layers "F.Cu" "B.Cu")
		(net "BMC_EMMC_CD_N")
	)
	(via
		(at 46.89983 -39.776146)
		(size 0.4572)
		(drill 0.254)
		(layers "F.Cu" "B.Cu")
		(net "BMC_EMMC_CD_N")
	)
	(segment
		(start 71.859394 -71.38797)
		(end 71.859394 -71.010526)
		(width 0.11684)
		(layer "B.Cu")
		(net "BMC_EMMC_CD_N")
	)
	(segment
		(start 71.86422 -71.0057)
		(end 71.599806 -70.741286)
		(width 0.11684)
		(layer "B.Cu")
		(net "BMC_EMMC_CD_N")
	)
	(segment
		(start 71.599806 -70.741286)
		(end 71.599806 -69.976238)
		(width 0.11684)
		(layer "B.Cu")
		(net "BMC_EMMC_CD_N")
	)
	(segment
		(start 71.599806 -71.647558)
		(end 71.859394 -71.38797)
		(width 0.11684)
		(layer "B.Cu")
		(net "BMC_EMMC_CD_N")
	)
	(segment
		(start 71.859394 -71.010526)
		(end 71.86422 -71.0057)
		(width 0.11684)
		(layer "B.Cu")
		(net "BMC_EMMC_CD_N")
	)
	(segment
		(start 53.94071 -46.55947)
		(end 54.25567 -46.55947)
		(width 0.10668)
		(layer "In4.Cu")
		(net "BMC_EMMC_CD_N")
	)
	(segment
		(start 60.349384 -49.782984)
		(end 61.1378 -50.5714)
		(width 0.10668)
		(layer "In4.Cu")
		(net "BMC_EMMC_CD_N")
	)
	(segment
		(start 53.716174 -46.334934)
		(end 53.94071 -46.55947)
		(width 0.10668)
		(layer "In4.Cu")
		(net "BMC_EMMC_CD_N")
	)
	(segment
		(start 56.078882 -49.782984)
		(end 60.349384 -49.782984)
		(width 0.10668)
		(layer "In4.Cu")
		(net "BMC_EMMC_CD_N")
	)
	(segment
		(start 73.477374 -70.13448)
		(end 72.20712 -70.13448)
		(width 0.10668)
		(layer "In4.Cu")
		(net "BMC_EMMC_CD_N")
	)
	(segment
		(start 50.54092 -43.53052)
		(end 51.26228 -43.53052)
		(width 0.10668)
		(layer "In4.Cu")
		(net "BMC_EMMC_CD_N")
	)
	(segment
		(start 52.916328 -44.734988)
		(end 53.716174 -45.534834)
		(width 0.10668)
		(layer "In4.Cu")
		(net "BMC_EMMC_CD_N")
	)
	(segment
		(start 61.1378 -50.5714)
		(end 67.612006 -50.5714)
		(width 0.10668)
		(layer "In4.Cu")
		(net "BMC_EMMC_CD_N")
	)
	(segment
		(start 47.142146 -39.776146)
		(end 47.525686 -40.159686)
		(width 0.10668)
		(layer "In4.Cu")
		(net "BMC_EMMC_CD_N")
	)
	(segment
		(start 47.525686 -40.159686)
		(end 49.481486 -40.159686)
		(width 0.10668)
		(layer "In4.Cu")
		(net "BMC_EMMC_CD_N")
	)
	(segment
		(start 54.864 -48.568102)
		(end 56.078882 -49.782984)
		(width 0.10668)
		(layer "In4.Cu")
		(net "BMC_EMMC_CD_N")
	)
	(segment
		(start 54.25567 -46.55947)
		(end 54.864 -47.1678)
		(width 0.10668)
		(layer "In4.Cu")
		(net "BMC_EMMC_CD_N")
	)
	(segment
		(start 71.859394 -70.482206)
		(end 71.859394 -71.010526)
		(width 0.10668)
		(layer "In4.Cu")
		(net "BMC_EMMC_CD_N")
	)
	(segment
		(start 74.58964 -69.022214)
		(end 73.477374 -70.13448)
		(width 0.10668)
		(layer "In4.Cu")
		(net "BMC_EMMC_CD_N")
	)
	(segment
		(start 51.67376 -43.942)
		(end 52.408328 -43.942)
		(width 0.10668)
		(layer "In4.Cu")
		(net "BMC_EMMC_CD_N")
	)
	(segment
		(start 53.716174 -45.534834)
		(end 53.716174 -46.334934)
		(width 0.10668)
		(layer "In4.Cu")
		(net "BMC_EMMC_CD_N")
	)
	(segment
		(start 46.89983 -39.776146)
		(end 47.142146 -39.776146)
		(width 0.10668)
		(layer "In4.Cu")
		(net "BMC_EMMC_CD_N")
	)
	(segment
		(start 50.1904 -42.80916)
		(end 50.1904 -43.18)
		(width 0.10668)
		(layer "In4.Cu")
		(net "BMC_EMMC_CD_N")
	)
	(segment
		(start 69.868542 -51.50612)
		(end 72.00392 -53.641498)
		(width 0.10668)
		(layer "In4.Cu")
		(net "BMC_EMMC_CD_N")
	)
	(segment
		(start 49.716182 -42.334942)
		(end 50.1904 -42.80916)
		(width 0.10668)
		(layer "In4.Cu")
		(net "BMC_EMMC_CD_N")
	)
	(segment
		(start 50.1904 -43.18)
		(end 50.54092 -43.53052)
		(width 0.10668)
		(layer "In4.Cu")
		(net "BMC_EMMC_CD_N")
	)
	(segment
		(start 52.916328 -44.45)
		(end 52.916328 -44.734988)
		(width 0.10668)
		(layer "In4.Cu")
		(net "BMC_EMMC_CD_N")
	)
	(segment
		(start 51.26228 -43.53052)
		(end 51.67376 -43.942)
		(width 0.10668)
		(layer "In4.Cu")
		(net "BMC_EMMC_CD_N")
	)
	(segment
		(start 52.408328 -43.942)
		(end 52.916328 -44.45)
		(width 0.10668)
		(layer "In4.Cu")
		(net "BMC_EMMC_CD_N")
	)
	(segment
		(start 74.58964 -57.347612)
		(end 74.58964 -69.022214)
		(width 0.10668)
		(layer "In4.Cu")
		(net "BMC_EMMC_CD_N")
	)
	(segment
		(start 72.00392 -53.641498)
		(end 72.00392 -54.761892)
		(width 0.10668)
		(layer "In4.Cu")
		(net "BMC_EMMC_CD_N")
	)
	(segment
		(start 72.20712 -70.13448)
		(end 71.859394 -70.482206)
		(width 0.10668)
		(layer "In4.Cu")
		(net "BMC_EMMC_CD_N")
	)
	(segment
		(start 49.481486 -40.159686)
		(end 49.716182 -40.394382)
		(width 0.10668)
		(layer "In4.Cu")
		(net "BMC_EMMC_CD_N")
	)
	(segment
		(start 49.716182 -40.394382)
		(end 49.716182 -42.334942)
		(width 0.10668)
		(layer "In4.Cu")
		(net "BMC_EMMC_CD_N")
	)
	(segment
		(start 54.864 -47.1678)
		(end 54.864 -48.568102)
		(width 0.10668)
		(layer "In4.Cu")
		(net "BMC_EMMC_CD_N")
	)
	(segment
		(start 72.00392 -54.761892)
		(end 74.58964 -57.347612)
		(width 0.10668)
		(layer "In4.Cu")
		(net "BMC_EMMC_CD_N")
	)
	(segment
		(start 67.612006 -50.5714)
		(end 69.868542 -51.50612)
		(width 0.10668)
		(layer "In4.Cu")
		(net "BMC_EMMC_CD_N")
	)
	(via
		(at 46.193202 -73.627234)
		(size 0.6604)
		(drill 0.3302)
		(layers "F.Cu" "B.Cu")
		(net "BATTERY_DETECT_R")
	)
	(segment
		(start 46.193202 -73.627234)
		(end 47.116238 -73.627234)
		(width 0.11684)
		(layer "B.Cu")
		(net "BATTERY_DETECT_R")
	)
	(segment
		(start 47.446692 -74.951082)
		(end 47.446692 -73.957688)
		(width 0.11684)
		(layer "B.Cu")
		(net "BATTERY_DETECT_R")
	)
	(segment
		(start 45.675296 -73.627234)
		(end 46.193202 -73.627234)
		(width 0.11684)
		(layer "B.Cu")
		(net "BATTERY_DETECT_R")
	)
	(segment
		(start 45.558456 -73.744074)
		(end 45.675296 -73.627234)
		(width 0.11684)
		(layer "B.Cu")
		(net "BATTERY_DETECT_R")
	)
	(segment
		(start 47.449994 -74.954384)
		(end 47.446692 -74.951082)
		(width 0.11684)
		(layer "B.Cu")
		(net "BATTERY_DETECT_R")
	)
	(segment
		(start 45.558456 -74.683366)
		(end 45.558456 -73.744074)
		(width 0.11684)
		(layer "B.Cu")
		(net "BATTERY_DETECT_R")
	)
	(segment
		(start 45.286676 -74.955146)
		(end 45.558456 -74.683366)
		(width 0.11684)
		(layer "B.Cu")
		(net "BATTERY_DETECT_R")
	)
	(segment
		(start 44.631102 -74.955146)
		(end 45.286676 -74.955146)
		(width 0.11684)
		(layer "B.Cu")
		(net "BATTERY_DETECT_R")
	)
	(segment
		(start 47.116238 -73.627234)
		(end 47.446692 -73.957688)
		(width 0.11684)
		(layer "B.Cu")
		(net "BATTERY_DETECT_R")
	)
	(segment
		(start 53.695092 -58.57113)
		(end 53.299868 -58.966354)
		(width 0.11684)
		(layer "F.Cu")
		(net "BATTERY_DETECT")
	)
	(via
		(at 53.299868 -58.966354)
		(size 0.4572)
		(drill 0.254)
		(layers "F.Cu" "B.Cu")
		(net "BATTERY_DETECT")
	)
	(via
		(at 48.86452 -74.1426)
		(size 0.762)
		(drill 0.254)
		(layers "F.Cu" "B.Cu")
		(net "BATTERY_DETECT")
	)
	(segment
		(start 48.86452 -74.400664)
		(end 48.3108 -74.954384)
		(width 0.11684)
		(layer "B.Cu")
		(net "BATTERY_DETECT")
	)
	(segment
		(start 48.3108 -74.954384)
		(end 48.250094 -74.954384)
		(width 0.11684)
		(layer "B.Cu")
		(net "BATTERY_DETECT")
	)
	(segment
		(start 48.86452 -74.1426)
		(end 48.86452 -74.400664)
		(width 0.11684)
		(layer "B.Cu")
		(net "BATTERY_DETECT")
	)
	(segment
		(start 49.04232 -73.9648)
		(end 48.86452 -74.1426)
		(width 0.10668)
		(layer "In4.Cu")
		(net "BATTERY_DETECT")
	)
	(segment
		(start 53.003704 -64.459104)
		(end 53.213 -64.964564)
		(width 0.10668)
		(layer "In4.Cu")
		(net "BATTERY_DETECT")
	)
	(segment
		(start 53.213 -66.9036)
		(end 53.0606 -67.056)
		(width 0.10668)
		(layer "In4.Cu")
		(net "BATTERY_DETECT")
	)
	(segment
		(start 53.0606 -68.37934)
		(end 52.65674 -68.7832)
		(width 0.10668)
		(layer "In4.Cu")
		(net "BATTERY_DETECT")
	)
	(segment
		(start 53.299868 -59.213242)
		(end 52.552092 -59.961018)
		(width 0.10668)
		(layer "In4.Cu")
		(net "BATTERY_DETECT")
	)
	(segment
		(start 53.0606 -67.056)
		(end 53.0606 -68.37934)
		(width 0.10668)
		(layer "In4.Cu")
		(net "BATTERY_DETECT")
	)
	(segment
		(start 51.801014 -63.256414)
		(end 53.003704 -64.459104)
		(width 0.10668)
		(layer "In4.Cu")
		(net "BATTERY_DETECT")
	)
	(segment
		(start 52.65674 -73.3298)
		(end 52.02174 -73.9648)
		(width 0.10668)
		(layer "In4.Cu")
		(net "BATTERY_DETECT")
	)
	(segment
		(start 52.552092 -61.953394)
		(end 51.801014 -62.704472)
		(width 0.10668)
		(layer "In4.Cu")
		(net "BATTERY_DETECT")
	)
	(segment
		(start 51.801014 -62.704472)
		(end 51.801014 -63.256414)
		(width 0.10668)
		(layer "In4.Cu")
		(net "BATTERY_DETECT")
	)
	(segment
		(start 52.65674 -68.7832)
		(end 52.65674 -73.3298)
		(width 0.10668)
		(layer "In4.Cu")
		(net "BATTERY_DETECT")
	)
	(segment
		(start 53.299868 -58.966354)
		(end 53.299868 -59.213242)
		(width 0.10668)
		(layer "In4.Cu")
		(net "BATTERY_DETECT")
	)
	(segment
		(start 53.213 -64.964564)
		(end 53.213 -66.9036)
		(width 0.10668)
		(layer "In4.Cu")
		(net "BATTERY_DETECT")
	)
	(segment
		(start 52.02174 -73.9648)
		(end 49.04232 -73.9648)
		(width 0.10668)
		(layer "In4.Cu")
		(net "BATTERY_DETECT")
	)
	(segment
		(start 52.552092 -59.961018)
		(end 52.552092 -61.953394)
		(width 0.10668)
		(layer "In4.Cu")
		(net "BATTERY_DETECT")
	)
	(segment
		(start 52.094892 -59.37123)
		(end 51.699668 -59.766454)
		(width 0.3556)
		(layer "F.Cu")
		(net "ADCVREFEXT1")
	)
	(via
		(at 62.614556 -74.75855)
		(size 0.508)
		(drill 0.254)
		(layers "F.Cu" "B.Cu")
		(net "ADCVREFEXT1")
	)
	(via
		(at 60.6806 -75.4253)
		(size 0.6604)
		(drill 0.3302)
		(layers "F.Cu" "B.Cu")
		(net "ADCVREFEXT1")
	)
	(via
		(at 57.602882 -75.907646)
		(size 0.6604)
		(drill 0.3302)
		(layers "F.Cu" "B.Cu")
		(net "ADCVREFEXT1")
	)
	(via
		(at 62.614556 -75.39355)
		(size 0.508)
		(drill 0.254)
		(layers "F.Cu" "B.Cu")
		(net "ADCVREFEXT1")
	)
	(via
		(at 61.280802 -71.794116)
		(size 0.508)
		(drill 0.254)
		(layers "F.Cu" "B.Cu")
		(net "ADCVREFEXT1")
	)
	(via
		(at 51.699668 -59.766454)
		(size 0.4572)
		(drill 0.254)
		(layers "F.Cu" "B.Cu")
		(net "ADCVREFEXT1")
	)
	(segment
		(start 51.857402 -60.153042)
		(end 51.857402 -59.924188)
		(width 0.381)
		(layer "B.Cu")
		(net "ADCVREFEXT1")
	)
	(segment
		(start 51.857402 -59.924188)
		(end 51.699668 -59.766454)
		(width 0.381)
		(layer "B.Cu")
		(net "ADCVREFEXT1")
	)
	(segment
		(start 52.238656 -60.534296)
		(end 51.857402 -60.153042)
		(width 0.381)
		(layer "B.Cu")
		(net "ADCVREFEXT1")
	)
	(segment
		(start 52.384452 -60.534296)
		(end 52.238656 -60.534296)
		(width 0.381)
		(layer "B.Cu")
		(net "ADCVREFEXT1")
	)
	(segment
		(start 50.494946 -59.37123)
		(end 50.099722 -59.766454)
		(width 0.3556)
		(layer "F.Cu")
		(net "ADCVREFEXT0")
	)
	(via
		(at 56.099964 -69.12864)
		(size 0.762)
		(drill 0.254)
		(layers "F.Cu" "B.Cu")
		(net "ADCVREFEXT0")
	)
	(via
		(at 50.099722 -59.766454)
		(size 0.4572)
		(drill 0.254)
		(layers "F.Cu" "B.Cu")
		(net "ADCVREFEXT0")
	)
	(segment
		(start 49.39919 -59.807602)
		(end 50.058574 -59.807602)
		(width 0.381)
		(layer "B.Cu")
		(net "ADCVREFEXT0")
	)
	(segment
		(start 50.058574 -59.807602)
		(end 50.099722 -59.766454)
		(width 0.381)
		(layer "B.Cu")
		(net "ADCVREFEXT0")
	)
	(segment
		(start 105.04424 -81.8007)
		(end 98.81997 -80.702912)
		(width 0.14224)
		(layer "F.Cu")
		(net "85_5INCH_TOP_DP")
	)
	(segment
		(start 104.925114 -95.314008)
		(end 104.707182 -96.548194)
		(width 0.14224)
		(layer "F.Cu")
		(net "85_5INCH_TOP_DP")
	)
	(segment
		(start 105.62336 -81.394808)
		(end 105.04424 -81.8007)
		(width 0.14224)
		(layer "F.Cu")
		(net "85_5INCH_TOP_DP")
	)
	(segment
		(start 105.832656 -72.501506)
		(end 105.614724 -73.735692)
		(width 0.14224)
		(layer "F.Cu")
		(net "85_5INCH_TOP_DP")
	)
	(segment
		(start 105.426764 -71.92264)
		(end 105.832656 -72.501506)
		(width 0.14224)
		(layer "F.Cu")
		(net "85_5INCH_TOP_DP")
	)
	(segment
		(start 98.724974 -84.51469)
		(end 98.395282 -84.745576)
		(width 0.14224)
		(layer "F.Cu")
		(net "85_5INCH_TOP_DP")
	)
	(segment
		(start 105.44683 -75.754738)
		(end 105.852722 -76.333858)
		(width 0.14224)
		(layer "F.Cu")
		(net "85_5INCH_TOP_DP")
	)
	(segment
		(start 101.34092 -98.002852)
		(end 101.746812 -98.581972)
		(width 0.14224)
		(layer "F.Cu")
		(net "85_5INCH_TOP_DP")
	)
	(segment
		(start 98.876104 -76.884022)
		(end 98.546412 -77.114654)
		(width 0.14224)
		(layer "F.Cu")
		(net "85_5INCH_TOP_DP")
	)
	(segment
		(start 104.090724 -93.118686)
		(end 98.484182 -92.12961)
		(width 0.14224)
		(layer "F.Cu")
		(net "85_5INCH_TOP_DP")
	)
	(segment
		(start 101.82352 -71.286624)
		(end 105.426764 -71.92264)
		(width 0.14224)
		(layer "F.Cu")
		(net "85_5INCH_TOP_DP")
	)
	(segment
		(start 105.05567 -77.973936)
		(end 98.876104 -76.884022)
		(width 0.14224)
		(layer "F.Cu")
		(net "85_5INCH_TOP_DP")
	)
	(segment
		(start 105.852722 -76.333858)
		(end 105.63479 -77.568044)
		(width 0.14224)
		(layer "F.Cu")
		(net "85_5INCH_TOP_DP")
	)
	(segment
		(start 98.383852 -89.823544)
		(end 104.481884 -90.899488)
		(width 0.14224)
		(layer "F.Cu")
		(net "85_5INCH_TOP_DP")
	)
	(segment
		(start 98.371152 -74.218292)
		(end 98.601784 -74.547222)
		(width 0.14224)
		(layer "F.Cu")
		(net "85_5INCH_TOP_DP")
	)
	(segment
		(start 104.481884 -90.899488)
		(end 104.887776 -91.478608)
		(width 0.14224)
		(layer "F.Cu")
		(net "85_5INCH_TOP_DP")
	)
	(segment
		(start 98.325432 -81.867756)
		(end 98.556064 -82.196686)
		(width 0.14224)
		(layer "F.Cu")
		(net "85_5INCH_TOP_DP")
	)
	(segment
		(start 98.15449 -92.360496)
		(end 97.989644 -93.294454)
		(width 0.14224)
		(layer "F.Cu")
		(net "85_5INCH_TOP_DP")
	)
	(segment
		(start 101.46665 -103.716074)
		(end 101.532436 -103.78186)
		(width 0.14224)
		(layer "F.Cu")
		(net "85_5INCH_TOP_DP")
	)
	(segment
		(start 98.381566 -78.048866)
		(end 98.611944 -78.377796)
		(width 0.14224)
		(layer "F.Cu")
		(net "85_5INCH_TOP_DP")
	)
	(segment
		(start 105.035858 -74.141838)
		(end 98.86569 -73.053448)
		(width 0.14224)
		(layer "F.Cu")
		(net "85_5INCH_TOP_DP")
	)
	(segment
		(start 98.86569 -73.053448)
		(end 98.535998 -73.28408)
		(width 0.14224)
		(layer "F.Cu")
		(net "85_5INCH_TOP_DP")
	)
	(segment
		(start 105.168192 -83.363054)
		(end 105.574084 -83.94192)
		(width 0.14224)
		(layer "F.Cu")
		(net "85_5INCH_TOP_DP")
	)
	(segment
		(start 101.532436 -103.78186)
		(end 101.532436 -103.93934)
		(width 0.14224)
		(layer "F.Cu")
		(net "85_5INCH_TOP_DP")
	)
	(segment
		(start 98.484182 -92.12961)
		(end 98.15449 -92.360496)
		(width 0.14224)
		(layer "F.Cu")
		(net "85_5INCH_TOP_DP")
	)
	(segment
		(start 98.611944 -78.377796)
		(end 105.4354 -79.581502)
		(width 0.14224)
		(layer "F.Cu")
		(net "85_5INCH_TOP_DP")
	)
	(segment
		(start 104.519476 -94.734634)
		(end 104.925114 -95.314008)
		(width 0.14224)
		(layer "F.Cu")
		(net "85_5INCH_TOP_DP")
	)
	(segment
		(start 97.989644 -93.294454)
		(end 98.220276 -93.623384)
		(width 0.14224)
		(layer "F.Cu")
		(net "85_5INCH_TOP_DP")
	)
	(segment
		(start 99.607116 -96.445578)
		(end 99.44227 -97.379536)
		(width 0.14224)
		(layer "F.Cu")
		(net "85_5INCH_TOP_DP")
	)
	(segment
		(start 98.220276 -93.623384)
		(end 104.519476 -94.734634)
		(width 0.14224)
		(layer "F.Cu")
		(net "85_5INCH_TOP_DP")
	)
	(segment
		(start 104.599232 -88.871552)
		(end 104.020112 -89.277444)
		(width 0.14224)
		(layer "F.Cu")
		(net "85_5INCH_TOP_DP")
	)
	(segment
		(start 99.672902 -97.70872)
		(end 101.34092 -98.002852)
		(width 0.14224)
		(layer "F.Cu")
		(net "85_5INCH_TOP_DP")
	)
	(segment
		(start 105.841292 -80.160622)
		(end 105.62336 -81.394808)
		(width 0.14224)
		(layer "F.Cu")
		(net "85_5INCH_TOP_DP")
	)
	(segment
		(start 104.817164 -87.637366)
		(end 104.599232 -88.871552)
		(width 0.14224)
		(layer "F.Cu")
		(net "85_5INCH_TOP_DP")
	)
	(segment
		(start 105.356152 -85.176106)
		(end 104.776778 -85.581998)
		(width 0.14224)
		(layer "F.Cu")
		(net "85_5INCH_TOP_DP")
	)
	(segment
		(start 104.128316 -96.954086)
		(end 99.936808 -96.214692)
		(width 0.14224)
		(layer "F.Cu")
		(net "85_5INCH_TOP_DP")
	)
	(segment
		(start 101.532436 -66.4591)
		(end 101.532436 -66.61658)
		(width 0.14224)
		(layer "F.Cu")
		(net "85_5INCH_TOP_DP")
	)
	(segment
		(start 98.81997 -80.702912)
		(end 98.490278 -80.933544)
		(width 0.14224)
		(layer "F.Cu")
		(net "85_5INCH_TOP_DP")
	)
	(segment
		(start 105.63479 -77.568044)
		(end 105.05567 -77.973936)
		(width 0.14224)
		(layer "F.Cu")
		(net "85_5INCH_TOP_DP")
	)
	(segment
		(start 99.936808 -96.214692)
		(end 99.607116 -96.445578)
		(width 0.14224)
		(layer "F.Cu")
		(net "85_5INCH_TOP_DP")
	)
	(segment
		(start 101.46665 -66.682366)
		(end 101.46665 -70.7771)
		(width 0.14224)
		(layer "F.Cu")
		(net "85_5INCH_TOP_DP")
	)
	(segment
		(start 104.707182 -96.548194)
		(end 104.128316 -96.954086)
		(width 0.14224)
		(layer "F.Cu")
		(net "85_5INCH_TOP_DP")
	)
	(segment
		(start 101.46665 -100.168964)
		(end 101.46665 -103.716074)
		(width 0.14224)
		(layer "F.Cu")
		(net "85_5INCH_TOP_DP")
	)
	(segment
		(start 101.746812 -98.581972)
		(end 101.46665 -100.168964)
		(width 0.14224)
		(layer "F.Cu")
		(net "85_5INCH_TOP_DP")
	)
	(segment
		(start 98.230436 -85.679534)
		(end 98.461068 -86.008718)
		(width 0.14224)
		(layer "F.Cu")
		(net "85_5INCH_TOP_DP")
	)
	(segment
		(start 98.601784 -74.547222)
		(end 105.44683 -75.754738)
		(width 0.14224)
		(layer "F.Cu")
		(net "85_5INCH_TOP_DP")
	)
	(segment
		(start 105.614724 -73.735692)
		(end 105.035858 -74.141838)
		(width 0.14224)
		(layer "F.Cu")
		(net "85_5INCH_TOP_DP")
	)
	(segment
		(start 98.546412 -77.114654)
		(end 98.381566 -78.048866)
		(width 0.14224)
		(layer "F.Cu")
		(net "85_5INCH_TOP_DP")
	)
	(segment
		(start 98.395282 -84.745576)
		(end 98.230436 -85.679534)
		(width 0.14224)
		(layer "F.Cu")
		(net "85_5INCH_TOP_DP")
	)
	(segment
		(start 104.887776 -91.478608)
		(end 104.669844 -92.712794)
		(width 0.14224)
		(layer "F.Cu")
		(net "85_5INCH_TOP_DP")
	)
	(segment
		(start 98.318066 -88.560656)
		(end 98.15322 -89.494614)
		(width 0.14224)
		(layer "F.Cu")
		(net "85_5INCH_TOP_DP")
	)
	(segment
		(start 98.556064 -82.196686)
		(end 105.168192 -83.363054)
		(width 0.14224)
		(layer "F.Cu")
		(net "85_5INCH_TOP_DP")
	)
	(segment
		(start 105.574084 -83.94192)
		(end 105.356152 -85.176106)
		(width 0.14224)
		(layer "F.Cu")
		(net "85_5INCH_TOP_DP")
	)
	(segment
		(start 104.776778 -85.581998)
		(end 98.724974 -84.51469)
		(width 0.14224)
		(layer "F.Cu")
		(net "85_5INCH_TOP_DP")
	)
	(segment
		(start 101.46665 -70.7771)
		(end 101.82352 -71.286624)
		(width 0.14224)
		(layer "F.Cu")
		(net "85_5INCH_TOP_DP")
	)
	(segment
		(start 105.4354 -79.581502)
		(end 105.841292 -80.160622)
		(width 0.14224)
		(layer "F.Cu")
		(net "85_5INCH_TOP_DP")
	)
	(segment
		(start 104.411272 -87.058246)
		(end 104.817164 -87.637366)
		(width 0.14224)
		(layer "F.Cu")
		(net "85_5INCH_TOP_DP")
	)
	(segment
		(start 98.461068 -86.008718)
		(end 104.411272 -87.058246)
		(width 0.14224)
		(layer "F.Cu")
		(net "85_5INCH_TOP_DP")
	)
	(segment
		(start 99.44227 -97.379536)
		(end 99.672902 -97.70872)
		(width 0.14224)
		(layer "F.Cu")
		(net "85_5INCH_TOP_DP")
	)
	(segment
		(start 104.669844 -92.712794)
		(end 104.090724 -93.118686)
		(width 0.14224)
		(layer "F.Cu")
		(net "85_5INCH_TOP_DP")
	)
	(segment
		(start 104.020112 -89.277444)
		(end 98.648012 -88.32977)
		(width 0.14224)
		(layer "F.Cu")
		(net "85_5INCH_TOP_DP")
	)
	(segment
		(start 101.532436 -66.61658)
		(end 101.46665 -66.682366)
		(width 0.14224)
		(layer "F.Cu")
		(net "85_5INCH_TOP_DP")
	)
	(segment
		(start 98.648012 -88.32977)
		(end 98.318066 -88.560656)
		(width 0.14224)
		(layer "F.Cu")
		(net "85_5INCH_TOP_DP")
	)
	(segment
		(start 98.535998 -73.28408)
		(end 98.371152 -74.218292)
		(width 0.14224)
		(layer "F.Cu")
		(net "85_5INCH_TOP_DP")
	)
	(segment
		(start 98.490278 -80.933544)
		(end 98.325432 -81.867756)
		(width 0.14224)
		(layer "F.Cu")
		(net "85_5INCH_TOP_DP")
	)
	(segment
		(start 98.15322 -89.494614)
		(end 98.383852 -89.823544)
		(width 0.14224)
		(layer "F.Cu")
		(net "85_5INCH_TOP_DP")
	)
	(segment
		(start 99.850448 -95.82531)
		(end 99.27082 -96.231202)
		(width 0.14224)
		(layer "F.Cu")
		(net "85_5INCH_TOP_DN")
	)
	(segment
		(start 101.09835 -70.893432)
		(end 101.609398 -71.62292)
		(width 0.14224)
		(layer "F.Cu")
		(net "85_5INCH_TOP_DN")
	)
	(segment
		(start 104.041956 -96.564704)
		(end 99.850448 -95.82531)
		(width 0.14224)
		(layer "F.Cu")
		(net "85_5INCH_TOP_DN")
	)
	(segment
		(start 105.443274 -72.587866)
		(end 105.278428 -73.52157)
		(width 0.14224)
		(layer "F.Cu")
		(net "85_5INCH_TOP_DN")
	)
	(segment
		(start 105.221278 -79.917798)
		(end 105.45191 -80.246982)
		(width 0.14224)
		(layer "F.Cu")
		(net "85_5INCH_TOP_DN")
	)
	(segment
		(start 97.93605 -81.95437)
		(end 98.341942 -82.532982)
		(width 0.14224)
		(layer "F.Cu")
		(net "85_5INCH_TOP_DN")
	)
	(segment
		(start 97.763838 -89.580974)
		(end 98.16973 -90.15984)
		(width 0.14224)
		(layer "F.Cu")
		(net "85_5INCH_TOP_DN")
	)
	(segment
		(start 105.232708 -76.091034)
		(end 105.46334 -76.420218)
		(width 0.14224)
		(layer "F.Cu")
		(net "85_5INCH_TOP_DN")
	)
	(segment
		(start 99.052888 -97.465896)
		(end 99.45878 -98.045016)
		(width 0.14224)
		(layer "F.Cu")
		(net "85_5INCH_TOP_DN")
	)
	(segment
		(start 101.032564 -103.78186)
		(end 101.032564 -103.93934)
		(width 0.14224)
		(layer "F.Cu")
		(net "85_5INCH_TOP_DN")
	)
	(segment
		(start 104.333548 -92.498672)
		(end 104.004364 -92.729304)
		(width 0.14224)
		(layer "F.Cu")
		(net "85_5INCH_TOP_DN")
	)
	(segment
		(start 101.032564 -66.61658)
		(end 101.09835 -66.682366)
		(width 0.14224)
		(layer "F.Cu")
		(net "85_5INCH_TOP_DN")
	)
	(segment
		(start 105.298494 -77.353922)
		(end 104.96931 -77.584554)
		(width 0.14224)
		(layer "F.Cu")
		(net "85_5INCH_TOP_DN")
	)
	(segment
		(start 101.609398 -71.62292)
		(end 105.212642 -72.258936)
		(width 0.14224)
		(layer "F.Cu")
		(net "85_5INCH_TOP_DN")
	)
	(segment
		(start 97.600262 -93.380814)
		(end 98.006154 -93.95968)
		(width 0.14224)
		(layer "F.Cu")
		(net "85_5INCH_TOP_DN")
	)
	(segment
		(start 101.09835 -103.716074)
		(end 101.032564 -103.78186)
		(width 0.14224)
		(layer "F.Cu")
		(net "85_5INCH_TOP_DN")
	)
	(segment
		(start 98.77933 -72.664066)
		(end 98.199702 -73.069704)
		(width 0.14224)
		(layer "F.Cu")
		(net "85_5INCH_TOP_DN")
	)
	(segment
		(start 104.3051 -95.07093)
		(end 104.535732 -95.400368)
		(width 0.14224)
		(layer "F.Cu")
		(net "85_5INCH_TOP_DN")
	)
	(segment
		(start 98.210116 -76.900278)
		(end 97.992184 -78.135226)
		(width 0.14224)
		(layer "F.Cu")
		(net "85_5INCH_TOP_DN")
	)
	(segment
		(start 98.16973 -90.15984)
		(end 104.267762 -91.235784)
		(width 0.14224)
		(layer "F.Cu")
		(net "85_5INCH_TOP_DN")
	)
	(segment
		(start 97.841054 -85.765894)
		(end 98.246946 -86.345014)
		(width 0.14224)
		(layer "F.Cu")
		(net "85_5INCH_TOP_DN")
	)
	(segment
		(start 104.498394 -91.564968)
		(end 104.333548 -92.498672)
		(width 0.14224)
		(layer "F.Cu")
		(net "85_5INCH_TOP_DN")
	)
	(segment
		(start 104.949244 -73.752456)
		(end 98.77933 -72.664066)
		(width 0.14224)
		(layer "F.Cu")
		(net "85_5INCH_TOP_DN")
	)
	(segment
		(start 104.19715 -87.394542)
		(end 104.427782 -87.723726)
		(width 0.14224)
		(layer "F.Cu")
		(net "85_5INCH_TOP_DN")
	)
	(segment
		(start 101.09835 -66.682366)
		(end 101.09835 -70.893432)
		(width 0.14224)
		(layer "F.Cu")
		(net "85_5INCH_TOP_DN")
	)
	(segment
		(start 104.370886 -96.334072)
		(end 104.041956 -96.564704)
		(width 0.14224)
		(layer "F.Cu")
		(net "85_5INCH_TOP_DN")
	)
	(segment
		(start 105.184702 -84.02828)
		(end 105.019856 -84.961984)
		(width 0.14224)
		(layer "F.Cu")
		(net "85_5INCH_TOP_DN")
	)
	(segment
		(start 98.387662 -74.883518)
		(end 105.232708 -76.091034)
		(width 0.14224)
		(layer "F.Cu")
		(net "85_5INCH_TOP_DN")
	)
	(segment
		(start 97.98177 -74.304652)
		(end 98.387662 -74.883518)
		(width 0.14224)
		(layer "F.Cu")
		(net "85_5INCH_TOP_DN")
	)
	(segment
		(start 97.992184 -78.135226)
		(end 98.397822 -78.714092)
		(width 0.14224)
		(layer "F.Cu")
		(net "85_5INCH_TOP_DN")
	)
	(segment
		(start 104.267762 -91.235784)
		(end 104.498394 -91.564968)
		(width 0.14224)
		(layer "F.Cu")
		(net "85_5INCH_TOP_DN")
	)
	(segment
		(start 101.35743 -98.668332)
		(end 101.09835 -100.136706)
		(width 0.14224)
		(layer "F.Cu")
		(net "85_5INCH_TOP_DN")
	)
	(segment
		(start 98.397822 -78.714092)
		(end 105.221278 -79.917798)
		(width 0.14224)
		(layer "F.Cu")
		(net "85_5INCH_TOP_DN")
	)
	(segment
		(start 98.058986 -84.5312)
		(end 97.841054 -85.765894)
		(width 0.14224)
		(layer "F.Cu")
		(net "85_5INCH_TOP_DN")
	)
	(segment
		(start 99.45878 -98.045016)
		(end 101.126798 -98.339148)
		(width 0.14224)
		(layer "F.Cu")
		(net "85_5INCH_TOP_DN")
	)
	(segment
		(start 105.287064 -81.180686)
		(end 104.95788 -81.411318)
		(width 0.14224)
		(layer "F.Cu")
		(net "85_5INCH_TOP_DN")
	)
	(segment
		(start 98.638614 -84.125308)
		(end 98.058986 -84.5312)
		(width 0.14224)
		(layer "F.Cu")
		(net "85_5INCH_TOP_DN")
	)
	(segment
		(start 104.262936 -88.65743)
		(end 103.933752 -88.888062)
		(width 0.14224)
		(layer "F.Cu")
		(net "85_5INCH_TOP_DN")
	)
	(segment
		(start 98.561652 -87.940388)
		(end 97.98177 -88.34628)
		(width 0.14224)
		(layer "F.Cu")
		(net "85_5INCH_TOP_DN")
	)
	(segment
		(start 105.019856 -84.961984)
		(end 104.690418 -85.192616)
		(width 0.14224)
		(layer "F.Cu")
		(net "85_5INCH_TOP_DN")
	)
	(segment
		(start 105.45191 -80.246982)
		(end 105.287064 -81.180686)
		(width 0.14224)
		(layer "F.Cu")
		(net "85_5INCH_TOP_DN")
	)
	(segment
		(start 105.212642 -72.258936)
		(end 105.443274 -72.587866)
		(width 0.14224)
		(layer "F.Cu")
		(net "85_5INCH_TOP_DN")
	)
	(segment
		(start 101.09835 -100.136706)
		(end 101.09835 -103.716074)
		(width 0.14224)
		(layer "F.Cu")
		(net "85_5INCH_TOP_DN")
	)
	(segment
		(start 98.341942 -82.532982)
		(end 104.95407 -83.69935)
		(width 0.14224)
		(layer "F.Cu")
		(net "85_5INCH_TOP_DN")
	)
	(segment
		(start 104.004364 -92.729304)
		(end 98.397822 -91.740228)
		(width 0.14224)
		(layer "F.Cu")
		(net "85_5INCH_TOP_DN")
	)
	(segment
		(start 98.153982 -80.719168)
		(end 97.93605 -81.95437)
		(width 0.14224)
		(layer "F.Cu")
		(net "85_5INCH_TOP_DN")
	)
	(segment
		(start 105.278428 -73.52157)
		(end 104.949244 -73.752456)
		(width 0.14224)
		(layer "F.Cu")
		(net "85_5INCH_TOP_DN")
	)
	(segment
		(start 97.818194 -92.14612)
		(end 97.600262 -93.380814)
		(width 0.14224)
		(layer "F.Cu")
		(net "85_5INCH_TOP_DN")
	)
	(segment
		(start 104.535732 -95.400368)
		(end 104.370886 -96.334072)
		(width 0.14224)
		(layer "F.Cu")
		(net "85_5INCH_TOP_DN")
	)
	(segment
		(start 104.427782 -87.723726)
		(end 104.262936 -88.65743)
		(width 0.14224)
		(layer "F.Cu")
		(net "85_5INCH_TOP_DN")
	)
	(segment
		(start 101.032564 -66.4591)
		(end 101.032564 -66.61658)
		(width 0.14224)
		(layer "F.Cu")
		(net "85_5INCH_TOP_DN")
	)
	(segment
		(start 105.46334 -76.420218)
		(end 105.298494 -77.353922)
		(width 0.14224)
		(layer "F.Cu")
		(net "85_5INCH_TOP_DN")
	)
	(segment
		(start 98.006154 -93.95968)
		(end 104.3051 -95.07093)
		(width 0.14224)
		(layer "F.Cu")
		(net "85_5INCH_TOP_DN")
	)
	(segment
		(start 99.27082 -96.231202)
		(end 99.052888 -97.465896)
		(width 0.14224)
		(layer "F.Cu")
		(net "85_5INCH_TOP_DN")
	)
	(segment
		(start 98.246946 -86.345014)
		(end 104.19715 -87.394542)
		(width 0.14224)
		(layer "F.Cu")
		(net "85_5INCH_TOP_DN")
	)
	(segment
		(start 98.199702 -73.069704)
		(end 97.98177 -74.304652)
		(width 0.14224)
		(layer "F.Cu")
		(net "85_5INCH_TOP_DN")
	)
	(segment
		(start 104.95407 -83.69935)
		(end 105.184702 -84.02828)
		(width 0.14224)
		(layer "F.Cu")
		(net "85_5INCH_TOP_DN")
	)
	(segment
		(start 104.96931 -77.584554)
		(end 98.789744 -76.49464)
		(width 0.14224)
		(layer "F.Cu")
		(net "85_5INCH_TOP_DN")
	)
	(segment
		(start 101.126798 -98.339148)
		(end 101.35743 -98.668332)
		(width 0.14224)
		(layer "F.Cu")
		(net "85_5INCH_TOP_DN")
	)
	(segment
		(start 97.98177 -88.34628)
		(end 97.763838 -89.580974)
		(width 0.14224)
		(layer "F.Cu")
		(net "85_5INCH_TOP_DN")
	)
	(segment
		(start 104.690418 -85.192616)
		(end 98.638614 -84.125308)
		(width 0.14224)
		(layer "F.Cu")
		(net "85_5INCH_TOP_DN")
	)
	(segment
		(start 98.789744 -76.49464)
		(end 98.210116 -76.900278)
		(width 0.14224)
		(layer "F.Cu")
		(net "85_5INCH_TOP_DN")
	)
	(segment
		(start 98.73361 -80.31353)
		(end 98.153982 -80.719168)
		(width 0.14224)
		(layer "F.Cu")
		(net "85_5INCH_TOP_DN")
	)
	(segment
		(start 104.95788 -81.411318)
		(end 98.73361 -80.31353)
		(width 0.14224)
		(layer "F.Cu")
		(net "85_5INCH_TOP_DN")
	)
	(segment
		(start 98.397822 -91.740228)
		(end 97.818194 -92.14612)
		(width 0.14224)
		(layer "F.Cu")
		(net "85_5INCH_TOP_DN")
	)
	(segment
		(start 103.933752 -88.888062)
		(end 98.561652 -87.940388)
		(width 0.14224)
		(layer "F.Cu")
		(net "85_5INCH_TOP_DN")
	)
	(segment
		(start 96.15424 41.260014)
		(end 96.336104 40.607742)
		(width 0.12954)
		(layer "F.Cu")
		(net "85_5INCH_IN4_DP")
	)
	(segment
		(start 96.176592 -3.779774)
		(end 96.358456 -3.127502)
		(width 0.12954)
		(layer "F.Cu")
		(net "85_5INCH_IN4_DP")
	)
	(via
		(at 96.358456 -3.127502)
		(size 0.508)
		(drill 0.254)
		(layers "F.Cu" "B.Cu")
		(net "85_5INCH_IN4_DP")
	)
	(via
		(at 96.336104 40.607742)
		(size 0.508)
		(drill 0.254)
		(layers "F.Cu" "B.Cu")
		(net "85_5INCH_IN4_DP")
	)
	(segment
		(start 93.788484 5.261102)
		(end 98.7171 4.304538)
		(width 0.1143)
		(layer "In9.Cu")
		(net "85_5INCH_IN4_DP")
	)
	(segment
		(start 98.228658 10.15873)
		(end 94.163642 10.875772)
		(width 0.1143)
		(layer "In9.Cu")
		(net "85_5INCH_IN4_DP")
	)
	(segment
		(start 93.898974 10.690606)
		(end 93.693234 9.524238)
		(width 0.1143)
		(layer "In9.Cu")
		(net "85_5INCH_IN4_DP")
	)
	(segment
		(start 94.163642 10.875772)
		(end 93.898974 10.690606)
		(width 0.1143)
		(layer "In9.Cu")
		(net "85_5INCH_IN4_DP")
	)
	(segment
		(start 98.707702 8.407654)
		(end 99.052634 7.915402)
		(width 0.1143)
		(layer "In9.Cu")
		(net "85_5INCH_IN4_DP")
	)
	(segment
		(start 98.629978 12.435078)
		(end 98.97491 11.942826)
		(width 0.1143)
		(layer "In9.Cu")
		(net "85_5INCH_IN4_DP")
	)
	(segment
		(start 97.972372 26.260298)
		(end 94.227396 26.920952)
		(width 0.1143)
		(layer "In9.Cu")
		(net "85_5INCH_IN4_DP")
	)
	(segment
		(start 93.959172 18.708116)
		(end 93.753432 17.541748)
		(width 0.1143)
		(layer "In9.Cu")
		(net "85_5INCH_IN4_DP")
	)
	(segment
		(start 98.592894 30.596586)
		(end 98.100642 30.252162)
		(width 0.1143)
		(layer "In9.Cu")
		(net "85_5INCH_IN4_DP")
	)
	(segment
		(start 97.903284 14.23035)
		(end 94.198186 14.883892)
		(width 0.1143)
		(layer "In9.Cu")
		(net "85_5INCH_IN4_DP")
	)
	(segment
		(start 93.965014 34.763456)
		(end 93.759274 33.597342)
		(width 0.1143)
		(layer "In9.Cu")
		(net "85_5INCH_IN4_DP")
	)
	(segment
		(start 98.355912 24.525732)
		(end 98.700844 24.033734)
		(width 0.1143)
		(layer "In9.Cu")
		(net "85_5INCH_IN4_DP")
	)
	(segment
		(start 96.071944 40.343582)
		(end 96.071944 37.088572)
		(width 0.1143)
		(layer "In9.Cu")
		(net "85_5INCH_IN4_DP")
	)
	(segment
		(start 93.941646 25.30475)
		(end 98.355912 24.525732)
		(width 0.1143)
		(layer "In9.Cu")
		(net "85_5INCH_IN4_DP")
	)
	(segment
		(start 97.954338 22.249892)
		(end 94.224856 22.907244)
		(width 0.1143)
		(layer "In9.Cu")
		(net "85_5INCH_IN4_DP")
	)
	(segment
		(start 98.44659 22.594316)
		(end 97.954338 22.249892)
		(width 0.1143)
		(layer "In9.Cu")
		(net "85_5INCH_IN4_DP")
	)
	(segment
		(start 96.094296 -0.084328)
		(end 96.094296 -2.863342)
		(width 0.1143)
		(layer "In9.Cu")
		(net "85_5INCH_IN4_DP")
	)
	(segment
		(start 96.071944 37.088572)
		(end 96.187514 36.95065)
		(width 0.1143)
		(layer "In9.Cu")
		(net "85_5INCH_IN4_DP")
	)
	(segment
		(start 94.224856 22.907244)
		(end 93.960188 22.722078)
		(width 0.1143)
		(layer "In9.Cu")
		(net "85_5INCH_IN4_DP")
	)
	(segment
		(start 96.179132 0.393954)
		(end 96.094296 -0.084328)
		(width 0.1143)
		(layer "In9.Cu")
		(net "85_5INCH_IN4_DP")
	)
	(segment
		(start 97.681034 18.283936)
		(end 94.22384 18.893282)
		(width 0.1143)
		(layer "In9.Cu")
		(net "85_5INCH_IN4_DP")
	)
	(segment
		(start 96.187514 36.95065)
		(end 98.667062 36.514278)
		(width 0.1143)
		(layer "In9.Cu")
		(net "85_5INCH_IN4_DP")
	)
	(segment
		(start 93.809058 6.692392)
		(end 93.603318 5.52577)
		(width 0.1143)
		(layer "In9.Cu")
		(net "85_5INCH_IN4_DP")
	)
	(segment
		(start 96.336104 40.607742)
		(end 96.071944 40.343582)
		(width 0.1143)
		(layer "In9.Cu")
		(net "85_5INCH_IN4_DP")
	)
	(segment
		(start 98.464878 26.605484)
		(end 97.972372 26.260298)
		(width 0.1143)
		(layer "In9.Cu")
		(net "85_5INCH_IN4_DP")
	)
	(segment
		(start 93.939614 21.29155)
		(end 98.082354 20.560792)
		(width 0.1143)
		(layer "In9.Cu")
		(net "85_5INCH_IN4_DP")
	)
	(segment
		(start 98.667062 36.514278)
		(end 99.011994 36.022534)
		(width 0.1143)
		(layer "In9.Cu")
		(net "85_5INCH_IN4_DP")
	)
	(segment
		(start 98.720656 10.503662)
		(end 98.228658 10.15873)
		(width 0.1143)
		(layer "In9.Cu")
		(net "85_5INCH_IN4_DP")
	)
	(segment
		(start 93.603318 5.52577)
		(end 93.788484 5.261102)
		(width 0.1143)
		(layer "In9.Cu")
		(net "85_5INCH_IN4_DP")
	)
	(segment
		(start 93.96222 26.735786)
		(end 93.75648 25.569418)
		(width 0.1143)
		(layer "In9.Cu")
		(net "85_5INCH_IN4_DP")
	)
	(segment
		(start 98.173286 18.628868)
		(end 97.681034 18.283936)
		(width 0.1143)
		(layer "In9.Cu")
		(net "85_5INCH_IN4_DP")
	)
	(segment
		(start 93.693234 9.524238)
		(end 93.8784 9.25957)
		(width 0.1143)
		(layer "In9.Cu")
		(net "85_5INCH_IN4_DP")
	)
	(segment
		(start 94.208346 30.938724)
		(end 93.944694 30.753304)
		(width 0.1143)
		(layer "In9.Cu")
		(net "85_5INCH_IN4_DP")
	)
	(segment
		(start 98.847402 32.036004)
		(end 98.592894 30.596586)
		(width 0.1143)
		(layer "In9.Cu")
		(net "85_5INCH_IN4_DP")
	)
	(segment
		(start 93.707204 1.261618)
		(end 95.8342 0.886206)
		(width 0.1143)
		(layer "In9.Cu")
		(net "85_5INCH_IN4_DP")
	)
	(segment
		(start 94.227396 26.920952)
		(end 93.96222 26.735786)
		(width 0.1143)
		(layer "In9.Cu")
		(net "85_5INCH_IN4_DP")
	)
	(segment
		(start 98.649282 16.014446)
		(end 98.395028 14.575028)
		(width 0.1143)
		(layer "In9.Cu")
		(net "85_5INCH_IN4_DP")
	)
	(segment
		(start 93.75648 25.569418)
		(end 93.941646 25.30475)
		(width 0.1143)
		(layer "In9.Cu")
		(net "85_5INCH_IN4_DP")
	)
	(segment
		(start 93.8784 9.25957)
		(end 98.707702 8.407654)
		(width 0.1143)
		(layer "In9.Cu")
		(net "85_5INCH_IN4_DP")
	)
	(segment
		(start 98.97491 11.942826)
		(end 98.720656 10.503662)
		(width 0.1143)
		(layer "In9.Cu")
		(net "85_5INCH_IN4_DP")
	)
	(segment
		(start 94.22384 18.893282)
		(end 93.959172 18.708116)
		(width 0.1143)
		(layer "In9.Cu")
		(net "85_5INCH_IN4_DP")
	)
	(segment
		(start 98.30435 16.506952)
		(end 98.649282 16.014446)
		(width 0.1143)
		(layer "In9.Cu")
		(net "85_5INCH_IN4_DP")
	)
	(segment
		(start 93.754448 21.555964)
		(end 93.939614 21.29155)
		(width 0.1143)
		(layer "In9.Cu")
		(net "85_5INCH_IN4_DP")
	)
	(segment
		(start 93.960188 22.722078)
		(end 93.754448 21.555964)
		(width 0.1143)
		(layer "In9.Cu")
		(net "85_5INCH_IN4_DP")
	)
	(segment
		(start 95.8342 0.886206)
		(end 96.179132 0.393954)
		(width 0.1143)
		(layer "In9.Cu")
		(net "85_5INCH_IN4_DP")
	)
	(segment
		(start 93.738192 29.586428)
		(end 93.923358 29.321506)
		(width 0.1143)
		(layer "In9.Cu")
		(net "85_5INCH_IN4_DP")
	)
	(segment
		(start 93.753432 17.541748)
		(end 93.938598 17.27708)
		(width 0.1143)
		(layer "In9.Cu")
		(net "85_5INCH_IN4_DP")
	)
	(segment
		(start 94.229682 34.948622)
		(end 93.965014 34.763456)
		(width 0.1143)
		(layer "In9.Cu")
		(net "85_5INCH_IN4_DP")
	)
	(segment
		(start 99.052634 7.915402)
		(end 98.79838 6.475984)
		(width 0.1143)
		(layer "In9.Cu")
		(net "85_5INCH_IN4_DP")
	)
	(segment
		(start 98.718878 28.045156)
		(end 98.464878 26.605484)
		(width 0.1143)
		(layer "In9.Cu")
		(net "85_5INCH_IN4_DP")
	)
	(segment
		(start 98.72853 2.486152)
		(end 98.222308 2.132584)
		(width 0.1143)
		(layer "In9.Cu")
		(net "85_5INCH_IN4_DP")
	)
	(segment
		(start 98.757486 34.583624)
		(end 98.263964 34.237676)
		(width 0.1143)
		(layer "In9.Cu")
		(net "85_5INCH_IN4_DP")
	)
	(segment
		(start 93.938598 17.27708)
		(end 98.30435 16.506952)
		(width 0.1143)
		(layer "In9.Cu")
		(net "85_5INCH_IN4_DP")
	)
	(segment
		(start 93.992446 2.877566)
		(end 93.727778 2.6924)
		(width 0.1143)
		(layer "In9.Cu")
		(net "85_5INCH_IN4_DP")
	)
	(segment
		(start 98.222308 2.132584)
		(end 93.992446 2.877566)
		(width 0.1143)
		(layer "In9.Cu")
		(net "85_5INCH_IN4_DP")
	)
	(segment
		(start 98.395028 14.575028)
		(end 97.903284 14.23035)
		(width 0.1143)
		(layer "In9.Cu")
		(net "85_5INCH_IN4_DP")
	)
	(segment
		(start 93.944694 30.753304)
		(end 93.738192 29.586428)
		(width 0.1143)
		(layer "In9.Cu")
		(net "85_5INCH_IN4_DP")
	)
	(segment
		(start 99.011994 36.022534)
		(end 98.757486 34.583624)
		(width 0.1143)
		(layer "In9.Cu")
		(net "85_5INCH_IN4_DP")
	)
	(segment
		(start 94.198186 14.883892)
		(end 93.93301 14.698726)
		(width 0.1143)
		(layer "In9.Cu")
		(net "85_5INCH_IN4_DP")
	)
	(segment
		(start 93.727778 2.6924)
		(end 93.522038 1.525778)
		(width 0.1143)
		(layer "In9.Cu")
		(net "85_5INCH_IN4_DP")
	)
	(segment
		(start 93.759274 33.597342)
		(end 93.94444 33.332674)
		(width 0.1143)
		(layer "In9.Cu")
		(net "85_5INCH_IN4_DP")
	)
	(segment
		(start 93.912436 13.26769)
		(end 98.629978 12.435078)
		(width 0.1143)
		(layer "In9.Cu")
		(net "85_5INCH_IN4_DP")
	)
	(segment
		(start 98.50247 32.52851)
		(end 98.847402 32.036004)
		(width 0.1143)
		(layer "In9.Cu")
		(net "85_5INCH_IN4_DP")
	)
	(segment
		(start 98.306636 6.13156)
		(end 94.073472 6.877558)
		(width 0.1143)
		(layer "In9.Cu")
		(net "85_5INCH_IN4_DP")
	)
	(segment
		(start 96.094296 -2.863342)
		(end 96.358456 -3.127502)
		(width 0.1143)
		(layer "In9.Cu")
		(net "85_5INCH_IN4_DP")
	)
	(segment
		(start 93.923358 29.321506)
		(end 98.373946 28.537408)
		(width 0.1143)
		(layer "In9.Cu")
		(net "85_5INCH_IN4_DP")
	)
	(segment
		(start 98.373946 28.537408)
		(end 98.718878 28.045156)
		(width 0.1143)
		(layer "In9.Cu")
		(net "85_5INCH_IN4_DP")
	)
	(segment
		(start 98.7171 4.304538)
		(end 98.982022 3.92557)
		(width 0.1143)
		(layer "In9.Cu")
		(net "85_5INCH_IN4_DP")
	)
	(segment
		(start 93.72727 13.532358)
		(end 93.912436 13.26769)
		(width 0.1143)
		(layer "In9.Cu")
		(net "85_5INCH_IN4_DP")
	)
	(segment
		(start 98.79838 6.475984)
		(end 98.306636 6.13156)
		(width 0.1143)
		(layer "In9.Cu")
		(net "85_5INCH_IN4_DP")
	)
	(segment
		(start 98.100642 30.252162)
		(end 94.208346 30.938724)
		(width 0.1143)
		(layer "In9.Cu")
		(net "85_5INCH_IN4_DP")
	)
	(segment
		(start 93.93301 14.698726)
		(end 93.72727 13.532358)
		(width 0.1143)
		(layer "In9.Cu")
		(net "85_5INCH_IN4_DP")
	)
	(segment
		(start 98.982022 3.92557)
		(end 98.72853 2.486152)
		(width 0.1143)
		(layer "In9.Cu")
		(net "85_5INCH_IN4_DP")
	)
	(segment
		(start 93.94444 33.332674)
		(end 98.50247 32.52851)
		(width 0.1143)
		(layer "In9.Cu")
		(net "85_5INCH_IN4_DP")
	)
	(segment
		(start 98.263964 34.237676)
		(end 94.229682 34.948622)
		(width 0.1143)
		(layer "In9.Cu")
		(net "85_5INCH_IN4_DP")
	)
	(segment
		(start 94.073472 6.877558)
		(end 93.809058 6.692392)
		(width 0.1143)
		(layer "In9.Cu")
		(net "85_5INCH_IN4_DP")
	)
	(segment
		(start 98.082354 20.560792)
		(end 98.427032 20.068286)
		(width 0.1143)
		(layer "In9.Cu")
		(net "85_5INCH_IN4_DP")
	)
	(segment
		(start 98.700844 24.033734)
		(end 98.44659 22.594316)
		(width 0.1143)
		(layer "In9.Cu")
		(net "85_5INCH_IN4_DP")
	)
	(segment
		(start 93.522038 1.525778)
		(end 93.707204 1.261618)
		(width 0.1143)
		(layer "In9.Cu")
		(net "85_5INCH_IN4_DP")
	)
	(segment
		(start 98.427032 20.068286)
		(end 98.173286 18.628868)
		(width 0.1143)
		(layer "In9.Cu")
		(net "85_5INCH_IN4_DP")
	)
	(segment
		(start 95.654368 41.260014)
		(end 95.472504 40.607742)
		(width 0.12954)
		(layer "F.Cu")
		(net "85_5INCH_IN4_DN")
	)
	(segment
		(start 95.67672 -3.779774)
		(end 95.494856 -3.127502)
		(width 0.12954)
		(layer "F.Cu")
		(net "85_5INCH_IN4_DN")
	)
	(via
		(at 95.472504 40.607742)
		(size 0.508)
		(drill 0.254)
		(layers "F.Cu" "B.Cu")
		(net "85_5INCH_IN4_DN")
	)
	(via
		(at 95.494856 -3.127502)
		(size 0.508)
		(drill 0.254)
		(layers "F.Cu" "B.Cu")
		(net "85_5INCH_IN4_DN")
	)
	(segment
		(start 95.759016 -0.054864)
		(end 95.759016 -2.863342)
		(width 0.1143)
		(layer "In9.Cu")
		(net "85_5INCH_IN4_DN")
	)
	(segment
		(start 95.759016 -2.863342)
		(end 95.494856 -3.127502)
		(width 0.1143)
		(layer "In9.Cu")
		(net "85_5INCH_IN4_DN")
	)
	(segment
		(start 98.472244 36.207954)
		(end 98.65741 35.943794)
		(width 0.1143)
		(layer "In9.Cu")
		(net "85_5INCH_IN4_DN")
	)
	(segment
		(start 97.893632 26.614882)
		(end 94.14891 27.275282)
		(width 0.1143)
		(layer "In9.Cu")
		(net "85_5INCH_IN4_DN")
	)
	(segment
		(start 94.118938 15.238476)
		(end 93.62694 14.893798)
		(width 0.1143)
		(layer "In9.Cu")
		(net "85_5INCH_IN4_DN")
	)
	(segment
		(start 98.434906 12.129008)
		(end 98.620326 11.86434)
		(width 0.1143)
		(layer "In9.Cu")
		(net "85_5INCH_IN4_DN")
	)
	(segment
		(start 93.629734 22.780244)
		(end 93.629988 22.780244)
		(width 0.1143)
		(layer "In9.Cu")
		(net "85_5INCH_IN4_DN")
	)
	(segment
		(start 93.653102 18.903188)
		(end 93.399102 17.463262)
		(width 0.1143)
		(layer "In9.Cu")
		(net "85_5INCH_IN4_DN")
	)
	(segment
		(start 93.65615 26.930858)
		(end 93.631766 26.793952)
		(width 0.1143)
		(layer "In9.Cu")
		(net "85_5INCH_IN4_DN")
	)
	(segment
		(start 98.422206 2.681478)
		(end 98.143822 2.486914)
		(width 0.1143)
		(layer "In9.Cu")
		(net "85_5INCH_IN4_DN")
	)
	(segment
		(start 93.399102 17.463262)
		(end 93.743526 16.97101)
		(width 0.1143)
		(layer "In9.Cu")
		(net "85_5INCH_IN4_DN")
	)
	(segment
		(start 93.654118 22.91715)
		(end 93.629734 22.780244)
		(width 0.1143)
		(layer "In9.Cu")
		(net "85_5INCH_IN4_DN")
	)
	(segment
		(start 93.383608 29.507942)
		(end 93.728032 29.015182)
		(width 0.1143)
		(layer "In9.Cu")
		(net "85_5INCH_IN4_DN")
	)
	(segment
		(start 98.178874 28.231084)
		(end 98.364294 27.966416)
		(width 0.1143)
		(layer "In9.Cu")
		(net "85_5INCH_IN4_DN")
	)
	(segment
		(start 98.65741 35.943794)
		(end 98.451416 34.778696)
		(width 0.1143)
		(layer "In9.Cu")
		(net "85_5INCH_IN4_DN")
	)
	(segment
		(start 93.512132 0.955294)
		(end 95.639128 0.580136)
		(width 0.1143)
		(layer "In9.Cu")
		(net "85_5INCH_IN4_DN")
	)
	(segment
		(start 93.746574 24.99868)
		(end 98.16084 24.219408)
		(width 0.1143)
		(layer "In9.Cu")
		(net "85_5INCH_IN4_DN")
	)
	(segment
		(start 98.14052 22.789388)
		(end 97.875852 22.604222)
		(width 0.1143)
		(layer "In9.Cu")
		(net "85_5INCH_IN4_DN")
	)
	(segment
		(start 98.34626 23.954994)
		(end 98.14052 22.789388)
		(width 0.1143)
		(layer "In9.Cu")
		(net "85_5INCH_IN4_DN")
	)
	(segment
		(start 98.16084 24.219408)
		(end 98.34626 23.954994)
		(width 0.1143)
		(layer "In9.Cu")
		(net "85_5INCH_IN4_DN")
	)
	(segment
		(start 98.307398 32.22244)
		(end 98.492818 31.957518)
		(width 0.1143)
		(layer "In9.Cu")
		(net "85_5INCH_IN4_DN")
	)
	(segment
		(start 93.478604 6.750558)
		(end 93.478858 6.750558)
		(width 0.1143)
		(layer "In9.Cu")
		(net "85_5INCH_IN4_DN")
	)
	(segment
		(start 93.248988 5.447284)
		(end 93.59138 4.957572)
		(width 0.1143)
		(layer "In9.Cu")
		(net "85_5INCH_IN4_DN")
	)
	(segment
		(start 93.683328 8.9535)
		(end 98.51263 8.101584)
		(width 0.1143)
		(layer "In9.Cu")
		(net "85_5INCH_IN4_DN")
	)
	(segment
		(start 98.286824 30.791658)
		(end 98.022156 30.606492)
		(width 0.1143)
		(layer "In9.Cu")
		(net "85_5INCH_IN4_DN")
	)
	(segment
		(start 93.62694 14.893798)
		(end 93.602556 14.756892)
		(width 0.1143)
		(layer "In9.Cu")
		(net "85_5INCH_IN4_DN")
	)
	(segment
		(start 98.109278 16.200882)
		(end 98.294698 15.93596)
		(width 0.1143)
		(layer "In9.Cu")
		(net "85_5INCH_IN4_DN")
	)
	(segment
		(start 93.994986 7.231888)
		(end 93.502988 6.887464)
		(width 0.1143)
		(layer "In9.Cu")
		(net "85_5INCH_IN4_DN")
	)
	(segment
		(start 97.602294 18.638266)
		(end 94.145354 19.247612)
		(width 0.1143)
		(layer "In9.Cu")
		(net "85_5INCH_IN4_DN")
	)
	(segment
		(start 96.008952 36.641532)
		(end 98.472244 36.207954)
		(width 0.1143)
		(layer "In9.Cu")
		(net "85_5INCH_IN4_DN")
	)
	(segment
		(start 98.414332 10.698734)
		(end 98.149918 10.513314)
		(width 0.1143)
		(layer "In9.Cu")
		(net "85_5INCH_IN4_DN")
	)
	(segment
		(start 93.63202 26.793952)
		(end 93.40215 25.490932)
		(width 0.1143)
		(layer "In9.Cu")
		(net "85_5INCH_IN4_DN")
	)
	(segment
		(start 93.91396 3.231896)
		(end 93.421708 2.887472)
		(width 0.1143)
		(layer "In9.Cu")
		(net "85_5INCH_IN4_DN")
	)
	(segment
		(start 93.629988 22.780244)
		(end 93.399864 21.477224)
		(width 0.1143)
		(layer "In9.Cu")
		(net "85_5INCH_IN4_DN")
	)
	(segment
		(start 98.149918 10.513314)
		(end 94.084902 11.230356)
		(width 0.1143)
		(layer "In9.Cu")
		(net "85_5INCH_IN4_DN")
	)
	(segment
		(start 93.63837 30.948122)
		(end 93.383608 29.507942)
		(width 0.1143)
		(layer "In9.Cu")
		(net "85_5INCH_IN4_DN")
	)
	(segment
		(start 93.743526 16.97101)
		(end 98.109278 16.200882)
		(width 0.1143)
		(layer "In9.Cu")
		(net "85_5INCH_IN4_DN")
	)
	(segment
		(start 93.717364 12.96162)
		(end 98.434906 12.129008)
		(width 0.1143)
		(layer "In9.Cu")
		(net "85_5INCH_IN4_DN")
	)
	(segment
		(start 93.749368 33.026604)
		(end 98.307398 32.22244)
		(width 0.1143)
		(layer "In9.Cu")
		(net "85_5INCH_IN4_DN")
	)
	(segment
		(start 97.866962 18.82394)
		(end 97.602294 18.638266)
		(width 0.1143)
		(layer "In9.Cu")
		(net "85_5INCH_IN4_DN")
	)
	(segment
		(start 98.364294 27.966416)
		(end 98.158554 26.800556)
		(width 0.1143)
		(layer "In9.Cu")
		(net "85_5INCH_IN4_DN")
	)
	(segment
		(start 95.639128 0.580136)
		(end 95.824548 0.315468)
		(width 0.1143)
		(layer "In9.Cu")
		(net "85_5INCH_IN4_DN")
	)
	(segment
		(start 93.40215 25.490932)
		(end 93.746574 24.99868)
		(width 0.1143)
		(layer "In9.Cu")
		(net "85_5INCH_IN4_DN")
	)
	(segment
		(start 98.158554 26.800556)
		(end 97.893632 26.614882)
		(width 0.1143)
		(layer "In9.Cu")
		(net "85_5INCH_IN4_DN")
	)
	(segment
		(start 93.33865 9.445498)
		(end 93.683328 8.9535)
		(width 0.1143)
		(layer "In9.Cu")
		(net "85_5INCH_IN4_DN")
	)
	(segment
		(start 98.227896 6.48589)
		(end 93.994986 7.231888)
		(width 0.1143)
		(layer "In9.Cu")
		(net "85_5INCH_IN4_DN")
	)
	(segment
		(start 98.519996 4.001008)
		(end 98.627692 3.847084)
		(width 0.1143)
		(layer "In9.Cu")
		(net "85_5INCH_IN4_DN")
	)
	(segment
		(start 95.472504 40.607742)
		(end 95.736664 40.343582)
		(width 0.1143)
		(layer "In9.Cu")
		(net "85_5INCH_IN4_DN")
	)
	(segment
		(start 97.887282 20.254722)
		(end 98.072702 19.9898)
		(width 0.1143)
		(layer "In9.Cu")
		(net "85_5INCH_IN4_DN")
	)
	(segment
		(start 93.631766 26.793952)
		(end 93.63202 26.793952)
		(width 0.1143)
		(layer "In9.Cu")
		(net "85_5INCH_IN4_DN")
	)
	(segment
		(start 98.492818 31.957518)
		(end 98.286824 30.791658)
		(width 0.1143)
		(layer "In9.Cu")
		(net "85_5INCH_IN4_DN")
	)
	(segment
		(start 93.728032 29.015182)
		(end 98.178874 28.231084)
		(width 0.1143)
		(layer "In9.Cu")
		(net "85_5INCH_IN4_DN")
	)
	(segment
		(start 98.294698 15.93596)
		(end 98.088704 14.7701)
		(width 0.1143)
		(layer "In9.Cu")
		(net "85_5INCH_IN4_DN")
	)
	(segment
		(start 94.14891 27.275282)
		(end 93.65615 26.930858)
		(width 0.1143)
		(layer "In9.Cu")
		(net "85_5INCH_IN4_DN")
	)
	(segment
		(start 98.451416 34.778696)
		(end 98.185224 34.592006)
		(width 0.1143)
		(layer "In9.Cu")
		(net "85_5INCH_IN4_DN")
	)
	(segment
		(start 98.088704 14.7701)
		(end 97.824544 14.584934)
		(width 0.1143)
		(layer "In9.Cu")
		(net "85_5INCH_IN4_DN")
	)
	(segment
		(start 93.502988 6.887464)
		(end 93.478604 6.750558)
		(width 0.1143)
		(layer "In9.Cu")
		(net "85_5INCH_IN4_DN")
	)
	(segment
		(start 94.129352 31.293308)
		(end 93.63837 30.948122)
		(width 0.1143)
		(layer "In9.Cu")
		(net "85_5INCH_IN4_DN")
	)
	(segment
		(start 98.185224 34.592006)
		(end 94.151196 35.302952)
		(width 0.1143)
		(layer "In9.Cu")
		(net "85_5INCH_IN4_DN")
	)
	(segment
		(start 93.404944 33.518856)
		(end 93.749368 33.026604)
		(width 0.1143)
		(layer "In9.Cu")
		(net "85_5INCH_IN4_DN")
	)
	(segment
		(start 93.658944 34.958528)
		(end 93.404944 33.518856)
		(width 0.1143)
		(layer "In9.Cu")
		(net "85_5INCH_IN4_DN")
	)
	(segment
		(start 98.022156 30.606492)
		(end 94.129352 31.293308)
		(width 0.1143)
		(layer "In9.Cu")
		(net "85_5INCH_IN4_DN")
	)
	(segment
		(start 93.399864 21.477224)
		(end 93.744542 20.985226)
		(width 0.1143)
		(layer "In9.Cu")
		(net "85_5INCH_IN4_DN")
	)
	(segment
		(start 95.824548 0.315468)
		(end 95.759016 -0.054864)
		(width 0.1143)
		(layer "In9.Cu")
		(net "85_5INCH_IN4_DN")
	)
	(segment
		(start 93.744542 20.985226)
		(end 97.887282 20.254722)
		(width 0.1143)
		(layer "In9.Cu")
		(net "85_5INCH_IN4_DN")
	)
	(segment
		(start 93.59138 4.957572)
		(end 98.519996 4.001008)
		(width 0.1143)
		(layer "In9.Cu")
		(net "85_5INCH_IN4_DN")
	)
	(segment
		(start 98.492056 6.671056)
		(end 98.227896 6.48589)
		(width 0.1143)
		(layer "In9.Cu")
		(net "85_5INCH_IN4_DN")
	)
	(segment
		(start 95.736664 40.343582)
		(end 95.736664 36.966652)
		(width 0.1143)
		(layer "In9.Cu")
		(net "85_5INCH_IN4_DN")
	)
	(segment
		(start 98.627692 3.847084)
		(end 98.422206 2.681478)
		(width 0.1143)
		(layer "In9.Cu")
		(net "85_5INCH_IN4_DN")
	)
	(segment
		(start 98.620326 11.86434)
		(end 98.414332 10.698734)
		(width 0.1143)
		(layer "In9.Cu")
		(net "85_5INCH_IN4_DN")
	)
	(segment
		(start 93.421708 2.887472)
		(end 93.167454 1.447038)
		(width 0.1143)
		(layer "In9.Cu")
		(net "85_5INCH_IN4_DN")
	)
	(segment
		(start 93.478858 6.750558)
		(end 93.248988 5.447284)
		(width 0.1143)
		(layer "In9.Cu")
		(net "85_5INCH_IN4_DN")
	)
	(segment
		(start 93.167454 1.447038)
		(end 93.512132 0.955294)
		(width 0.1143)
		(layer "In9.Cu")
		(net "85_5INCH_IN4_DN")
	)
	(segment
		(start 97.875852 22.604222)
		(end 94.146116 23.261828)
		(width 0.1143)
		(layer "In9.Cu")
		(net "85_5INCH_IN4_DN")
	)
	(segment
		(start 94.146116 23.261828)
		(end 93.654118 22.91715)
		(width 0.1143)
		(layer "In9.Cu")
		(net "85_5INCH_IN4_DN")
	)
	(segment
		(start 98.51263 8.101584)
		(end 98.69805 7.836916)
		(width 0.1143)
		(layer "In9.Cu")
		(net "85_5INCH_IN4_DN")
	)
	(segment
		(start 98.69805 7.836916)
		(end 98.492056 6.671056)
		(width 0.1143)
		(layer "In9.Cu")
		(net "85_5INCH_IN4_DN")
	)
	(segment
		(start 93.602556 14.756892)
		(end 93.60281 14.756892)
		(width 0.1143)
		(layer "In9.Cu")
		(net "85_5INCH_IN4_DN")
	)
	(segment
		(start 97.824544 14.584934)
		(end 94.118938 15.238476)
		(width 0.1143)
		(layer "In9.Cu")
		(net "85_5INCH_IN4_DN")
	)
	(segment
		(start 98.072702 19.9898)
		(end 97.866962 18.82394)
		(width 0.1143)
		(layer "In9.Cu")
		(net "85_5INCH_IN4_DN")
	)
	(segment
		(start 94.151196 35.302952)
		(end 93.658944 34.958528)
		(width 0.1143)
		(layer "In9.Cu")
		(net "85_5INCH_IN4_DN")
	)
	(segment
		(start 93.37294 13.453872)
		(end 93.717364 12.96162)
		(width 0.1143)
		(layer "In9.Cu")
		(net "85_5INCH_IN4_DN")
	)
	(segment
		(start 95.736664 36.966652)
		(end 96.008952 36.641532)
		(width 0.1143)
		(layer "In9.Cu")
		(net "85_5INCH_IN4_DN")
	)
	(segment
		(start 93.60281 14.756892)
		(end 93.37294 13.453872)
		(width 0.1143)
		(layer "In9.Cu")
		(net "85_5INCH_IN4_DN")
	)
	(segment
		(start 94.145354 19.247612)
		(end 93.653102 18.903188)
		(width 0.1143)
		(layer "In9.Cu")
		(net "85_5INCH_IN4_DN")
	)
	(segment
		(start 98.143822 2.486914)
		(end 93.91396 3.231896)
		(width 0.1143)
		(layer "In9.Cu")
		(net "85_5INCH_IN4_DN")
	)
	(segment
		(start 93.592904 10.885678)
		(end 93.33865 9.445498)
		(width 0.1143)
		(layer "In9.Cu")
		(net "85_5INCH_IN4_DN")
	)
	(segment
		(start 94.084902 11.230356)
		(end 93.592904 10.885678)
		(width 0.1143)
		(layer "In9.Cu")
		(net "85_5INCH_IN4_DN")
	)
	(via
		(at 96.343216 111.28883)
		(size 0.508)
		(drill 0.254)
		(layers "F.Cu" "B.Cu")
		(net "85_5INCH_IN1_DP")
	)
	(via
		(at 96.358456 54.853586)
		(size 0.508)
		(drill 0.254)
		(layers "F.Cu" "B.Cu")
		(net "85_5INCH_IN1_DP")
	)
	(segment
		(start 96.176592 54.201314)
		(end 96.358456 54.853586)
		(width 0.12954)
		(layer "B.Cu")
		(net "85_5INCH_IN1_DP")
	)
	(segment
		(start 96.161352 111.941102)
		(end 96.343216 111.28883)
		(width 0.12954)
		(layer "B.Cu")
		(net "85_5INCH_IN1_DP")
	)
	(segment
		(start 96.432116 76.484988)
		(end 96.92386 76.830428)
		(width 0.1143)
		(layer "In2.Cu")
		(net "85_5INCH_IN1_DP")
	)
	(segment
		(start 93.738192 87.567516)
		(end 93.944694 88.734392)
		(width 0.1143)
		(layer "In2.Cu")
		(net "85_5INCH_IN1_DP")
	)
	(segment
		(start 96.358456 54.853586)
		(end 96.094296 55.117746)
		(width 0.1143)
		(layer "In2.Cu")
		(net "85_5INCH_IN1_DP")
	)
	(segment
		(start 97.14611 94.331536)
		(end 96.801178 94.823788)
		(width 0.1143)
		(layer "In2.Cu")
		(net "85_5INCH_IN1_DP")
	)
	(segment
		(start 96.878394 106.852466)
		(end 96.38538 106.939334)
		(width 0.1143)
		(layer "In2.Cu")
		(net "85_5INCH_IN1_DP")
	)
	(segment
		(start 97.202498 102.349808)
		(end 96.857566 102.841806)
		(width 0.1143)
		(layer "In2.Cu")
		(net "85_5INCH_IN1_DP")
	)
	(segment
		(start 96.38538 106.939334)
		(end 96.079056 107.245658)
		(width 0.1143)
		(layer "In2.Cu")
		(net "85_5INCH_IN1_DP")
	)
	(segment
		(start 96.847406 70.730872)
		(end 93.912436 71.248778)
		(width 0.1143)
		(layer "In2.Cu")
		(net "85_5INCH_IN1_DP")
	)
	(segment
		(start 93.912436 71.248778)
		(end 93.72727 71.513446)
		(width 0.1143)
		(layer "In2.Cu")
		(net "85_5INCH_IN1_DP")
	)
	(segment
		(start 97.176844 62.072266)
		(end 97.200974 62.208918)
		(width 0.1143)
		(layer "In2.Cu")
		(net "85_5INCH_IN1_DP")
	)
	(segment
		(start 93.94444 91.313762)
		(end 93.759274 91.578176)
		(width 0.1143)
		(layer "In2.Cu")
		(net "85_5INCH_IN1_DP")
	)
	(segment
		(start 94.206822 100.961952)
		(end 96.455738 100.565458)
		(width 0.1143)
		(layer "In2.Cu")
		(net "85_5INCH_IN1_DP")
	)
	(segment
		(start 93.96222 84.716874)
		(end 94.226888 84.90204)
		(width 0.1143)
		(layer "In2.Cu")
		(net "85_5INCH_IN1_DP")
	)
	(segment
		(start 96.857566 102.841806)
		(end 93.91015 103.361998)
		(width 0.1143)
		(layer "In2.Cu")
		(net "85_5INCH_IN1_DP")
	)
	(segment
		(start 97.17659 62.072266)
		(end 97.176844 62.072266)
		(width 0.1143)
		(layer "In2.Cu")
		(net "85_5INCH_IN1_DP")
	)
	(segment
		(start 96.425258 72.472042)
		(end 96.917256 72.816974)
		(width 0.1143)
		(layer "In2.Cu")
		(net "85_5INCH_IN1_DP")
	)
	(segment
		(start 94.236286 96.942656)
		(end 96.417638 96.5581)
		(width 0.1143)
		(layer "In2.Cu")
		(net "85_5INCH_IN1_DP")
	)
	(segment
		(start 93.809058 64.67348)
		(end 94.073472 64.858646)
		(width 0.1143)
		(layer "In2.Cu")
		(net "85_5INCH_IN1_DP")
	)
	(segment
		(start 96.46539 80.493108)
		(end 96.957388 80.83804)
		(width 0.1143)
		(layer "In2.Cu")
		(net "85_5INCH_IN1_DP")
	)
	(segment
		(start 93.736414 99.61118)
		(end 93.942408 100.776532)
		(width 0.1143)
		(layer "In2.Cu")
		(net "85_5INCH_IN1_DP")
	)
	(segment
		(start 93.942408 100.776532)
		(end 94.206822 100.961952)
		(width 0.1143)
		(layer "In2.Cu")
		(net "85_5INCH_IN1_DP")
	)
	(segment
		(start 96.844612 86.78799)
		(end 93.923358 87.302848)
		(width 0.1143)
		(layer "In2.Cu")
		(net "85_5INCH_IN1_DP")
	)
	(segment
		(start 93.788484 63.24219)
		(end 93.603318 63.506858)
		(width 0.1143)
		(layer "In2.Cu")
		(net "85_5INCH_IN1_DP")
	)
	(segment
		(start 97.198434 90.308176)
		(end 96.853502 90.800682)
		(width 0.1143)
		(layer "In2.Cu")
		(net "85_5INCH_IN1_DP")
	)
	(segment
		(start 97.190814 66.224912)
		(end 96.845882 66.717164)
		(width 0.1143)
		(layer "In2.Cu")
		(net "85_5INCH_IN1_DP")
	)
	(segment
		(start 93.939614 79.272384)
		(end 93.754448 79.536798)
		(width 0.1143)
		(layer "In2.Cu")
		(net "85_5INCH_IN1_DP")
	)
	(segment
		(start 96.957388 80.83804)
		(end 97.211642 82.277458)
		(width 0.1143)
		(layer "In2.Cu")
		(net "85_5INCH_IN1_DP")
	)
	(segment
		(start 96.399604 92.547186)
		(end 96.891602 92.892626)
		(width 0.1143)
		(layer "In2.Cu")
		(net "85_5INCH_IN1_DP")
	)
	(segment
		(start 96.969326 104.920796)
		(end 97.223326 106.360214)
		(width 0.1143)
		(layer "In2.Cu")
		(net "85_5INCH_IN1_DP")
	)
	(segment
		(start 97.192338 70.23862)
		(end 96.847406 70.730872)
		(width 0.1143)
		(layer "In2.Cu")
		(net "85_5INCH_IN1_DP")
	)
	(segment
		(start 97.178114 78.269592)
		(end 96.833182 78.762098)
		(width 0.1143)
		(layer "In2.Cu")
		(net "85_5INCH_IN1_DP")
	)
	(segment
		(start 94.208346 88.919812)
		(end 96.451928 88.52408)
		(width 0.1143)
		(layer "In2.Cu")
		(net "85_5INCH_IN1_DP")
	)
	(segment
		(start 97.223326 106.360214)
		(end 96.878394 106.852466)
		(width 0.1143)
		(layer "In2.Cu")
		(net "85_5INCH_IN1_DP")
	)
	(segment
		(start 96.079056 111.02467)
		(end 96.343216 111.28883)
		(width 0.1143)
		(layer "In2.Cu")
		(net "85_5INCH_IN1_DP")
	)
	(segment
		(start 96.443546 84.511134)
		(end 96.93529 84.85632)
		(width 0.1143)
		(layer "In2.Cu")
		(net "85_5INCH_IN1_DP")
	)
	(segment
		(start 97.163636 98.342704)
		(end 96.818704 98.834956)
		(width 0.1143)
		(layer "In2.Cu")
		(net "85_5INCH_IN1_DP")
	)
	(segment
		(start 94.197678 72.86498)
		(end 96.425258 72.472042)
		(width 0.1143)
		(layer "In2.Cu")
		(net "85_5INCH_IN1_DP")
	)
	(segment
		(start 95.8342 58.867294)
		(end 93.707204 59.242706)
		(width 0.1143)
		(layer "In2.Cu")
		(net "85_5INCH_IN1_DP")
	)
	(segment
		(start 97.166684 66.08826)
		(end 97.190814 66.224912)
		(width 0.1143)
		(layer "In2.Cu")
		(net "85_5INCH_IN1_DP")
	)
	(segment
		(start 93.522038 59.506866)
		(end 93.728032 60.673234)
		(width 0.1143)
		(layer "In2.Cu")
		(net "85_5INCH_IN1_DP")
	)
	(segment
		(start 96.801178 94.823788)
		(end 93.951044 95.326454)
		(width 0.1143)
		(layer "In2.Cu")
		(net "85_5INCH_IN1_DP")
	)
	(segment
		(start 96.938084 68.799202)
		(end 97.192338 70.23862)
		(width 0.1143)
		(layer "In2.Cu")
		(net "85_5INCH_IN1_DP")
	)
	(segment
		(start 93.72727 71.513446)
		(end 93.93301 72.679814)
		(width 0.1143)
		(layer "In2.Cu")
		(net "85_5INCH_IN1_DP")
	)
	(segment
		(start 96.853502 90.800682)
		(end 93.94444 91.313762)
		(width 0.1143)
		(layer "In2.Cu")
		(net "85_5INCH_IN1_DP")
	)
	(segment
		(start 96.93529 84.85632)
		(end 97.189544 86.295484)
		(width 0.1143)
		(layer "In2.Cu")
		(net "85_5INCH_IN1_DP")
	)
	(segment
		(start 96.446086 68.45427)
		(end 96.938084 68.799202)
		(width 0.1143)
		(layer "In2.Cu")
		(net "85_5INCH_IN1_DP")
	)
	(segment
		(start 93.91015 103.361998)
		(end 93.724984 103.626412)
		(width 0.1143)
		(layer "In2.Cu")
		(net "85_5INCH_IN1_DP")
	)
	(segment
		(start 93.728032 60.673234)
		(end 93.9927 60.858654)
		(width 0.1143)
		(layer "In2.Cu")
		(net "85_5INCH_IN1_DP")
	)
	(segment
		(start 93.938598 75.258168)
		(end 93.753432 75.522836)
		(width 0.1143)
		(layer "In2.Cu")
		(net "85_5INCH_IN1_DP")
	)
	(segment
		(start 96.92386 76.830428)
		(end 97.178114 78.269592)
		(width 0.1143)
		(layer "In2.Cu")
		(net "85_5INCH_IN1_DP")
	)
	(segment
		(start 96.094296 57.89676)
		(end 96.179132 58.375042)
		(width 0.1143)
		(layer "In2.Cu")
		(net "85_5INCH_IN1_DP")
	)
	(segment
		(start 96.909636 96.903794)
		(end 97.163636 98.342704)
		(width 0.1143)
		(layer "In2.Cu")
		(net "85_5INCH_IN1_DP")
	)
	(segment
		(start 94.073472 64.858646)
		(end 96.444562 64.440816)
		(width 0.1143)
		(layer "In2.Cu")
		(net "85_5INCH_IN1_DP")
	)
	(segment
		(start 93.965014 92.744544)
		(end 94.229682 92.92971)
		(width 0.1143)
		(layer "In2.Cu")
		(net "85_5INCH_IN1_DP")
	)
	(segment
		(start 93.765878 95.591884)
		(end 93.972126 96.757744)
		(width 0.1143)
		(layer "In2.Cu")
		(net "85_5INCH_IN1_DP")
	)
	(segment
		(start 96.179132 58.375042)
		(end 95.8342 58.867294)
		(width 0.1143)
		(layer "In2.Cu")
		(net "85_5INCH_IN1_DP")
	)
	(segment
		(start 93.707204 59.242706)
		(end 93.522038 59.506866)
		(width 0.1143)
		(layer "In2.Cu")
		(net "85_5INCH_IN1_DP")
	)
	(segment
		(start 94.226888 84.90204)
		(end 96.443546 84.511134)
		(width 0.1143)
		(layer "In2.Cu")
		(net "85_5INCH_IN1_DP")
	)
	(segment
		(start 94.195646 104.9782)
		(end 96.477074 104.57561)
		(width 0.1143)
		(layer "In2.Cu")
		(net "85_5INCH_IN1_DP")
	)
	(segment
		(start 93.603318 63.506858)
		(end 93.809058 64.67348)
		(width 0.1143)
		(layer "In2.Cu")
		(net "85_5INCH_IN1_DP")
	)
	(segment
		(start 93.972126 96.757744)
		(end 94.236286 96.942656)
		(width 0.1143)
		(layer "In2.Cu")
		(net "85_5INCH_IN1_DP")
	)
	(segment
		(start 93.92158 99.34575)
		(end 93.736414 99.61118)
		(width 0.1143)
		(layer "In2.Cu")
		(net "85_5INCH_IN1_DP")
	)
	(segment
		(start 96.917256 72.816974)
		(end 97.17151 74.256392)
		(width 0.1143)
		(layer "In2.Cu")
		(net "85_5INCH_IN1_DP")
	)
	(segment
		(start 96.943926 88.868758)
		(end 97.198434 90.308176)
		(width 0.1143)
		(layer "In2.Cu")
		(net "85_5INCH_IN1_DP")
	)
	(segment
		(start 93.93301 72.679814)
		(end 94.197678 72.86498)
		(width 0.1143)
		(layer "In2.Cu")
		(net "85_5INCH_IN1_DP")
	)
	(segment
		(start 96.417638 96.5581)
		(end 96.909636 96.903794)
		(width 0.1143)
		(layer "In2.Cu")
		(net "85_5INCH_IN1_DP")
	)
	(segment
		(start 96.833182 78.762098)
		(end 93.939614 79.272384)
		(width 0.1143)
		(layer "In2.Cu")
		(net "85_5INCH_IN1_DP")
	)
	(segment
		(start 93.941646 83.285838)
		(end 93.75648 83.550506)
		(width 0.1143)
		(layer "In2.Cu")
		(net "85_5INCH_IN1_DP")
	)
	(segment
		(start 97.17151 74.256392)
		(end 96.826578 74.748644)
		(width 0.1143)
		(layer "In2.Cu")
		(net "85_5INCH_IN1_DP")
	)
	(segment
		(start 96.079056 107.245658)
		(end 96.079056 111.02467)
		(width 0.1143)
		(layer "In2.Cu")
		(net "85_5INCH_IN1_DP")
	)
	(segment
		(start 96.94672 60.7695)
		(end 97.17659 62.072266)
		(width 0.1143)
		(layer "In2.Cu")
		(net "85_5INCH_IN1_DP")
	)
	(segment
		(start 94.163642 68.85686)
		(end 96.446086 68.45427)
		(width 0.1143)
		(layer "In2.Cu")
		(net "85_5INCH_IN1_DP")
	)
	(segment
		(start 96.454722 60.424822)
		(end 96.94672 60.7695)
		(width 0.1143)
		(layer "In2.Cu")
		(net "85_5INCH_IN1_DP")
	)
	(segment
		(start 96.94799 100.910644)
		(end 97.202498 102.349808)
		(width 0.1143)
		(layer "In2.Cu")
		(net "85_5INCH_IN1_DP")
	)
	(segment
		(start 93.944694 88.734392)
		(end 94.208346 88.919812)
		(width 0.1143)
		(layer "In2.Cu")
		(net "85_5INCH_IN1_DP")
	)
	(segment
		(start 93.693234 67.505326)
		(end 93.898974 68.671694)
		(width 0.1143)
		(layer "In2.Cu")
		(net "85_5INCH_IN1_DP")
	)
	(segment
		(start 93.724984 103.626412)
		(end 93.931232 104.793034)
		(width 0.1143)
		(layer "In2.Cu")
		(net "85_5INCH_IN1_DP")
	)
	(segment
		(start 96.845882 66.717164)
		(end 93.8784 67.240658)
		(width 0.1143)
		(layer "In2.Cu")
		(net "85_5INCH_IN1_DP")
	)
	(segment
		(start 96.451928 88.52408)
		(end 96.943926 88.868758)
		(width 0.1143)
		(layer "In2.Cu")
		(net "85_5INCH_IN1_DP")
	)
	(segment
		(start 93.759274 91.578176)
		(end 93.965014 92.744544)
		(width 0.1143)
		(layer "In2.Cu")
		(net "85_5INCH_IN1_DP")
	)
	(segment
		(start 97.211642 82.277458)
		(end 96.86671 82.76971)
		(width 0.1143)
		(layer "In2.Cu")
		(net "85_5INCH_IN1_DP")
	)
	(segment
		(start 96.094296 55.117746)
		(end 96.094296 57.89676)
		(width 0.1143)
		(layer "In2.Cu")
		(net "85_5INCH_IN1_DP")
	)
	(segment
		(start 96.86671 82.76971)
		(end 93.941646 83.285838)
		(width 0.1143)
		(layer "In2.Cu")
		(net "85_5INCH_IN1_DP")
	)
	(segment
		(start 93.898974 68.671694)
		(end 94.163642 68.85686)
		(width 0.1143)
		(layer "In2.Cu")
		(net "85_5INCH_IN1_DP")
	)
	(segment
		(start 93.960188 80.703166)
		(end 94.224856 80.888332)
		(width 0.1143)
		(layer "In2.Cu")
		(net "85_5INCH_IN1_DP")
	)
	(segment
		(start 93.8784 67.240658)
		(end 93.693234 67.505326)
		(width 0.1143)
		(layer "In2.Cu")
		(net "85_5INCH_IN1_DP")
	)
	(segment
		(start 93.9927 60.858654)
		(end 96.454722 60.424822)
		(width 0.1143)
		(layer "In2.Cu")
		(net "85_5INCH_IN1_DP")
	)
	(segment
		(start 96.444562 64.440816)
		(end 96.93656 64.785494)
		(width 0.1143)
		(layer "In2.Cu")
		(net "85_5INCH_IN1_DP")
	)
	(segment
		(start 94.229682 92.92971)
		(end 96.399604 92.547186)
		(width 0.1143)
		(layer "In2.Cu")
		(net "85_5INCH_IN1_DP")
	)
	(segment
		(start 96.826578 74.748644)
		(end 93.938598 75.258168)
		(width 0.1143)
		(layer "In2.Cu")
		(net "85_5INCH_IN1_DP")
	)
	(segment
		(start 96.455738 100.565458)
		(end 96.94799 100.910644)
		(width 0.1143)
		(layer "In2.Cu")
		(net "85_5INCH_IN1_DP")
	)
	(segment
		(start 97.200974 62.208918)
		(end 96.856042 62.70117)
		(width 0.1143)
		(layer "In2.Cu")
		(net "85_5INCH_IN1_DP")
	)
	(segment
		(start 94.22384 76.87437)
		(end 96.432116 76.484988)
		(width 0.1143)
		(layer "In2.Cu")
		(net "85_5INCH_IN1_DP")
	)
	(segment
		(start 94.224856 80.888332)
		(end 96.46539 80.493108)
		(width 0.1143)
		(layer "In2.Cu")
		(net "85_5INCH_IN1_DP")
	)
	(segment
		(start 96.891602 92.892626)
		(end 97.14611 94.331536)
		(width 0.1143)
		(layer "In2.Cu")
		(net "85_5INCH_IN1_DP")
	)
	(segment
		(start 93.923358 87.302848)
		(end 93.738192 87.567516)
		(width 0.1143)
		(layer "In2.Cu")
		(net "85_5INCH_IN1_DP")
	)
	(segment
		(start 93.75648 83.550506)
		(end 93.96222 84.716874)
		(width 0.1143)
		(layer "In2.Cu")
		(net "85_5INCH_IN1_DP")
	)
	(segment
		(start 96.477074 104.57561)
		(end 96.969326 104.920796)
		(width 0.1143)
		(layer "In2.Cu")
		(net "85_5INCH_IN1_DP")
	)
	(segment
		(start 96.818704 98.834956)
		(end 93.92158 99.34575)
		(width 0.1143)
		(layer "In2.Cu")
		(net "85_5INCH_IN1_DP")
	)
	(segment
		(start 97.16643 66.08826)
		(end 97.166684 66.08826)
		(width 0.1143)
		(layer "In2.Cu")
		(net "85_5INCH_IN1_DP")
	)
	(segment
		(start 97.189544 86.295484)
		(end 96.844612 86.78799)
		(width 0.1143)
		(layer "In2.Cu")
		(net "85_5INCH_IN1_DP")
	)
	(segment
		(start 93.753432 75.522836)
		(end 93.959172 76.689204)
		(width 0.1143)
		(layer "In2.Cu")
		(net "85_5INCH_IN1_DP")
	)
	(segment
		(start 93.931232 104.793034)
		(end 94.195646 104.9782)
		(width 0.1143)
		(layer "In2.Cu")
		(net "85_5INCH_IN1_DP")
	)
	(segment
		(start 96.93656 64.785494)
		(end 97.16643 66.08826)
		(width 0.1143)
		(layer "In2.Cu")
		(net "85_5INCH_IN1_DP")
	)
	(segment
		(start 93.959172 76.689204)
		(end 94.22384 76.87437)
		(width 0.1143)
		(layer "In2.Cu")
		(net "85_5INCH_IN1_DP")
	)
	(segment
		(start 93.754448 79.536798)
		(end 93.960188 80.703166)
		(width 0.1143)
		(layer "In2.Cu")
		(net "85_5INCH_IN1_DP")
	)
	(segment
		(start 93.951044 95.326454)
		(end 93.765878 95.591884)
		(width 0.1143)
		(layer "In2.Cu")
		(net "85_5INCH_IN1_DP")
	)
	(segment
		(start 96.856042 62.70117)
		(end 93.788484 63.24219)
		(width 0.1143)
		(layer "In2.Cu")
		(net "85_5INCH_IN1_DP")
	)
	(via
		(at 95.479616 111.28883)
		(size 0.508)
		(drill 0.254)
		(layers "F.Cu" "B.Cu")
		(net "85_5INCH_IN1_DN")
	)
	(via
		(at 95.494856 54.853586)
		(size 0.508)
		(drill 0.254)
		(layers "F.Cu" "B.Cu")
		(net "85_5INCH_IN1_DN")
	)
	(segment
		(start 95.66148 111.941102)
		(end 95.479616 111.28883)
		(width 0.12954)
		(layer "B.Cu")
		(net "85_5INCH_IN1_DN")
	)
	(segment
		(start 95.67672 54.201314)
		(end 95.494856 54.853586)
		(width 0.12954)
		(layer "B.Cu")
		(net "85_5INCH_IN1_DN")
	)
	(segment
		(start 93.248734 63.428372)
		(end 93.502988 64.868552)
		(width 0.1143)
		(layer "In2.Cu")
		(net "85_5INCH_IN1_DN")
	)
	(segment
		(start 96.64954 86.481666)
		(end 93.728286 86.996778)
		(width 0.1143)
		(layer "In2.Cu")
		(net "85_5INCH_IN1_DN")
	)
	(segment
		(start 95.494856 54.853586)
		(end 95.759016 55.117746)
		(width 0.1143)
		(layer "In2.Cu")
		(net "85_5INCH_IN1_DN")
	)
	(segment
		(start 95.824548 58.296556)
		(end 95.639128 58.561224)
		(width 0.1143)
		(layer "In2.Cu")
		(net "85_5INCH_IN1_DN")
	)
	(segment
		(start 93.382084 99.532948)
		(end 93.636084 100.971604)
		(width 0.1143)
		(layer "In2.Cu")
		(net "85_5INCH_IN1_DN")
	)
	(segment
		(start 93.63837 88.92921)
		(end 94.129352 89.274396)
		(width 0.1143)
		(layer "In2.Cu")
		(net "85_5INCH_IN1_DN")
	)
	(segment
		(start 93.512132 58.936382)
		(end 93.167454 59.428126)
		(width 0.1143)
		(layer "In2.Cu")
		(net "85_5INCH_IN1_DN")
	)
	(segment
		(start 96.84639 62.130432)
		(end 96.66097 62.3951)
		(width 0.1143)
		(layer "In2.Cu")
		(net "85_5INCH_IN1_DN")
	)
	(segment
		(start 94.129352 89.274396)
		(end 96.373442 88.878664)
		(width 0.1143)
		(layer "In2.Cu")
		(net "85_5INCH_IN1_DN")
	)
	(segment
		(start 93.625162 104.988106)
		(end 94.11716 105.332784)
		(width 0.1143)
		(layer "In2.Cu")
		(net "85_5INCH_IN1_DN")
	)
	(segment
		(start 96.663002 105.115868)
		(end 96.868742 106.281474)
		(width 0.1143)
		(layer "In2.Cu")
		(net "85_5INCH_IN1_DN")
	)
	(segment
		(start 96.375982 60.779152)
		(end 96.640396 60.964572)
		(width 0.1143)
		(layer "In2.Cu")
		(net "85_5INCH_IN1_DN")
	)
	(segment
		(start 93.411548 95.513652)
		(end 93.666056 96.952816)
		(width 0.1143)
		(layer "In2.Cu")
		(net "85_5INCH_IN1_DN")
	)
	(segment
		(start 93.658944 92.939616)
		(end 94.151196 93.28404)
		(width 0.1143)
		(layer "In2.Cu")
		(net "85_5INCH_IN1_DN")
	)
	(segment
		(start 93.654118 80.898238)
		(end 94.14637 81.242662)
		(width 0.1143)
		(layer "In2.Cu")
		(net "85_5INCH_IN1_DN")
	)
	(segment
		(start 95.639128 58.561224)
		(end 93.512132 58.936382)
		(width 0.1143)
		(layer "In2.Cu")
		(net "85_5INCH_IN1_DN")
	)
	(segment
		(start 96.868742 106.281474)
		(end 96.683322 106.546142)
		(width 0.1143)
		(layer "In2.Cu")
		(net "85_5INCH_IN1_DN")
	)
	(segment
		(start 93.167454 59.428126)
		(end 93.421708 60.86856)
		(width 0.1143)
		(layer "In2.Cu")
		(net "85_5INCH_IN1_DN")
	)
	(segment
		(start 96.65843 90.494612)
		(end 93.749368 91.007692)
		(width 0.1143)
		(layer "In2.Cu")
		(net "85_5INCH_IN1_DN")
	)
	(segment
		(start 93.592904 68.866766)
		(end 94.085156 69.21119)
		(width 0.1143)
		(layer "In2.Cu")
		(net "85_5INCH_IN1_DN")
	)
	(segment
		(start 96.83623 66.146426)
		(end 96.65081 66.411094)
		(width 0.1143)
		(layer "In2.Cu")
		(net "85_5INCH_IN1_DN")
	)
	(segment
		(start 93.421708 60.86856)
		(end 93.914214 61.212984)
		(width 0.1143)
		(layer "In2.Cu")
		(net "85_5INCH_IN1_DN")
	)
	(segment
		(start 94.148402 85.25637)
		(end 96.364806 84.865718)
		(width 0.1143)
		(layer "In2.Cu")
		(net "85_5INCH_IN1_DN")
	)
	(segment
		(start 93.683328 66.934588)
		(end 93.33865 67.426586)
		(width 0.1143)
		(layer "In2.Cu")
		(net "85_5INCH_IN1_DN")
	)
	(segment
		(start 96.66097 62.3951)
		(end 93.593412 62.93612)
		(width 0.1143)
		(layer "In2.Cu")
		(net "85_5INCH_IN1_DN")
	)
	(segment
		(start 96.688402 93.669866)
		(end 96.791526 94.25305)
		(width 0.1143)
		(layer "In2.Cu")
		(net "85_5INCH_IN1_DN")
	)
	(segment
		(start 96.373442 88.878664)
		(end 96.637856 89.06383)
		(width 0.1143)
		(layer "In2.Cu")
		(net "85_5INCH_IN1_DN")
	)
	(segment
		(start 96.63176 68.994274)
		(end 96.837754 70.160134)
		(width 0.1143)
		(layer "In2.Cu")
		(net "85_5INCH_IN1_DN")
	)
	(segment
		(start 96.320864 92.90177)
		(end 96.585532 93.087444)
		(width 0.1143)
		(layer "In2.Cu")
		(net "85_5INCH_IN1_DN")
	)
	(segment
		(start 93.65615 84.911946)
		(end 94.148402 85.25637)
		(width 0.1143)
		(layer "In2.Cu")
		(net "85_5INCH_IN1_DN")
	)
	(segment
		(start 96.809052 98.264218)
		(end 96.623632 98.528632)
		(width 0.1143)
		(layer "In2.Cu")
		(net "85_5INCH_IN1_DN")
	)
	(segment
		(start 94.14637 81.242662)
		(end 96.38665 80.847692)
		(width 0.1143)
		(layer "In2.Cu")
		(net "85_5INCH_IN1_DN")
	)
	(segment
		(start 96.816926 74.177906)
		(end 96.631506 74.442574)
		(width 0.1143)
		(layer "In2.Cu")
		(net "85_5INCH_IN1_DN")
	)
	(segment
		(start 93.715078 103.055928)
		(end 93.3704 103.547926)
		(width 0.1143)
		(layer "In2.Cu")
		(net "85_5INCH_IN1_DN")
	)
	(segment
		(start 95.759016 57.926224)
		(end 95.824548 58.296556)
		(width 0.1143)
		(layer "In2.Cu")
		(net "85_5INCH_IN1_DN")
	)
	(segment
		(start 96.610932 73.012046)
		(end 96.816926 74.177906)
		(width 0.1143)
		(layer "In2.Cu")
		(net "85_5INCH_IN1_DN")
	)
	(segment
		(start 96.84385 90.22969)
		(end 96.65843 90.494612)
		(width 0.1143)
		(layer "In2.Cu")
		(net "85_5INCH_IN1_DN")
	)
	(segment
		(start 96.223074 106.627422)
		(end 95.743776 107.10672)
		(width 0.1143)
		(layer "In2.Cu")
		(net "85_5INCH_IN1_DN")
	)
	(segment
		(start 96.688148 93.669866)
		(end 96.688402 93.669866)
		(width 0.1143)
		(layer "In2.Cu")
		(net "85_5INCH_IN1_DN")
	)
	(segment
		(start 96.398334 104.930194)
		(end 96.663002 105.115868)
		(width 0.1143)
		(layer "In2.Cu")
		(net "85_5INCH_IN1_DN")
	)
	(segment
		(start 93.401896 83.471766)
		(end 93.65615 84.911946)
		(width 0.1143)
		(layer "In2.Cu")
		(net "85_5INCH_IN1_DN")
	)
	(segment
		(start 93.383608 87.48903)
		(end 93.63837 88.92921)
		(width 0.1143)
		(layer "In2.Cu")
		(net "85_5INCH_IN1_DN")
	)
	(segment
		(start 96.606106 94.517464)
		(end 93.755718 95.020384)
		(width 0.1143)
		(layer "In2.Cu")
		(net "85_5INCH_IN1_DN")
	)
	(segment
		(start 93.399864 79.458058)
		(end 93.654118 80.898238)
		(width 0.1143)
		(layer "In2.Cu")
		(net "85_5INCH_IN1_DN")
	)
	(segment
		(start 93.728286 86.996778)
		(end 93.383608 87.48903)
		(width 0.1143)
		(layer "In2.Cu")
		(net "85_5INCH_IN1_DN")
	)
	(segment
		(start 94.1578 97.296986)
		(end 96.338644 96.912684)
		(width 0.1143)
		(layer "In2.Cu")
		(net "85_5INCH_IN1_DN")
	)
	(segment
		(start 94.085156 69.21119)
		(end 96.367346 68.808854)
		(width 0.1143)
		(layer "In2.Cu")
		(net "85_5INCH_IN1_DN")
	)
	(segment
		(start 93.717364 70.942708)
		(end 93.372686 71.434706)
		(width 0.1143)
		(layer "In2.Cu")
		(net "85_5INCH_IN1_DN")
	)
	(segment
		(start 96.82353 78.191106)
		(end 96.63811 78.455774)
		(width 0.1143)
		(layer "In2.Cu")
		(net "85_5INCH_IN1_DN")
	)
	(segment
		(start 94.119192 73.21931)
		(end 96.346518 72.826626)
		(width 0.1143)
		(layer "In2.Cu")
		(net "85_5INCH_IN1_DN")
	)
	(segment
		(start 93.726254 99.03968)
		(end 93.382084 99.532948)
		(width 0.1143)
		(layer "In2.Cu")
		(net "85_5INCH_IN1_DN")
	)
	(segment
		(start 94.145354 77.2287)
		(end 96.353122 76.839572)
		(width 0.1143)
		(layer "In2.Cu")
		(net "85_5INCH_IN1_DN")
	)
	(segment
		(start 96.641666 101.105716)
		(end 96.847914 102.271322)
		(width 0.1143)
		(layer "In2.Cu")
		(net "85_5INCH_IN1_DN")
	)
	(segment
		(start 96.637856 89.06383)
		(end 96.84385 90.22969)
		(width 0.1143)
		(layer "In2.Cu")
		(net "85_5INCH_IN1_DN")
	)
	(segment
		(start 96.640396 60.964572)
		(end 96.84639 62.130432)
		(width 0.1143)
		(layer "In2.Cu")
		(net "85_5INCH_IN1_DN")
	)
	(segment
		(start 94.11716 105.332784)
		(end 96.398334 104.930194)
		(width 0.1143)
		(layer "In2.Cu")
		(net "85_5INCH_IN1_DN")
	)
	(segment
		(start 96.652334 70.424802)
		(end 93.717364 70.942708)
		(width 0.1143)
		(layer "In2.Cu")
		(net "85_5INCH_IN1_DN")
	)
	(segment
		(start 96.791526 94.25305)
		(end 96.606106 94.517464)
		(width 0.1143)
		(layer "In2.Cu")
		(net "85_5INCH_IN1_DN")
	)
	(segment
		(start 96.630236 64.980566)
		(end 96.83623 66.146426)
		(width 0.1143)
		(layer "In2.Cu")
		(net "85_5INCH_IN1_DN")
	)
	(segment
		(start 93.746574 82.979768)
		(end 93.401896 83.471766)
		(width 0.1143)
		(layer "In2.Cu")
		(net "85_5INCH_IN1_DN")
	)
	(segment
		(start 96.63811 78.455774)
		(end 93.744542 78.96606)
		(width 0.1143)
		(layer "In2.Cu")
		(net "85_5INCH_IN1_DN")
	)
	(segment
		(start 96.365822 64.795146)
		(end 96.630236 64.980566)
		(width 0.1143)
		(layer "In2.Cu")
		(net "85_5INCH_IN1_DN")
	)
	(segment
		(start 93.502988 64.868552)
		(end 93.994986 65.212976)
		(width 0.1143)
		(layer "In2.Cu")
		(net "85_5INCH_IN1_DN")
	)
	(segment
		(start 96.38665 80.847692)
		(end 96.651064 81.033112)
		(width 0.1143)
		(layer "In2.Cu")
		(net "85_5INCH_IN1_DN")
	)
	(segment
		(start 95.759016 55.117746)
		(end 95.759016 57.926224)
		(width 0.1143)
		(layer "In2.Cu")
		(net "85_5INCH_IN1_DN")
	)
	(segment
		(start 96.585532 93.087444)
		(end 96.688148 93.669866)
		(width 0.1143)
		(layer "In2.Cu")
		(net "85_5INCH_IN1_DN")
	)
	(segment
		(start 96.847914 102.271322)
		(end 96.662494 102.535482)
		(width 0.1143)
		(layer "In2.Cu")
		(net "85_5INCH_IN1_DN")
	)
	(segment
		(start 93.33865 67.426586)
		(end 93.592904 68.866766)
		(width 0.1143)
		(layer "In2.Cu")
		(net "85_5INCH_IN1_DN")
	)
	(segment
		(start 96.617536 77.025246)
		(end 96.82353 78.191106)
		(width 0.1143)
		(layer "In2.Cu")
		(net "85_5INCH_IN1_DN")
	)
	(segment
		(start 93.755718 95.020384)
		(end 93.411548 95.513652)
		(width 0.1143)
		(layer "In2.Cu")
		(net "85_5INCH_IN1_DN")
	)
	(segment
		(start 93.3704 103.547926)
		(end 93.625162 104.988106)
		(width 0.1143)
		(layer "In2.Cu")
		(net "85_5INCH_IN1_DN")
	)
	(segment
		(start 94.128082 101.316536)
		(end 96.376998 100.920042)
		(width 0.1143)
		(layer "In2.Cu")
		(net "85_5INCH_IN1_DN")
	)
	(segment
		(start 93.653102 76.884276)
		(end 94.145354 77.2287)
		(width 0.1143)
		(layer "In2.Cu")
		(net "85_5INCH_IN1_DN")
	)
	(segment
		(start 96.631506 74.442574)
		(end 93.743526 74.952098)
		(width 0.1143)
		(layer "In2.Cu")
		(net "85_5INCH_IN1_DN")
	)
	(segment
		(start 93.994986 65.212976)
		(end 96.365822 64.795146)
		(width 0.1143)
		(layer "In2.Cu")
		(net "85_5INCH_IN1_DN")
	)
	(segment
		(start 96.83496 86.216998)
		(end 96.64954 86.481666)
		(width 0.1143)
		(layer "In2.Cu")
		(net "85_5INCH_IN1_DN")
	)
	(segment
		(start 96.338644 96.912684)
		(end 96.603312 97.098612)
		(width 0.1143)
		(layer "In2.Cu")
		(net "85_5INCH_IN1_DN")
	)
	(segment
		(start 93.749368 91.007692)
		(end 93.40469 91.49969)
		(width 0.1143)
		(layer "In2.Cu")
		(net "85_5INCH_IN1_DN")
	)
	(segment
		(start 95.743776 107.10672)
		(end 95.743776 111.02467)
		(width 0.1143)
		(layer "In2.Cu")
		(net "85_5INCH_IN1_DN")
	)
	(segment
		(start 96.603312 97.098612)
		(end 96.809052 98.264218)
		(width 0.1143)
		(layer "In2.Cu")
		(net "85_5INCH_IN1_DN")
	)
	(segment
		(start 96.623632 98.528632)
		(end 93.726254 99.03968)
		(width 0.1143)
		(layer "In2.Cu")
		(net "85_5INCH_IN1_DN")
	)
	(segment
		(start 93.40469 91.49969)
		(end 93.658944 92.939616)
		(width 0.1143)
		(layer "In2.Cu")
		(net "85_5INCH_IN1_DN")
	)
	(segment
		(start 93.398848 75.444096)
		(end 93.653102 76.884276)
		(width 0.1143)
		(layer "In2.Cu")
		(net "85_5INCH_IN1_DN")
	)
	(segment
		(start 94.151196 93.28404)
		(end 96.320864 92.90177)
		(width 0.1143)
		(layer "In2.Cu")
		(net "85_5INCH_IN1_DN")
	)
	(segment
		(start 96.367346 68.808854)
		(end 96.63176 68.994274)
		(width 0.1143)
		(layer "In2.Cu")
		(net "85_5INCH_IN1_DN")
	)
	(segment
		(start 96.353122 76.839572)
		(end 96.617536 77.025246)
		(width 0.1143)
		(layer "In2.Cu")
		(net "85_5INCH_IN1_DN")
	)
	(segment
		(start 96.628966 85.051138)
		(end 96.83496 86.216998)
		(width 0.1143)
		(layer "In2.Cu")
		(net "85_5INCH_IN1_DN")
	)
	(segment
		(start 93.636084 100.971604)
		(end 94.128082 101.316536)
		(width 0.1143)
		(layer "In2.Cu")
		(net "85_5INCH_IN1_DN")
	)
	(segment
		(start 93.372686 71.434706)
		(end 93.62694 72.874886)
		(width 0.1143)
		(layer "In2.Cu")
		(net "85_5INCH_IN1_DN")
	)
	(segment
		(start 96.65081 66.411094)
		(end 93.683328 66.934588)
		(width 0.1143)
		(layer "In2.Cu")
		(net "85_5INCH_IN1_DN")
	)
	(segment
		(start 95.743776 111.02467)
		(end 95.479616 111.28883)
		(width 0.1143)
		(layer "In2.Cu")
		(net "85_5INCH_IN1_DN")
	)
	(segment
		(start 96.837754 70.160134)
		(end 96.652334 70.424802)
		(width 0.1143)
		(layer "In2.Cu")
		(net "85_5INCH_IN1_DN")
	)
	(segment
		(start 93.744542 78.96606)
		(end 93.399864 79.458058)
		(width 0.1143)
		(layer "In2.Cu")
		(net "85_5INCH_IN1_DN")
	)
	(segment
		(start 96.651064 81.033112)
		(end 96.857058 82.198972)
		(width 0.1143)
		(layer "In2.Cu")
		(net "85_5INCH_IN1_DN")
	)
	(segment
		(start 93.593412 62.93612)
		(end 93.248734 63.428372)
		(width 0.1143)
		(layer "In2.Cu")
		(net "85_5INCH_IN1_DN")
	)
	(segment
		(start 96.662494 102.535482)
		(end 93.715078 103.055928)
		(width 0.1143)
		(layer "In2.Cu")
		(net "85_5INCH_IN1_DN")
	)
	(segment
		(start 93.62694 72.874886)
		(end 94.119192 73.21931)
		(width 0.1143)
		(layer "In2.Cu")
		(net "85_5INCH_IN1_DN")
	)
	(segment
		(start 93.914214 61.212984)
		(end 96.375982 60.779152)
		(width 0.1143)
		(layer "In2.Cu")
		(net "85_5INCH_IN1_DN")
	)
	(segment
		(start 93.743526 74.952098)
		(end 93.398848 75.444096)
		(width 0.1143)
		(layer "In2.Cu")
		(net "85_5INCH_IN1_DN")
	)
	(segment
		(start 96.683322 106.546142)
		(end 96.223074 106.627422)
		(width 0.1143)
		(layer "In2.Cu")
		(net "85_5INCH_IN1_DN")
	)
	(segment
		(start 93.666056 96.952816)
		(end 94.1578 97.296986)
		(width 0.1143)
		(layer "In2.Cu")
		(net "85_5INCH_IN1_DN")
	)
	(segment
		(start 96.671638 82.46364)
		(end 93.746574 82.979768)
		(width 0.1143)
		(layer "In2.Cu")
		(net "85_5INCH_IN1_DN")
	)
	(segment
		(start 96.364806 84.865718)
		(end 96.628966 85.051138)
		(width 0.1143)
		(layer "In2.Cu")
		(net "85_5INCH_IN1_DN")
	)
	(segment
		(start 96.346518 72.826626)
		(end 96.610932 73.012046)
		(width 0.1143)
		(layer "In2.Cu")
		(net "85_5INCH_IN1_DN")
	)
	(segment
		(start 96.376998 100.920042)
		(end 96.641666 101.105716)
		(width 0.1143)
		(layer "In2.Cu")
		(net "85_5INCH_IN1_DN")
	)
	(segment
		(start 96.857058 82.198972)
		(end 96.671638 82.46364)
		(width 0.1143)
		(layer "In2.Cu")
		(net "85_5INCH_IN1_DN")
	)
	(segment
		(start 107.59567 -77.973936)
		(end 101.416104 -76.884022)
		(width 0.14224)
		(layer "B.Cu")
		(net "85_5INCH_BOT_DP")
	)
	(segment
		(start 107.98683 -75.754738)
		(end 108.392722 -76.333858)
		(width 0.14224)
		(layer "B.Cu")
		(net "85_5INCH_BOT_DP")
	)
	(segment
		(start 108.114084 -83.94192)
		(end 107.896152 -85.176106)
		(width 0.14224)
		(layer "B.Cu")
		(net "85_5INCH_BOT_DP")
	)
	(segment
		(start 102.476808 -96.214692)
		(end 102.147116 -96.445578)
		(width 0.14224)
		(layer "B.Cu")
		(net "85_5INCH_BOT_DP")
	)
	(segment
		(start 107.316778 -85.581998)
		(end 101.264974 -84.51469)
		(width 0.14224)
		(layer "B.Cu")
		(net "85_5INCH_BOT_DP")
	)
	(segment
		(start 104.072436 -103.78186)
		(end 104.072436 -103.93934)
		(width 0.14224)
		(layer "B.Cu")
		(net "85_5INCH_BOT_DP")
	)
	(segment
		(start 101.030278 -80.933544)
		(end 100.865432 -81.867756)
		(width 0.14224)
		(layer "B.Cu")
		(net "85_5INCH_BOT_DP")
	)
	(segment
		(start 100.935282 -84.745576)
		(end 100.770436 -85.679534)
		(width 0.14224)
		(layer "B.Cu")
		(net "85_5INCH_BOT_DP")
	)
	(segment
		(start 100.529644 -93.294454)
		(end 100.760276 -93.623384)
		(width 0.14224)
		(layer "B.Cu")
		(net "85_5INCH_BOT_DP")
	)
	(segment
		(start 101.151944 -78.377796)
		(end 107.9754 -79.581502)
		(width 0.14224)
		(layer "B.Cu")
		(net "85_5INCH_BOT_DP")
	)
	(segment
		(start 107.021884 -90.899488)
		(end 107.427776 -91.478608)
		(width 0.14224)
		(layer "B.Cu")
		(net "85_5INCH_BOT_DP")
	)
	(segment
		(start 100.770436 -85.679534)
		(end 101.001068 -86.008718)
		(width 0.14224)
		(layer "B.Cu")
		(net "85_5INCH_BOT_DP")
	)
	(segment
		(start 101.141784 -74.547222)
		(end 107.98683 -75.754738)
		(width 0.14224)
		(layer "B.Cu")
		(net "85_5INCH_BOT_DP")
	)
	(segment
		(start 107.427776 -91.478608)
		(end 107.209844 -92.712794)
		(width 0.14224)
		(layer "B.Cu")
		(net "85_5INCH_BOT_DP")
	)
	(segment
		(start 101.416104 -76.884022)
		(end 101.086412 -77.114654)
		(width 0.14224)
		(layer "B.Cu")
		(net "85_5INCH_BOT_DP")
	)
	(segment
		(start 104.286812 -98.581972)
		(end 104.00665 -100.168964)
		(width 0.14224)
		(layer "B.Cu")
		(net "85_5INCH_BOT_DP")
	)
	(segment
		(start 107.708192 -83.363054)
		(end 108.114084 -83.94192)
		(width 0.14224)
		(layer "B.Cu")
		(net "85_5INCH_BOT_DP")
	)
	(segment
		(start 103.88092 -98.002852)
		(end 104.286812 -98.581972)
		(width 0.14224)
		(layer "B.Cu")
		(net "85_5INCH_BOT_DP")
	)
	(segment
		(start 107.139232 -88.871552)
		(end 106.560112 -89.277444)
		(width 0.14224)
		(layer "B.Cu")
		(net "85_5INCH_BOT_DP")
	)
	(segment
		(start 107.575858 -74.141838)
		(end 101.40569 -73.053448)
		(width 0.14224)
		(layer "B.Cu")
		(net "85_5INCH_BOT_DP")
	)
	(segment
		(start 100.858066 -88.560656)
		(end 100.69322 -89.494614)
		(width 0.14224)
		(layer "B.Cu")
		(net "85_5INCH_BOT_DP")
	)
	(segment
		(start 108.17479 -77.568044)
		(end 107.59567 -77.973936)
		(width 0.14224)
		(layer "B.Cu")
		(net "85_5INCH_BOT_DP")
	)
	(segment
		(start 107.247182 -96.548194)
		(end 106.668316 -96.954086)
		(width 0.14224)
		(layer "B.Cu")
		(net "85_5INCH_BOT_DP")
	)
	(segment
		(start 108.154724 -73.735692)
		(end 107.575858 -74.141838)
		(width 0.14224)
		(layer "B.Cu")
		(net "85_5INCH_BOT_DP")
	)
	(segment
		(start 107.209844 -92.712794)
		(end 106.630724 -93.118686)
		(width 0.14224)
		(layer "B.Cu")
		(net "85_5INCH_BOT_DP")
	)
	(segment
		(start 107.357164 -87.637366)
		(end 107.139232 -88.871552)
		(width 0.14224)
		(layer "B.Cu")
		(net "85_5INCH_BOT_DP")
	)
	(segment
		(start 104.00665 -66.682366)
		(end 104.00665 -70.7771)
		(width 0.14224)
		(layer "B.Cu")
		(net "85_5INCH_BOT_DP")
	)
	(segment
		(start 101.096064 -82.196686)
		(end 107.708192 -83.363054)
		(width 0.14224)
		(layer "B.Cu")
		(net "85_5INCH_BOT_DP")
	)
	(segment
		(start 108.381292 -80.160622)
		(end 108.16336 -81.394808)
		(width 0.14224)
		(layer "B.Cu")
		(net "85_5INCH_BOT_DP")
	)
	(segment
		(start 101.35997 -80.702912)
		(end 101.030278 -80.933544)
		(width 0.14224)
		(layer "B.Cu")
		(net "85_5INCH_BOT_DP")
	)
	(segment
		(start 104.00665 -70.7771)
		(end 104.36352 -71.286624)
		(width 0.14224)
		(layer "B.Cu")
		(net "85_5INCH_BOT_DP")
	)
	(segment
		(start 101.264974 -84.51469)
		(end 100.935282 -84.745576)
		(width 0.14224)
		(layer "B.Cu")
		(net "85_5INCH_BOT_DP")
	)
	(segment
		(start 106.630724 -93.118686)
		(end 101.024182 -92.12961)
		(width 0.14224)
		(layer "B.Cu")
		(net "85_5INCH_BOT_DP")
	)
	(segment
		(start 104.00665 -100.168964)
		(end 104.00665 -103.716074)
		(width 0.14224)
		(layer "B.Cu")
		(net "85_5INCH_BOT_DP")
	)
	(segment
		(start 100.923852 -89.823544)
		(end 107.021884 -90.899488)
		(width 0.14224)
		(layer "B.Cu")
		(net "85_5INCH_BOT_DP")
	)
	(segment
		(start 107.059476 -94.734634)
		(end 107.465114 -95.314008)
		(width 0.14224)
		(layer "B.Cu")
		(net "85_5INCH_BOT_DP")
	)
	(segment
		(start 108.16336 -81.394808)
		(end 107.58424 -81.8007)
		(width 0.14224)
		(layer "B.Cu")
		(net "85_5INCH_BOT_DP")
	)
	(segment
		(start 108.392722 -76.333858)
		(end 108.17479 -77.568044)
		(width 0.14224)
		(layer "B.Cu")
		(net "85_5INCH_BOT_DP")
	)
	(segment
		(start 107.58424 -81.8007)
		(end 101.35997 -80.702912)
		(width 0.14224)
		(layer "B.Cu")
		(net "85_5INCH_BOT_DP")
	)
	(segment
		(start 101.188012 -88.32977)
		(end 100.858066 -88.560656)
		(width 0.14224)
		(layer "B.Cu")
		(net "85_5INCH_BOT_DP")
	)
	(segment
		(start 101.024182 -92.12961)
		(end 100.69449 -92.360496)
		(width 0.14224)
		(layer "B.Cu")
		(net "85_5INCH_BOT_DP")
	)
	(segment
		(start 107.966764 -71.92264)
		(end 108.372656 -72.501506)
		(width 0.14224)
		(layer "B.Cu")
		(net "85_5INCH_BOT_DP")
	)
	(segment
		(start 100.865432 -81.867756)
		(end 101.096064 -82.196686)
		(width 0.14224)
		(layer "B.Cu")
		(net "85_5INCH_BOT_DP")
	)
	(segment
		(start 108.372656 -72.501506)
		(end 108.154724 -73.735692)
		(width 0.14224)
		(layer "B.Cu")
		(net "85_5INCH_BOT_DP")
	)
	(segment
		(start 101.086412 -77.114654)
		(end 100.921566 -78.048866)
		(width 0.14224)
		(layer "B.Cu")
		(net "85_5INCH_BOT_DP")
	)
	(segment
		(start 104.072436 -66.4591)
		(end 104.072436 -66.61658)
		(width 0.14224)
		(layer "B.Cu")
		(net "85_5INCH_BOT_DP")
	)
	(segment
		(start 101.40569 -73.053448)
		(end 101.075998 -73.28408)
		(width 0.14224)
		(layer "B.Cu")
		(net "85_5INCH_BOT_DP")
	)
	(segment
		(start 104.36352 -71.286624)
		(end 107.966764 -71.92264)
		(width 0.14224)
		(layer "B.Cu")
		(net "85_5INCH_BOT_DP")
	)
	(segment
		(start 106.668316 -96.954086)
		(end 102.476808 -96.214692)
		(width 0.14224)
		(layer "B.Cu")
		(net "85_5INCH_BOT_DP")
	)
	(segment
		(start 107.9754 -79.581502)
		(end 108.381292 -80.160622)
		(width 0.14224)
		(layer "B.Cu")
		(net "85_5INCH_BOT_DP")
	)
	(segment
		(start 101.075998 -73.28408)
		(end 100.911152 -74.218292)
		(width 0.14224)
		(layer "B.Cu")
		(net "85_5INCH_BOT_DP")
	)
	(segment
		(start 101.001068 -86.008718)
		(end 106.951272 -87.058246)
		(width 0.14224)
		(layer "B.Cu")
		(net "85_5INCH_BOT_DP")
	)
	(segment
		(start 104.00665 -103.716074)
		(end 104.072436 -103.78186)
		(width 0.14224)
		(layer "B.Cu")
		(net "85_5INCH_BOT_DP")
	)
	(segment
		(start 106.951272 -87.058246)
		(end 107.357164 -87.637366)
		(width 0.14224)
		(layer "B.Cu")
		(net "85_5INCH_BOT_DP")
	)
	(segment
		(start 100.760276 -93.623384)
		(end 107.059476 -94.734634)
		(width 0.14224)
		(layer "B.Cu")
		(net "85_5INCH_BOT_DP")
	)
	(segment
		(start 100.911152 -74.218292)
		(end 101.141784 -74.547222)
		(width 0.14224)
		(layer "B.Cu")
		(net "85_5INCH_BOT_DP")
	)
	(segment
		(start 100.921566 -78.048866)
		(end 101.151944 -78.377796)
		(width 0.14224)
		(layer "B.Cu")
		(net "85_5INCH_BOT_DP")
	)
	(segment
		(start 107.465114 -95.314008)
		(end 107.247182 -96.548194)
		(width 0.14224)
		(layer "B.Cu")
		(net "85_5INCH_BOT_DP")
	)
	(segment
		(start 102.147116 -96.445578)
		(end 101.98227 -97.379536)
		(width 0.14224)
		(layer "B.Cu")
		(net "85_5INCH_BOT_DP")
	)
	(segment
		(start 101.98227 -97.379536)
		(end 102.212902 -97.70872)
		(width 0.14224)
		(layer "B.Cu")
		(net "85_5INCH_BOT_DP")
	)
	(segment
		(start 100.69322 -89.494614)
		(end 100.923852 -89.823544)
		(width 0.14224)
		(layer "B.Cu")
		(net "85_5INCH_BOT_DP")
	)
	(segment
		(start 106.560112 -89.277444)
		(end 101.188012 -88.32977)
		(width 0.14224)
		(layer "B.Cu")
		(net "85_5INCH_BOT_DP")
	)
	(segment
		(start 107.896152 -85.176106)
		(end 107.316778 -85.581998)
		(width 0.14224)
		(layer "B.Cu")
		(net "85_5INCH_BOT_DP")
	)
	(segment
		(start 104.072436 -66.61658)
		(end 104.00665 -66.682366)
		(width 0.14224)
		(layer "B.Cu")
		(net "85_5INCH_BOT_DP")
	)
	(segment
		(start 102.212902 -97.70872)
		(end 103.88092 -98.002852)
		(width 0.14224)
		(layer "B.Cu")
		(net "85_5INCH_BOT_DP")
	)
	(segment
		(start 100.69449 -92.360496)
		(end 100.529644 -93.294454)
		(width 0.14224)
		(layer "B.Cu")
		(net "85_5INCH_BOT_DP")
	)
	(segment
		(start 100.358194 -92.14612)
		(end 100.140262 -93.380814)
		(width 0.14224)
		(layer "B.Cu")
		(net "85_5INCH_BOT_DN")
	)
	(segment
		(start 107.49788 -81.411318)
		(end 101.27361 -80.31353)
		(width 0.14224)
		(layer "B.Cu")
		(net "85_5INCH_BOT_DN")
	)
	(segment
		(start 101.329744 -76.49464)
		(end 100.750116 -76.900278)
		(width 0.14224)
		(layer "B.Cu")
		(net "85_5INCH_BOT_DN")
	)
	(segment
		(start 107.99191 -80.246982)
		(end 107.827064 -81.180686)
		(width 0.14224)
		(layer "B.Cu")
		(net "85_5INCH_BOT_DN")
	)
	(segment
		(start 101.81082 -96.231202)
		(end 101.592888 -97.465896)
		(width 0.14224)
		(layer "B.Cu")
		(net "85_5INCH_BOT_DN")
	)
	(segment
		(start 100.303838 -89.580974)
		(end 100.70973 -90.15984)
		(width 0.14224)
		(layer "B.Cu")
		(net "85_5INCH_BOT_DN")
	)
	(segment
		(start 106.807762 -91.235784)
		(end 107.038394 -91.564968)
		(width 0.14224)
		(layer "B.Cu")
		(net "85_5INCH_BOT_DN")
	)
	(segment
		(start 106.581956 -96.564704)
		(end 102.390448 -95.82531)
		(width 0.14224)
		(layer "B.Cu")
		(net "85_5INCH_BOT_DN")
	)
	(segment
		(start 106.544364 -92.729304)
		(end 100.937822 -91.740228)
		(width 0.14224)
		(layer "B.Cu")
		(net "85_5INCH_BOT_DN")
	)
	(segment
		(start 107.50931 -77.584554)
		(end 101.329744 -76.49464)
		(width 0.14224)
		(layer "B.Cu")
		(net "85_5INCH_BOT_DN")
	)
	(segment
		(start 100.598986 -84.5312)
		(end 100.381054 -85.765894)
		(width 0.14224)
		(layer "B.Cu")
		(net "85_5INCH_BOT_DN")
	)
	(segment
		(start 103.63835 -103.716074)
		(end 103.572564 -103.78186)
		(width 0.14224)
		(layer "B.Cu")
		(net "85_5INCH_BOT_DN")
	)
	(segment
		(start 100.52177 -74.304652)
		(end 100.927662 -74.883518)
		(width 0.14224)
		(layer "B.Cu")
		(net "85_5INCH_BOT_DN")
	)
	(segment
		(start 107.818428 -73.52157)
		(end 107.489244 -73.752456)
		(width 0.14224)
		(layer "B.Cu")
		(net "85_5INCH_BOT_DN")
	)
	(segment
		(start 101.592888 -97.465896)
		(end 101.99878 -98.045016)
		(width 0.14224)
		(layer "B.Cu")
		(net "85_5INCH_BOT_DN")
	)
	(segment
		(start 107.038394 -91.564968)
		(end 106.873548 -92.498672)
		(width 0.14224)
		(layer "B.Cu")
		(net "85_5INCH_BOT_DN")
	)
	(segment
		(start 103.89743 -98.668332)
		(end 103.63835 -100.136706)
		(width 0.14224)
		(layer "B.Cu")
		(net "85_5INCH_BOT_DN")
	)
	(segment
		(start 100.546154 -93.95968)
		(end 106.8451 -95.07093)
		(width 0.14224)
		(layer "B.Cu")
		(net "85_5INCH_BOT_DN")
	)
	(segment
		(start 103.572564 -66.61658)
		(end 103.63835 -66.682366)
		(width 0.14224)
		(layer "B.Cu")
		(net "85_5INCH_BOT_DN")
	)
	(segment
		(start 104.149398 -71.62292)
		(end 107.752642 -72.258936)
		(width 0.14224)
		(layer "B.Cu")
		(net "85_5INCH_BOT_DN")
	)
	(segment
		(start 100.532184 -78.135226)
		(end 100.937822 -78.714092)
		(width 0.14224)
		(layer "B.Cu")
		(net "85_5INCH_BOT_DN")
	)
	(segment
		(start 103.572564 -103.78186)
		(end 103.572564 -103.93934)
		(width 0.14224)
		(layer "B.Cu")
		(net "85_5INCH_BOT_DN")
	)
	(segment
		(start 107.489244 -73.752456)
		(end 101.31933 -72.664066)
		(width 0.14224)
		(layer "B.Cu")
		(net "85_5INCH_BOT_DN")
	)
	(segment
		(start 100.47605 -81.95437)
		(end 100.881942 -82.532982)
		(width 0.14224)
		(layer "B.Cu")
		(net "85_5INCH_BOT_DN")
	)
	(segment
		(start 100.52177 -88.34628)
		(end 100.303838 -89.580974)
		(width 0.14224)
		(layer "B.Cu")
		(net "85_5INCH_BOT_DN")
	)
	(segment
		(start 103.572564 -66.4591)
		(end 103.572564 -66.61658)
		(width 0.14224)
		(layer "B.Cu")
		(net "85_5INCH_BOT_DN")
	)
	(segment
		(start 101.27361 -80.31353)
		(end 100.693982 -80.719168)
		(width 0.14224)
		(layer "B.Cu")
		(net "85_5INCH_BOT_DN")
	)
	(segment
		(start 100.693982 -80.719168)
		(end 100.47605 -81.95437)
		(width 0.14224)
		(layer "B.Cu")
		(net "85_5INCH_BOT_DN")
	)
	(segment
		(start 100.937822 -78.714092)
		(end 107.761278 -79.917798)
		(width 0.14224)
		(layer "B.Cu")
		(net "85_5INCH_BOT_DN")
	)
	(segment
		(start 100.937822 -91.740228)
		(end 100.358194 -92.14612)
		(width 0.14224)
		(layer "B.Cu")
		(net "85_5INCH_BOT_DN")
	)
	(segment
		(start 101.31933 -72.664066)
		(end 100.739702 -73.069704)
		(width 0.14224)
		(layer "B.Cu")
		(net "85_5INCH_BOT_DN")
	)
	(segment
		(start 106.73715 -87.394542)
		(end 106.967782 -87.723726)
		(width 0.14224)
		(layer "B.Cu")
		(net "85_5INCH_BOT_DN")
	)
	(segment
		(start 107.49407 -83.69935)
		(end 107.724702 -84.02828)
		(width 0.14224)
		(layer "B.Cu")
		(net "85_5INCH_BOT_DN")
	)
	(segment
		(start 107.559856 -84.961984)
		(end 107.230418 -85.192616)
		(width 0.14224)
		(layer "B.Cu")
		(net "85_5INCH_BOT_DN")
	)
	(segment
		(start 100.881942 -82.532982)
		(end 107.49407 -83.69935)
		(width 0.14224)
		(layer "B.Cu")
		(net "85_5INCH_BOT_DN")
	)
	(segment
		(start 100.70973 -90.15984)
		(end 106.807762 -91.235784)
		(width 0.14224)
		(layer "B.Cu")
		(net "85_5INCH_BOT_DN")
	)
	(segment
		(start 107.752642 -72.258936)
		(end 107.983274 -72.587866)
		(width 0.14224)
		(layer "B.Cu")
		(net "85_5INCH_BOT_DN")
	)
	(segment
		(start 100.786946 -86.345014)
		(end 106.73715 -87.394542)
		(width 0.14224)
		(layer "B.Cu")
		(net "85_5INCH_BOT_DN")
	)
	(segment
		(start 100.927662 -74.883518)
		(end 107.772708 -76.091034)
		(width 0.14224)
		(layer "B.Cu")
		(net "85_5INCH_BOT_DN")
	)
	(segment
		(start 103.63835 -66.682366)
		(end 103.63835 -70.893432)
		(width 0.14224)
		(layer "B.Cu")
		(net "85_5INCH_BOT_DN")
	)
	(segment
		(start 103.666798 -98.339148)
		(end 103.89743 -98.668332)
		(width 0.14224)
		(layer "B.Cu")
		(net "85_5INCH_BOT_DN")
	)
	(segment
		(start 107.772708 -76.091034)
		(end 108.00334 -76.420218)
		(width 0.14224)
		(layer "B.Cu")
		(net "85_5INCH_BOT_DN")
	)
	(segment
		(start 106.802936 -88.65743)
		(end 106.473752 -88.888062)
		(width 0.14224)
		(layer "B.Cu")
		(net "85_5INCH_BOT_DN")
	)
	(segment
		(start 106.910886 -96.334072)
		(end 106.581956 -96.564704)
		(width 0.14224)
		(layer "B.Cu")
		(net "85_5INCH_BOT_DN")
	)
	(segment
		(start 107.827064 -81.180686)
		(end 107.49788 -81.411318)
		(width 0.14224)
		(layer "B.Cu")
		(net "85_5INCH_BOT_DN")
	)
	(segment
		(start 100.381054 -85.765894)
		(end 100.786946 -86.345014)
		(width 0.14224)
		(layer "B.Cu")
		(net "85_5INCH_BOT_DN")
	)
	(segment
		(start 107.075732 -95.400368)
		(end 106.910886 -96.334072)
		(width 0.14224)
		(layer "B.Cu")
		(net "85_5INCH_BOT_DN")
	)
	(segment
		(start 106.8451 -95.07093)
		(end 107.075732 -95.400368)
		(width 0.14224)
		(layer "B.Cu")
		(net "85_5INCH_BOT_DN")
	)
	(segment
		(start 103.63835 -70.893432)
		(end 104.149398 -71.62292)
		(width 0.14224)
		(layer "B.Cu")
		(net "85_5INCH_BOT_DN")
	)
	(segment
		(start 107.983274 -72.587866)
		(end 107.818428 -73.52157)
		(width 0.14224)
		(layer "B.Cu")
		(net "85_5INCH_BOT_DN")
	)
	(segment
		(start 107.838494 -77.353922)
		(end 107.50931 -77.584554)
		(width 0.14224)
		(layer "B.Cu")
		(net "85_5INCH_BOT_DN")
	)
	(segment
		(start 101.178614 -84.125308)
		(end 100.598986 -84.5312)
		(width 0.14224)
		(layer "B.Cu")
		(net "85_5INCH_BOT_DN")
	)
	(segment
		(start 107.724702 -84.02828)
		(end 107.559856 -84.961984)
		(width 0.14224)
		(layer "B.Cu")
		(net "85_5INCH_BOT_DN")
	)
	(segment
		(start 106.967782 -87.723726)
		(end 106.802936 -88.65743)
		(width 0.14224)
		(layer "B.Cu")
		(net "85_5INCH_BOT_DN")
	)
	(segment
		(start 106.873548 -92.498672)
		(end 106.544364 -92.729304)
		(width 0.14224)
		(layer "B.Cu")
		(net "85_5INCH_BOT_DN")
	)
	(segment
		(start 100.140262 -93.380814)
		(end 100.546154 -93.95968)
		(width 0.14224)
		(layer "B.Cu")
		(net "85_5INCH_BOT_DN")
	)
	(segment
		(start 103.63835 -100.136706)
		(end 103.63835 -103.716074)
		(width 0.14224)
		(layer "B.Cu")
		(net "85_5INCH_BOT_DN")
	)
	(segment
		(start 102.390448 -95.82531)
		(end 101.81082 -96.231202)
		(width 0.14224)
		(layer "B.Cu")
		(net "85_5INCH_BOT_DN")
	)
	(segment
		(start 107.761278 -79.917798)
		(end 107.99191 -80.246982)
		(width 0.14224)
		(layer "B.Cu")
		(net "85_5INCH_BOT_DN")
	)
	(segment
		(start 106.473752 -88.888062)
		(end 101.101652 -87.940388)
		(width 0.14224)
		(layer "B.Cu")
		(net "85_5INCH_BOT_DN")
	)
	(segment
		(start 100.750116 -76.900278)
		(end 100.532184 -78.135226)
		(width 0.14224)
		(layer "B.Cu")
		(net "85_5INCH_BOT_DN")
	)
	(segment
		(start 101.101652 -87.940388)
		(end 100.52177 -88.34628)
		(width 0.14224)
		(layer "B.Cu")
		(net "85_5INCH_BOT_DN")
	)
	(segment
		(start 101.99878 -98.045016)
		(end 103.666798 -98.339148)
		(width 0.14224)
		(layer "B.Cu")
		(net "85_5INCH_BOT_DN")
	)
	(segment
		(start 108.00334 -76.420218)
		(end 107.838494 -77.353922)
		(width 0.14224)
		(layer "B.Cu")
		(net "85_5INCH_BOT_DN")
	)
	(segment
		(start 107.230418 -85.192616)
		(end 101.178614 -84.125308)
		(width 0.14224)
		(layer "B.Cu")
		(net "85_5INCH_BOT_DN")
	)
	(segment
		(start 100.739702 -73.069704)
		(end 100.52177 -74.304652)
		(width 0.14224)
		(layer "B.Cu")
		(net "85_5INCH_BOT_DN")
	)
	(segment
		(start 39.482014 -69.9262)
		(end 39.482014 -69.522594)
		(width 0.11684)
		(layer "F.Cu")
		(net "SYS_BMC_PWRBTN_R_N")
	)
	(segment
		(start 39.355014 -70.0532)
		(end 39.482014 -69.9262)
		(width 0.11684)
		(layer "F.Cu")
		(net "SYS_BMC_PWRBTN_R_N")
	)
	(segment
		(start 38.70452 -70.0532)
		(end 39.355014 -70.0532)
		(width 0.11684)
		(layer "F.Cu")
		(net "SYS_BMC_PWRBTN_R_N")
	)
	(segment
		(start 38.16096 -70.59676)
		(end 38.70452 -70.0532)
		(width 0.11684)
		(layer "F.Cu")
		(net "SYS_BMC_PWRBTN_R_N")
	)
	(via
		(at 38.16096 -70.59676)
		(size 0.508)
		(drill 0.254)
		(layers "F.Cu" "B.Cu")
		(net "SYS_BMC_PWRBTN_R_N")
	)
	(via
		(at 37.3761 -69.342)
		(size 0.6604)
		(drill 0.3302)
		(layers "F.Cu" "B.Cu")
		(net "SYS_BMC_PWRBTN_R_N")
	)
	(segment
		(start 37.3761 -69.342)
		(end 37.3761 -69.8119)
		(width 0.11684)
		(layer "B.Cu")
		(net "SYS_BMC_PWRBTN_R_N")
	)
	(segment
		(start 37.592 -62.21476)
		(end 37.592 -67.61226)
		(width 0.11684)
		(layer "B.Cu")
		(net "SYS_BMC_PWRBTN_R_N")
	)
	(segment
		(start 38.497764 -61.589666)
		(end 38.28923 -61.381132)
		(width 0.11684)
		(layer "B.Cu")
		(net "SYS_BMC_PWRBTN_R_N")
	)
	(segment
		(start 39.247064 -61.627766)
		(end 38.83279 -61.627766)
		(width 0.11684)
		(layer "B.Cu")
		(net "SYS_BMC_PWRBTN_R_N")
	)
	(segment
		(start 38.28923 -61.381132)
		(end 37.840412 -61.381132)
		(width 0.11684)
		(layer "B.Cu")
		(net "SYS_BMC_PWRBTN_R_N")
	)
	(segment
		(start 37.592 -67.61226)
		(end 37.3761 -67.82816)
		(width 0.11684)
		(layer "B.Cu")
		(net "SYS_BMC_PWRBTN_R_N")
	)
	(segment
		(start 37.389308 -61.832236)
		(end 37.389308 -62.012068)
		(width 0.11684)
		(layer "B.Cu")
		(net "SYS_BMC_PWRBTN_R_N")
	)
	(segment
		(start 37.3761 -67.82816)
		(end 37.3761 -69.342)
		(width 0.11684)
		(layer "B.Cu")
		(net "SYS_BMC_PWRBTN_R_N")
	)
	(segment
		(start 38.79469 -61.589666)
		(end 38.497764 -61.589666)
		(width 0.11684)
		(layer "B.Cu")
		(net "SYS_BMC_PWRBTN_R_N")
	)
	(segment
		(start 37.840412 -61.381132)
		(end 37.389308 -61.832236)
		(width 0.11684)
		(layer "B.Cu")
		(net "SYS_BMC_PWRBTN_R_N")
	)
	(segment
		(start 37.389308 -62.012068)
		(end 37.592 -62.21476)
		(width 0.11684)
		(layer "B.Cu")
		(net "SYS_BMC_PWRBTN_R_N")
	)
	(segment
		(start 37.3761 -69.8119)
		(end 38.16096 -70.59676)
		(width 0.11684)
		(layer "B.Cu")
		(net "SYS_BMC_PWRBTN_R_N")
	)
	(segment
		(start 38.83279 -61.627766)
		(end 38.79469 -61.589666)
		(width 0.11684)
		(layer "B.Cu")
		(net "SYS_BMC_PWRBTN_R_N")
	)
	(segment
		(start 61.70676 -68.199)
		(end 61.70676 -66.431414)
		(width 0.11684)
		(layer "F.Cu")
		(net "SPI_BMC_BIOS_CS0_N")
	)
	(via
		(at 61.70676 -68.199)
		(size 0.508)
		(drill 0.254)
		(layers "F.Cu" "B.Cu")
		(net "SPI_BMC_BIOS_CS0_N")
	)
	(via
		(at 62.972442 -80.3656)
		(size 0.508)
		(drill 0.254)
		(layers "F.Cu" "B.Cu")
		(net "SPI_BMC_BIOS_CS0_N")
	)
	(via
		(at 35.4076 -99.68484)
		(size 0.508)
		(drill 0.254)
		(layers "F.Cu" "B.Cu")
		(net "SPI_BMC_BIOS_CS0_N")
	)
	(via
		(at 35.8013 -99.0727)
		(size 0.6604)
		(drill 0.3302)
		(layers "F.Cu" "B.Cu")
		(net "SPI_BMC_BIOS_CS0_N")
	)
	(via
		(at 60.11418 -100.2157)
		(size 0.508)
		(drill 0.254)
		(layers "F.Cu" "B.Cu")
		(net "SPI_BMC_BIOS_CS0_N")
	)
	(segment
		(start 37.00145 -99.568)
		(end 36.50615 -99.0727)
		(width 0.11684)
		(layer "B.Cu")
		(net "SPI_BMC_BIOS_CS0_N")
	)
	(segment
		(start 36.50615 -99.0727)
		(end 35.8013 -99.0727)
		(width 0.11684)
		(layer "B.Cu")
		(net "SPI_BMC_BIOS_CS0_N")
	)
	(segment
		(start 35.4076 -99.4664)
		(end 35.4076 -99.68484)
		(width 0.11684)
		(layer "B.Cu")
		(net "SPI_BMC_BIOS_CS0_N")
	)
	(segment
		(start 35.8013 -99.0727)
		(end 35.4076 -99.4664)
		(width 0.11684)
		(layer "B.Cu")
		(net "SPI_BMC_BIOS_CS0_N")
	)
	(segment
		(start 35.4076 -99.68484)
		(end 35.54349 -99.54895)
		(width 0.08382)
		(layer "In2.Cu")
		(net "SPI_BMC_BIOS_CS0_N")
	)
	(segment
		(start 35.54349 -99.54895)
		(end 36.474908 -99.54895)
		(width 0.08382)
		(layer "In2.Cu")
		(net "SPI_BMC_BIOS_CS0_N")
	)
	(segment
		(start 59.7535 -100.2157)
		(end 60.11418 -100.2157)
		(width 0.08382)
		(layer "In2.Cu")
		(net "SPI_BMC_BIOS_CS0_N")
	)
	(segment
		(start 37.455856 -100.529898)
		(end 45.393102 -100.529898)
		(width 0.08382)
		(layer "In2.Cu")
		(net "SPI_BMC_BIOS_CS0_N")
	)
	(segment
		(start 53.54574 -97.28962)
		(end 56.26354 -100.00742)
		(width 0.08382)
		(layer "In2.Cu")
		(net "SPI_BMC_BIOS_CS0_N")
	)
	(segment
		(start 56.26354 -100.00742)
		(end 59.54522 -100.00742)
		(width 0.08382)
		(layer "In2.Cu")
		(net "SPI_BMC_BIOS_CS0_N")
	)
	(segment
		(start 45.393102 -100.529898)
		(end 48.633126 -97.289874)
		(width 0.08382)
		(layer "In2.Cu")
		(net "SPI_BMC_BIOS_CS0_N")
	)
	(segment
		(start 59.54522 -100.00742)
		(end 59.7535 -100.2157)
		(width 0.08382)
		(layer "In2.Cu")
		(net "SPI_BMC_BIOS_CS0_N")
	)
	(segment
		(start 48.633888 -97.28962)
		(end 53.54574 -97.28962)
		(width 0.08382)
		(layer "In2.Cu")
		(net "SPI_BMC_BIOS_CS0_N")
	)
	(segment
		(start 48.633126 -97.289874)
		(end 48.633888 -97.28962)
		(width 0.08382)
		(layer "In2.Cu")
		(net "SPI_BMC_BIOS_CS0_N")
	)
	(segment
		(start 36.474908 -99.54895)
		(end 37.455856 -100.529898)
		(width 0.08382)
		(layer "In2.Cu")
		(net "SPI_BMC_BIOS_CS0_N")
	)
	(segment
		(start 62.865 -84.893404)
		(end 62.84976 -84.908644)
		(width 0.10668)
		(layer "In4.Cu")
		(net "SPI_BMC_BIOS_CS0_N")
	)
	(segment
		(start 62.972442 -84.344764)
		(end 62.865 -84.604098)
		(width 0.10668)
		(layer "In4.Cu")
		(net "SPI_BMC_BIOS_CS0_N")
	)
	(segment
		(start 62.84976 -95.602044)
		(end 62.409324 -96.04248)
		(width 0.10668)
		(layer "In4.Cu")
		(net "SPI_BMC_BIOS_CS0_N")
	)
	(segment
		(start 62.972442 -82.124296)
		(end 62.972442 -84.344764)
		(width 0.10668)
		(layer "In4.Cu")
		(net "SPI_BMC_BIOS_CS0_N")
	)
	(segment
		(start 63.5 -80.893158)
		(end 63.5 -81.596738)
		(width 0.10668)
		(layer "In4.Cu")
		(net "SPI_BMC_BIOS_CS0_N")
	)
	(segment
		(start 61.33846 -98.443542)
		(end 60.11418 -99.667822)
		(width 0.10668)
		(layer "In4.Cu")
		(net "SPI_BMC_BIOS_CS0_N")
	)
	(segment
		(start 61.989462 -96.04248)
		(end 61.33846 -96.693482)
		(width 0.10668)
		(layer "In4.Cu")
		(net "SPI_BMC_BIOS_CS0_N")
	)
	(segment
		(start 60.11418 -99.667822)
		(end 60.11418 -100.2157)
		(width 0.10668)
		(layer "In4.Cu")
		(net "SPI_BMC_BIOS_CS0_N")
	)
	(segment
		(start 62.972442 -80.3656)
		(end 63.5 -80.893158)
		(width 0.10668)
		(layer "In4.Cu")
		(net "SPI_BMC_BIOS_CS0_N")
	)
	(segment
		(start 62.409324 -96.04248)
		(end 61.989462 -96.04248)
		(width 0.10668)
		(layer "In4.Cu")
		(net "SPI_BMC_BIOS_CS0_N")
	)
	(segment
		(start 61.33846 -96.693482)
		(end 61.33846 -98.443542)
		(width 0.10668)
		(layer "In4.Cu")
		(net "SPI_BMC_BIOS_CS0_N")
	)
	(segment
		(start 63.5 -81.596738)
		(end 62.972442 -82.124296)
		(width 0.10668)
		(layer "In4.Cu")
		(net "SPI_BMC_BIOS_CS0_N")
	)
	(segment
		(start 62.865 -84.604098)
		(end 62.865 -84.893404)
		(width 0.10668)
		(layer "In4.Cu")
		(net "SPI_BMC_BIOS_CS0_N")
	)
	(segment
		(start 62.84976 -84.908644)
		(end 62.84976 -95.602044)
		(width 0.10668)
		(layer "In4.Cu")
		(net "SPI_BMC_BIOS_CS0_N")
	)
	(segment
		(start 63.77178 -78.69682)
		(end 63.77178 -79.839566)
		(width 0.08382)
		(layer "In9.Cu")
		(net "SPI_BMC_BIOS_CS0_N")
	)
	(segment
		(start 63.77178 -73.733152)
		(end 63.77178 -76.3778)
		(width 0.08382)
		(layer "In9.Cu")
		(net "SPI_BMC_BIOS_CS0_N")
	)
	(segment
		(start 62.51956 -69.700902)
		(end 62.51956 -69.721984)
		(width 0.08382)
		(layer "In9.Cu")
		(net "SPI_BMC_BIOS_CS0_N")
	)
	(segment
		(start 62.054994 -68.579238)
		(end 62.51956 -69.700902)
		(width 0.08382)
		(layer "In9.Cu")
		(net "SPI_BMC_BIOS_CS0_N")
	)
	(segment
		(start 64.563244 -77.905356)
		(end 63.77178 -78.69682)
		(width 0.08382)
		(layer "In9.Cu")
		(net "SPI_BMC_BIOS_CS0_N")
	)
	(segment
		(start 62.51956 -69.721984)
		(end 62.536832 -69.721984)
		(width 0.08382)
		(layer "In9.Cu")
		(net "SPI_BMC_BIOS_CS0_N")
	)
	(segment
		(start 63.77178 -76.3778)
		(end 64.563244 -77.169264)
		(width 0.08382)
		(layer "In9.Cu")
		(net "SPI_BMC_BIOS_CS0_N")
	)
	(segment
		(start 61.70676 -68.231004)
		(end 62.054994 -68.579238)
		(width 0.08382)
		(layer "In9.Cu")
		(net "SPI_BMC_BIOS_CS0_N")
	)
	(segment
		(start 64.563244 -77.169264)
		(end 64.563244 -77.905356)
		(width 0.08382)
		(layer "In9.Cu")
		(net "SPI_BMC_BIOS_CS0_N")
	)
	(segment
		(start 61.70676 -68.199)
		(end 61.70676 -68.231004)
		(width 0.08382)
		(layer "In9.Cu")
		(net "SPI_BMC_BIOS_CS0_N")
	)
	(segment
		(start 62.536832 -69.721984)
		(end 63.40602 -70.591172)
		(width 0.08382)
		(layer "In9.Cu")
		(net "SPI_BMC_BIOS_CS0_N")
	)
	(segment
		(start 63.40602 -73.367392)
		(end 63.77178 -73.733152)
		(width 0.08382)
		(layer "In9.Cu")
		(net "SPI_BMC_BIOS_CS0_N")
	)
	(segment
		(start 63.245746 -80.3656)
		(end 62.972442 -80.3656)
		(width 0.08382)
		(layer "In9.Cu")
		(net "SPI_BMC_BIOS_CS0_N")
	)
	(segment
		(start 63.40602 -70.591172)
		(end 63.40602 -73.367392)
		(width 0.08382)
		(layer "In9.Cu")
		(net "SPI_BMC_BIOS_CS0_N")
	)
	(segment
		(start 63.77178 -79.839566)
		(end 63.245746 -80.3656)
		(width 0.08382)
		(layer "In9.Cu")
		(net "SPI_BMC_BIOS_CS0_N")
	)
	(segment
		(start 33.0708 -87.3252)
		(end 36.5506 -87.3252)
		(width 0.11684)
		(layer "F.Cu")
		(net "FM_BMC_ONCTL_R_N")
	)
	(segment
		(start 30.5308 -93.4466)
		(end 31.2674 -93.4466)
		(width 0.11684)
		(layer "F.Cu")
		(net "FM_BMC_ONCTL_R_N")
	)
	(segment
		(start 39.090854 -87.6046)
		(end 39.4462 -87.249254)
		(width 0.11684)
		(layer "F.Cu")
		(net "FM_BMC_ONCTL_R_N")
	)
	(segment
		(start 17.464278 -95.982282)
		(end 17.859502 -95.587058)
		(width 0.11684)
		(layer "F.Cu")
		(net "FM_BMC_ONCTL_R_N")
	)
	(segment
		(start 32.6898 -91.180666)
		(end 32.6898 -87.7062)
		(width 0.11684)
		(layer "F.Cu")
		(net "FM_BMC_ONCTL_R_N")
	)
	(segment
		(start 39.4462 -87.249254)
		(end 39.4462 -86.4362)
		(width 0.11684)
		(layer "F.Cu")
		(net "FM_BMC_ONCTL_R_N")
	)
	(segment
		(start 36.83 -87.6046)
		(end 39.090854 -87.6046)
		(width 0.11684)
		(layer "F.Cu")
		(net "FM_BMC_ONCTL_R_N")
	)
	(segment
		(start 39.4462 -86.4362)
		(end 40.4622 -85.4202)
		(width 0.11684)
		(layer "F.Cu")
		(net "FM_BMC_ONCTL_R_N")
	)
	(segment
		(start 40.4622 -82.6516)
		(end 39.37 -81.5594)
		(width 0.11684)
		(layer "F.Cu")
		(net "FM_BMC_ONCTL_R_N")
	)
	(segment
		(start 29.82214 -94.15526)
		(end 30.5308 -93.4466)
		(width 0.11684)
		(layer "F.Cu")
		(net "FM_BMC_ONCTL_R_N")
	)
	(segment
		(start 29.82214 -96.8629)
		(end 29.82214 -94.15526)
		(width 0.11684)
		(layer "F.Cu")
		(net "FM_BMC_ONCTL_R_N")
	)
	(segment
		(start 36.5506 -87.3252)
		(end 36.83 -87.6046)
		(width 0.11684)
		(layer "F.Cu")
		(net "FM_BMC_ONCTL_R_N")
	)
	(segment
		(start 31.2674 -93.4466)
		(end 32.31896 -92.39504)
		(width 0.11684)
		(layer "F.Cu")
		(net "FM_BMC_ONCTL_R_N")
	)
	(segment
		(start 32.6898 -87.7062)
		(end 33.0708 -87.3252)
		(width 0.11684)
		(layer "F.Cu")
		(net "FM_BMC_ONCTL_R_N")
	)
	(segment
		(start 32.31896 -92.39504)
		(end 32.31896 -91.551506)
		(width 0.11684)
		(layer "F.Cu")
		(net "FM_BMC_ONCTL_R_N")
	)
	(segment
		(start 32.31896 -91.551506)
		(end 32.6898 -91.180666)
		(width 0.11684)
		(layer "F.Cu")
		(net "FM_BMC_ONCTL_R_N")
	)
	(segment
		(start 40.4622 -85.4202)
		(end 40.4622 -82.6516)
		(width 0.11684)
		(layer "F.Cu")
		(net "FM_BMC_ONCTL_R_N")
	)
	(segment
		(start 53.695092 -56.971184)
		(end 53.299868 -57.366408)
		(width 0.11684)
		(layer "F.Cu")
		(net "FM_BMC_ONCTL_R_N")
	)
	(via
		(at 20.00758 -73.839832)
		(size 0.508)
		(drill 0.254)
		(layers "F.Cu" "B.Cu")
		(net "FM_BMC_ONCTL_R_N")
	)
	(via
		(at 17.464278 -95.982282)
		(size 0.4572)
		(drill 0.254)
		(layers "F.Cu" "B.Cu")
		(net "FM_BMC_ONCTL_R_N")
	)
	(via
		(at 18.3261 -52.02174)
		(size 0.508)
		(drill 0.254)
		(layers "F.Cu" "B.Cu")
		(net "FM_BMC_ONCTL_R_N")
	)
	(via
		(at 53.299868 -57.366408)
		(size 0.4572)
		(drill 0.254)
		(layers "F.Cu" "B.Cu")
		(net "FM_BMC_ONCTL_R_N")
	)
	(via
		(at 29.82214 -96.8629)
		(size 0.508)
		(drill 0.254)
		(layers "F.Cu" "B.Cu")
		(net "FM_BMC_ONCTL_R_N")
	)
	(via
		(at 39.37 -81.5594)
		(size 0.508)
		(drill 0.254)
		(layers "F.Cu" "B.Cu")
		(net "FM_BMC_ONCTL_R_N")
	)
	(segment
		(start 40.42156 -85.45576)
		(end 41.167558 -85.45576)
		(width 0.11684)
		(layer "B.Cu")
		(net "FM_BMC_ONCTL_R_N")
	)
	(segment
		(start 39.815008 -83.861656)
		(end 39.815008 -84.849208)
		(width 0.11684)
		(layer "B.Cu")
		(net "FM_BMC_ONCTL_R_N")
	)
	(segment
		(start 39.37 -81.5594)
		(end 39.7256 -81.915)
		(width 0.11684)
		(layer "B.Cu")
		(net "FM_BMC_ONCTL_R_N")
	)
	(segment
		(start 39.7256 -81.915)
		(end 39.7256 -82.747104)
		(width 0.11684)
		(layer "B.Cu")
		(net "FM_BMC_ONCTL_R_N")
	)
	(segment
		(start 39.7256 -82.747104)
		(end 39.815008 -82.836512)
		(width 0.11684)
		(layer "B.Cu")
		(net "FM_BMC_ONCTL_R_N")
	)
	(segment
		(start 39.815008 -84.849208)
		(end 40.42156 -85.45576)
		(width 0.11684)
		(layer "B.Cu")
		(net "FM_BMC_ONCTL_R_N")
	)
	(segment
		(start 39.815008 -82.836512)
		(end 39.815008 -83.861656)
		(width 0.11684)
		(layer "B.Cu")
		(net "FM_BMC_ONCTL_R_N")
	)
	(segment
		(start 26.085546 -81.6356)
		(end 26.3906 -81.6356)
		(width 0.08382)
		(layer "In2.Cu")
		(net "FM_BMC_ONCTL_R_N")
	)
	(segment
		(start 46.253908 -47.40402)
		(end 44.46778 -47.40402)
		(width 0.08382)
		(layer "In2.Cu")
		(net "FM_BMC_ONCTL_R_N")
	)
	(segment
		(start 30.40126 -45.08246)
		(end 28.32354 -43.00474)
		(width 0.08382)
		(layer "In2.Cu")
		(net "FM_BMC_ONCTL_R_N")
	)
	(segment
		(start 25.697434 -43.00474)
		(end 23.471632 -45.230542)
		(width 0.08382)
		(layer "In2.Cu")
		(net "FM_BMC_ONCTL_R_N")
	)
	(segment
		(start 34.181288 -49.206912)
		(end 32.503618 -49.206912)
		(width 0.08382)
		(layer "In2.Cu")
		(net "FM_BMC_ONCTL_R_N")
	)
	(segment
		(start 23.3172 -76.438506)
		(end 23.3172 -79.299054)
		(width 0.08382)
		(layer "In2.Cu")
		(net "FM_BMC_ONCTL_R_N")
	)
	(segment
		(start 52.874672 -56.27751)
		(end 52.788312 -56.19115)
		(width 0.08382)
		(layer "In2.Cu")
		(net "FM_BMC_ONCTL_R_N")
	)
	(segment
		(start 20.718526 -73.839832)
		(end 23.3172 -76.438506)
		(width 0.08382)
		(layer "In2.Cu")
		(net "FM_BMC_ONCTL_R_N")
	)
	(segment
		(start 19.07286 -52.02174)
		(end 18.3261 -52.02174)
		(width 0.08382)
		(layer "In2.Cu")
		(net "FM_BMC_ONCTL_R_N")
	)
	(segment
		(start 52.102512 -56.013604)
		(end 52.102512 -55.459122)
		(width 0.08382)
		(layer "In2.Cu")
		(net "FM_BMC_ONCTL_R_N")
	)
	(segment
		(start 52.102512 -55.459122)
		(end 51.76012 -55.11673)
		(width 0.08382)
		(layer "In2.Cu")
		(net "FM_BMC_ONCTL_R_N")
	)
	(segment
		(start 52.874672 -56.941212)
		(end 52.874672 -56.27751)
		(width 0.08382)
		(layer "In2.Cu")
		(net "FM_BMC_ONCTL_R_N")
	)
	(segment
		(start 46.47184 -47.621952)
		(end 46.253908 -47.40402)
		(width 0.08382)
		(layer "In2.Cu")
		(net "FM_BMC_ONCTL_R_N")
	)
	(segment
		(start 39.688262 -48.830738)
		(end 39.0906 -49.4284)
		(width 0.08382)
		(layer "In2.Cu")
		(net "FM_BMC_ONCTL_R_N")
	)
	(segment
		(start 48.3616 -49.0474)
		(end 47.50562 -48.19142)
		(width 0.08382)
		(layer "In2.Cu")
		(net "FM_BMC_ONCTL_R_N")
	)
	(segment
		(start 23.471632 -49.50206)
		(end 21.119592 -51.8541)
		(width 0.08382)
		(layer "In2.Cu")
		(net "FM_BMC_ONCTL_R_N")
	)
	(segment
		(start 28.47594 -81.62544)
		(end 34.765488 -81.62544)
		(width 0.08382)
		(layer "In2.Cu")
		(net "FM_BMC_ONCTL_R_N")
	)
	(segment
		(start 34.765488 -81.62544)
		(end 34.874708 -81.73466)
		(width 0.08382)
		(layer "In2.Cu")
		(net "FM_BMC_ONCTL_R_N")
	)
	(segment
		(start 37.569648 -81.73466)
		(end 38.249098 -82.41411)
		(width 0.08382)
		(layer "In2.Cu")
		(net "FM_BMC_ONCTL_R_N")
	)
	(segment
		(start 27.42438 -82.677)
		(end 28.47594 -81.62544)
		(width 0.08382)
		(layer "In2.Cu")
		(net "FM_BMC_ONCTL_R_N")
	)
	(segment
		(start 30.40126 -47.104554)
		(end 30.40126 -45.08246)
		(width 0.08382)
		(layer "In2.Cu")
		(net "FM_BMC_ONCTL_R_N")
	)
	(segment
		(start 49.368964 -53.88991)
		(end 49.368964 -49.954942)
		(width 0.08382)
		(layer "In2.Cu")
		(net "FM_BMC_ONCTL_R_N")
	)
	(segment
		(start 26.61158 -82.44586)
		(end 26.84272 -82.677)
		(width 0.08382)
		(layer "In2.Cu")
		(net "FM_BMC_ONCTL_R_N")
	)
	(segment
		(start 20.00758 -73.839832)
		(end 20.718526 -73.839832)
		(width 0.08382)
		(layer "In2.Cu")
		(net "FM_BMC_ONCTL_R_N")
	)
	(segment
		(start 36.486592 -48.848264)
		(end 35.999928 -48.3616)
		(width 0.08382)
		(layer "In2.Cu")
		(net "FM_BMC_ONCTL_R_N")
	)
	(segment
		(start 38.621716 -82.41411)
		(end 39.37 -81.665826)
		(width 0.08382)
		(layer "In2.Cu")
		(net "FM_BMC_ONCTL_R_N")
	)
	(segment
		(start 23.799546 -79.7814)
		(end 24.231346 -79.7814)
		(width 0.08382)
		(layer "In2.Cu")
		(net "FM_BMC_ONCTL_R_N")
	)
	(segment
		(start 21.119592 -51.8541)
		(end 19.2405 -51.8541)
		(width 0.08382)
		(layer "In2.Cu")
		(net "FM_BMC_ONCTL_R_N")
	)
	(segment
		(start 23.3172 -79.299054)
		(end 23.799546 -79.7814)
		(width 0.08382)
		(layer "In2.Cu")
		(net "FM_BMC_ONCTL_R_N")
	)
	(segment
		(start 48.461422 -49.0474)
		(end 48.3616 -49.0474)
		(width 0.08382)
		(layer "In2.Cu")
		(net "FM_BMC_ONCTL_R_N")
	)
	(segment
		(start 46.47184 -47.89424)
		(end 46.47184 -47.621952)
		(width 0.08382)
		(layer "In2.Cu")
		(net "FM_BMC_ONCTL_R_N")
	)
	(segment
		(start 28.32354 -43.00474)
		(end 25.697434 -43.00474)
		(width 0.08382)
		(layer "In2.Cu")
		(net "FM_BMC_ONCTL_R_N")
	)
	(segment
		(start 34.874708 -81.73466)
		(end 37.569648 -81.73466)
		(width 0.08382)
		(layer "In2.Cu")
		(net "FM_BMC_ONCTL_R_N")
	)
	(segment
		(start 19.2405 -51.8541)
		(end 19.07286 -52.02174)
		(width 0.08382)
		(layer "In2.Cu")
		(net "FM_BMC_ONCTL_R_N")
	)
	(segment
		(start 32.503618 -49.206912)
		(end 30.40126 -47.104554)
		(width 0.08382)
		(layer "In2.Cu")
		(net "FM_BMC_ONCTL_R_N")
	)
	(segment
		(start 51.76012 -55.11673)
		(end 50.595784 -55.11673)
		(width 0.08382)
		(layer "In2.Cu")
		(net "FM_BMC_ONCTL_R_N")
	)
	(segment
		(start 44.25442 -47.61738)
		(end 42.73042 -47.61738)
		(width 0.08382)
		(layer "In2.Cu")
		(net "FM_BMC_ONCTL_R_N")
	)
	(segment
		(start 50.595784 -55.11673)
		(end 49.368964 -53.88991)
		(width 0.08382)
		(layer "In2.Cu")
		(net "FM_BMC_ONCTL_R_N")
	)
	(segment
		(start 47.50562 -48.19142)
		(end 46.76902 -48.19142)
		(width 0.08382)
		(layer "In2.Cu")
		(net "FM_BMC_ONCTL_R_N")
	)
	(segment
		(start 52.788312 -56.19115)
		(end 52.280058 -56.19115)
		(width 0.08382)
		(layer "In2.Cu")
		(net "FM_BMC_ONCTL_R_N")
	)
	(segment
		(start 24.231346 -79.7814)
		(end 26.085546 -81.6356)
		(width 0.08382)
		(layer "In2.Cu")
		(net "FM_BMC_ONCTL_R_N")
	)
	(segment
		(start 41.517062 -48.830738)
		(end 39.688262 -48.830738)
		(width 0.08382)
		(layer "In2.Cu")
		(net "FM_BMC_ONCTL_R_N")
	)
	(segment
		(start 37.887402 -49.4284)
		(end 36.486592 -48.848264)
		(width 0.08382)
		(layer "In2.Cu")
		(net "FM_BMC_ONCTL_R_N")
	)
	(segment
		(start 23.471632 -45.230542)
		(end 23.471632 -49.50206)
		(width 0.08382)
		(layer "In2.Cu")
		(net "FM_BMC_ONCTL_R_N")
	)
	(segment
		(start 39.37 -81.665826)
		(end 39.37 -81.5594)
		(width 0.08382)
		(layer "In2.Cu")
		(net "FM_BMC_ONCTL_R_N")
	)
	(segment
		(start 26.3906 -81.6356)
		(end 26.61158 -81.85658)
		(width 0.08382)
		(layer "In2.Cu")
		(net "FM_BMC_ONCTL_R_N")
	)
	(segment
		(start 46.76902 -48.19142)
		(end 46.47184 -47.89424)
		(width 0.08382)
		(layer "In2.Cu")
		(net "FM_BMC_ONCTL_R_N")
	)
	(segment
		(start 38.249098 -82.41411)
		(end 38.621716 -82.41411)
		(width 0.08382)
		(layer "In2.Cu")
		(net "FM_BMC_ONCTL_R_N")
	)
	(segment
		(start 39.0906 -49.4284)
		(end 37.887402 -49.4284)
		(width 0.08382)
		(layer "In2.Cu")
		(net "FM_BMC_ONCTL_R_N")
	)
	(segment
		(start 26.61158 -81.85658)
		(end 26.61158 -82.44586)
		(width 0.08382)
		(layer "In2.Cu")
		(net "FM_BMC_ONCTL_R_N")
	)
	(segment
		(start 52.280058 -56.19115)
		(end 52.102512 -56.013604)
		(width 0.08382)
		(layer "In2.Cu")
		(net "FM_BMC_ONCTL_R_N")
	)
	(segment
		(start 35.999928 -48.3616)
		(end 35.0266 -48.3616)
		(width 0.08382)
		(layer "In2.Cu")
		(net "FM_BMC_ONCTL_R_N")
	)
	(segment
		(start 42.73042 -47.61738)
		(end 41.517062 -48.830738)
		(width 0.08382)
		(layer "In2.Cu")
		(net "FM_BMC_ONCTL_R_N")
	)
	(segment
		(start 44.46778 -47.40402)
		(end 44.25442 -47.61738)
		(width 0.08382)
		(layer "In2.Cu")
		(net "FM_BMC_ONCTL_R_N")
	)
	(segment
		(start 53.299868 -57.366408)
		(end 52.874672 -56.941212)
		(width 0.08382)
		(layer "In2.Cu")
		(net "FM_BMC_ONCTL_R_N")
	)
	(segment
		(start 26.84272 -82.677)
		(end 27.42438 -82.677)
		(width 0.08382)
		(layer "In2.Cu")
		(net "FM_BMC_ONCTL_R_N")
	)
	(segment
		(start 49.368964 -49.954942)
		(end 48.461422 -49.0474)
		(width 0.08382)
		(layer "In2.Cu")
		(net "FM_BMC_ONCTL_R_N")
	)
	(segment
		(start 35.0266 -48.3616)
		(end 34.181288 -49.206912)
		(width 0.08382)
		(layer "In2.Cu")
		(net "FM_BMC_ONCTL_R_N")
	)
	(segment
		(start 18.90776 -58.64606)
		(end 17.176242 -56.914542)
		(width 0.10668)
		(layer "In4.Cu")
		(net "FM_BMC_ONCTL_R_N")
	)
	(segment
		(start 17.176242 -53.486558)
		(end 18.3261 -52.3367)
		(width 0.10668)
		(layer "In4.Cu")
		(net "FM_BMC_ONCTL_R_N")
	)
	(segment
		(start 19.258788 -73.37806)
		(end 18.49882 -72.618092)
		(width 0.10668)
		(layer "In4.Cu")
		(net "FM_BMC_ONCTL_R_N")
	)
	(segment
		(start 19.09826 -66.826384)
		(end 19.09826 -64.11214)
		(width 0.10668)
		(layer "In4.Cu")
		(net "FM_BMC_ONCTL_R_N")
	)
	(segment
		(start 18.49882 -70.760844)
		(end 17.47012 -69.732144)
		(width 0.10668)
		(layer "In4.Cu")
		(net "FM_BMC_ONCTL_R_N")
	)
	(segment
		(start 18.90776 -61.4426)
		(end 18.90776 -58.64606)
		(width 0.10668)
		(layer "In4.Cu")
		(net "FM_BMC_ONCTL_R_N")
	)
	(segment
		(start 20.00758 -73.839832)
		(end 20.00758 -73.832212)
		(width 0.10668)
		(layer "In4.Cu")
		(net "FM_BMC_ONCTL_R_N")
	)
	(segment
		(start 18.49882 -72.618092)
		(end 18.49882 -70.760844)
		(width 0.10668)
		(layer "In4.Cu")
		(net "FM_BMC_ONCTL_R_N")
	)
	(segment
		(start 18.3261 -52.3367)
		(end 18.3261 -52.02174)
		(width 0.10668)
		(layer "In4.Cu")
		(net "FM_BMC_ONCTL_R_N")
	)
	(segment
		(start 19.8882 -63.3222)
		(end 19.8882 -62.42304)
		(width 0.10668)
		(layer "In4.Cu")
		(net "FM_BMC_ONCTL_R_N")
	)
	(segment
		(start 20.00758 -73.832212)
		(end 19.553428 -73.37806)
		(width 0.10668)
		(layer "In4.Cu")
		(net "FM_BMC_ONCTL_R_N")
	)
	(segment
		(start 19.09826 -64.11214)
		(end 19.8882 -63.3222)
		(width 0.10668)
		(layer "In4.Cu")
		(net "FM_BMC_ONCTL_R_N")
	)
	(segment
		(start 19.553428 -73.37806)
		(end 19.258788 -73.37806)
		(width 0.10668)
		(layer "In4.Cu")
		(net "FM_BMC_ONCTL_R_N")
	)
	(segment
		(start 17.47012 -68.454524)
		(end 19.09826 -66.826384)
		(width 0.10668)
		(layer "In4.Cu")
		(net "FM_BMC_ONCTL_R_N")
	)
	(segment
		(start 17.176242 -56.914542)
		(end 17.176242 -53.486558)
		(width 0.10668)
		(layer "In4.Cu")
		(net "FM_BMC_ONCTL_R_N")
	)
	(segment
		(start 19.8882 -62.42304)
		(end 18.90776 -61.4426)
		(width 0.10668)
		(layer "In4.Cu")
		(net "FM_BMC_ONCTL_R_N")
	)
	(segment
		(start 17.47012 -69.732144)
		(end 17.47012 -68.454524)
		(width 0.10668)
		(layer "In4.Cu")
		(net "FM_BMC_ONCTL_R_N")
	)
	(segment
		(start 17.0688 -95.7326)
		(end 17.318482 -95.982282)
		(width 0.08382)
		(layer "In9.Cu")
		(net "FM_BMC_ONCTL_R_N")
	)
	(segment
		(start 17.318482 -95.982282)
		(end 17.464278 -95.982282)
		(width 0.08382)
		(layer "In9.Cu")
		(net "FM_BMC_ONCTL_R_N")
	)
	(segment
		(start 17.272 -94.0054)
		(end 17.0688 -94.2086)
		(width 0.08382)
		(layer "In9.Cu")
		(net "FM_BMC_ONCTL_R_N")
	)
	(segment
		(start 29.82214 -96.8629)
		(end 28.2575 -96.8629)
		(width 0.08382)
		(layer "In9.Cu")
		(net "FM_BMC_ONCTL_R_N")
	)
	(segment
		(start 17.0688 -94.2086)
		(end 17.0688 -95.7326)
		(width 0.08382)
		(layer "In9.Cu")
		(net "FM_BMC_ONCTL_R_N")
	)
	(segment
		(start 28.2575 -96.8629)
		(end 25.4 -94.0054)
		(width 0.08382)
		(layer "In9.Cu")
		(net "FM_BMC_ONCTL_R_N")
	)
	(segment
		(start 25.4 -94.0054)
		(end 17.272 -94.0054)
		(width 0.08382)
		(layer "In9.Cu")
		(net "FM_BMC_ONCTL_R_N")
	)
	(segment
		(start 63.560452 -68.174362)
		(end 62.917832 -67.531742)
		(width 0.381)
		(layer "F.Cu")
		(net "PGPPA_BMC_AUX")
	)
	(segment
		(start 63.573152 -68.187062)
		(end 63.560452 -68.174362)
		(width 0.381)
		(layer "F.Cu")
		(net "PGPPA_BMC_AUX")
	)
	(segment
		(start 62.917832 -67.531742)
		(end 62.917832 -66.926968)
		(width 0.381)
		(layer "F.Cu")
		(net "PGPPA_BMC_AUX")
	)
	(segment
		(start 53.695092 -53.771292)
		(end 53.299868 -54.166516)
		(width 0.3556)
		(layer "F.Cu")
		(net "PGPPA_BMC_AUX")
	)
	(segment
		(start 64.51854 -106.37774)
		(end 63.9572 -105.8164)
		(width 0.254)
		(layer "F.Cu")
		(net "PGPPA_BMC_AUX")
	)
	(segment
		(start 63.7286 -105.8164)
		(end 62.64656 -104.73436)
		(width 0.254)
		(layer "F.Cu")
		(net "PGPPA_BMC_AUX")
	)
	(segment
		(start 62.705742 -66.714878)
		(end 62.917832 -66.926968)
		(width 0.381)
		(layer "F.Cu")
		(net "PGPPA_BMC_AUX")
	)
	(segment
		(start 64.51854 -107.604306)
		(end 64.51854 -106.37774)
		(width 0.254)
		(layer "F.Cu")
		(net "PGPPA_BMC_AUX")
	)
	(segment
		(start 63.9572 -105.8164)
		(end 63.7286 -105.8164)
		(width 0.254)
		(layer "F.Cu")
		(net "PGPPA_BMC_AUX")
	)
	(segment
		(start 60.591192 -103.882952)
		(end 60.16244 -103.4542)
		(width 0.254)
		(layer "F.Cu")
		(net "PGPPA_BMC_AUX")
	)
	(segment
		(start 62.705742 -65.37071)
		(end 62.705742 -66.714878)
		(width 0.381)
		(layer "F.Cu")
		(net "PGPPA_BMC_AUX")
	)
	(segment
		(start 62.64656 -104.73436)
		(end 60.591192 -103.882952)
		(width 0.254)
		(layer "F.Cu")
		(net "PGPPA_BMC_AUX")
	)
	(segment
		(start 63.573152 -69.489574)
		(end 63.573152 -68.187062)
		(width 0.381)
		(layer "F.Cu")
		(net "PGPPA_BMC_AUX")
	)
	(via
		(at 53.299868 -54.166516)
		(size 0.4572)
		(drill 0.254)
		(layers "F.Cu" "B.Cu")
		(net "PGPPA_BMC_AUX")
	)
	(via
		(at 63.573152 -69.489574)
		(size 0.508)
		(drill 0.254)
		(layers "F.Cu" "B.Cu")
		(net "PGPPA_BMC_AUX")
	)
	(via
		(at 60.16244 -103.4542)
		(size 0.508)
		(drill 0.254)
		(layers "F.Cu" "B.Cu")
		(net "PGPPA_BMC_AUX")
	)
	(via
		(at 61.284358 -69.760846)
		(size 0.6604)
		(drill 0.3302)
		(layers "F.Cu" "B.Cu")
		(net "PGPPA_BMC_AUX")
	)
	(via
		(at 63.9572 -105.8164)
		(size 0.762)
		(drill 0.381)
		(layers "F.Cu" "B.Cu")
		(net "PGPPA_BMC_AUX")
	)
	(segment
		(start 53.424582 -54.73192)
		(end 53.424582 -54.29123)
		(width 0.381)
		(layer "B.Cu")
		(net "PGPPA_BMC_AUX")
	)
	(segment
		(start 53.424582 -54.29123)
		(end 53.299868 -54.166516)
		(width 0.381)
		(layer "B.Cu")
		(net "PGPPA_BMC_AUX")
	)
	(segment
		(start 64.9986 -71.7042)
		(end 63.573152 -70.278752)
		(width 0.254)
		(layer "In4.Cu")
		(net "PGPPA_BMC_AUX")
	)
	(segment
		(start 61.272674 -104.20477)
		(end 62.4078 -103.069644)
		(width 0.254)
		(layer "In4.Cu")
		(net "PGPPA_BMC_AUX")
	)
	(segment
		(start 63.383922 -82.183478)
		(end 64.0588 -81.5086)
		(width 0.254)
		(layer "In4.Cu")
		(net "PGPPA_BMC_AUX")
	)
	(segment
		(start 63.23838 -84.945982)
		(end 63.383922 -84.80044)
		(width 0.254)
		(layer "In4.Cu")
		(net "PGPPA_BMC_AUX")
	)
	(segment
		(start 63.573152 -70.278752)
		(end 63.573152 -69.489574)
		(width 0.254)
		(layer "In4.Cu")
		(net "PGPPA_BMC_AUX")
	)
	(segment
		(start 61.943996 -97.517204)
		(end 63.1825 -96.2787)
		(width 0.254)
		(layer "In4.Cu")
		(net "PGPPA_BMC_AUX")
	)
	(segment
		(start 65.480692 -73.584308)
		(end 66.0908 -72.671178)
		(width 0.254)
		(layer "In4.Cu")
		(net "PGPPA_BMC_AUX")
	)
	(segment
		(start 60.91301 -104.20477)
		(end 61.272674 -104.20477)
		(width 0.254)
		(layer "In4.Cu")
		(net "PGPPA_BMC_AUX")
	)
	(segment
		(start 64.0588 -75.0062)
		(end 65.480692 -73.584308)
		(width 0.254)
		(layer "In4.Cu")
		(net "PGPPA_BMC_AUX")
	)
	(segment
		(start 60.16244 -103.4542)
		(end 60.91301 -104.20477)
		(width 0.254)
		(layer "In4.Cu")
		(net "PGPPA_BMC_AUX")
	)
	(segment
		(start 62.4078 -101.454712)
		(end 61.943996 -100.990908)
		(width 0.254)
		(layer "In4.Cu")
		(net "PGPPA_BMC_AUX")
	)
	(segment
		(start 66.0908 -71.9582)
		(end 65.8368 -71.7042)
		(width 0.254)
		(layer "In4.Cu")
		(net "PGPPA_BMC_AUX")
	)
	(segment
		(start 63.1825 -96.2787)
		(end 63.1825 -85.046566)
		(width 0.254)
		(layer "In4.Cu")
		(net "PGPPA_BMC_AUX")
	)
	(segment
		(start 63.1825 -85.046566)
		(end 63.23838 -84.990686)
		(width 0.254)
		(layer "In4.Cu")
		(net "PGPPA_BMC_AUX")
	)
	(segment
		(start 61.943996 -100.990908)
		(end 61.943996 -97.517204)
		(width 0.254)
		(layer "In4.Cu")
		(net "PGPPA_BMC_AUX")
	)
	(segment
		(start 64.0588 -81.5086)
		(end 64.0588 -75.0062)
		(width 0.254)
		(layer "In4.Cu")
		(net "PGPPA_BMC_AUX")
	)
	(segment
		(start 63.383922 -84.80044)
		(end 63.383922 -82.183478)
		(width 0.254)
		(layer "In4.Cu")
		(net "PGPPA_BMC_AUX")
	)
	(segment
		(start 63.23838 -84.990686)
		(end 63.23838 -84.945982)
		(width 0.254)
		(layer "In4.Cu")
		(net "PGPPA_BMC_AUX")
	)
	(segment
		(start 62.4078 -103.069644)
		(end 62.4078 -101.454712)
		(width 0.254)
		(layer "In4.Cu")
		(net "PGPPA_BMC_AUX")
	)
	(segment
		(start 66.0908 -72.671178)
		(end 66.0908 -71.9582)
		(width 0.254)
		(layer "In4.Cu")
		(net "PGPPA_BMC_AUX")
	)
	(segment
		(start 65.8368 -71.7042)
		(end 64.9986 -71.7042)
		(width 0.254)
		(layer "In4.Cu")
		(net "PGPPA_BMC_AUX")
	)
	(segment
		(start 60.36437 -35.037776)
		(end 60.36437 -35.987736)
		(width 0.11684)
		(layer "F.Cu")
		(net "JTAG_SCM_TMS")
	)
	(segment
		(start 60.36437 -35.987736)
		(end 60.01766 -36.824412)
		(width 0.11684)
		(layer "F.Cu")
		(net "JTAG_SCM_TMS")
	)
	(segment
		(start 58.57875 -39.168832)
		(end 58.49493 -39.37127)
		(width 0.11684)
		(layer "F.Cu")
		(net "JTAG_SCM_TMS")
	)
	(segment
		(start 60.01766 -36.824412)
		(end 59.025536 -37.816536)
		(width 0.11684)
		(layer "F.Cu")
		(net "JTAG_SCM_TMS")
	)
	(segment
		(start 65.37325 -23.518114)
		(end 65.37325 -24.1554)
		(width 0.11684)
		(layer "F.Cu")
		(net "JTAG_SCM_TMS")
	)
	(segment
		(start 59.025536 -37.816536)
		(end 58.57875 -38.263322)
		(width 0.11684)
		(layer "F.Cu")
		(net "JTAG_SCM_TMS")
	)
	(segment
		(start 58.57875 -38.263322)
		(end 58.57875 -39.168832)
		(width 0.11684)
		(layer "F.Cu")
		(net "JTAG_SCM_TMS")
	)
	(segment
		(start 66.013076 -22.878288)
		(end 65.37325 -23.518114)
		(width 0.11684)
		(layer "F.Cu")
		(net "JTAG_SCM_TMS")
	)
	(via
		(at 59.025536 -37.816536)
		(size 0.508)
		(drill 0.254)
		(layers "F.Cu" "B.Cu")
		(net "JTAG_SCM_TMS")
	)
	(via
		(at 66.013076 -22.878288)
		(size 0.508)
		(drill 0.254)
		(layers "F.Cu" "B.Cu")
		(net "JTAG_SCM_TMS")
	)
	(segment
		(start 65.883028 -24.276812)
		(end 66.313558 -24.276812)
		(width 0.10668)
		(layer "In7.Cu")
		(net "JTAG_SCM_TMS")
	)
	(segment
		(start 64.629538 -27.97048)
		(end 63.58382 -29.016198)
		(width 0.10668)
		(layer "In7.Cu")
		(net "JTAG_SCM_TMS")
	)
	(segment
		(start 59.025536 -36.54679)
		(end 59.025536 -37.816536)
		(width 0.10668)
		(layer "In7.Cu")
		(net "JTAG_SCM_TMS")
	)
	(segment
		(start 66.773806 -27.223212)
		(end 66.026538 -27.97048)
		(width 0.10668)
		(layer "In7.Cu")
		(net "JTAG_SCM_TMS")
	)
	(segment
		(start 62.569598 -30.61462)
		(end 61.13018 -32.054038)
		(width 0.10668)
		(layer "In7.Cu")
		(net "JTAG_SCM_TMS")
	)
	(segment
		(start 65.613788 -23.277576)
		(end 65.613788 -24.007572)
		(width 0.10668)
		(layer "In7.Cu")
		(net "JTAG_SCM_TMS")
	)
	(segment
		(start 66.026538 -27.97048)
		(end 64.629538 -27.97048)
		(width 0.10668)
		(layer "In7.Cu")
		(net "JTAG_SCM_TMS")
	)
	(segment
		(start 66.313558 -24.276812)
		(end 66.773806 -24.73706)
		(width 0.10668)
		(layer "In7.Cu")
		(net "JTAG_SCM_TMS")
	)
	(segment
		(start 63.58382 -29.016198)
		(end 63.58382 -30.149038)
		(width 0.10668)
		(layer "In7.Cu")
		(net "JTAG_SCM_TMS")
	)
	(segment
		(start 66.773806 -24.73706)
		(end 66.773806 -27.223212)
		(width 0.10668)
		(layer "In7.Cu")
		(net "JTAG_SCM_TMS")
	)
	(segment
		(start 61.13018 -34.442146)
		(end 59.025536 -36.54679)
		(width 0.10668)
		(layer "In7.Cu")
		(net "JTAG_SCM_TMS")
	)
	(segment
		(start 66.013076 -22.878288)
		(end 65.613788 -23.277576)
		(width 0.10668)
		(layer "In7.Cu")
		(net "JTAG_SCM_TMS")
	)
	(segment
		(start 63.58382 -30.149038)
		(end 63.118238 -30.61462)
		(width 0.10668)
		(layer "In7.Cu")
		(net "JTAG_SCM_TMS")
	)
	(segment
		(start 65.613788 -24.007572)
		(end 65.883028 -24.276812)
		(width 0.10668)
		(layer "In7.Cu")
		(net "JTAG_SCM_TMS")
	)
	(segment
		(start 63.118238 -30.61462)
		(end 62.569598 -30.61462)
		(width 0.10668)
		(layer "In7.Cu")
		(net "JTAG_SCM_TMS")
	)
	(segment
		(start 61.13018 -32.054038)
		(end 61.13018 -34.442146)
		(width 0.10668)
		(layer "In7.Cu")
		(net "JTAG_SCM_TMS")
	)
	(segment
		(start 70.2056 -25.13457)
		(end 70.30593 -25.2349)
		(width 0.11684)
		(layer "F.Cu")
		(net "JTAG_SCM_TDO")
	)
	(segment
		(start 70.2056 -23.4442)
		(end 70.2056 -25.13457)
		(width 0.11684)
		(layer "F.Cu")
		(net "JTAG_SCM_TDO")
	)
	(segment
		(start 58.49493 -40.971216)
		(end 58.890154 -40.575992)
		(width 0.11684)
		(layer "F.Cu")
		(net "JTAG_SCM_TDO")
	)
	(via
		(at 60.864496 -39.132256)
		(size 0.6604)
		(drill 0.3302)
		(layers "F.Cu" "B.Cu")
		(net "JTAG_SCM_TDO")
	)
	(via
		(at 70.2056 -23.4442)
		(size 0.508)
		(drill 0.254)
		(layers "F.Cu" "B.Cu")
		(net "JTAG_SCM_TDO")
	)
	(via
		(at 58.890154 -40.575992)
		(size 0.4572)
		(drill 0.254)
		(layers "F.Cu" "B.Cu")
		(net "JTAG_SCM_TDO")
	)
	(segment
		(start 60.458858 -39.132256)
		(end 60.864496 -39.132256)
		(width 0.11684)
		(layer "B.Cu")
		(net "JTAG_SCM_TDO")
	)
	(segment
		(start 63.4238 -35.868864)
		(end 63.4238 -36.449)
		(width 0.11684)
		(layer "B.Cu")
		(net "JTAG_SCM_TDO")
	)
	(segment
		(start 60.099702 -39.950644)
		(end 60.099702 -39.491412)
		(width 0.11684)
		(layer "B.Cu")
		(net "JTAG_SCM_TDO")
	)
	(segment
		(start 63.0809 -36.738052)
		(end 60.864496 -38.954456)
		(width 0.11684)
		(layer "B.Cu")
		(net "JTAG_SCM_TDO")
	)
	(segment
		(start 63.817246 -35.45205)
		(end 63.470282 -35.799014)
		(width 0.11684)
		(layer "B.Cu")
		(net "JTAG_SCM_TDO")
	)
	(segment
		(start 65.108582 -31.267654)
		(end 65.108582 -32.425132)
		(width 0.11684)
		(layer "B.Cu")
		(net "JTAG_SCM_TDO")
	)
	(segment
		(start 63.134748 -36.738052)
		(end 63.0809 -36.738052)
		(width 0.11684)
		(layer "B.Cu")
		(net "JTAG_SCM_TDO")
	)
	(segment
		(start 58.890154 -40.575992)
		(end 59.140598 -40.575992)
		(width 0.11684)
		(layer "B.Cu")
		(net "JTAG_SCM_TDO")
	)
	(segment
		(start 64.76619 -35.116008)
		(end 64.430148 -35.45205)
		(width 0.11684)
		(layer "B.Cu")
		(net "JTAG_SCM_TDO")
	)
	(segment
		(start 59.140598 -40.575992)
		(end 59.537346 -40.179244)
		(width 0.11684)
		(layer "B.Cu")
		(net "JTAG_SCM_TDO")
	)
	(segment
		(start 63.4238 -36.449)
		(end 63.134748 -36.738052)
		(width 0.11684)
		(layer "B.Cu")
		(net "JTAG_SCM_TDO")
	)
	(segment
		(start 65.108582 -32.425132)
		(end 64.8208 -32.712914)
		(width 0.11684)
		(layer "B.Cu")
		(net "JTAG_SCM_TDO")
	)
	(segment
		(start 64.8208 -33.87725)
		(end 64.76619 -33.93186)
		(width 0.11684)
		(layer "B.Cu")
		(net "JTAG_SCM_TDO")
	)
	(segment
		(start 59.871102 -40.179244)
		(end 60.099702 -39.950644)
		(width 0.11684)
		(layer "B.Cu")
		(net "JTAG_SCM_TDO")
	)
	(segment
		(start 64.8208 -32.712914)
		(end 64.8208 -33.87725)
		(width 0.11684)
		(layer "B.Cu")
		(net "JTAG_SCM_TDO")
	)
	(segment
		(start 64.76619 -33.93186)
		(end 64.76619 -35.116008)
		(width 0.11684)
		(layer "B.Cu")
		(net "JTAG_SCM_TDO")
	)
	(segment
		(start 60.099702 -39.491412)
		(end 60.458858 -39.132256)
		(width 0.11684)
		(layer "B.Cu")
		(net "JTAG_SCM_TDO")
	)
	(segment
		(start 63.470282 -35.799014)
		(end 63.4238 -35.868864)
		(width 0.11684)
		(layer "B.Cu")
		(net "JTAG_SCM_TDO")
	)
	(segment
		(start 59.537346 -40.179244)
		(end 59.871102 -40.179244)
		(width 0.11684)
		(layer "B.Cu")
		(net "JTAG_SCM_TDO")
	)
	(segment
		(start 64.430148 -35.45205)
		(end 63.817246 -35.45205)
		(width 0.11684)
		(layer "B.Cu")
		(net "JTAG_SCM_TDO")
	)
	(segment
		(start 60.864496 -38.954456)
		(end 60.864496 -39.132256)
		(width 0.11684)
		(layer "B.Cu")
		(net "JTAG_SCM_TDO")
	)
	(segment
		(start 68.123562 -26.989278)
		(end 68.123562 -26.354278)
		(width 0.10668)
		(layer "In7.Cu")
		(net "JTAG_SCM_TDO")
	)
	(segment
		(start 68.123562 -26.354278)
		(end 69.15404 -25.3238)
		(width 0.10668)
		(layer "In7.Cu")
		(net "JTAG_SCM_TDO")
	)
	(segment
		(start 60.073794 -39.13505)
		(end 60.073794 -36.446968)
		(width 0.10668)
		(layer "In7.Cu")
		(net "JTAG_SCM_TDO")
	)
	(segment
		(start 63.307976 -32.582866)
		(end 65.08242 -30.808422)
		(width 0.10668)
		(layer "In7.Cu")
		(net "JTAG_SCM_TDO")
	)
	(segment
		(start 65.08242 -30.03042)
		(end 68.123562 -26.989278)
		(width 0.10668)
		(layer "In7.Cu")
		(net "JTAG_SCM_TDO")
	)
	(segment
		(start 69.15404 -24.511)
		(end 70.2056 -23.45944)
		(width 0.10668)
		(layer "In7.Cu")
		(net "JTAG_SCM_TDO")
	)
	(segment
		(start 60.073794 -36.446968)
		(end 61.16574 -35.355022)
		(width 0.10668)
		(layer "In7.Cu")
		(net "JTAG_SCM_TDO")
	)
	(segment
		(start 65.08242 -30.808422)
		(end 65.08242 -30.03042)
		(width 0.10668)
		(layer "In7.Cu")
		(net "JTAG_SCM_TDO")
	)
	(segment
		(start 61.16574 -35.355022)
		(end 62.019434 -35.355022)
		(width 0.10668)
		(layer "In7.Cu")
		(net "JTAG_SCM_TDO")
	)
	(segment
		(start 62.019434 -35.355022)
		(end 63.307976 -34.06648)
		(width 0.10668)
		(layer "In7.Cu")
		(net "JTAG_SCM_TDO")
	)
	(segment
		(start 63.307976 -34.06648)
		(end 63.307976 -32.582866)
		(width 0.10668)
		(layer "In7.Cu")
		(net "JTAG_SCM_TDO")
	)
	(segment
		(start 58.890154 -40.575992)
		(end 59.283346 -40.1828)
		(width 0.10668)
		(layer "In7.Cu")
		(net "JTAG_SCM_TDO")
	)
	(segment
		(start 70.2056 -23.45944)
		(end 70.2056 -23.4442)
		(width 0.10668)
		(layer "In7.Cu")
		(net "JTAG_SCM_TDO")
	)
	(segment
		(start 59.283346 -40.1828)
		(end 59.283346 -39.64051)
		(width 0.10668)
		(layer "In7.Cu")
		(net "JTAG_SCM_TDO")
	)
	(segment
		(start 59.283346 -39.64051)
		(end 59.56427 -39.359586)
		(width 0.10668)
		(layer "In7.Cu")
		(net "JTAG_SCM_TDO")
	)
	(segment
		(start 69.15404 -25.3238)
		(end 69.15404 -24.511)
		(width 0.10668)
		(layer "In7.Cu")
		(net "JTAG_SCM_TDO")
	)
	(segment
		(start 59.849258 -39.359586)
		(end 60.073794 -39.13505)
		(width 0.10668)
		(layer "In7.Cu")
		(net "JTAG_SCM_TDO")
	)
	(segment
		(start 59.56427 -39.359586)
		(end 59.849258 -39.359586)
		(width 0.10668)
		(layer "In7.Cu")
		(net "JTAG_SCM_TDO")
	)
	(segment
		(start 65.37325 -25.0444)
		(end 66.28638 -25.0444)
		(width 0.11684)
		(layer "F.Cu")
		(net "JTAG_SCM_TDI")
	)
	(segment
		(start 58.49493 -41.771316)
		(end 58.890154 -41.376092)
		(width 0.11684)
		(layer "F.Cu")
		(net "JTAG_SCM_TDI")
	)
	(via
		(at 58.890154 -41.376092)
		(size 0.4572)
		(drill 0.254)
		(layers "F.Cu" "B.Cu")
		(net "JTAG_SCM_TDI")
	)
	(via
		(at 66.4972 -27.2542)
		(size 0.7112)
		(drill 0.3556)
		(layers "F.Cu" "B.Cu")
		(net "JTAG_SCM_TDI")
	)
	(via
		(at 66.28638 -25.0444)
		(size 0.508)
		(drill 0.254)
		(layers "F.Cu" "B.Cu")
		(net "JTAG_SCM_TDI")
	)
	(segment
		(start 65.80505 -27.94635)
		(end 66.4972 -27.2542)
		(width 0.11684)
		(layer "B.Cu")
		(net "JTAG_SCM_TDI")
	)
	(segment
		(start 66.4972 -26.36393)
		(end 66.40322 -26.136854)
		(width 0.11684)
		(layer "B.Cu")
		(net "JTAG_SCM_TDI")
	)
	(segment
		(start 66.40322 -25.16124)
		(end 66.28638 -25.0444)
		(width 0.11684)
		(layer "B.Cu")
		(net "JTAG_SCM_TDI")
	)
	(segment
		(start 65.0494 -27.94635)
		(end 65.80505 -27.94635)
		(width 0.11684)
		(layer "B.Cu")
		(net "JTAG_SCM_TDI")
	)
	(segment
		(start 66.4972 -27.2542)
		(end 66.4972 -26.36393)
		(width 0.11684)
		(layer "B.Cu")
		(net "JTAG_SCM_TDI")
	)
	(segment
		(start 66.40322 -26.136854)
		(end 66.40322 -25.16124)
		(width 0.11684)
		(layer "B.Cu")
		(net "JTAG_SCM_TDI")
	)
	(segment
		(start 65.8876 -27.6352)
		(end 66.438526 -27.084274)
		(width 0.10668)
		(layer "In7.Cu")
		(net "JTAG_SCM_TDI")
	)
	(segment
		(start 58.484262 -38.103556)
		(end 58.484262 -36.613846)
		(width 0.10668)
		(layer "In7.Cu")
		(net "JTAG_SCM_TDI")
	)
	(segment
		(start 58.506614 -40.992552)
		(end 58.506614 -39.617142)
		(width 0.10668)
		(layer "In7.Cu")
		(net "JTAG_SCM_TDI")
	)
	(segment
		(start 60.7949 -31.9151)
		(end 62.43066 -30.27934)
		(width 0.10668)
		(layer "In7.Cu")
		(net "JTAG_SCM_TDI")
	)
	(segment
		(start 62.9793 -30.27934)
		(end 63.24854 -30.0101)
		(width 0.10668)
		(layer "In7.Cu")
		(net "JTAG_SCM_TDI")
	)
	(segment
		(start 66.438526 -25.188926)
		(end 66.294 -25.0444)
		(width 0.10668)
		(layer "In7.Cu")
		(net "JTAG_SCM_TDI")
	)
	(segment
		(start 62.43066 -30.27934)
		(end 62.9793 -30.27934)
		(width 0.10668)
		(layer "In7.Cu")
		(net "JTAG_SCM_TDI")
	)
	(segment
		(start 63.24854 -28.87726)
		(end 64.4906 -27.6352)
		(width 0.10668)
		(layer "In7.Cu")
		(net "JTAG_SCM_TDI")
	)
	(segment
		(start 63.24854 -30.0101)
		(end 63.24854 -28.87726)
		(width 0.10668)
		(layer "In7.Cu")
		(net "JTAG_SCM_TDI")
	)
	(segment
		(start 58.506614 -39.617142)
		(end 58.63082 -39.492936)
		(width 0.10668)
		(layer "In7.Cu")
		(net "JTAG_SCM_TDI")
	)
	(segment
		(start 64.4906 -27.6352)
		(end 65.8876 -27.6352)
		(width 0.10668)
		(layer "In7.Cu")
		(net "JTAG_SCM_TDI")
	)
	(segment
		(start 58.890154 -41.376092)
		(end 58.506614 -40.992552)
		(width 0.10668)
		(layer "In7.Cu")
		(net "JTAG_SCM_TDI")
	)
	(segment
		(start 58.484262 -36.613846)
		(end 60.7949 -34.303208)
		(width 0.10668)
		(layer "In7.Cu")
		(net "JTAG_SCM_TDI")
	)
	(segment
		(start 60.7949 -34.303208)
		(end 60.7949 -31.9151)
		(width 0.10668)
		(layer "In7.Cu")
		(net "JTAG_SCM_TDI")
	)
	(segment
		(start 58.63082 -38.250114)
		(end 58.484262 -38.103556)
		(width 0.10668)
		(layer "In7.Cu")
		(net "JTAG_SCM_TDI")
	)
	(segment
		(start 58.63082 -39.492936)
		(end 58.63082 -38.250114)
		(width 0.10668)
		(layer "In7.Cu")
		(net "JTAG_SCM_TDI")
	)
	(segment
		(start 66.294 -25.0444)
		(end 66.28638 -25.0444)
		(width 0.10668)
		(layer "In7.Cu")
		(net "JTAG_SCM_TDI")
	)
	(segment
		(start 66.438526 -27.084274)
		(end 66.438526 -25.188926)
		(width 0.10668)
		(layer "In7.Cu")
		(net "JTAG_SCM_TDI")
	)
	(segment
		(start 58.890154 -39.776146)
		(end 58.49493 -40.17137)
		(width 0.11684)
		(layer "F.Cu")
		(net "JTAG_SCM_TCK")
	)
	(segment
		(start 62.460886 -31.237936)
		(end 61.541914 -31.237936)
		(width 0.11684)
		(layer "F.Cu")
		(net "JTAG_SCM_TCK")
	)
	(segment
		(start 58.885328 -39.77132)
		(end 58.890154 -39.776146)
		(width 0.11684)
		(layer "F.Cu")
		(net "JTAG_SCM_TCK")
	)
	(segment
		(start 67.513454 -26.93416)
		(end 68.38569 -26.93416)
		(width 0.11684)
		(layer "F.Cu")
		(net "JTAG_SCM_TCK")
	)
	(segment
		(start 61.5188 -31.623254)
		(end 61.085476 -32.056578)
		(width 0.11684)
		(layer "F.Cu")
		(net "JTAG_SCM_TCK")
	)
	(segment
		(start 61.085476 -32.056578)
		(end 60.8584 -32.604964)
		(width 0.11684)
		(layer "F.Cu")
		(net "JTAG_SCM_TCK")
	)
	(segment
		(start 60.8584 -32.604964)
		(end 60.8584 -36.838128)
		(width 0.11684)
		(layer "F.Cu")
		(net "JTAG_SCM_TCK")
	)
	(segment
		(start 58.885328 -38.8112)
		(end 58.885328 -39.77132)
		(width 0.11684)
		(layer "F.Cu")
		(net "JTAG_SCM_TCK")
	)
	(segment
		(start 68.38569 -26.93416)
		(end 68.5292 -26.79065)
		(width 0.11684)
		(layer "F.Cu")
		(net "JTAG_SCM_TCK")
	)
	(segment
		(start 60.8584 -36.838128)
		(end 58.885328 -38.8112)
		(width 0.11684)
		(layer "F.Cu")
		(net "JTAG_SCM_TCK")
	)
	(segment
		(start 62.484 -31.26105)
		(end 62.460886 -31.237936)
		(width 0.11684)
		(layer "F.Cu")
		(net "JTAG_SCM_TCK")
	)
	(segment
		(start 61.541914 -31.237936)
		(end 61.5188 -31.26105)
		(width 0.11684)
		(layer "F.Cu")
		(net "JTAG_SCM_TCK")
	)
	(segment
		(start 61.5188 -31.26105)
		(end 61.5188 -31.623254)
		(width 0.11684)
		(layer "F.Cu")
		(net "JTAG_SCM_TCK")
	)
	(via
		(at 66.4718 -29.1338)
		(size 0.7112)
		(drill 0.3556)
		(layers "F.Cu" "B.Cu")
		(net "JTAG_SCM_TCK")
	)
	(via
		(at 67.513454 -26.93416)
		(size 0.508)
		(drill 0.254)
		(layers "F.Cu" "B.Cu")
		(net "JTAG_SCM_TCK")
	)
	(via
		(at 58.890154 -39.776146)
		(size 0.4572)
		(drill 0.254)
		(layers "F.Cu" "B.Cu")
		(net "JTAG_SCM_TCK")
	)
	(segment
		(start 67.513454 -28.092146)
		(end 66.4718 -29.1338)
		(width 0.11684)
		(layer "B.Cu")
		(net "JTAG_SCM_TCK")
	)
	(segment
		(start 67.513454 -26.93416)
		(end 67.513454 -28.092146)
		(width 0.11684)
		(layer "B.Cu")
		(net "JTAG_SCM_TCK")
	)
	(segment
		(start 58.890154 -38.88613)
		(end 59.485276 -38.291008)
		(width 0.10668)
		(layer "In7.Cu")
		(net "JTAG_SCM_TCK")
	)
	(segment
		(start 62.972696 -33.927288)
		(end 62.972696 -32.443928)
		(width 0.10668)
		(layer "In7.Cu")
		(net "JTAG_SCM_TCK")
	)
	(segment
		(start 64.74714 -29.891482)
		(end 67.513454 -27.125168)
		(width 0.10668)
		(layer "In7.Cu")
		(net "JTAG_SCM_TCK")
	)
	(segment
		(start 67.513454 -27.125168)
		(end 67.513454 -26.93416)
		(width 0.10668)
		(layer "In7.Cu")
		(net "JTAG_SCM_TCK")
	)
	(segment
		(start 62.972696 -32.443928)
		(end 64.74714 -30.669484)
		(width 0.10668)
		(layer "In7.Cu")
		(net "JTAG_SCM_TCK")
	)
	(segment
		(start 64.74714 -30.669484)
		(end 64.74714 -29.891482)
		(width 0.10668)
		(layer "In7.Cu")
		(net "JTAG_SCM_TCK")
	)
	(segment
		(start 61.026802 -35.019742)
		(end 61.880242 -35.019742)
		(width 0.10668)
		(layer "In7.Cu")
		(net "JTAG_SCM_TCK")
	)
	(segment
		(start 58.890154 -39.776146)
		(end 58.890154 -38.88613)
		(width 0.10668)
		(layer "In7.Cu")
		(net "JTAG_SCM_TCK")
	)
	(segment
		(start 59.485276 -36.561268)
		(end 61.026802 -35.019742)
		(width 0.10668)
		(layer "In7.Cu")
		(net "JTAG_SCM_TCK")
	)
	(segment
		(start 61.880242 -35.019742)
		(end 62.972696 -33.927288)
		(width 0.10668)
		(layer "In7.Cu")
		(net "JTAG_SCM_TCK")
	)
	(segment
		(start 59.485276 -38.291008)
		(end 59.485276 -36.561268)
		(width 0.10668)
		(layer "In7.Cu")
		(net "JTAG_SCM_TCK")
	)
	(via
		(at 35.86099 -108.432346)
		(size 0.6604)
		(drill 0.3302)
		(layers "F.Cu" "B.Cu")
		(net "JTAG_MB_TDO")
	)
	(segment
		(start 35.86099 -108.632244)
		(end 36.53028 -109.301534)
		(width 0.11684)
		(layer "B.Cu")
		(net "JTAG_MB_TDO")
	)
	(segment
		(start 38.455092 -116.026438)
		(end 38.455092 -118.25986)
		(width 0.11684)
		(layer "B.Cu")
		(net "JTAG_MB_TDO")
	)
	(segment
		(start 36.53028 -112.50168)
		(end 36.7284 -112.6998)
		(width 0.11684)
		(layer "B.Cu")
		(net "JTAG_MB_TDO")
	)
	(segment
		(start 35.052 -106.76255)
		(end 36.068 -106.76255)
		(width 0.11684)
		(layer "B.Cu")
		(net "JTAG_MB_TDO")
	)
	(segment
		(start 35.86099 -108.432346)
		(end 35.86099 -107.57154)
		(width 0.11684)
		(layer "B.Cu")
		(net "JTAG_MB_TDO")
	)
	(segment
		(start 36.7284 -112.6998)
		(end 36.7284 -114.299746)
		(width 0.11684)
		(layer "B.Cu")
		(net "JTAG_MB_TDO")
	)
	(segment
		(start 36.7284 -114.299746)
		(end 38.455092 -116.026438)
		(width 0.11684)
		(layer "B.Cu")
		(net "JTAG_MB_TDO")
	)
	(segment
		(start 35.86099 -107.57154)
		(end 35.052 -106.76255)
		(width 0.11684)
		(layer "B.Cu")
		(net "JTAG_MB_TDO")
	)
	(segment
		(start 35.86099 -108.432346)
		(end 35.86099 -108.632244)
		(width 0.11684)
		(layer "B.Cu")
		(net "JTAG_MB_TDO")
	)
	(segment
		(start 36.53028 -109.301534)
		(end 36.53028 -112.50168)
		(width 0.11684)
		(layer "B.Cu")
		(net "JTAG_MB_TDO")
	)
	(segment
		(start 52.991258 -34.237676)
		(end 52.991258 -33.628076)
		(width 0.11684)
		(layer "F.Cu")
		(net "JTAG_MB_TDI")
	)
	(via
		(at 37.084 -109.1946)
		(size 0.6604)
		(drill 0.3302)
		(layers "F.Cu" "B.Cu")
		(net "JTAG_MB_TDI")
	)
	(via
		(at 52.991258 -33.628076)
		(size 0.508)
		(drill 0.254)
		(layers "F.Cu" "B.Cu")
		(net "JTAG_MB_TDI")
	)
	(via
		(at 35.7124 -104.7242)
		(size 0.508)
		(drill 0.254)
		(layers "F.Cu" "B.Cu")
		(net "JTAG_MB_TDI")
	)
	(via
		(at 6.401308 -108.033566)
		(size 0.508)
		(drill 0.254)
		(layers "F.Cu" "B.Cu")
		(net "JTAG_MB_TDI")
	)
	(segment
		(start 36.39566 -104.7242)
		(end 36.78682 -105.11536)
		(width 0.11684)
		(layer "B.Cu")
		(net "JTAG_MB_TDI")
	)
	(segment
		(start 39.05504 -116.068094)
		(end 39.05504 -118.25986)
		(width 0.11684)
		(layer "B.Cu")
		(net "JTAG_MB_TDI")
	)
	(segment
		(start 36.54298 -105.77322)
		(end 36.54298 -106.57967)
		(width 0.11684)
		(layer "B.Cu")
		(net "JTAG_MB_TDI")
	)
	(segment
		(start 36.78682 -105.52938)
		(end 36.54298 -105.77322)
		(width 0.11684)
		(layer "B.Cu")
		(net "JTAG_MB_TDI")
	)
	(segment
		(start 36.72586 -106.76255)
		(end 37.084 -106.76255)
		(width 0.11684)
		(layer "B.Cu")
		(net "JTAG_MB_TDI")
	)
	(segment
		(start 36.54298 -106.57967)
		(end 36.72586 -106.76255)
		(width 0.11684)
		(layer "B.Cu")
		(net "JTAG_MB_TDI")
	)
	(segment
		(start 36.449762 -107.396788)
		(end 36.449762 -108.560362)
		(width 0.11684)
		(layer "B.Cu")
		(net "JTAG_MB_TDI")
	)
	(segment
		(start 36.449762 -108.560362)
		(end 37.084 -109.1946)
		(width 0.11684)
		(layer "B.Cu")
		(net "JTAG_MB_TDI")
	)
	(segment
		(start 37.084 -109.1946)
		(end 37.084 -114.097054)
		(width 0.11684)
		(layer "B.Cu")
		(net "JTAG_MB_TDI")
	)
	(segment
		(start 37.084 -114.097054)
		(end 39.05504 -116.068094)
		(width 0.11684)
		(layer "B.Cu")
		(net "JTAG_MB_TDI")
	)
	(segment
		(start 36.78682 -105.11536)
		(end 36.78682 -105.52938)
		(width 0.11684)
		(layer "B.Cu")
		(net "JTAG_MB_TDI")
	)
	(segment
		(start 35.7124 -104.7242)
		(end 36.39566 -104.7242)
		(width 0.11684)
		(layer "B.Cu")
		(net "JTAG_MB_TDI")
	)
	(segment
		(start 37.084 -106.76255)
		(end 36.449762 -107.396788)
		(width 0.11684)
		(layer "B.Cu")
		(net "JTAG_MB_TDI")
	)
	(segment
		(start 28.477972 -109.12094)
		(end 29.83865 -107.760262)
		(width 0.08382)
		(layer "In2.Cu")
		(net "JTAG_MB_TDI")
	)
	(segment
		(start 32.05988 -105.83672)
		(end 32.786828 -105.109772)
		(width 0.08382)
		(layer "In2.Cu")
		(net "JTAG_MB_TDI")
	)
	(segment
		(start 33.796986 -105.008426)
		(end 33.818322 -104.98709)
		(width 0.08382)
		(layer "In2.Cu")
		(net "JTAG_MB_TDI")
	)
	(segment
		(start 29.83865 -106.543602)
		(end 30.545532 -105.83672)
		(width 0.08382)
		(layer "In2.Cu")
		(net "JTAG_MB_TDI")
	)
	(segment
		(start 30.545532 -105.83672)
		(end 32.05988 -105.83672)
		(width 0.08382)
		(layer "In2.Cu")
		(net "JTAG_MB_TDI")
	)
	(segment
		(start 9.08431 -108.09351)
		(end 11.81989 -108.09351)
		(width 0.08382)
		(layer "In2.Cu")
		(net "JTAG_MB_TDI")
	)
	(segment
		(start 33.695386 -105.109772)
		(end 33.796732 -105.008426)
		(width 0.08382)
		(layer "In2.Cu")
		(net "JTAG_MB_TDI")
	)
	(segment
		(start 33.796732 -105.008426)
		(end 33.796986 -105.008426)
		(width 0.08382)
		(layer "In2.Cu")
		(net "JTAG_MB_TDI")
	)
	(segment
		(start 18.523458 -106.88447)
		(end 24.417528 -106.88447)
		(width 0.08382)
		(layer "In2.Cu")
		(net "JTAG_MB_TDI")
	)
	(segment
		(start 13.91158 -106.00182)
		(end 17.640808 -106.00182)
		(width 0.08382)
		(layer "In2.Cu")
		(net "JTAG_MB_TDI")
	)
	(segment
		(start 6.613144 -107.82173)
		(end 8.81253 -107.82173)
		(width 0.08382)
		(layer "In2.Cu")
		(net "JTAG_MB_TDI")
	)
	(segment
		(start 25.10536 -107.572302)
		(end 25.10536 -108.19384)
		(width 0.08382)
		(layer "In2.Cu")
		(net "JTAG_MB_TDI")
	)
	(segment
		(start 6.401308 -108.033566)
		(end 6.613144 -107.82173)
		(width 0.08382)
		(layer "In2.Cu")
		(net "JTAG_MB_TDI")
	)
	(segment
		(start 35.0266 -104.7242)
		(end 35.7124 -104.7242)
		(width 0.08382)
		(layer "In2.Cu")
		(net "JTAG_MB_TDI")
	)
	(segment
		(start 24.417528 -106.88447)
		(end 25.10536 -107.572302)
		(width 0.08382)
		(layer "In2.Cu")
		(net "JTAG_MB_TDI")
	)
	(segment
		(start 26.03246 -109.12094)
		(end 28.477972 -109.12094)
		(width 0.08382)
		(layer "In2.Cu")
		(net "JTAG_MB_TDI")
	)
	(segment
		(start 29.83865 -107.760262)
		(end 29.83865 -106.543602)
		(width 0.08382)
		(layer "In2.Cu")
		(net "JTAG_MB_TDI")
	)
	(segment
		(start 32.786828 -105.109772)
		(end 33.695386 -105.109772)
		(width 0.08382)
		(layer "In2.Cu")
		(net "JTAG_MB_TDI")
	)
	(segment
		(start 34.76371 -104.98709)
		(end 35.0266 -104.7242)
		(width 0.08382)
		(layer "In2.Cu")
		(net "JTAG_MB_TDI")
	)
	(segment
		(start 11.81989 -108.09351)
		(end 13.91158 -106.00182)
		(width 0.08382)
		(layer "In2.Cu")
		(net "JTAG_MB_TDI")
	)
	(segment
		(start 17.640808 -106.00182)
		(end 18.523458 -106.88447)
		(width 0.08382)
		(layer "In2.Cu")
		(net "JTAG_MB_TDI")
	)
	(segment
		(start 33.818322 -104.98709)
		(end 34.76371 -104.98709)
		(width 0.08382)
		(layer "In2.Cu")
		(net "JTAG_MB_TDI")
	)
	(segment
		(start 25.10536 -108.19384)
		(end 26.03246 -109.12094)
		(width 0.08382)
		(layer "In2.Cu")
		(net "JTAG_MB_TDI")
	)
	(segment
		(start 8.81253 -107.82173)
		(end 9.08431 -108.09351)
		(width 0.08382)
		(layer "In2.Cu")
		(net "JTAG_MB_TDI")
	)
	(segment
		(start 44.854114 -26.41346)
		(end 48.279558 -26.41346)
		(width 0.10668)
		(layer "In4.Cu")
		(net "JTAG_MB_TDI")
	)
	(segment
		(start 13.06957 -25.158954)
		(end 13.69314 -24.535384)
		(width 0.10668)
		(layer "In4.Cu")
		(net "JTAG_MB_TDI")
	)
	(segment
		(start 1.993392 -31.017972)
		(end 4.911344 -28.10002)
		(width 0.10668)
		(layer "In4.Cu")
		(net "JTAG_MB_TDI")
	)
	(segment
		(start 13.69314 -23.04034)
		(end 11.95832 -21.30552)
		(width 0.10668)
		(layer "In4.Cu")
		(net "JTAG_MB_TDI")
	)
	(segment
		(start 30.06852 -21.584666)
		(end 33.731454 -25.2476)
		(width 0.10668)
		(layer "In4.Cu")
		(net "JTAG_MB_TDI")
	)
	(segment
		(start 26.98496 -14.69136)
		(end 29.13126 -16.83766)
		(width 0.10668)
		(layer "In4.Cu")
		(net "JTAG_MB_TDI")
	)
	(segment
		(start 53.230272 -31.539942)
		(end 53.44668 -31.863792)
		(width 0.10668)
		(layer "In4.Cu")
		(net "JTAG_MB_TDI")
	)
	(segment
		(start 15.15364 -14.69136)
		(end 26.98496 -14.69136)
		(width 0.10668)
		(layer "In4.Cu")
		(net "JTAG_MB_TDI")
	)
	(segment
		(start 13.208 -16.637)
		(end 15.15364 -14.69136)
		(width 0.10668)
		(layer "In4.Cu")
		(net "JTAG_MB_TDI")
	)
	(segment
		(start 43.581574 -25.14092)
		(end 44.854114 -26.41346)
		(width 0.10668)
		(layer "In4.Cu")
		(net "JTAG_MB_TDI")
	)
	(segment
		(start 30.06852 -20.8788)
		(end 30.06852 -21.584666)
		(width 0.10668)
		(layer "In4.Cu")
		(net "JTAG_MB_TDI")
	)
	(segment
		(start 13.06957 -25.80767)
		(end 13.06957 -25.158954)
		(width 0.10668)
		(layer "In4.Cu")
		(net "JTAG_MB_TDI")
	)
	(segment
		(start 53.44668 -31.863792)
		(end 53.44668 -33.172654)
		(width 0.10668)
		(layer "In4.Cu")
		(net "JTAG_MB_TDI")
	)
	(segment
		(start 42.809922 -25.14092)
		(end 43.581574 -25.14092)
		(width 0.10668)
		(layer "In4.Cu")
		(net "JTAG_MB_TDI")
	)
	(segment
		(start 29.13126 -16.83766)
		(end 29.13126 -19.94154)
		(width 0.10668)
		(layer "In4.Cu")
		(net "JTAG_MB_TDI")
	)
	(segment
		(start 52.76215 -31.34614)
		(end 53.230272 -31.539942)
		(width 0.10668)
		(layer "In4.Cu")
		(net "JTAG_MB_TDI")
	)
	(segment
		(start 8.51916 -28.63596)
		(end 9.14908 -28.00604)
		(width 0.10668)
		(layer "In4.Cu")
		(net "JTAG_MB_TDI")
	)
	(segment
		(start 11.95832 -17.02308)
		(end 12.3444 -16.637)
		(width 0.10668)
		(layer "In4.Cu")
		(net "JTAG_MB_TDI")
	)
	(segment
		(start 1.993392 -78.12405)
		(end 1.993392 -31.017972)
		(width 0.10668)
		(layer "In4.Cu")
		(net "JTAG_MB_TDI")
	)
	(segment
		(start 52.20208 -30.78607)
		(end 52.76215 -31.34614)
		(width 0.10668)
		(layer "In4.Cu")
		(net "JTAG_MB_TDI")
	)
	(segment
		(start 52.20208 -29.118052)
		(end 52.20208 -30.78607)
		(width 0.10668)
		(layer "In4.Cu")
		(net "JTAG_MB_TDI")
	)
	(segment
		(start 11.87704 -27.0002)
		(end 13.06957 -25.80767)
		(width 0.10668)
		(layer "In4.Cu")
		(net "JTAG_MB_TDI")
	)
	(segment
		(start 11.95832 -21.30552)
		(end 11.95832 -17.02308)
		(width 0.10668)
		(layer "In4.Cu")
		(net "JTAG_MB_TDI")
	)
	(segment
		(start 7.26948 -28.10002)
		(end 7.80542 -28.63596)
		(width 0.10668)
		(layer "In4.Cu")
		(net "JTAG_MB_TDI")
	)
	(segment
		(start 5.461508 -108.033566)
		(end 2.094992 -104.66705)
		(width 0.10668)
		(layer "In4.Cu")
		(net "JTAG_MB_TDI")
	)
	(segment
		(start 12.3444 -16.637)
		(end 13.208 -16.637)
		(width 0.10668)
		(layer "In4.Cu")
		(net "JTAG_MB_TDI")
	)
	(segment
		(start 29.13126 -19.94154)
		(end 30.06852 -20.8788)
		(width 0.10668)
		(layer "In4.Cu")
		(net "JTAG_MB_TDI")
	)
	(segment
		(start 7.80542 -28.63596)
		(end 8.51916 -28.63596)
		(width 0.10668)
		(layer "In4.Cu")
		(net "JTAG_MB_TDI")
	)
	(segment
		(start 9.7536 -27.0002)
		(end 11.87704 -27.0002)
		(width 0.10668)
		(layer "In4.Cu")
		(net "JTAG_MB_TDI")
	)
	(segment
		(start 51.940714 -28.856686)
		(end 52.20208 -29.118052)
		(width 0.10668)
		(layer "In4.Cu")
		(net "JTAG_MB_TDI")
	)
	(segment
		(start 42.703242 -25.2476)
		(end 42.809922 -25.14092)
		(width 0.10668)
		(layer "In4.Cu")
		(net "JTAG_MB_TDI")
	)
	(segment
		(start 48.279558 -26.41346)
		(end 50.722784 -28.856686)
		(width 0.10668)
		(layer "In4.Cu")
		(net "JTAG_MB_TDI")
	)
	(segment
		(start 13.69314 -24.535384)
		(end 13.69314 -23.04034)
		(width 0.10668)
		(layer "In4.Cu")
		(net "JTAG_MB_TDI")
	)
	(segment
		(start 4.911344 -28.10002)
		(end 7.26948 -28.10002)
		(width 0.10668)
		(layer "In4.Cu")
		(net "JTAG_MB_TDI")
	)
	(segment
		(start 4.743196 -80.873854)
		(end 1.993392 -78.12405)
		(width 0.10668)
		(layer "In4.Cu")
		(net "JTAG_MB_TDI")
	)
	(segment
		(start 4.743196 -85.53323)
		(end 4.743196 -80.873854)
		(width 0.10668)
		(layer "In4.Cu")
		(net "JTAG_MB_TDI")
	)
	(segment
		(start 33.731454 -25.2476)
		(end 42.703242 -25.2476)
		(width 0.10668)
		(layer "In4.Cu")
		(net "JTAG_MB_TDI")
	)
	(segment
		(start 53.44668 -33.172654)
		(end 52.991258 -33.628076)
		(width 0.10668)
		(layer "In4.Cu")
		(net "JTAG_MB_TDI")
	)
	(segment
		(start 6.401308 -108.033566)
		(end 5.461508 -108.033566)
		(width 0.10668)
		(layer "In4.Cu")
		(net "JTAG_MB_TDI")
	)
	(segment
		(start 9.14908 -28.00604)
		(end 9.14908 -27.60472)
		(width 0.10668)
		(layer "In4.Cu")
		(net "JTAG_MB_TDI")
	)
	(segment
		(start 2.094992 -104.66705)
		(end 2.094992 -88.181434)
		(width 0.10668)
		(layer "In4.Cu")
		(net "JTAG_MB_TDI")
	)
	(segment
		(start 9.14908 -27.60472)
		(end 9.7536 -27.0002)
		(width 0.10668)
		(layer "In4.Cu")
		(net "JTAG_MB_TDI")
	)
	(segment
		(start 2.094992 -88.181434)
		(end 4.743196 -85.53323)
		(width 0.10668)
		(layer "In4.Cu")
		(net "JTAG_MB_TDI")
	)
	(segment
		(start 50.722784 -28.856686)
		(end 51.940714 -28.856686)
		(width 0.10668)
		(layer "In4.Cu")
		(net "JTAG_MB_TDI")
	)
	(via
		(at 12.178792 -51.054)
		(size 0.508)
		(drill 0.254)
		(layers "F.Cu" "B.Cu")
		(net "JTAG_1_BMC_TDO_R")
	)
	(via
		(at 36.322 -105.3084)
		(size 0.508)
		(drill 0.254)
		(layers "F.Cu" "B.Cu")
		(net "JTAG_1_BMC_TDO_R")
	)
	(via
		(at 31.581852 -52.004468)
		(size 0.508)
		(drill 0.254)
		(layers "F.Cu" "B.Cu")
		(net "JTAG_1_BMC_TDO_R")
	)
	(via
		(at 8.382 -80.9498)
		(size 0.508)
		(drill 0.254)
		(layers "F.Cu" "B.Cu")
		(net "JTAG_1_BMC_TDO_R")
	)
	(segment
		(start 31.581852 -52.004468)
		(end 32.178752 -52.004468)
		(width 0.11684)
		(layer "B.Cu")
		(net "JTAG_1_BMC_TDO_R")
	)
	(segment
		(start 34.065464 -50.117756)
		(end 34.065464 -49.705514)
		(width 0.11684)
		(layer "B.Cu")
		(net "JTAG_1_BMC_TDO_R")
	)
	(segment
		(start 32.178752 -52.004468)
		(end 34.065464 -50.117756)
		(width 0.11684)
		(layer "B.Cu")
		(net "JTAG_1_BMC_TDO_R")
	)
	(segment
		(start 34.065464 -49.705514)
		(end 34.04235 -49.6824)
		(width 0.11684)
		(layer "B.Cu")
		(net "JTAG_1_BMC_TDO_R")
	)
	(segment
		(start 36.322 -105.3084)
		(end 36.2966 -105.3084)
		(width 0.11684)
		(layer "B.Cu")
		(net "JTAG_1_BMC_TDO_R")
	)
	(segment
		(start 36.068 -105.537)
		(end 36.068 -105.96245)
		(width 0.11684)
		(layer "B.Cu")
		(net "JTAG_1_BMC_TDO_R")
	)
	(segment
		(start 36.2966 -105.3084)
		(end 36.068 -105.537)
		(width 0.11684)
		(layer "B.Cu")
		(net "JTAG_1_BMC_TDO_R")
	)
	(segment
		(start 30.697932 -52.004468)
		(end 31.581852 -52.004468)
		(width 0.08382)
		(layer "In2.Cu")
		(net "JTAG_1_BMC_TDO_R")
	)
	(segment
		(start 24.669242 -57.409842)
		(end 25.758902 -57.8612)
		(width 0.08382)
		(layer "In2.Cu")
		(net "JTAG_1_BMC_TDO_R")
	)
	(segment
		(start 27.460702 -57.8612)
		(end 28.498546 -57.431178)
		(width 0.08382)
		(layer "In2.Cu")
		(net "JTAG_1_BMC_TDO_R")
	)
	(segment
		(start 30.48762 -55.66918)
		(end 30.48762 -52.21478)
		(width 0.08382)
		(layer "In2.Cu")
		(net "JTAG_1_BMC_TDO_R")
	)
	(segment
		(start 25.758902 -57.8612)
		(end 27.460702 -57.8612)
		(width 0.08382)
		(layer "In2.Cu")
		(net "JTAG_1_BMC_TDO_R")
	)
	(segment
		(start 12.65936 -51.054)
		(end 13.06576 -51.4604)
		(width 0.08382)
		(layer "In2.Cu")
		(net "JTAG_1_BMC_TDO_R")
	)
	(segment
		(start 30.48762 -52.21478)
		(end 30.697932 -52.004468)
		(width 0.08382)
		(layer "In2.Cu")
		(net "JTAG_1_BMC_TDO_R")
	)
	(segment
		(start 13.06576 -51.4604)
		(end 14.732 -51.4604)
		(width 0.08382)
		(layer "In2.Cu")
		(net "JTAG_1_BMC_TDO_R")
	)
	(segment
		(start 16.747998 -53.476398)
		(end 20.735798 -53.476398)
		(width 0.08382)
		(layer "In2.Cu")
		(net "JTAG_1_BMC_TDO_R")
	)
	(segment
		(start 14.732 -51.4604)
		(end 16.747998 -53.476398)
		(width 0.08382)
		(layer "In2.Cu")
		(net "JTAG_1_BMC_TDO_R")
	)
	(segment
		(start 29.182314 -56.974486)
		(end 30.48762 -55.66918)
		(width 0.08382)
		(layer "In2.Cu")
		(net "JTAG_1_BMC_TDO_R")
	)
	(segment
		(start 28.498546 -57.431178)
		(end 29.182314 -56.974486)
		(width 0.08382)
		(layer "In2.Cu")
		(net "JTAG_1_BMC_TDO_R")
	)
	(segment
		(start 12.178792 -51.054)
		(end 12.65936 -51.054)
		(width 0.08382)
		(layer "In2.Cu")
		(net "JTAG_1_BMC_TDO_R")
	)
	(segment
		(start 20.735798 -53.476398)
		(end 24.669242 -57.409842)
		(width 0.08382)
		(layer "In2.Cu")
		(net "JTAG_1_BMC_TDO_R")
	)
	(segment
		(start 22.17928 -110.129574)
		(end 20.777454 -111.5314)
		(width 0.10668)
		(layer "In4.Cu")
		(net "JTAG_1_BMC_TDO_R")
	)
	(segment
		(start 8.4836 -109.61116)
		(end 8.4836 -108.001054)
		(width 0.10668)
		(layer "In4.Cu")
		(net "JTAG_1_BMC_TDO_R")
	)
	(segment
		(start 3.61188 -100.282502)
		(end 3.61188 -92.630498)
		(width 0.10668)
		(layer "In4.Cu")
		(net "JTAG_1_BMC_TDO_R")
	)
	(segment
		(start 4.10972 -92.132658)
		(end 4.10972 -91.726258)
		(width 0.10668)
		(layer "In4.Cu")
		(net "JTAG_1_BMC_TDO_R")
	)
	(segment
		(start 4.10972 -91.726258)
		(end 4.38404 -91.451938)
		(width 0.10668)
		(layer "In4.Cu")
		(net "JTAG_1_BMC_TDO_R")
	)
	(segment
		(start 4.3942 -105.47731)
		(end 4.30784 -105.39095)
		(width 0.10668)
		(layer "In4.Cu")
		(net "JTAG_1_BMC_TDO_R")
	)
	(segment
		(start 7.37108 -81.96072)
		(end 8.382 -80.9498)
		(width 0.10668)
		(layer "In4.Cu")
		(net "JTAG_1_BMC_TDO_R")
	)
	(segment
		(start 19.093688 -112.046258)
		(end 17.700498 -112.046258)
		(width 0.10668)
		(layer "In4.Cu")
		(net "JTAG_1_BMC_TDO_R")
	)
	(segment
		(start 4.3942 -105.477564)
		(end 4.3942 -105.47731)
		(width 0.10668)
		(layer "In4.Cu")
		(net "JTAG_1_BMC_TDO_R")
	)
	(segment
		(start 4.02336 -102.474014)
		(end 4.02336 -100.693982)
		(width 0.10668)
		(layer "In4.Cu")
		(net "JTAG_1_BMC_TDO_R")
	)
	(segment
		(start 4.30784 -105.39095)
		(end 4.30784 -102.758494)
		(width 0.10668)
		(layer "In4.Cu")
		(net "JTAG_1_BMC_TDO_R")
	)
	(segment
		(start 6.30682 -105.824274)
		(end 4.74091 -105.824274)
		(width 0.10668)
		(layer "In4.Cu")
		(net "JTAG_1_BMC_TDO_R")
	)
	(segment
		(start 4.38404 -91.451938)
		(end 4.38404 -90.10904)
		(width 0.10668)
		(layer "In4.Cu")
		(net "JTAG_1_BMC_TDO_R")
	)
	(segment
		(start 7.37108 -84.07908)
		(end 7.37108 -81.96072)
		(width 0.10668)
		(layer "In4.Cu")
		(net "JTAG_1_BMC_TDO_R")
	)
	(segment
		(start 4.3942 -88.256618)
		(end 5.020818 -87.63)
		(width 0.10668)
		(layer "In4.Cu")
		(net "JTAG_1_BMC_TDO_R")
	)
	(segment
		(start 5.020818 -87.63)
		(end 8.001 -87.63)
		(width 0.10668)
		(layer "In4.Cu")
		(net "JTAG_1_BMC_TDO_R")
	)
	(segment
		(start 8.382 -85.09)
		(end 7.37108 -84.07908)
		(width 0.10668)
		(layer "In4.Cu")
		(net "JTAG_1_BMC_TDO_R")
	)
	(segment
		(start 25.234392 -110.129574)
		(end 22.17928 -110.129574)
		(width 0.10668)
		(layer "In4.Cu")
		(net "JTAG_1_BMC_TDO_R")
	)
	(segment
		(start 17.19072 -111.53648)
		(end 9.977882 -111.53648)
		(width 0.10668)
		(layer "In4.Cu")
		(net "JTAG_1_BMC_TDO_R")
	)
	(segment
		(start 34.68116 -111.82604)
		(end 26.930858 -111.82604)
		(width 0.10668)
		(layer "In4.Cu")
		(net "JTAG_1_BMC_TDO_R")
	)
	(segment
		(start 8.001 -87.63)
		(end 8.382 -87.249)
		(width 0.10668)
		(layer "In4.Cu")
		(net "JTAG_1_BMC_TDO_R")
	)
	(segment
		(start 8.382 -87.249)
		(end 8.382 -85.09)
		(width 0.10668)
		(layer "In4.Cu")
		(net "JTAG_1_BMC_TDO_R")
	)
	(segment
		(start 8.4836 -108.001054)
		(end 6.30682 -105.824274)
		(width 0.10668)
		(layer "In4.Cu")
		(net "JTAG_1_BMC_TDO_R")
	)
	(segment
		(start 36.322 -105.3084)
		(end 36.322 -110.1852)
		(width 0.10668)
		(layer "In4.Cu")
		(net "JTAG_1_BMC_TDO_R")
	)
	(segment
		(start 19.608546 -111.5314)
		(end 19.093688 -112.046258)
		(width 0.10668)
		(layer "In4.Cu")
		(net "JTAG_1_BMC_TDO_R")
	)
	(segment
		(start 36.322 -110.1852)
		(end 34.68116 -111.82604)
		(width 0.10668)
		(layer "In4.Cu")
		(net "JTAG_1_BMC_TDO_R")
	)
	(segment
		(start 8.61314 -109.7407)
		(end 8.4836 -109.61116)
		(width 0.10668)
		(layer "In4.Cu")
		(net "JTAG_1_BMC_TDO_R")
	)
	(segment
		(start 20.777454 -111.5314)
		(end 19.608546 -111.5314)
		(width 0.10668)
		(layer "In4.Cu")
		(net "JTAG_1_BMC_TDO_R")
	)
	(segment
		(start 4.38404 -90.10904)
		(end 4.3942 -90.09888)
		(width 0.10668)
		(layer "In4.Cu")
		(net "JTAG_1_BMC_TDO_R")
	)
	(segment
		(start 3.61188 -92.630498)
		(end 4.10972 -92.132658)
		(width 0.10668)
		(layer "In4.Cu")
		(net "JTAG_1_BMC_TDO_R")
	)
	(segment
		(start 4.02336 -100.693982)
		(end 3.61188 -100.282502)
		(width 0.10668)
		(layer "In4.Cu")
		(net "JTAG_1_BMC_TDO_R")
	)
	(segment
		(start 9.977882 -111.53648)
		(end 8.61314 -110.171738)
		(width 0.10668)
		(layer "In4.Cu")
		(net "JTAG_1_BMC_TDO_R")
	)
	(segment
		(start 17.700498 -112.046258)
		(end 17.19072 -111.53648)
		(width 0.10668)
		(layer "In4.Cu")
		(net "JTAG_1_BMC_TDO_R")
	)
	(segment
		(start 8.61314 -110.171738)
		(end 8.61314 -109.7407)
		(width 0.10668)
		(layer "In4.Cu")
		(net "JTAG_1_BMC_TDO_R")
	)
	(segment
		(start 4.3942 -90.09888)
		(end 4.3942 -88.256618)
		(width 0.10668)
		(layer "In4.Cu")
		(net "JTAG_1_BMC_TDO_R")
	)
	(segment
		(start 4.30784 -102.758494)
		(end 4.02336 -102.474014)
		(width 0.10668)
		(layer "In4.Cu")
		(net "JTAG_1_BMC_TDO_R")
	)
	(segment
		(start 26.930858 -111.82604)
		(end 25.234392 -110.129574)
		(width 0.10668)
		(layer "In4.Cu")
		(net "JTAG_1_BMC_TDO_R")
	)
	(segment
		(start 4.74091 -105.824274)
		(end 4.3942 -105.477564)
		(width 0.10668)
		(layer "In4.Cu")
		(net "JTAG_1_BMC_TDO_R")
	)
	(segment
		(start 12.008866 -66.780918)
		(end 12.008866 -59.070494)
		(width 0.10668)
		(layer "In7.Cu")
		(net "JTAG_1_BMC_TDO_R")
	)
	(segment
		(start 12.008866 -59.070494)
		(end 12.8778 -58.20156)
		(width 0.10668)
		(layer "In7.Cu")
		(net "JTAG_1_BMC_TDO_R")
	)
	(segment
		(start 11.97102 -53.106828)
		(end 11.97102 -51.261772)
		(width 0.10668)
		(layer "In7.Cu")
		(net "JTAG_1_BMC_TDO_R")
	)
	(segment
		(start 11.14552 -79.27086)
		(end 11.14552 -76.699364)
		(width 0.10668)
		(layer "In7.Cu")
		(net "JTAG_1_BMC_TDO_R")
	)
	(segment
		(start 11.85926 -75.985624)
		(end 12.253976 -75.985624)
		(width 0.10668)
		(layer "In7.Cu")
		(net "JTAG_1_BMC_TDO_R")
	)
	(segment
		(start 12.542266 -67.314318)
		(end 12.008866 -66.780918)
		(width 0.10668)
		(layer "In7.Cu")
		(net "JTAG_1_BMC_TDO_R")
	)
	(segment
		(start 8.792972 -80.538828)
		(end 9.877552 -80.538828)
		(width 0.10668)
		(layer "In7.Cu")
		(net "JTAG_1_BMC_TDO_R")
	)
	(segment
		(start 11.97102 -51.261772)
		(end 12.178792 -51.054)
		(width 0.10668)
		(layer "In7.Cu")
		(net "JTAG_1_BMC_TDO_R")
	)
	(segment
		(start 12.666726 -53.802534)
		(end 11.97102 -53.106828)
		(width 0.10668)
		(layer "In7.Cu")
		(net "JTAG_1_BMC_TDO_R")
	)
	(segment
		(start 12.666726 -55.618126)
		(end 12.666726 -53.802534)
		(width 0.10668)
		(layer "In7.Cu")
		(net "JTAG_1_BMC_TDO_R")
	)
	(segment
		(start 9.877552 -80.538828)
		(end 11.14552 -79.27086)
		(width 0.10668)
		(layer "In7.Cu")
		(net "JTAG_1_BMC_TDO_R")
	)
	(segment
		(start 8.382 -80.9498)
		(end 8.792972 -80.538828)
		(width 0.10668)
		(layer "In7.Cu")
		(net "JTAG_1_BMC_TDO_R")
	)
	(segment
		(start 12.542266 -75.697334)
		(end 12.542266 -67.314318)
		(width 0.10668)
		(layer "In7.Cu")
		(net "JTAG_1_BMC_TDO_R")
	)
	(segment
		(start 12.253976 -75.985624)
		(end 12.542266 -75.697334)
		(width 0.10668)
		(layer "In7.Cu")
		(net "JTAG_1_BMC_TDO_R")
	)
	(segment
		(start 11.14552 -76.699364)
		(end 11.85926 -75.985624)
		(width 0.10668)
		(layer "In7.Cu")
		(net "JTAG_1_BMC_TDO_R")
	)
	(segment
		(start 12.8778 -55.8292)
		(end 12.666726 -55.618126)
		(width 0.10668)
		(layer "In7.Cu")
		(net "JTAG_1_BMC_TDO_R")
	)
	(segment
		(start 12.8778 -58.20156)
		(end 12.8778 -55.8292)
		(width 0.10668)
		(layer "In7.Cu")
		(net "JTAG_1_BMC_TDO_R")
	)
	(segment
		(start 25.527 -103.14305)
		(end 25.516078 -103.153972)
		(width 0.11684)
		(layer "F.Cu")
		(net "FM_BMC_SUSACK_N")
	)
	(segment
		(start 25.516078 -103.153972)
		(end 25.516078 -103.9114)
		(width 0.11684)
		(layer "F.Cu")
		(net "FM_BMC_SUSACK_N")
	)
	(via
		(at 55.21706 -101.94036)
		(size 0.508)
		(drill 0.254)
		(layers "F.Cu" "B.Cu")
		(net "FM_BMC_SUSACK_N")
	)
	(via
		(at 31.623 -107.69727)
		(size 0.508)
		(drill 0.254)
		(layers "F.Cu" "B.Cu")
		(net "FM_BMC_SUSACK_N")
	)
	(via
		(at 25.516078 -103.9114)
		(size 0.508)
		(drill 0.254)
		(layers "F.Cu" "B.Cu")
		(net "FM_BMC_SUSACK_N")
	)
	(via
		(at 54.364636 -66.416428)
		(size 0.762)
		(drill 0.254)
		(layers "F.Cu" "B.Cu")
		(net "FM_BMC_SUSACK_N")
	)
	(segment
		(start 52.228242 -66.30035)
		(end 52.469542 -66.54165)
		(width 0.11684)
		(layer "B.Cu")
		(net "FM_BMC_SUSACK_N")
	)
	(segment
		(start 51.816 -66.30035)
		(end 52.228242 -66.30035)
		(width 0.11684)
		(layer "B.Cu")
		(net "FM_BMC_SUSACK_N")
	)
	(segment
		(start 54.318408 -66.3702)
		(end 53.13045 -66.3702)
		(width 0.11684)
		(layer "B.Cu")
		(net "FM_BMC_SUSACK_N")
	)
	(segment
		(start 53.13045 -66.3702)
		(end 52.959 -66.54165)
		(width 0.11684)
		(layer "B.Cu")
		(net "FM_BMC_SUSACK_N")
	)
	(segment
		(start 52.469542 -66.54165)
		(end 52.959 -66.54165)
		(width 0.11684)
		(layer "B.Cu")
		(net "FM_BMC_SUSACK_N")
	)
	(segment
		(start 54.364636 -66.416428)
		(end 54.318408 -66.3702)
		(width 0.11684)
		(layer "B.Cu")
		(net "FM_BMC_SUSACK_N")
	)
	(segment
		(start 39.215314 -106.217466)
		(end 33.838134 -106.217466)
		(width 0.08382)
		(layer "In2.Cu")
		(net "FM_BMC_SUSACK_N")
	)
	(segment
		(start 54.985666 -102.174294)
		(end 52.486306 -102.174294)
		(width 0.08382)
		(layer "In2.Cu")
		(net "FM_BMC_SUSACK_N")
	)
	(segment
		(start 51.7906 -102.87)
		(end 51.7906 -104.30002)
		(width 0.08382)
		(layer "In2.Cu")
		(net "FM_BMC_SUSACK_N")
	)
	(segment
		(start 55.21706 -101.9429)
		(end 54.985666 -102.174294)
		(width 0.08382)
		(layer "In2.Cu")
		(net "FM_BMC_SUSACK_N")
	)
	(segment
		(start 52.486306 -102.174294)
		(end 51.7906 -102.87)
		(width 0.08382)
		(layer "In2.Cu")
		(net "FM_BMC_SUSACK_N")
	)
	(segment
		(start 40.259 -104.5464)
		(end 39.8018 -105.0036)
		(width 0.08382)
		(layer "In2.Cu")
		(net "FM_BMC_SUSACK_N")
	)
	(segment
		(start 33.838134 -106.217466)
		(end 32.35833 -107.69727)
		(width 0.08382)
		(layer "In2.Cu")
		(net "FM_BMC_SUSACK_N")
	)
	(segment
		(start 39.8018 -105.63098)
		(end 39.215314 -106.217466)
		(width 0.08382)
		(layer "In2.Cu")
		(net "FM_BMC_SUSACK_N")
	)
	(segment
		(start 39.8018 -105.0036)
		(end 39.8018 -105.63098)
		(width 0.08382)
		(layer "In2.Cu")
		(net "FM_BMC_SUSACK_N")
	)
	(segment
		(start 32.35833 -107.69727)
		(end 31.623 -107.69727)
		(width 0.08382)
		(layer "In2.Cu")
		(net "FM_BMC_SUSACK_N")
	)
	(segment
		(start 51.17973 -104.91089)
		(end 47.73549 -104.91089)
		(width 0.08382)
		(layer "In2.Cu")
		(net "FM_BMC_SUSACK_N")
	)
	(segment
		(start 51.7906 -104.30002)
		(end 51.17973 -104.91089)
		(width 0.08382)
		(layer "In2.Cu")
		(net "FM_BMC_SUSACK_N")
	)
	(segment
		(start 55.21706 -101.94036)
		(end 55.21706 -101.9429)
		(width 0.08382)
		(layer "In2.Cu")
		(net "FM_BMC_SUSACK_N")
	)
	(segment
		(start 47.371 -104.5464)
		(end 40.259 -104.5464)
		(width 0.08382)
		(layer "In2.Cu")
		(net "FM_BMC_SUSACK_N")
	)
	(segment
		(start 47.73549 -104.91089)
		(end 47.371 -104.5464)
		(width 0.08382)
		(layer "In2.Cu")
		(net "FM_BMC_SUSACK_N")
	)
	(segment
		(start 30.48 -105.2322)
		(end 31.623 -106.3752)
		(width 0.10668)
		(layer "In4.Cu")
		(net "FM_BMC_SUSACK_N")
	)
	(segment
		(start 25.516078 -103.9114)
		(end 25.516078 -104.281478)
		(width 0.10668)
		(layer "In4.Cu")
		(net "FM_BMC_SUSACK_N")
	)
	(segment
		(start 31.623 -106.3752)
		(end 31.623 -107.69727)
		(width 0.10668)
		(layer "In4.Cu")
		(net "FM_BMC_SUSACK_N")
	)
	(segment
		(start 26.4668 -105.2322)
		(end 30.48 -105.2322)
		(width 0.10668)
		(layer "In4.Cu")
		(net "FM_BMC_SUSACK_N")
	)
	(segment
		(start 25.516078 -104.281478)
		(end 26.4668 -105.2322)
		(width 0.10668)
		(layer "In4.Cu")
		(net "FM_BMC_SUSACK_N")
	)
	(segment
		(start 56.40324 -100.24364)
		(end 55.21706 -101.42982)
		(width 0.08382)
		(layer "In9.Cu")
		(net "FM_BMC_SUSACK_N")
	)
	(segment
		(start 55.150004 -78.104746)
		(end 56.134 -80.480154)
		(width 0.08382)
		(layer "In9.Cu")
		(net "FM_BMC_SUSACK_N")
	)
	(segment
		(start 58.92546 -100.24364)
		(end 56.40324 -100.24364)
		(width 0.08382)
		(layer "In9.Cu")
		(net "FM_BMC_SUSACK_N")
	)
	(segment
		(start 56.68391 -83.70951)
		(end 56.68391 -90.35415)
		(width 0.08382)
		(layer "In9.Cu")
		(net "FM_BMC_SUSACK_N")
	)
	(segment
		(start 55.21706 -101.42982)
		(end 55.21706 -101.94036)
		(width 0.08382)
		(layer "In9.Cu")
		(net "FM_BMC_SUSACK_N")
	)
	(segment
		(start 56.134 -83.1596)
		(end 56.68391 -83.70951)
		(width 0.08382)
		(layer "In9.Cu")
		(net "FM_BMC_SUSACK_N")
	)
	(segment
		(start 54.364636 -66.416428)
		(end 54.364636 -67.14109)
		(width 0.08382)
		(layer "In9.Cu")
		(net "FM_BMC_SUSACK_N")
	)
	(segment
		(start 55.16118 -70.821804)
		(end 54.824376 -71.158608)
		(width 0.08382)
		(layer "In9.Cu")
		(net "FM_BMC_SUSACK_N")
	)
	(segment
		(start 55.16118 -67.937634)
		(end 55.16118 -70.821804)
		(width 0.08382)
		(layer "In9.Cu")
		(net "FM_BMC_SUSACK_N")
	)
	(segment
		(start 59.8678 -93.53804)
		(end 59.8678 -99.3013)
		(width 0.08382)
		(layer "In9.Cu")
		(net "FM_BMC_SUSACK_N")
	)
	(segment
		(start 59.8678 -99.3013)
		(end 58.92546 -100.24364)
		(width 0.08382)
		(layer "In9.Cu")
		(net "FM_BMC_SUSACK_N")
	)
	(segment
		(start 54.824376 -74.481182)
		(end 55.150004 -74.80681)
		(width 0.08382)
		(layer "In9.Cu")
		(net "FM_BMC_SUSACK_N")
	)
	(segment
		(start 55.150004 -74.80681)
		(end 55.150004 -78.104746)
		(width 0.08382)
		(layer "In9.Cu")
		(net "FM_BMC_SUSACK_N")
	)
	(segment
		(start 56.134 -80.480154)
		(end 56.134 -83.1596)
		(width 0.08382)
		(layer "In9.Cu")
		(net "FM_BMC_SUSACK_N")
	)
	(segment
		(start 54.824376 -71.158608)
		(end 54.824376 -74.481182)
		(width 0.08382)
		(layer "In9.Cu")
		(net "FM_BMC_SUSACK_N")
	)
	(segment
		(start 54.364636 -67.14109)
		(end 55.16118 -67.937634)
		(width 0.08382)
		(layer "In9.Cu")
		(net "FM_BMC_SUSACK_N")
	)
	(segment
		(start 56.68391 -90.35415)
		(end 59.8678 -93.53804)
		(width 0.08382)
		(layer "In9.Cu")
		(net "FM_BMC_SUSACK_N")
	)
	(segment
		(start 6.9088 -97.865946)
		(end 6.9088 -97.16389)
		(width 0.11684)
		(layer "F.Cu")
		(net "JTAG_SCM_PLD_R1_JTAGEN")
	)
	(segment
		(start 6.9088 -97.16389)
		(end 6.050026 -96.305116)
		(width 0.11684)
		(layer "F.Cu")
		(net "JTAG_SCM_PLD_R1_JTAGEN")
	)
	(segment
		(start 8.731504 -98.69805)
		(end 8.458454 -98.425)
		(width 0.11684)
		(layer "F.Cu")
		(net "JTAG_SCM_PLD_R1_JTAGEN")
	)
	(segment
		(start 8.458454 -98.425)
		(end 7.467854 -98.425)
		(width 0.11684)
		(layer "F.Cu")
		(net "JTAG_SCM_PLD_R1_JTAGEN")
	)
	(segment
		(start 10.287 -98.69805)
		(end 8.731504 -98.69805)
		(width 0.11684)
		(layer "F.Cu")
		(net "JTAG_SCM_PLD_R1_JTAGEN")
	)
	(segment
		(start 7.467854 -98.425)
		(end 6.9088 -97.865946)
		(width 0.11684)
		(layer "F.Cu")
		(net "JTAG_SCM_PLD_R1_JTAGEN")
	)
	(segment
		(start 20.574 -84.16544)
		(end 19.4818 -85.25764)
		(width 0.11684)
		(layer "F.Cu")
		(net "JTAG_SCM_PLD_TMS")
	)
	(segment
		(start 19.4818 -85.25764)
		(end 19.4818 -85.8012)
		(width 0.11684)
		(layer "F.Cu")
		(net "JTAG_SCM_PLD_TMS")
	)
	(segment
		(start 9.6774 -94.21495)
		(end 9.6012 -94.29115)
		(width 0.11684)
		(layer "F.Cu")
		(net "JTAG_SCM_PLD_TMS")
	)
	(segment
		(start 21.463 -86.7918)
		(end 21.209 -86.5378)
		(width 0.11684)
		(layer "F.Cu")
		(net "JTAG_SCM_PLD_TMS")
	)
	(segment
		(start 21.209 -86.5378)
		(end 20.4978 -86.5378)
		(width 0.11684)
		(layer "F.Cu")
		(net "JTAG_SCM_PLD_TMS")
	)
	(segment
		(start 20.4978 -86.5378)
		(end 20.313904 -86.353904)
		(width 0.11684)
		(layer "F.Cu")
		(net "JTAG_SCM_PLD_TMS")
	)
	(segment
		(start 20.574 -81.7626)
		(end 20.574 -84.16544)
		(width 0.11684)
		(layer "F.Cu")
		(net "JTAG_SCM_PLD_TMS")
	)
	(segment
		(start 21.859494 -88.387174)
		(end 21.463 -87.99068)
		(width 0.11684)
		(layer "F.Cu")
		(net "JTAG_SCM_PLD_TMS")
	)
	(segment
		(start 20.313904 -86.353904)
		(end 19.995896 -86.353904)
		(width 0.11684)
		(layer "F.Cu")
		(net "JTAG_SCM_PLD_TMS")
	)
	(segment
		(start 19.4818 -85.8012)
		(end 19.995896 -86.315296)
		(width 0.11684)
		(layer "F.Cu")
		(net "JTAG_SCM_PLD_TMS")
	)
	(segment
		(start 19.995896 -86.315296)
		(end 19.995896 -86.353904)
		(width 0.11684)
		(layer "F.Cu")
		(net "JTAG_SCM_PLD_TMS")
	)
	(segment
		(start 21.463 -87.99068)
		(end 21.463 -86.7918)
		(width 0.11684)
		(layer "F.Cu")
		(net "JTAG_SCM_PLD_TMS")
	)
	(segment
		(start 64.135 -24.1554)
		(end 63.8048 -23.8252)
		(width 0.11684)
		(layer "F.Cu")
		(net "JTAG_SCM_PLD_TMS")
	)
	(segment
		(start 19.995896 -86.353904)
		(end 19.9898 -86.36)
		(width 0.11684)
		(layer "F.Cu")
		(net "JTAG_SCM_PLD_TMS")
	)
	(segment
		(start 10.287 -94.21495)
		(end 9.6774 -94.21495)
		(width 0.11684)
		(layer "F.Cu")
		(net "JTAG_SCM_PLD_TMS")
	)
	(segment
		(start 64.57315 -24.1554)
		(end 64.135 -24.1554)
		(width 0.11684)
		(layer "F.Cu")
		(net "JTAG_SCM_PLD_TMS")
	)
	(via
		(at 9.6012 -94.29115)
		(size 0.508)
		(drill 0.254)
		(layers "F.Cu" "B.Cu")
		(net "JTAG_SCM_PLD_TMS")
	)
	(via
		(at 20.574 -81.7626)
		(size 0.508)
		(drill 0.254)
		(layers "F.Cu" "B.Cu")
		(net "JTAG_SCM_PLD_TMS")
	)
	(via
		(at 19.9898 -86.36)
		(size 0.508)
		(drill 0.254)
		(layers "F.Cu" "B.Cu")
		(net "JTAG_SCM_PLD_TMS")
	)
	(via
		(at 63.8048 -23.8252)
		(size 0.508)
		(drill 0.254)
		(layers "F.Cu" "B.Cu")
		(net "JTAG_SCM_PLD_TMS")
	)
	(segment
		(start 10.17778 -93.71457)
		(end 9.6012 -94.29115)
		(width 0.08382)
		(layer "In2.Cu")
		(net "JTAG_SCM_PLD_TMS")
	)
	(segment
		(start 18.5166 -86.0552)
		(end 17.9578 -86.0552)
		(width 0.08382)
		(layer "In2.Cu")
		(net "JTAG_SCM_PLD_TMS")
	)
	(segment
		(start 17.526 -86.487)
		(end 14.07668 -86.487)
		(width 0.08382)
		(layer "In2.Cu")
		(net "JTAG_SCM_PLD_TMS")
	)
	(segment
		(start 14.07668 -86.487)
		(end 11.72337 -88.84031)
		(width 0.08382)
		(layer "In2.Cu")
		(net "JTAG_SCM_PLD_TMS")
	)
	(segment
		(start 19.9898 -86.36)
		(end 18.8214 -86.36)
		(width 0.08382)
		(layer "In2.Cu")
		(net "JTAG_SCM_PLD_TMS")
	)
	(segment
		(start 18.8214 -86.36)
		(end 18.5166 -86.0552)
		(width 0.08382)
		(layer "In2.Cu")
		(net "JTAG_SCM_PLD_TMS")
	)
	(segment
		(start 11.72337 -88.84031)
		(end 11.03249 -88.84031)
		(width 0.08382)
		(layer "In2.Cu")
		(net "JTAG_SCM_PLD_TMS")
	)
	(segment
		(start 17.9578 -86.0552)
		(end 17.526 -86.487)
		(width 0.08382)
		(layer "In2.Cu")
		(net "JTAG_SCM_PLD_TMS")
	)
	(segment
		(start 11.03249 -88.84031)
		(end 10.17778 -89.69502)
		(width 0.08382)
		(layer "In2.Cu")
		(net "JTAG_SCM_PLD_TMS")
	)
	(segment
		(start 10.17778 -89.69502)
		(end 10.17778 -93.71457)
		(width 0.08382)
		(layer "In2.Cu")
		(net "JTAG_SCM_PLD_TMS")
	)
	(segment
		(start 20.688046 -17.843754)
		(end 19.603974 -17.843754)
		(width 0.10668)
		(layer "In7.Cu")
		(net "JTAG_SCM_PLD_TMS")
	)
	(segment
		(start 56.650636 -21.662644)
		(end 54.078632 -19.09064)
		(width 0.10668)
		(layer "In7.Cu")
		(net "JTAG_SCM_PLD_TMS")
	)
	(segment
		(start 16.368522 -62.581282)
		(end 17.9832 -64.19596)
		(width 0.10668)
		(layer "In7.Cu")
		(net "JTAG_SCM_PLD_TMS")
	)
	(segment
		(start 20.955 -17.5768)
		(end 20.688046 -17.843754)
		(width 0.10668)
		(layer "In7.Cu")
		(net "JTAG_SCM_PLD_TMS")
	)
	(segment
		(start 17.9832 -66.34861)
		(end 17.71396 -66.61785)
		(width 0.10668)
		(layer "In7.Cu")
		(net "JTAG_SCM_PLD_TMS")
	)
	(segment
		(start 15.40764 -22.381464)
		(end 15.40764 -28.44292)
		(width 0.10668)
		(layer "In7.Cu")
		(net "JTAG_SCM_PLD_TMS")
	)
	(segment
		(start 15.40764 -28.44292)
		(end 15.728188 -28.763468)
		(width 0.10668)
		(layer "In7.Cu")
		(net "JTAG_SCM_PLD_TMS")
	)
	(segment
		(start 19.603974 -17.843754)
		(end 18.533364 -18.914364)
		(width 0.10668)
		(layer "In7.Cu")
		(net "JTAG_SCM_PLD_TMS")
	)
	(segment
		(start 17.9832 -64.19596)
		(end 17.9832 -66.34861)
		(width 0.10668)
		(layer "In7.Cu")
		(net "JTAG_SCM_PLD_TMS")
	)
	(segment
		(start 14.611604 -50.821844)
		(end 15.0241 -51.23434)
		(width 0.10668)
		(layer "In7.Cu")
		(net "JTAG_SCM_PLD_TMS")
	)
	(segment
		(start 15.88262 -51.794918)
		(end 15.88262 -52.920392)
		(width 0.10668)
		(layer "In7.Cu")
		(net "JTAG_SCM_PLD_TMS")
	)
	(segment
		(start 18.161 -78.5368)
		(end 19.431 -79.8068)
		(width 0.10668)
		(layer "In7.Cu")
		(net "JTAG_SCM_PLD_TMS")
	)
	(segment
		(start 16.163798 -34.139378)
		(end 16.407892 -34.302192)
		(width 0.10668)
		(layer "In7.Cu")
		(net "JTAG_SCM_PLD_TMS")
	)
	(segment
		(start 15.5702 -60.198)
		(end 15.5702 -60.654184)
		(width 0.10668)
		(layer "In7.Cu")
		(net "JTAG_SCM_PLD_TMS")
	)
	(segment
		(start 63.37554 -23.8252)
		(end 61.212984 -21.662644)
		(width 0.10668)
		(layer "In7.Cu")
		(net "JTAG_SCM_PLD_TMS")
	)
	(segment
		(start 14.611604 -47.11827)
		(end 14.611604 -50.821844)
		(width 0.10668)
		(layer "In7.Cu")
		(net "JTAG_SCM_PLD_TMS")
	)
	(segment
		(start 25.83307 -15.367254)
		(end 25.071324 -16.129)
		(width 0.10668)
		(layer "In7.Cu")
		(net "JTAG_SCM_PLD_TMS")
	)
	(segment
		(start 15.898368 -33.49879)
		(end 16.163798 -34.139378)
		(width 0.10668)
		(layer "In7.Cu")
		(net "JTAG_SCM_PLD_TMS")
	)
	(segment
		(start 36.532312 -16.00962)
		(end 28.07462 -16.00962)
		(width 0.10668)
		(layer "In7.Cu")
		(net "JTAG_SCM_PLD_TMS")
	)
	(segment
		(start 15.5702 -60.654184)
		(end 16.368522 -62.581282)
		(width 0.10668)
		(layer "In7.Cu")
		(net "JTAG_SCM_PLD_TMS")
	)
	(segment
		(start 15.728188 -29.128212)
		(end 15.70736 -29.14904)
		(width 0.10668)
		(layer "In7.Cu")
		(net "JTAG_SCM_PLD_TMS")
	)
	(segment
		(start 16.071342 -53.109114)
		(end 16.071342 -56.97855)
		(width 0.10668)
		(layer "In7.Cu")
		(net "JTAG_SCM_PLD_TMS")
	)
	(segment
		(start 15.70736 -57.342532)
		(end 15.70736 -60.06084)
		(width 0.10668)
		(layer "In7.Cu")
		(net "JTAG_SCM_PLD_TMS")
	)
	(segment
		(start 20.2692 -80.2132)
		(end 20.2692 -81.4578)
		(width 0.10668)
		(layer "In7.Cu")
		(net "JTAG_SCM_PLD_TMS")
	)
	(segment
		(start 15.728188 -28.763468)
		(end 15.728188 -29.128212)
		(width 0.10668)
		(layer "In7.Cu")
		(net "JTAG_SCM_PLD_TMS")
	)
	(segment
		(start 17.907 -75.0316)
		(end 17.907 -77.3684)
		(width 0.10668)
		(layer "In7.Cu")
		(net "JTAG_SCM_PLD_TMS")
	)
	(segment
		(start 16.071342 -56.97855)
		(end 15.70736 -57.342532)
		(width 0.10668)
		(layer "In7.Cu")
		(net "JTAG_SCM_PLD_TMS")
	)
	(segment
		(start 61.212984 -21.662644)
		(end 56.650636 -21.662644)
		(width 0.10668)
		(layer "In7.Cu")
		(net "JTAG_SCM_PLD_TMS")
	)
	(segment
		(start 20.2692 -81.4578)
		(end 20.574 -81.7626)
		(width 0.10668)
		(layer "In7.Cu")
		(net "JTAG_SCM_PLD_TMS")
	)
	(segment
		(start 16.407892 -34.302192)
		(end 16.44523 -34.33953)
		(width 0.10668)
		(layer "In7.Cu")
		(net "JTAG_SCM_PLD_TMS")
	)
	(segment
		(start 17.43202 -74.55662)
		(end 17.907 -75.0316)
		(width 0.10668)
		(layer "In7.Cu")
		(net "JTAG_SCM_PLD_TMS")
	)
	(segment
		(start 28.07462 -16.00962)
		(end 27.432 -15.367)
		(width 0.10668)
		(layer "In7.Cu")
		(net "JTAG_SCM_PLD_TMS")
	)
	(segment
		(start 15.86992 -45.859954)
		(end 14.611604 -47.11827)
		(width 0.10668)
		(layer "In7.Cu")
		(net "JTAG_SCM_PLD_TMS")
	)
	(segment
		(start 25.833832 -15.367)
		(end 25.83307 -15.367254)
		(width 0.10668)
		(layer "In7.Cu")
		(net "JTAG_SCM_PLD_TMS")
	)
	(segment
		(start 19.8628 -79.8068)
		(end 20.2692 -80.2132)
		(width 0.10668)
		(layer "In7.Cu")
		(net "JTAG_SCM_PLD_TMS")
	)
	(segment
		(start 15.70736 -32.538162)
		(end 15.898368 -33.49879)
		(width 0.10668)
		(layer "In7.Cu")
		(net "JTAG_SCM_PLD_TMS")
	)
	(segment
		(start 14.91234 -74.55662)
		(end 17.43202 -74.55662)
		(width 0.10668)
		(layer "In7.Cu")
		(net "JTAG_SCM_PLD_TMS")
	)
	(segment
		(start 18.533364 -19.25574)
		(end 15.40764 -22.381464)
		(width 0.10668)
		(layer "In7.Cu")
		(net "JTAG_SCM_PLD_TMS")
	)
	(segment
		(start 15.88262 -52.920392)
		(end 16.071342 -53.109114)
		(width 0.10668)
		(layer "In7.Cu")
		(net "JTAG_SCM_PLD_TMS")
	)
	(segment
		(start 14.41196 -74.05624)
		(end 14.91234 -74.55662)
		(width 0.10668)
		(layer "In7.Cu")
		(net "JTAG_SCM_PLD_TMS")
	)
	(segment
		(start 15.322042 -51.23434)
		(end 15.88262 -51.794918)
		(width 0.10668)
		(layer "In7.Cu")
		(net "JTAG_SCM_PLD_TMS")
	)
	(segment
		(start 15.70736 -29.14904)
		(end 15.70736 -32.538162)
		(width 0.10668)
		(layer "In7.Cu")
		(net "JTAG_SCM_PLD_TMS")
	)
	(segment
		(start 16.33474 -69.4055)
		(end 14.41196 -71.32828)
		(width 0.10668)
		(layer "In7.Cu")
		(net "JTAG_SCM_PLD_TMS")
	)
	(segment
		(start 25.071324 -16.129)
		(end 21.336 -16.129)
		(width 0.10668)
		(layer "In7.Cu")
		(net "JTAG_SCM_PLD_TMS")
	)
	(segment
		(start 16.44523 -35.028886)
		(end 16.269208 -35.204908)
		(width 0.10668)
		(layer "In7.Cu")
		(net "JTAG_SCM_PLD_TMS")
	)
	(segment
		(start 21.336 -16.129)
		(end 20.955 -16.51)
		(width 0.10668)
		(layer "In7.Cu")
		(net "JTAG_SCM_PLD_TMS")
	)
	(segment
		(start 18.161 -77.6224)
		(end 18.161 -78.5368)
		(width 0.10668)
		(layer "In7.Cu")
		(net "JTAG_SCM_PLD_TMS")
	)
	(segment
		(start 18.533364 -18.914364)
		(end 18.533364 -19.25574)
		(width 0.10668)
		(layer "In7.Cu")
		(net "JTAG_SCM_PLD_TMS")
	)
	(segment
		(start 16.269208 -35.204908)
		(end 15.86992 -36.168838)
		(width 0.10668)
		(layer "In7.Cu")
		(net "JTAG_SCM_PLD_TMS")
	)
	(segment
		(start 16.33474 -67.43446)
		(end 16.33474 -69.4055)
		(width 0.10668)
		(layer "In7.Cu")
		(net "JTAG_SCM_PLD_TMS")
	)
	(segment
		(start 45.936408 -17.1831)
		(end 37.705792 -17.1831)
		(width 0.10668)
		(layer "In7.Cu")
		(net "JTAG_SCM_PLD_TMS")
	)
	(segment
		(start 20.955 -16.51)
		(end 20.955 -17.5768)
		(width 0.10668)
		(layer "In7.Cu")
		(net "JTAG_SCM_PLD_TMS")
	)
	(segment
		(start 48.09744 -18.47342)
		(end 47.226728 -18.47342)
		(width 0.10668)
		(layer "In7.Cu")
		(net "JTAG_SCM_PLD_TMS")
	)
	(segment
		(start 15.0241 -51.23434)
		(end 15.322042 -51.23434)
		(width 0.10668)
		(layer "In7.Cu")
		(net "JTAG_SCM_PLD_TMS")
	)
	(segment
		(start 47.226728 -18.47342)
		(end 45.936408 -17.1831)
		(width 0.10668)
		(layer "In7.Cu")
		(net "JTAG_SCM_PLD_TMS")
	)
	(segment
		(start 54.078632 -19.09064)
		(end 48.71466 -19.09064)
		(width 0.10668)
		(layer "In7.Cu")
		(net "JTAG_SCM_PLD_TMS")
	)
	(segment
		(start 17.15135 -66.61785)
		(end 16.33474 -67.43446)
		(width 0.10668)
		(layer "In7.Cu")
		(net "JTAG_SCM_PLD_TMS")
	)
	(segment
		(start 15.86992 -36.168838)
		(end 15.86992 -45.859954)
		(width 0.10668)
		(layer "In7.Cu")
		(net "JTAG_SCM_PLD_TMS")
	)
	(segment
		(start 63.8048 -23.8252)
		(end 63.37554 -23.8252)
		(width 0.10668)
		(layer "In7.Cu")
		(net "JTAG_SCM_PLD_TMS")
	)
	(segment
		(start 27.432 -15.367)
		(end 25.833832 -15.367)
		(width 0.10668)
		(layer "In7.Cu")
		(net "JTAG_SCM_PLD_TMS")
	)
	(segment
		(start 48.71466 -19.09064)
		(end 48.09744 -18.47342)
		(width 0.10668)
		(layer "In7.Cu")
		(net "JTAG_SCM_PLD_TMS")
	)
	(segment
		(start 17.71396 -66.61785)
		(end 17.15135 -66.61785)
		(width 0.10668)
		(layer "In7.Cu")
		(net "JTAG_SCM_PLD_TMS")
	)
	(segment
		(start 14.41196 -71.32828)
		(end 14.41196 -74.05624)
		(width 0.10668)
		(layer "In7.Cu")
		(net "JTAG_SCM_PLD_TMS")
	)
	(segment
		(start 37.705792 -17.1831)
		(end 36.532312 -16.00962)
		(width 0.10668)
		(layer "In7.Cu")
		(net "JTAG_SCM_PLD_TMS")
	)
	(segment
		(start 17.907 -77.3684)
		(end 18.161 -77.6224)
		(width 0.10668)
		(layer "In7.Cu")
		(net "JTAG_SCM_PLD_TMS")
	)
	(segment
		(start 16.44523 -34.33953)
		(end 16.44523 -35.028886)
		(width 0.10668)
		(layer "In7.Cu")
		(net "JTAG_SCM_PLD_TMS")
	)
	(segment
		(start 15.70736 -60.06084)
		(end 15.5702 -60.198)
		(width 0.10668)
		(layer "In7.Cu")
		(net "JTAG_SCM_PLD_TMS")
	)
	(segment
		(start 19.431 -79.8068)
		(end 19.8628 -79.8068)
		(width 0.10668)
		(layer "In7.Cu")
		(net "JTAG_SCM_PLD_TMS")
	)
	(segment
		(start 9.69137 -101.45395)
		(end 9.415018 -101.177598)
		(width 0.11684)
		(layer "F.Cu")
		(net "JTAG_SCM_PLD_TDO")
	)
	(segment
		(start 69.50583 -25.2349)
		(end 69.4436 -25.17267)
		(width 0.11684)
		(layer "F.Cu")
		(net "JTAG_SCM_PLD_TDO")
	)
	(segment
		(start 23.854664 -88.791796)
		(end 23.45944 -89.18702)
		(width 0.11684)
		(layer "F.Cu")
		(net "JTAG_SCM_PLD_TDO")
	)
	(segment
		(start 10.287 -101.45395)
		(end 9.69137 -101.45395)
		(width 0.11684)
		(layer "F.Cu")
		(net "JTAG_SCM_PLD_TDO")
	)
	(segment
		(start 69.4436 -25.17267)
		(end 69.4436 -23.5712)
		(width 0.11684)
		(layer "F.Cu")
		(net "JTAG_SCM_PLD_TDO")
	)
	(via
		(at 69.4436 -23.5712)
		(size 0.508)
		(drill 0.254)
		(layers "F.Cu" "B.Cu")
		(net "JTAG_SCM_PLD_TDO")
	)
	(via
		(at 23.854664 -88.791796)
		(size 0.4572)
		(drill 0.254)
		(layers "F.Cu" "B.Cu")
		(net "JTAG_SCM_PLD_TDO")
	)
	(via
		(at 17.52346 -66.15811)
		(size 0.508)
		(drill 0.254)
		(layers "F.Cu" "B.Cu")
		(net "JTAG_SCM_PLD_TDO")
	)
	(via
		(at 23.545292 -82.098896)
		(size 0.508)
		(drill 0.254)
		(layers "F.Cu" "B.Cu")
		(net "JTAG_SCM_PLD_TDO")
	)
	(via
		(at 9.415018 -101.177598)
		(size 0.508)
		(drill 0.254)
		(layers "F.Cu" "B.Cu")
		(net "JTAG_SCM_PLD_TDO")
	)
	(segment
		(start 23.603204 -88.791796)
		(end 23.854664 -88.791796)
		(width 0.08382)
		(layer "In2.Cu")
		(net "JTAG_SCM_PLD_TDO")
	)
	(segment
		(start 10.93089 -97.98431)
		(end 11.64209 -97.98431)
		(width 0.08382)
		(layer "In2.Cu")
		(net "JTAG_SCM_PLD_TDO")
	)
	(segment
		(start 11.8872 -97.7392)
		(end 11.8872 -96.4184)
		(width 0.08382)
		(layer "In2.Cu")
		(net "JTAG_SCM_PLD_TDO")
	)
	(segment
		(start 22.8854 -89.2048)
		(end 23.1902 -89.2048)
		(width 0.08382)
		(layer "In2.Cu")
		(net "JTAG_SCM_PLD_TDO")
	)
	(segment
		(start 22.626828 -89.746074)
		(end 22.626828 -89.463372)
		(width 0.08382)
		(layer "In2.Cu")
		(net "JTAG_SCM_PLD_TDO")
	)
	(segment
		(start 22.626828 -89.463372)
		(end 22.8854 -89.2048)
		(width 0.08382)
		(layer "In2.Cu")
		(net "JTAG_SCM_PLD_TDO")
	)
	(segment
		(start 9.415018 -101.177598)
		(end 9.65708 -100.935536)
		(width 0.08382)
		(layer "In2.Cu")
		(net "JTAG_SCM_PLD_TDO")
	)
	(segment
		(start 9.65708 -100.935536)
		(end 9.65708 -100.74402)
		(width 0.08382)
		(layer "In2.Cu")
		(net "JTAG_SCM_PLD_TDO")
	)
	(segment
		(start 13.233146 -90.7796)
		(end 14.8336 -90.7796)
		(width 0.08382)
		(layer "In2.Cu")
		(net "JTAG_SCM_PLD_TDO")
	)
	(segment
		(start 11.684 -93.9292)
		(end 12.4206 -93.1926)
		(width 0.08382)
		(layer "In2.Cu")
		(net "JTAG_SCM_PLD_TDO")
	)
	(segment
		(start 11.5316 -96.0628)
		(end 11.049 -96.0628)
		(width 0.08382)
		(layer "In2.Cu")
		(net "JTAG_SCM_PLD_TDO")
	)
	(segment
		(start 10.53338 -99.782376)
		(end 10.53338 -98.38182)
		(width 0.08382)
		(layer "In2.Cu")
		(net "JTAG_SCM_PLD_TDO")
	)
	(segment
		(start 10.73404 -94.24416)
		(end 11.049 -93.9292)
		(width 0.08382)
		(layer "In2.Cu")
		(net "JTAG_SCM_PLD_TDO")
	)
	(segment
		(start 23.1902 -89.2048)
		(end 23.603204 -88.791796)
		(width 0.08382)
		(layer "In2.Cu")
		(net "JTAG_SCM_PLD_TDO")
	)
	(segment
		(start 11.049 -96.0628)
		(end 10.73404 -95.74784)
		(width 0.08382)
		(layer "In2.Cu")
		(net "JTAG_SCM_PLD_TDO")
	)
	(segment
		(start 11.8872 -96.4184)
		(end 11.5316 -96.0628)
		(width 0.08382)
		(layer "In2.Cu")
		(net "JTAG_SCM_PLD_TDO")
	)
	(segment
		(start 9.717532 -100.598224)
		(end 10.53338 -99.782376)
		(width 0.08382)
		(layer "In2.Cu")
		(net "JTAG_SCM_PLD_TDO")
	)
	(segment
		(start 11.049 -93.9292)
		(end 11.684 -93.9292)
		(width 0.08382)
		(layer "In2.Cu")
		(net "JTAG_SCM_PLD_TDO")
	)
	(segment
		(start 11.64209 -97.98431)
		(end 11.8872 -97.7392)
		(width 0.08382)
		(layer "In2.Cu")
		(net "JTAG_SCM_PLD_TDO")
	)
	(segment
		(start 10.53338 -98.38182)
		(end 10.93089 -97.98431)
		(width 0.08382)
		(layer "In2.Cu")
		(net "JTAG_SCM_PLD_TDO")
	)
	(segment
		(start 14.8336 -90.7796)
		(end 15.649194 -89.964006)
		(width 0.08382)
		(layer "In2.Cu")
		(net "JTAG_SCM_PLD_TDO")
	)
	(segment
		(start 12.4206 -93.1926)
		(end 12.4206 -91.592146)
		(width 0.08382)
		(layer "In2.Cu")
		(net "JTAG_SCM_PLD_TDO")
	)
	(segment
		(start 12.4206 -91.592146)
		(end 13.233146 -90.7796)
		(width 0.08382)
		(layer "In2.Cu")
		(net "JTAG_SCM_PLD_TDO")
	)
	(segment
		(start 15.649194 -89.964006)
		(end 22.408896 -89.964006)
		(width 0.08382)
		(layer "In2.Cu")
		(net "JTAG_SCM_PLD_TDO")
	)
	(segment
		(start 10.73404 -95.74784)
		(end 10.73404 -94.24416)
		(width 0.08382)
		(layer "In2.Cu")
		(net "JTAG_SCM_PLD_TDO")
	)
	(segment
		(start 22.408896 -89.964006)
		(end 22.626828 -89.746074)
		(width 0.08382)
		(layer "In2.Cu")
		(net "JTAG_SCM_PLD_TDO")
	)
	(segment
		(start 9.65708 -100.74402)
		(end 9.717532 -100.598224)
		(width 0.08382)
		(layer "In2.Cu")
		(net "JTAG_SCM_PLD_TDO")
	)
	(segment
		(start 23.04288 -83.741514)
		(end 23.04288 -84.279486)
		(width 0.10668)
		(layer "In4.Cu")
		(net "JTAG_SCM_PLD_TDO")
	)
	(segment
		(start 23.854664 -88.294464)
		(end 23.854664 -88.791796)
		(width 0.10668)
		(layer "In4.Cu")
		(net "JTAG_SCM_PLD_TDO")
	)
	(segment
		(start 23.28164 -84.518246)
		(end 23.28164 -87.72144)
		(width 0.10668)
		(layer "In4.Cu")
		(net "JTAG_SCM_PLD_TDO")
	)
	(segment
		(start 23.28164 -87.72144)
		(end 23.854664 -88.294464)
		(width 0.10668)
		(layer "In4.Cu")
		(net "JTAG_SCM_PLD_TDO")
	)
	(segment
		(start 23.545292 -82.098896)
		(end 23.28164 -82.362548)
		(width 0.10668)
		(layer "In4.Cu")
		(net "JTAG_SCM_PLD_TDO")
	)
	(segment
		(start 23.28164 -82.362548)
		(end 23.28164 -83.502754)
		(width 0.10668)
		(layer "In4.Cu")
		(net "JTAG_SCM_PLD_TDO")
	)
	(segment
		(start 23.28164 -83.502754)
		(end 23.04288 -83.741514)
		(width 0.10668)
		(layer "In4.Cu")
		(net "JTAG_SCM_PLD_TDO")
	)
	(segment
		(start 23.04288 -84.279486)
		(end 23.28164 -84.518246)
		(width 0.10668)
		(layer "In4.Cu")
		(net "JTAG_SCM_PLD_TDO")
	)
	(segment
		(start 14.73708 -28.349702)
		(end 14.73708 -22.097492)
		(width 0.10668)
		(layer "In7.Cu")
		(net "JTAG_SCM_PLD_TDO")
	)
	(segment
		(start 17.649952 -19.18462)
		(end 17.649952 -18.462244)
		(width 0.10668)
		(layer "In7.Cu")
		(net "JTAG_SCM_PLD_TDO")
	)
	(segment
		(start 49.226216 -17.117314)
		(end 49.784254 -17.348454)
		(width 0.10668)
		(layer "In7.Cu")
		(net "JTAG_SCM_PLD_TDO")
	)
	(segment
		(start 15.400782 -53.38699)
		(end 15.21206 -53.198268)
		(width 0.10668)
		(layer "In7.Cu")
		(net "JTAG_SCM_PLD_TDO")
	)
	(segment
		(start 59.623198 -19.693382)
		(end 60.17514 -19.14144)
		(width 0.10668)
		(layer "In7.Cu")
		(net "JTAG_SCM_PLD_TDO")
	)
	(segment
		(start 61.128656 -19.14144)
		(end 63.526416 -21.5392)
		(width 0.10668)
		(layer "In7.Cu")
		(net "JTAG_SCM_PLD_TDO")
	)
	(segment
		(start 55.942738 -19.693382)
		(end 59.623198 -19.693382)
		(width 0.10668)
		(layer "In7.Cu")
		(net "JTAG_SCM_PLD_TDO")
	)
	(segment
		(start 14.960854 -34.516822)
		(end 14.4272 -33.227518)
		(width 0.10668)
		(layer "In7.Cu")
		(net "JTAG_SCM_PLD_TDO")
	)
	(segment
		(start 37.983668 -16.51254)
		(end 46.185328 -16.51254)
		(width 0.10668)
		(layer "In7.Cu")
		(net "JTAG_SCM_PLD_TDO")
	)
	(segment
		(start 18.87474 -15.84706)
		(end 19.3802 -15.3416)
		(width 0.10668)
		(layer "In7.Cu")
		(net "JTAG_SCM_PLD_TDO")
	)
	(segment
		(start 15.044166 -51.9049)
		(end 14.746224 -51.9049)
		(width 0.10668)
		(layer "In7.Cu")
		(net "JTAG_SCM_PLD_TDO")
	)
	(segment
		(start 13.941044 -46.840394)
		(end 15.19936 -45.582078)
		(width 0.10668)
		(layer "In7.Cu")
		(net "JTAG_SCM_PLD_TDO")
	)
	(segment
		(start 17.649952 -18.462244)
		(end 18.87474 -17.237456)
		(width 0.10668)
		(layer "In7.Cu")
		(net "JTAG_SCM_PLD_TDO")
	)
	(segment
		(start 13.941044 -51.09972)
		(end 13.941044 -46.840394)
		(width 0.10668)
		(layer "In7.Cu")
		(net "JTAG_SCM_PLD_TDO")
	)
	(segment
		(start 14.36624 -59.601862)
		(end 15.0368 -58.931302)
		(width 0.10668)
		(layer "In7.Cu")
		(net "JTAG_SCM_PLD_TDO")
	)
	(segment
		(start 15.19936 -45.582078)
		(end 15.19936 -35.411664)
		(width 0.10668)
		(layer "In7.Cu")
		(net "JTAG_SCM_PLD_TDO")
	)
	(segment
		(start 46.185328 -16.51254)
		(end 49.226216 -17.117314)
		(width 0.10668)
		(layer "In7.Cu")
		(net "JTAG_SCM_PLD_TDO")
	)
	(segment
		(start 67.11823 -22.017228)
		(end 69.4436 -23.5712)
		(width 0.10668)
		(layer "In7.Cu")
		(net "JTAG_SCM_PLD_TDO")
	)
	(segment
		(start 15.19936 -35.411664)
		(end 14.961362 -34.83737)
		(width 0.10668)
		(layer "In7.Cu")
		(net "JTAG_SCM_PLD_TDO")
	)
	(segment
		(start 19.3802 -15.3416)
		(end 24.868632 -15.3416)
		(width 0.10668)
		(layer "In7.Cu")
		(net "JTAG_SCM_PLD_TDO")
	)
	(segment
		(start 16.266668 -65.369948)
		(end 14.36624 -60.781692)
		(width 0.10668)
		(layer "In7.Cu")
		(net "JTAG_SCM_PLD_TDO")
	)
	(segment
		(start 29.0322 -14.351)
		(end 29.523182 -13.860018)
		(width 0.10668)
		(layer "In7.Cu")
		(net "JTAG_SCM_PLD_TDO")
	)
	(segment
		(start 14.4272 -28.659582)
		(end 14.73708 -28.349702)
		(width 0.10668)
		(layer "In7.Cu")
		(net "JTAG_SCM_PLD_TDO")
	)
	(segment
		(start 14.36624 -60.781692)
		(end 14.36624 -59.601862)
		(width 0.10668)
		(layer "In7.Cu")
		(net "JTAG_SCM_PLD_TDO")
	)
	(segment
		(start 65.964308 -21.5392)
		(end 67.11823 -22.017228)
		(width 0.10668)
		(layer "In7.Cu")
		(net "JTAG_SCM_PLD_TDO")
	)
	(segment
		(start 15.0368 -58.931302)
		(end 15.0368 -57.064656)
		(width 0.10668)
		(layer "In7.Cu")
		(net "JTAG_SCM_PLD_TDO")
	)
	(segment
		(start 28.038044 -14.351)
		(end 29.0322 -14.351)
		(width 0.10668)
		(layer "In7.Cu")
		(net "JTAG_SCM_PLD_TDO")
	)
	(segment
		(start 15.0368 -57.064656)
		(end 15.400782 -56.700674)
		(width 0.10668)
		(layer "In7.Cu")
		(net "JTAG_SCM_PLD_TDO")
	)
	(segment
		(start 33.773618 -13.860018)
		(end 34.8488 -14.9352)
		(width 0.10668)
		(layer "In7.Cu")
		(net "JTAG_SCM_PLD_TDO")
	)
	(segment
		(start 29.523182 -13.860018)
		(end 33.773618 -13.860018)
		(width 0.10668)
		(layer "In7.Cu")
		(net "JTAG_SCM_PLD_TDO")
	)
	(segment
		(start 15.400782 -56.700674)
		(end 15.400782 -53.38699)
		(width 0.10668)
		(layer "In7.Cu")
		(net "JTAG_SCM_PLD_TDO")
	)
	(segment
		(start 60.17514 -19.14144)
		(end 61.128656 -19.14144)
		(width 0.10668)
		(layer "In7.Cu")
		(net "JTAG_SCM_PLD_TDO")
	)
	(segment
		(start 18.87474 -17.237456)
		(end 18.87474 -15.84706)
		(width 0.10668)
		(layer "In7.Cu")
		(net "JTAG_SCM_PLD_TDO")
	)
	(segment
		(start 14.4272 -33.227518)
		(end 14.4272 -28.659582)
		(width 0.10668)
		(layer "In7.Cu")
		(net "JTAG_SCM_PLD_TDO")
	)
	(segment
		(start 34.8488 -14.9352)
		(end 36.406328 -14.9352)
		(width 0.10668)
		(layer "In7.Cu")
		(net "JTAG_SCM_PLD_TDO")
	)
	(segment
		(start 17.339056 -66.15811)
		(end 17.12341 -65.942464)
		(width 0.10668)
		(layer "In7.Cu")
		(net "JTAG_SCM_PLD_TDO")
	)
	(segment
		(start 14.961362 -34.83737)
		(end 14.960854 -34.516822)
		(width 0.10668)
		(layer "In7.Cu")
		(net "JTAG_SCM_PLD_TDO")
	)
	(segment
		(start 36.406328 -14.9352)
		(end 37.983668 -16.51254)
		(width 0.10668)
		(layer "In7.Cu")
		(net "JTAG_SCM_PLD_TDO")
	)
	(segment
		(start 54.669436 -18.42008)
		(end 55.942738 -19.693382)
		(width 0.10668)
		(layer "In7.Cu")
		(net "JTAG_SCM_PLD_TDO")
	)
	(segment
		(start 49.784254 -17.348454)
		(end 50.85588 -18.42008)
		(width 0.10668)
		(layer "In7.Cu")
		(net "JTAG_SCM_PLD_TDO")
	)
	(segment
		(start 14.746224 -51.9049)
		(end 13.941044 -51.09972)
		(width 0.10668)
		(layer "In7.Cu")
		(net "JTAG_SCM_PLD_TDO")
	)
	(segment
		(start 15.21206 -53.198268)
		(end 15.21206 -52.072794)
		(width 0.10668)
		(layer "In7.Cu")
		(net "JTAG_SCM_PLD_TDO")
	)
	(segment
		(start 17.52346 -66.15811)
		(end 17.339056 -66.15811)
		(width 0.10668)
		(layer "In7.Cu")
		(net "JTAG_SCM_PLD_TDO")
	)
	(segment
		(start 24.868632 -15.3416)
		(end 25.530048 -14.680184)
		(width 0.10668)
		(layer "In7.Cu")
		(net "JTAG_SCM_PLD_TDO")
	)
	(segment
		(start 14.73708 -22.097492)
		(end 17.649952 -19.18462)
		(width 0.10668)
		(layer "In7.Cu")
		(net "JTAG_SCM_PLD_TDO")
	)
	(segment
		(start 25.530048 -14.680184)
		(end 27.70886 -14.680184)
		(width 0.10668)
		(layer "In7.Cu")
		(net "JTAG_SCM_PLD_TDO")
	)
	(segment
		(start 27.70886 -14.680184)
		(end 28.038044 -14.351)
		(width 0.10668)
		(layer "In7.Cu")
		(net "JTAG_SCM_PLD_TDO")
	)
	(segment
		(start 50.85588 -18.42008)
		(end 54.669436 -18.42008)
		(width 0.10668)
		(layer "In7.Cu")
		(net "JTAG_SCM_PLD_TDO")
	)
	(segment
		(start 15.21206 -52.072794)
		(end 15.044166 -51.9049)
		(width 0.10668)
		(layer "In7.Cu")
		(net "JTAG_SCM_PLD_TDO")
	)
	(segment
		(start 17.12341 -65.942464)
		(end 16.266668 -65.369948)
		(width 0.10668)
		(layer "In7.Cu")
		(net "JTAG_SCM_PLD_TDO")
	)
	(segment
		(start 63.526416 -21.5392)
		(end 65.964308 -21.5392)
		(width 0.10668)
		(layer "In7.Cu")
		(net "JTAG_SCM_PLD_TDO")
	)
	(segment
		(start 22.294596 -80.8482)
		(end 18.542 -80.8482)
		(width 0.08382)
		(layer "In9.Cu")
		(net "JTAG_SCM_PLD_TDO")
	)
	(segment
		(start 18.2372 -66.86042)
		(end 17.53489 -66.15811)
		(width 0.08382)
		(layer "In9.Cu")
		(net "JTAG_SCM_PLD_TDO")
	)
	(segment
		(start 18.10131 -78.223872)
		(end 18.01749 -78.140052)
		(width 0.08382)
		(layer "In9.Cu")
		(net "JTAG_SCM_PLD_TDO")
	)
	(segment
		(start 18.52422 -75.812142)
		(end 18.52422 -72.107806)
		(width 0.08382)
		(layer "In9.Cu")
		(net "JTAG_SCM_PLD_TDO")
	)
	(segment
		(start 18.542 -80.8482)
		(end 18.10131 -80.40751)
		(width 0.08382)
		(layer "In9.Cu")
		(net "JTAG_SCM_PLD_TDO")
	)
	(segment
		(start 18.10131 -80.40751)
		(end 18.10131 -78.223872)
		(width 0.08382)
		(layer "In9.Cu")
		(net "JTAG_SCM_PLD_TDO")
	)
	(segment
		(start 18.01749 -78.140052)
		(end 18.01749 -76.318872)
		(width 0.08382)
		(layer "In9.Cu")
		(net "JTAG_SCM_PLD_TDO")
	)
	(segment
		(start 23.545292 -82.098896)
		(end 22.294596 -80.8482)
		(width 0.08382)
		(layer "In9.Cu")
		(net "JTAG_SCM_PLD_TDO")
	)
	(segment
		(start 18.52422 -72.107806)
		(end 18.2372 -71.820786)
		(width 0.08382)
		(layer "In9.Cu")
		(net "JTAG_SCM_PLD_TDO")
	)
	(segment
		(start 18.2372 -71.820786)
		(end 18.2372 -66.86042)
		(width 0.08382)
		(layer "In9.Cu")
		(net "JTAG_SCM_PLD_TDO")
	)
	(segment
		(start 18.01749 -76.318872)
		(end 18.52422 -75.812142)
		(width 0.08382)
		(layer "In9.Cu")
		(net "JTAG_SCM_PLD_TDO")
	)
	(segment
		(start 17.53489 -66.15811)
		(end 17.52346 -66.15811)
		(width 0.08382)
		(layer "In9.Cu")
		(net "JTAG_SCM_PLD_TDO")
	)
	(segment
		(start 64.2874 -25.4254)
		(end 64.57315 -25.13965)
		(width 0.11684)
		(layer "F.Cu")
		(net "JTAG_SCM_PLD_TDI")
	)
	(segment
		(start 24.14524 -83.21675)
		(end 24.1808 -83.25231)
		(width 0.11684)
		(layer "F.Cu")
		(net "JTAG_SCM_PLD_TDI")
	)
	(segment
		(start 10.287 -100.47605)
		(end 9.798304 -100.47605)
		(width 0.11684)
		(layer "F.Cu")
		(net "JTAG_SCM_PLD_TDI")
	)
	(segment
		(start 23.45944 -85.37956)
		(end 23.45944 -87.587074)
		(width 0.11684)
		(layer "F.Cu")
		(net "JTAG_SCM_PLD_TDI")
	)
	(segment
		(start 64.57315 -25.13965)
		(end 64.57315 -25.0444)
		(width 0.11684)
		(layer "F.Cu")
		(net "JTAG_SCM_PLD_TDI")
	)
	(segment
		(start 24.1808 -83.25231)
		(end 24.1808 -84.6582)
		(width 0.11684)
		(layer "F.Cu")
		(net "JTAG_SCM_PLD_TDI")
	)
	(segment
		(start 24.1808 -84.6582)
		(end 23.45944 -85.37956)
		(width 0.11684)
		(layer "F.Cu")
		(net "JTAG_SCM_PLD_TDI")
	)
	(segment
		(start 63.9826 -25.4254)
		(end 64.2874 -25.4254)
		(width 0.11684)
		(layer "F.Cu")
		(net "JTAG_SCM_PLD_TDI")
	)
	(segment
		(start 9.798304 -100.47605)
		(end 9.630664 -100.30841)
		(width 0.11684)
		(layer "F.Cu")
		(net "JTAG_SCM_PLD_TDI")
	)
	(segment
		(start 9.630664 -100.30841)
		(end 9.375394 -100.30841)
		(width 0.11684)
		(layer "F.Cu")
		(net "JTAG_SCM_PLD_TDI")
	)
	(via
		(at 9.375394 -100.30841)
		(size 0.508)
		(drill 0.254)
		(layers "F.Cu" "B.Cu")
		(net "JTAG_SCM_PLD_TDI")
	)
	(via
		(at 24.14524 -83.21675)
		(size 0.508)
		(drill 0.254)
		(layers "F.Cu" "B.Cu")
		(net "JTAG_SCM_PLD_TDI")
	)
	(via
		(at 63.9826 -25.4254)
		(size 0.508)
		(drill 0.254)
		(layers "F.Cu" "B.Cu")
		(net "JTAG_SCM_PLD_TDI")
	)
	(via
		(at 19.27098 -73.8378)
		(size 0.508)
		(drill 0.254)
		(layers "F.Cu" "B.Cu")
		(net "JTAG_SCM_PLD_TDI")
	)
	(via
		(at 25.39746 -78.2066)
		(size 0.508)
		(drill 0.254)
		(layers "F.Cu" "B.Cu")
		(net "JTAG_SCM_PLD_TDI")
	)
	(segment
		(start 20.1168 -81.534254)
		(end 20.1168 -82.763868)
		(width 0.08382)
		(layer "In2.Cu")
		(net "JTAG_SCM_PLD_TDI")
	)
	(segment
		(start 10.1092 -95.1738)
		(end 10.1092 -99.764596)
		(width 0.08382)
		(layer "In2.Cu")
		(net "JTAG_SCM_PLD_TDI")
	)
	(segment
		(start 20.406614 -81.24444)
		(end 20.1168 -81.534254)
		(width 0.08382)
		(layer "In2.Cu")
		(net "JTAG_SCM_PLD_TDI")
	)
	(segment
		(start 19.915124 -73.391522)
		(end 20.712176 -73.391522)
		(width 0.08382)
		(layer "In2.Cu")
		(net "JTAG_SCM_PLD_TDI")
	)
	(segment
		(start 20.712176 -73.391522)
		(end 25.39746 -78.076806)
		(width 0.08382)
		(layer "In2.Cu")
		(net "JTAG_SCM_PLD_TDI")
	)
	(segment
		(start 17.535652 -83.39963)
		(end 17.343882 -83.5914)
		(width 0.08382)
		(layer "In2.Cu")
		(net "JTAG_SCM_PLD_TDI")
	)
	(segment
		(start 10.414 -86.934548)
		(end 7.9502 -89.398348)
		(width 0.08382)
		(layer "In2.Cu")
		(net "JTAG_SCM_PLD_TDI")
	)
	(segment
		(start 19.577304 -73.531476)
		(end 19.915124 -73.391522)
		(width 0.08382)
		(layer "In2.Cu")
		(net "JTAG_SCM_PLD_TDI")
	)
	(segment
		(start 9.565386 -100.30841)
		(end 9.375394 -100.30841)
		(width 0.08382)
		(layer "In2.Cu")
		(net "JTAG_SCM_PLD_TDI")
	)
	(segment
		(start 21.8948 -81.24444)
		(end 20.406614 -81.24444)
		(width 0.08382)
		(layer "In2.Cu")
		(net "JTAG_SCM_PLD_TDI")
	)
	(segment
		(start 19.481038 -83.39963)
		(end 17.535652 -83.39963)
		(width 0.08382)
		(layer "In2.Cu")
		(net "JTAG_SCM_PLD_TDI")
	)
	(segment
		(start 13.294614 -84.233004)
		(end 10.648696 -86.001098)
		(width 0.08382)
		(layer "In2.Cu")
		(net "JTAG_SCM_PLD_TDI")
	)
	(segment
		(start 20.1168 -82.763868)
		(end 19.481038 -83.39963)
		(width 0.08382)
		(layer "In2.Cu")
		(net "JTAG_SCM_PLD_TDI")
	)
	(segment
		(start 23.86711 -83.21675)
		(end 21.8948 -81.24444)
		(width 0.08382)
		(layer "In2.Cu")
		(net "JTAG_SCM_PLD_TDI")
	)
	(segment
		(start 17.343882 -83.5914)
		(end 14.843252 -83.5914)
		(width 0.08382)
		(layer "In2.Cu")
		(net "JTAG_SCM_PLD_TDI")
	)
	(segment
		(start 9.7282 -94.7928)
		(end 10.1092 -95.1738)
		(width 0.08382)
		(layer "In2.Cu")
		(net "JTAG_SCM_PLD_TDI")
	)
	(segment
		(start 24.14524 -83.21675)
		(end 23.86711 -83.21675)
		(width 0.08382)
		(layer "In2.Cu")
		(net "JTAG_SCM_PLD_TDI")
	)
	(segment
		(start 25.39746 -78.076806)
		(end 25.39746 -78.2066)
		(width 0.08382)
		(layer "In2.Cu")
		(net "JTAG_SCM_PLD_TDI")
	)
	(segment
		(start 8.381746 -94.7928)
		(end 9.7282 -94.7928)
		(width 0.08382)
		(layer "In2.Cu")
		(net "JTAG_SCM_PLD_TDI")
	)
	(segment
		(start 7.9502 -94.361254)
		(end 8.381746 -94.7928)
		(width 0.08382)
		(layer "In2.Cu")
		(net "JTAG_SCM_PLD_TDI")
	)
	(segment
		(start 7.9502 -89.398348)
		(end 7.9502 -94.361254)
		(width 0.08382)
		(layer "In2.Cu")
		(net "JTAG_SCM_PLD_TDI")
	)
	(segment
		(start 10.1092 -99.764596)
		(end 9.565386 -100.30841)
		(width 0.08382)
		(layer "In2.Cu")
		(net "JTAG_SCM_PLD_TDI")
	)
	(segment
		(start 10.414 -86.44001)
		(end 10.414 -86.934548)
		(width 0.08382)
		(layer "In2.Cu")
		(net "JTAG_SCM_PLD_TDI")
	)
	(segment
		(start 10.648696 -86.001098)
		(end 10.414 -86.44001)
		(width 0.08382)
		(layer "In2.Cu")
		(net "JTAG_SCM_PLD_TDI")
	)
	(segment
		(start 19.27098 -73.8378)
		(end 19.577304 -73.531476)
		(width 0.08382)
		(layer "In2.Cu")
		(net "JTAG_SCM_PLD_TDI")
	)
	(segment
		(start 14.843252 -83.5914)
		(end 13.294614 -84.233004)
		(width 0.08382)
		(layer "In2.Cu")
		(net "JTAG_SCM_PLD_TDI")
	)
	(segment
		(start 16.78051 -35.167824)
		(end 16.553434 -35.3949)
		(width 0.10668)
		(layer "In7.Cu")
		(net "JTAG_SCM_PLD_TDI")
	)
	(segment
		(start 19.27098 -73.79462)
		(end 19.27098 -73.8378)
		(width 0.10668)
		(layer "In7.Cu")
		(net "JTAG_SCM_PLD_TDI")
	)
	(segment
		(start 25.908 -19.304)
		(end 24.86279 -20.34921)
		(width 0.10668)
		(layer "In7.Cu")
		(net "JTAG_SCM_PLD_TDI")
	)
	(segment
		(start 18.31848 -64.057022)
		(end 18.31848 -66.487548)
		(width 0.10668)
		(layer "In7.Cu")
		(net "JTAG_SCM_PLD_TDI")
	)
	(segment
		(start 16.434562 -33.916874)
		(end 16.621506 -34.041588)
		(width 0.10668)
		(layer "In7.Cu")
		(net "JTAG_SCM_PLD_TDI")
	)
	(segment
		(start 27.893518 -17.1196)
		(end 27.3812 -17.1196)
		(width 0.10668)
		(layer "In7.Cu")
		(net "JTAG_SCM_PLD_TDI")
	)
	(segment
		(start 28.668218 -16.3449)
		(end 27.893518 -17.1196)
		(width 0.10668)
		(layer "In7.Cu")
		(net "JTAG_SCM_PLD_TDI")
	)
	(segment
		(start 16.67002 -69.17182)
		(end 18.2626 -70.7644)
		(width 0.10668)
		(layer "In7.Cu")
		(net "JTAG_SCM_PLD_TDI")
	)
	(segment
		(start 16.063468 -28.62453)
		(end 16.063468 -29.267404)
		(width 0.10668)
		(layer "In7.Cu")
		(net "JTAG_SCM_PLD_TDI")
	)
	(segment
		(start 16.2179 -51.65598)
		(end 16.2179 -52.781454)
		(width 0.10668)
		(layer "In7.Cu")
		(net "JTAG_SCM_PLD_TDI")
	)
	(segment
		(start 16.221202 -33.401762)
		(end 16.434562 -33.916874)
		(width 0.10668)
		(layer "In7.Cu")
		(net "JTAG_SCM_PLD_TDI")
	)
	(segment
		(start 19.2786 -73.787)
		(end 19.27098 -73.79462)
		(width 0.10668)
		(layer "In7.Cu")
		(net "JTAG_SCM_PLD_TDI")
	)
	(segment
		(start 16.2052 -36.23564)
		(end 16.2052 -45.998892)
		(width 0.10668)
		(layer "In7.Cu")
		(net "JTAG_SCM_PLD_TDI")
	)
	(segment
		(start 16.406622 -52.970176)
		(end 16.406622 -57.117488)
		(width 0.10668)
		(layer "In7.Cu")
		(net "JTAG_SCM_PLD_TDI")
	)
	(segment
		(start 16.406622 -57.117488)
		(end 16.04264 -57.48147)
		(width 0.10668)
		(layer "In7.Cu")
		(net "JTAG_SCM_PLD_TDI")
	)
	(segment
		(start 18.2626 -72.6186)
		(end 19.2786 -73.6346)
		(width 0.10668)
		(layer "In7.Cu")
		(net "JTAG_SCM_PLD_TDI")
	)
	(segment
		(start 47.08779 -18.8087)
		(end 45.79747 -17.51838)
		(width 0.10668)
		(layer "In7.Cu")
		(net "JTAG_SCM_PLD_TDI")
	)
	(segment
		(start 19.2786 -73.6346)
		(end 19.2786 -73.787)
		(width 0.10668)
		(layer "In7.Cu")
		(net "JTAG_SCM_PLD_TDI")
	)
	(segment
		(start 16.621506 -34.041588)
		(end 16.78051 -34.200592)
		(width 0.10668)
		(layer "In7.Cu")
		(net "JTAG_SCM_PLD_TDI")
	)
	(segment
		(start 25.908 -18.5928)
		(end 25.908 -19.304)
		(width 0.10668)
		(layer "In7.Cu")
		(net "JTAG_SCM_PLD_TDI")
	)
	(segment
		(start 17.99336 -20.34921)
		(end 15.74292 -22.59965)
		(width 0.10668)
		(layer "In7.Cu")
		(net "JTAG_SCM_PLD_TDI")
	)
	(segment
		(start 48.575722 -19.42592)
		(end 47.958502 -18.8087)
		(width 0.10668)
		(layer "In7.Cu")
		(net "JTAG_SCM_PLD_TDI")
	)
	(segment
		(start 18.2626 -70.7644)
		(end 18.2626 -72.6186)
		(width 0.10668)
		(layer "In7.Cu")
		(net "JTAG_SCM_PLD_TDI")
	)
	(segment
		(start 16.04264 -32.50438)
		(end 16.221202 -33.401762)
		(width 0.10668)
		(layer "In7.Cu")
		(net "JTAG_SCM_PLD_TDI")
	)
	(segment
		(start 63.9826 -25.4254)
		(end 63.9826 -25.242774)
		(width 0.10668)
		(layer "In7.Cu")
		(net "JTAG_SCM_PLD_TDI")
	)
	(segment
		(start 24.86279 -20.34921)
		(end 17.99336 -20.34921)
		(width 0.10668)
		(layer "In7.Cu")
		(net "JTAG_SCM_PLD_TDI")
	)
	(segment
		(start 16.04264 -57.48147)
		(end 16.04264 -59.10453)
		(width 0.10668)
		(layer "In7.Cu")
		(net "JTAG_SCM_PLD_TDI")
	)
	(segment
		(start 15.120874 -48.829468)
		(end 15.80896 -49.517554)
		(width 0.10668)
		(layer "In7.Cu")
		(net "JTAG_SCM_PLD_TDI")
	)
	(segment
		(start 60.761626 -22.0218)
		(end 56.514746 -22.0218)
		(width 0.10668)
		(layer "In7.Cu")
		(net "JTAG_SCM_PLD_TDI")
	)
	(segment
		(start 18.31848 -66.487548)
		(end 17.852898 -66.95313)
		(width 0.10668)
		(layer "In7.Cu")
		(net "JTAG_SCM_PLD_TDI")
	)
	(segment
		(start 16.04264 -29.288232)
		(end 16.04264 -32.50438)
		(width 0.10668)
		(layer "In7.Cu")
		(net "JTAG_SCM_PLD_TDI")
	)
	(segment
		(start 16.2179 -52.781454)
		(end 16.406622 -52.970176)
		(width 0.10668)
		(layer "In7.Cu")
		(net "JTAG_SCM_PLD_TDI")
	)
	(segment
		(start 56.514746 -22.0218)
		(end 53.918866 -19.42592)
		(width 0.10668)
		(layer "In7.Cu")
		(net "JTAG_SCM_PLD_TDI")
	)
	(segment
		(start 47.958502 -18.8087)
		(end 47.08779 -18.8087)
		(width 0.10668)
		(layer "In7.Cu")
		(net "JTAG_SCM_PLD_TDI")
	)
	(segment
		(start 16.063468 -29.267404)
		(end 16.04264 -29.288232)
		(width 0.10668)
		(layer "In7.Cu")
		(net "JTAG_SCM_PLD_TDI")
	)
	(segment
		(start 15.74292 -22.59965)
		(end 15.74292 -28.303982)
		(width 0.10668)
		(layer "In7.Cu")
		(net "JTAG_SCM_PLD_TDI")
	)
	(segment
		(start 16.04264 -59.10453)
		(end 16.70304 -59.76493)
		(width 0.10668)
		(layer "In7.Cu")
		(net "JTAG_SCM_PLD_TDI")
	)
	(segment
		(start 16.78051 -34.200592)
		(end 16.78051 -35.167824)
		(width 0.10668)
		(layer "In7.Cu")
		(net "JTAG_SCM_PLD_TDI")
	)
	(segment
		(start 63.9826 -25.242774)
		(end 60.761626 -22.0218)
		(width 0.10668)
		(layer "In7.Cu")
		(net "JTAG_SCM_PLD_TDI")
	)
	(segment
		(start 53.918866 -19.42592)
		(end 48.575722 -19.42592)
		(width 0.10668)
		(layer "In7.Cu")
		(net "JTAG_SCM_PLD_TDI")
	)
	(segment
		(start 27.3812 -17.1196)
		(end 25.908 -18.5928)
		(width 0.10668)
		(layer "In7.Cu")
		(net "JTAG_SCM_PLD_TDI")
	)
	(segment
		(start 17.290288 -66.95313)
		(end 16.67002 -67.573398)
		(width 0.10668)
		(layer "In7.Cu")
		(net "JTAG_SCM_PLD_TDI")
	)
	(segment
		(start 16.70304 -62.441582)
		(end 18.31848 -64.057022)
		(width 0.10668)
		(layer "In7.Cu")
		(net "JTAG_SCM_PLD_TDI")
	)
	(segment
		(start 16.70304 -59.76493)
		(end 16.70304 -62.441582)
		(width 0.10668)
		(layer "In7.Cu")
		(net "JTAG_SCM_PLD_TDI")
	)
	(segment
		(start 36.342574 -16.3449)
		(end 28.668218 -16.3449)
		(width 0.10668)
		(layer "In7.Cu")
		(net "JTAG_SCM_PLD_TDI")
	)
	(segment
		(start 16.2052 -45.998892)
		(end 15.120874 -47.083218)
		(width 0.10668)
		(layer "In7.Cu")
		(net "JTAG_SCM_PLD_TDI")
	)
	(segment
		(start 45.79747 -17.51838)
		(end 37.516054 -17.51838)
		(width 0.10668)
		(layer "In7.Cu")
		(net "JTAG_SCM_PLD_TDI")
	)
	(segment
		(start 15.120874 -47.083218)
		(end 15.120874 -48.829468)
		(width 0.10668)
		(layer "In7.Cu")
		(net "JTAG_SCM_PLD_TDI")
	)
	(segment
		(start 17.852898 -66.95313)
		(end 17.290288 -66.95313)
		(width 0.10668)
		(layer "In7.Cu")
		(net "JTAG_SCM_PLD_TDI")
	)
	(segment
		(start 15.74292 -28.303982)
		(end 16.063468 -28.62453)
		(width 0.10668)
		(layer "In7.Cu")
		(net "JTAG_SCM_PLD_TDI")
	)
	(segment
		(start 15.80896 -51.24704)
		(end 16.2179 -51.65598)
		(width 0.10668)
		(layer "In7.Cu")
		(net "JTAG_SCM_PLD_TDI")
	)
	(segment
		(start 15.80896 -49.517554)
		(end 15.80896 -51.24704)
		(width 0.10668)
		(layer "In7.Cu")
		(net "JTAG_SCM_PLD_TDI")
	)
	(segment
		(start 16.553434 -35.3949)
		(end 16.2052 -36.23564)
		(width 0.10668)
		(layer "In7.Cu")
		(net "JTAG_SCM_PLD_TDI")
	)
	(segment
		(start 16.67002 -67.573398)
		(end 16.67002 -69.17182)
		(width 0.10668)
		(layer "In7.Cu")
		(net "JTAG_SCM_PLD_TDI")
	)
	(segment
		(start 37.516054 -17.51838)
		(end 36.342574 -16.3449)
		(width 0.10668)
		(layer "In7.Cu")
		(net "JTAG_SCM_PLD_TDI")
	)
	(segment
		(start 24.983186 -78.620874)
		(end 25.39746 -78.2066)
		(width 0.08382)
		(layer "In9.Cu")
		(net "JTAG_SCM_PLD_TDI")
	)
	(segment
		(start 24.04618 -83.11769)
		(end 24.04618 -79.81696)
		(width 0.08382)
		(layer "In9.Cu")
		(net "JTAG_SCM_PLD_TDI")
	)
	(segment
		(start 24.14524 -83.21675)
		(end 24.04618 -83.11769)
		(width 0.08382)
		(layer "In9.Cu")
		(net "JTAG_SCM_PLD_TDI")
	)
	(segment
		(start 24.800052 -79.063088)
		(end 24.983186 -78.620874)
		(width 0.08382)
		(layer "In9.Cu")
		(net "JTAG_SCM_PLD_TDI")
	)
	(segment
		(start 24.04618 -79.81696)
		(end 24.800052 -79.063088)
		(width 0.08382)
		(layer "In9.Cu")
		(net "JTAG_SCM_PLD_TDI")
	)
	(segment
		(start 68.5292 -25.51684)
		(end 67.5005 -24.48814)
		(width 0.11684)
		(layer "F.Cu")
		(net "JTAG_SCM_PLD_TCK")
	)
	(segment
		(start 66.22288 -24.48814)
		(end 66.11366 -24.59736)
		(width 0.11684)
		(layer "F.Cu")
		(net "JTAG_SCM_PLD_TCK")
	)
	(segment
		(start 10.287 -92.43695)
		(end 10.287 -91.45905)
		(width 0.11684)
		(layer "F.Cu")
		(net "JTAG_SCM_PLD_TCK")
	)
	(segment
		(start 63.07074 -24.23414)
		(end 63.07074 -22.83714)
		(width 0.11684)
		(layer "F.Cu")
		(net "JTAG_SCM_PLD_TCK")
	)
	(segment
		(start 68.5292 -25.99055)
		(end 68.5292 -25.51684)
		(width 0.11684)
		(layer "F.Cu")
		(net "JTAG_SCM_PLD_TCK")
	)
	(segment
		(start 10.0584 -92.20835)
		(end 10.287 -92.43695)
		(width 0.11684)
		(layer "F.Cu")
		(net "JTAG_SCM_PLD_TCK")
	)
	(segment
		(start 63.07074 -22.83714)
		(end 63.73368 -22.1742)
		(width 0.11684)
		(layer "F.Cu")
		(net "JTAG_SCM_PLD_TCK")
	)
	(segment
		(start 22.65934 -86.56574)
		(end 22.65934 -87.587074)
		(width 0.11684)
		(layer "F.Cu")
		(net "JTAG_SCM_PLD_TCK")
	)
	(segment
		(start 63.43396 -24.59736)
		(end 63.07074 -24.23414)
		(width 0.11684)
		(layer "F.Cu")
		(net "JTAG_SCM_PLD_TCK")
	)
	(segment
		(start 21.717 -82.9818)
		(end 22.225 -83.4898)
		(width 0.11684)
		(layer "F.Cu")
		(net "JTAG_SCM_PLD_TCK")
	)
	(segment
		(start 22.225 -86.1314)
		(end 22.65934 -86.56574)
		(width 0.11684)
		(layer "F.Cu")
		(net "JTAG_SCM_PLD_TCK")
	)
	(segment
		(start 66.11366 -24.59736)
		(end 63.43396 -24.59736)
		(width 0.11684)
		(layer "F.Cu")
		(net "JTAG_SCM_PLD_TCK")
	)
	(segment
		(start 63.73368 -22.1742)
		(end 65.2526 -22.1742)
		(width 0.11684)
		(layer "F.Cu")
		(net "JTAG_SCM_PLD_TCK")
	)
	(segment
		(start 9.1186 -92.20835)
		(end 10.0584 -92.20835)
		(width 0.11684)
		(layer "F.Cu")
		(net "JTAG_SCM_PLD_TCK")
	)
	(segment
		(start 67.5005 -24.48814)
		(end 66.22288 -24.48814)
		(width 0.11684)
		(layer "F.Cu")
		(net "JTAG_SCM_PLD_TCK")
	)
	(segment
		(start 22.225 -83.4898)
		(end 22.225 -86.1314)
		(width 0.11684)
		(layer "F.Cu")
		(net "JTAG_SCM_PLD_TCK")
	)
	(via
		(at 64.7446 -23.495)
		(size 0.6604)
		(drill 0.3302)
		(layers "F.Cu" "B.Cu")
		(net "JTAG_SCM_PLD_TCK")
	)
	(via
		(at 9.1186 -92.20835)
		(size 0.508)
		(drill 0.254)
		(layers "F.Cu" "B.Cu")
		(net "JTAG_SCM_PLD_TCK")
	)
	(via
		(at 65.2526 -22.1742)
		(size 0.508)
		(drill 0.254)
		(layers "F.Cu" "B.Cu")
		(net "JTAG_SCM_PLD_TCK")
	)
	(via
		(at 16.70177 -65.03543)
		(size 0.508)
		(drill 0.254)
		(layers "F.Cu" "B.Cu")
		(net "JTAG_SCM_PLD_TCK")
	)
	(via
		(at 21.717 -82.9818)
		(size 0.508)
		(drill 0.254)
		(layers "F.Cu" "B.Cu")
		(net "JTAG_SCM_PLD_TCK")
	)
	(segment
		(start 64.7446 -22.6822)
		(end 65.2526 -22.1742)
		(width 0.11684)
		(layer "B.Cu")
		(net "JTAG_SCM_PLD_TCK")
	)
	(segment
		(start 64.7446 -23.495)
		(end 64.7446 -22.6822)
		(width 0.11684)
		(layer "B.Cu")
		(net "JTAG_SCM_PLD_TCK")
	)
	(segment
		(start 10.879836 -86.30539)
		(end 10.78357 -86.485476)
		(width 0.08382)
		(layer "In2.Cu")
		(net "JTAG_SCM_PLD_TCK")
	)
	(segment
		(start 19.740118 -84.02447)
		(end 17.794732 -84.02447)
		(width 0.08382)
		(layer "In2.Cu")
		(net "JTAG_SCM_PLD_TCK")
	)
	(segment
		(start 21.209 -83.4898)
		(end 20.274788 -83.4898)
		(width 0.08382)
		(layer "In2.Cu")
		(net "JTAG_SCM_PLD_TCK")
	)
	(segment
		(start 8.35406 -92.078048)
		(end 8.484362 -92.20835)
		(width 0.08382)
		(layer "In2.Cu")
		(net "JTAG_SCM_PLD_TCK")
	)
	(segment
		(start 17.542002 -84.2772)
		(end 14.095476 -84.2772)
		(width 0.08382)
		(layer "In2.Cu")
		(net "JTAG_SCM_PLD_TCK")
	)
	(segment
		(start 17.794732 -84.02447)
		(end 17.542002 -84.2772)
		(width 0.08382)
		(layer "In2.Cu")
		(net "JTAG_SCM_PLD_TCK")
	)
	(segment
		(start 14.095476 -84.2772)
		(end 13.61948 -84.474304)
		(width 0.08382)
		(layer "In2.Cu")
		(net "JTAG_SCM_PLD_TCK")
	)
	(segment
		(start 20.274788 -83.4898)
		(end 19.740118 -84.02447)
		(width 0.08382)
		(layer "In2.Cu")
		(net "JTAG_SCM_PLD_TCK")
	)
	(segment
		(start 21.717 -82.9818)
		(end 21.209 -83.4898)
		(width 0.08382)
		(layer "In2.Cu")
		(net "JTAG_SCM_PLD_TCK")
	)
	(segment
		(start 8.484362 -92.20835)
		(end 9.1186 -92.20835)
		(width 0.08382)
		(layer "In2.Cu")
		(net "JTAG_SCM_PLD_TCK")
	)
	(segment
		(start 10.78357 -87.006938)
		(end 8.35406 -89.436448)
		(width 0.08382)
		(layer "In2.Cu")
		(net "JTAG_SCM_PLD_TCK")
	)
	(segment
		(start 13.61948 -84.474304)
		(end 10.879836 -86.30539)
		(width 0.08382)
		(layer "In2.Cu")
		(net "JTAG_SCM_PLD_TCK")
	)
	(segment
		(start 8.35406 -89.436448)
		(end 8.35406 -92.078048)
		(width 0.08382)
		(layer "In2.Cu")
		(net "JTAG_SCM_PLD_TCK")
	)
	(segment
		(start 10.78357 -86.485476)
		(end 10.78357 -87.006938)
		(width 0.08382)
		(layer "In2.Cu")
		(net "JTAG_SCM_PLD_TCK")
	)
	(segment
		(start 15.385542 -34.25952)
		(end 15.809722 -34.25952)
		(width 0.10668)
		(layer "In7.Cu")
		(net "JTAG_SCM_PLD_TCK")
	)
	(segment
		(start 18.19021 -19.124422)
		(end 15.07236 -22.242272)
		(width 0.10668)
		(layer "In7.Cu")
		(net "JTAG_SCM_PLD_TCK")
	)
	(segment
		(start 15.53464 -45.721016)
		(end 14.276324 -46.979332)
		(width 0.10668)
		(layer "In7.Cu")
		(net "JTAG_SCM_PLD_TCK")
	)
	(segment
		(start 29.260546 -14.7574)
		(end 28.113482 -14.7574)
		(width 0.10668)
		(layer "In7.Cu")
		(net "JTAG_SCM_PLD_TCK")
	)
	(segment
		(start 15.54734 -51.933856)
		(end 15.54734 -53.05933)
		(width 0.10668)
		(layer "In7.Cu")
		(net "JTAG_SCM_PLD_TCK")
	)
	(segment
		(start 63.687198 -22.1742)
		(end 60.989718 -19.47672)
		(width 0.10668)
		(layer "In7.Cu")
		(net "JTAG_SCM_PLD_TCK")
	)
	(segment
		(start 28.113482 -14.7574)
		(end 27.851608 -15.019274)
		(width 0.10668)
		(layer "In7.Cu")
		(net "JTAG_SCM_PLD_TCK")
	)
	(segment
		(start 14.276324 -50.960782)
		(end 14.885162 -51.56962)
		(width 0.10668)
		(layer "In7.Cu")
		(net "JTAG_SCM_PLD_TCK")
	)
	(segment
		(start 25.687782 -15.019274)
		(end 24.959056 -15.748)
		(width 0.10668)
		(layer "In7.Cu")
		(net "JTAG_SCM_PLD_TCK")
	)
	(segment
		(start 14.276324 -46.979332)
		(end 14.276324 -50.960782)
		(width 0.10668)
		(layer "In7.Cu")
		(net "JTAG_SCM_PLD_TCK")
	)
	(segment
		(start 14.885162 -51.56962)
		(end 15.183104 -51.56962)
		(width 0.10668)
		(layer "In7.Cu")
		(net "JTAG_SCM_PLD_TCK")
	)
	(segment
		(start 16.043402 -34.4932)
		(end 16.043402 -34.873184)
		(width 0.10668)
		(layer "In7.Cu")
		(net "JTAG_SCM_PLD_TCK")
	)
	(segment
		(start 14.70152 -60.693554)
		(end 16.357346 -64.691006)
		(width 0.10668)
		(layer "In7.Cu")
		(net "JTAG_SCM_PLD_TCK")
	)
	(segment
		(start 15.37208 -59.07024)
		(end 14.70152 -59.7408)
		(width 0.10668)
		(layer "In7.Cu")
		(net "JTAG_SCM_PLD_TCK")
	)
	(segment
		(start 15.15364 -34.10458)
		(end 15.385542 -34.25952)
		(width 0.10668)
		(layer "In7.Cu")
		(net "JTAG_SCM_PLD_TCK")
	)
	(segment
		(start 15.809722 -34.25952)
		(end 16.043402 -34.4932)
		(width 0.10668)
		(layer "In7.Cu")
		(net "JTAG_SCM_PLD_TCK")
	)
	(segment
		(start 27.851608 -15.019274)
		(end 25.687782 -15.019274)
		(width 0.10668)
		(layer "In7.Cu")
		(net "JTAG_SCM_PLD_TCK")
	)
	(segment
		(start 15.736062 -56.839612)
		(end 15.37208 -57.203594)
		(width 0.10668)
		(layer "In7.Cu")
		(net "JTAG_SCM_PLD_TCK")
	)
	(segment
		(start 15.53464 -36.101782)
		(end 15.53464 -45.721016)
		(width 0.10668)
		(layer "In7.Cu")
		(net "JTAG_SCM_PLD_TCK")
	)
	(segment
		(start 14.70152 -59.7408)
		(end 14.70152 -60.693554)
		(width 0.10668)
		(layer "In7.Cu")
		(net "JTAG_SCM_PLD_TCK")
	)
	(segment
		(start 30.177486 -15.67434)
		(end 29.260546 -14.7574)
		(width 0.10668)
		(layer "In7.Cu")
		(net "JTAG_SCM_PLD_TCK")
	)
	(segment
		(start 60.989718 -19.47672)
		(end 60.314078 -19.47672)
		(width 0.10668)
		(layer "In7.Cu")
		(net "JTAG_SCM_PLD_TCK")
	)
	(segment
		(start 19.939 -16.485362)
		(end 19.939 -17.334484)
		(width 0.10668)
		(layer "In7.Cu")
		(net "JTAG_SCM_PLD_TCK")
	)
	(segment
		(start 46.075346 -16.84782)
		(end 37.84473 -16.84782)
		(width 0.10668)
		(layer "In7.Cu")
		(net "JTAG_SCM_PLD_TCK")
	)
	(segment
		(start 36.67125 -15.67434)
		(end 30.177486 -15.67434)
		(width 0.10668)
		(layer "In7.Cu")
		(net "JTAG_SCM_PLD_TCK")
	)
	(segment
		(start 54.530498 -18.75536)
		(end 48.853598 -18.75536)
		(width 0.10668)
		(layer "In7.Cu")
		(net "JTAG_SCM_PLD_TCK")
	)
	(segment
		(start 24.959056 -15.748)
		(end 20.676362 -15.748)
		(width 0.10668)
		(layer "In7.Cu")
		(net "JTAG_SCM_PLD_TCK")
	)
	(segment
		(start 14.76248 -28.79852)
		(end 14.76248 -33.160716)
		(width 0.10668)
		(layer "In7.Cu")
		(net "JTAG_SCM_PLD_TCK")
	)
	(segment
		(start 14.76248 -33.160716)
		(end 15.15364 -34.10458)
		(width 0.10668)
		(layer "In7.Cu")
		(net "JTAG_SCM_PLD_TCK")
	)
	(segment
		(start 16.357346 -64.691006)
		(end 16.70177 -65.03543)
		(width 0.10668)
		(layer "In7.Cu")
		(net "JTAG_SCM_PLD_TCK")
	)
	(segment
		(start 18.19021 -18.729198)
		(end 18.19021 -19.124422)
		(width 0.10668)
		(layer "In7.Cu")
		(net "JTAG_SCM_PLD_TCK")
	)
	(segment
		(start 15.736062 -53.248052)
		(end 15.736062 -56.839612)
		(width 0.10668)
		(layer "In7.Cu")
		(net "JTAG_SCM_PLD_TCK")
	)
	(segment
		(start 47.365666 -18.13814)
		(end 46.075346 -16.84782)
		(width 0.10668)
		(layer "In7.Cu")
		(net "JTAG_SCM_PLD_TCK")
	)
	(segment
		(start 19.812 -17.461484)
		(end 19.457924 -17.461484)
		(width 0.10668)
		(layer "In7.Cu")
		(net "JTAG_SCM_PLD_TCK")
	)
	(segment
		(start 60.314078 -19.47672)
		(end 59.761628 -20.02917)
		(width 0.10668)
		(layer "In7.Cu")
		(net "JTAG_SCM_PLD_TCK")
	)
	(segment
		(start 15.07236 -22.242272)
		(end 15.07236 -28.48864)
		(width 0.10668)
		(layer "In7.Cu")
		(net "JTAG_SCM_PLD_TCK")
	)
	(segment
		(start 48.853598 -18.75536)
		(end 48.236378 -18.13814)
		(width 0.10668)
		(layer "In7.Cu")
		(net "JTAG_SCM_PLD_TCK")
	)
	(segment
		(start 19.457924 -17.461484)
		(end 18.19021 -18.729198)
		(width 0.10668)
		(layer "In7.Cu")
		(net "JTAG_SCM_PLD_TCK")
	)
	(segment
		(start 16.043402 -34.873184)
		(end 15.53464 -36.101782)
		(width 0.10668)
		(layer "In7.Cu")
		(net "JTAG_SCM_PLD_TCK")
	)
	(segment
		(start 15.54734 -53.05933)
		(end 15.736062 -53.248052)
		(width 0.10668)
		(layer "In7.Cu")
		(net "JTAG_SCM_PLD_TCK")
	)
	(segment
		(start 15.183104 -51.56962)
		(end 15.54734 -51.933856)
		(width 0.10668)
		(layer "In7.Cu")
		(net "JTAG_SCM_PLD_TCK")
	)
	(segment
		(start 65.2526 -22.1742)
		(end 63.687198 -22.1742)
		(width 0.10668)
		(layer "In7.Cu")
		(net "JTAG_SCM_PLD_TCK")
	)
	(segment
		(start 19.939 -17.334484)
		(end 19.812 -17.461484)
		(width 0.10668)
		(layer "In7.Cu")
		(net "JTAG_SCM_PLD_TCK")
	)
	(segment
		(start 15.37208 -57.203594)
		(end 15.37208 -59.07024)
		(width 0.10668)
		(layer "In7.Cu")
		(net "JTAG_SCM_PLD_TCK")
	)
	(segment
		(start 15.07236 -28.48864)
		(end 14.76248 -28.79852)
		(width 0.10668)
		(layer "In7.Cu")
		(net "JTAG_SCM_PLD_TCK")
	)
	(segment
		(start 37.84473 -16.84782)
		(end 36.67125 -15.67434)
		(width 0.10668)
		(layer "In7.Cu")
		(net "JTAG_SCM_PLD_TCK")
	)
	(segment
		(start 55.804308 -20.02917)
		(end 54.530498 -18.75536)
		(width 0.10668)
		(layer "In7.Cu")
		(net "JTAG_SCM_PLD_TCK")
	)
	(segment
		(start 48.236378 -18.13814)
		(end 47.365666 -18.13814)
		(width 0.10668)
		(layer "In7.Cu")
		(net "JTAG_SCM_PLD_TCK")
	)
	(segment
		(start 20.676362 -15.748)
		(end 19.939 -16.485362)
		(width 0.10668)
		(layer "In7.Cu")
		(net "JTAG_SCM_PLD_TCK")
	)
	(segment
		(start 59.761628 -20.02917)
		(end 55.804308 -20.02917)
		(width 0.10668)
		(layer "In7.Cu")
		(net "JTAG_SCM_PLD_TCK")
	)
	(segment
		(start 21.209 -81.5848)
		(end 21.209 -82.4738)
		(width 0.08382)
		(layer "In9.Cu")
		(net "JTAG_SCM_PLD_TCK")
	)
	(segment
		(start 17.20469 -78.045056)
		(end 17.20469 -78.595728)
		(width 0.08382)
		(layer "In9.Cu")
		(net "JTAG_SCM_PLD_TCK")
	)
	(segment
		(start 18.2118 -75.682602)
		(end 17.70507 -76.189332)
		(width 0.08382)
		(layer "In9.Cu")
		(net "JTAG_SCM_PLD_TCK")
	)
	(segment
		(start 21.209 -82.4738)
		(end 21.717 -82.9818)
		(width 0.08382)
		(layer "In9.Cu")
		(net "JTAG_SCM_PLD_TCK")
	)
	(segment
		(start 17.3228 -68.2244)
		(end 17.3228 -71.348346)
		(width 0.08382)
		(layer "In9.Cu")
		(net "JTAG_SCM_PLD_TCK")
	)
	(segment
		(start 17.3228 -71.348346)
		(end 18.2118 -72.237346)
		(width 0.08382)
		(layer "In9.Cu")
		(net "JTAG_SCM_PLD_TCK")
	)
	(segment
		(start 18.2118 -72.237346)
		(end 18.2118 -75.682602)
		(width 0.08382)
		(layer "In9.Cu")
		(net "JTAG_SCM_PLD_TCK")
	)
	(segment
		(start 17.70507 -79.096108)
		(end 17.70507 -80.570324)
		(width 0.08382)
		(layer "In9.Cu")
		(net "JTAG_SCM_PLD_TCK")
	)
	(segment
		(start 20.9296 -81.3054)
		(end 21.209 -81.5848)
		(width 0.08382)
		(layer "In9.Cu")
		(net "JTAG_SCM_PLD_TCK")
	)
	(segment
		(start 17.70507 -80.570324)
		(end 18.440146 -81.3054)
		(width 0.08382)
		(layer "In9.Cu")
		(net "JTAG_SCM_PLD_TCK")
	)
	(segment
		(start 17.20469 -78.595728)
		(end 17.70507 -79.096108)
		(width 0.08382)
		(layer "In9.Cu")
		(net "JTAG_SCM_PLD_TCK")
	)
	(segment
		(start 16.70177 -65.03543)
		(end 16.256 -65.4812)
		(width 0.08382)
		(layer "In9.Cu")
		(net "JTAG_SCM_PLD_TCK")
	)
	(segment
		(start 16.256 -65.4812)
		(end 16.256 -67.1576)
		(width 0.08382)
		(layer "In9.Cu")
		(net "JTAG_SCM_PLD_TCK")
	)
	(segment
		(start 16.256 -67.1576)
		(end 17.3228 -68.2244)
		(width 0.08382)
		(layer "In9.Cu")
		(net "JTAG_SCM_PLD_TCK")
	)
	(segment
		(start 17.70507 -76.189332)
		(end 17.70507 -77.544676)
		(width 0.08382)
		(layer "In9.Cu")
		(net "JTAG_SCM_PLD_TCK")
	)
	(segment
		(start 18.440146 -81.3054)
		(end 20.9296 -81.3054)
		(width 0.08382)
		(layer "In9.Cu")
		(net "JTAG_SCM_PLD_TCK")
	)
	(segment
		(start 17.70507 -77.544676)
		(end 17.20469 -78.045056)
		(width 0.08382)
		(layer "In9.Cu")
		(net "JTAG_SCM_PLD_TCK")
	)
	(segment
		(start 61.620654 -81.5848)
		(end 61.214 -81.5848)
		(width 0.11684)
		(layer "F.Cu")
		(net "MB_JTAG_PLD_R_JTAGEN")
	)
	(segment
		(start 61.214 -81.5848)
		(end 60.4266 -82.3722)
		(width 0.11684)
		(layer "F.Cu")
		(net "MB_JTAG_PLD_R_JTAGEN")
	)
	(segment
		(start 61.869066 -81.336388)
		(end 61.620654 -81.5848)
		(width 0.11684)
		(layer "F.Cu")
		(net "MB_JTAG_PLD_R_JTAGEN")
	)
	(segment
		(start 60.4266 -82.3722)
		(end 60.03925 -81.98485)
		(width 0.11684)
		(layer "F.Cu")
		(net "MB_JTAG_PLD_R_JTAGEN")
	)
	(segment
		(start 61.869066 -81.10474)
		(end 61.869066 -81.336388)
		(width 0.11684)
		(layer "F.Cu")
		(net "MB_JTAG_PLD_R_JTAGEN")
	)
	(segment
		(start 62.84595 -81.788)
		(end 62.552326 -81.788)
		(width 0.11684)
		(layer "F.Cu")
		(net "MB_JTAG_PLD_R_JTAGEN")
	)
	(segment
		(start 62.552326 -81.788)
		(end 61.869066 -81.10474)
		(width 0.11684)
		(layer "F.Cu")
		(net "MB_JTAG_PLD_R_JTAGEN")
	)
	(segment
		(start 60.03925 -81.98485)
		(end 60.03925 -81.1276)
		(width 0.11684)
		(layer "F.Cu")
		(net "MB_JTAG_PLD_R_JTAGEN")
	)
	(via
		(at 60.4266 -82.3722)
		(size 0.762)
		(drill 0.381)
		(layers "F.Cu" "B.Cu")
		(net "MB_JTAG_PLD_R_JTAGEN")
	)
	(segment
		(start 10.0076 -97.79)
		(end 9.61136 -97.39376)
		(width 0.11684)
		(layer "F.Cu")
		(net "JTAG_SCM_PLD_JTAGEN")
	)
	(segment
		(start 8.722868 -97.39376)
		(end 8.0264 -96.697292)
		(width 0.11684)
		(layer "F.Cu")
		(net "JTAG_SCM_PLD_JTAGEN")
	)
	(segment
		(start 8.0264 -96.697292)
		(end 8.0264 -96.4184)
		(width 0.11684)
		(layer "F.Cu")
		(net "JTAG_SCM_PLD_JTAGEN")
	)
	(segment
		(start 9.61136 -97.39376)
		(end 8.722868 -97.39376)
		(width 0.11684)
		(layer "F.Cu")
		(net "JTAG_SCM_PLD_JTAGEN")
	)
	(segment
		(start 10.287 -97.89795)
		(end 10.17905 -97.79)
		(width 0.11684)
		(layer "F.Cu")
		(net "JTAG_SCM_PLD_JTAGEN")
	)
	(segment
		(start 59.23915 -81.1276)
		(end 57.9882 -81.1276)
		(width 0.11684)
		(layer "F.Cu")
		(net "JTAG_SCM_PLD_JTAGEN")
	)
	(segment
		(start 10.17905 -97.79)
		(end 10.0076 -97.79)
		(width 0.11684)
		(layer "F.Cu")
		(net "JTAG_SCM_PLD_JTAGEN")
	)
	(segment
		(start 57.9882 -82.00771)
		(end 57.4294 -82.56651)
		(width 0.11684)
		(layer "F.Cu")
		(net "JTAG_SCM_PLD_JTAGEN")
	)
	(segment
		(start 57.9882 -81.1276)
		(end 57.9882 -82.00771)
		(width 0.11684)
		(layer "F.Cu")
		(net "JTAG_SCM_PLD_JTAGEN")
	)
	(via
		(at 8.0264 -96.4184)
		(size 0.508)
		(drill 0.254)
		(layers "F.Cu" "B.Cu")
		(net "JTAG_SCM_PLD_JTAGEN")
	)
	(via
		(at 17.399 -82.5754)
		(size 0.508)
		(drill 0.254)
		(layers "F.Cu" "B.Cu")
		(net "JTAG_SCM_PLD_JTAGEN")
	)
	(via
		(at 57.4294 -82.56651)
		(size 0.508)
		(drill 0.254)
		(layers "F.Cu" "B.Cu")
		(net "JTAG_SCM_PLD_JTAGEN")
	)
	(via
		(at 57.9882 -81.1276)
		(size 0.762)
		(drill 0.381)
		(layers "F.Cu" "B.Cu")
		(net "JTAG_SCM_PLD_JTAGEN")
	)
	(segment
		(start 17.2974 -82.677)
		(end 17.399 -82.5754)
		(width 0.11684)
		(layer "B.Cu")
		(net "JTAG_SCM_PLD_JTAGEN")
	)
	(segment
		(start 17.2974 -83.29295)
		(end 17.2974 -82.677)
		(width 0.11684)
		(layer "B.Cu")
		(net "JTAG_SCM_PLD_JTAGEN")
	)
	(segment
		(start 37.440108 -82.04708)
		(end 34.745168 -82.04708)
		(width 0.08382)
		(layer "In2.Cu")
		(net "JTAG_SCM_PLD_JTAGEN")
	)
	(segment
		(start 28.837636 -83.1088)
		(end 27.94508 -84.001356)
		(width 0.08382)
		(layer "In2.Cu")
		(net "JTAG_SCM_PLD_JTAGEN")
	)
	(segment
		(start 34.745168 -82.04708)
		(end 34.635948 -81.93786)
		(width 0.08382)
		(layer "In2.Cu")
		(net "JTAG_SCM_PLD_JTAGEN")
	)
	(segment
		(start 26.546302 -84.001356)
		(end 26.10104 -83.556094)
		(width 0.08382)
		(layer "In2.Cu")
		(net "JTAG_SCM_PLD_JTAGEN")
	)
	(segment
		(start 26.10104 -83.556094)
		(end 26.10104 -83.388454)
		(width 0.08382)
		(layer "In2.Cu")
		(net "JTAG_SCM_PLD_JTAGEN")
	)
	(segment
		(start 45.2374 -82.31251)
		(end 42.949114 -82.31251)
		(width 0.08382)
		(layer "In2.Cu")
		(net "JTAG_SCM_PLD_JTAGEN")
	)
	(segment
		(start 27.94508 -84.001356)
		(end 26.546302 -84.001356)
		(width 0.08382)
		(layer "In2.Cu")
		(net "JTAG_SCM_PLD_JTAGEN")
	)
	(segment
		(start 7.62 -89.286588)
		(end 10.10158 -86.805008)
		(width 0.08382)
		(layer "In2.Cu")
		(net "JTAG_SCM_PLD_JTAGEN")
	)
	(segment
		(start 32.1818 -82.710528)
		(end 31.783528 -83.1088)
		(width 0.08382)
		(layer "In2.Cu")
		(net "JTAG_SCM_PLD_JTAGEN")
	)
	(segment
		(start 26.10104 -83.388454)
		(end 25.34158 -82.628994)
		(width 0.08382)
		(layer "In2.Cu")
		(net "JTAG_SCM_PLD_JTAGEN")
	)
	(segment
		(start 31.783528 -83.1088)
		(end 28.837636 -83.1088)
		(width 0.08382)
		(layer "In2.Cu")
		(net "JTAG_SCM_PLD_JTAGEN")
	)
	(segment
		(start 8.0264 -96.4184)
		(end 8.0264 -94.894654)
		(width 0.08382)
		(layer "In2.Cu")
		(net "JTAG_SCM_PLD_JTAGEN")
	)
	(segment
		(start 32.1818 -82.397854)
		(end 32.1818 -82.710528)
		(width 0.08382)
		(layer "In2.Cu")
		(net "JTAG_SCM_PLD_JTAGEN")
	)
	(segment
		(start 47.793402 -81.720944)
		(end 45.828966 -81.720944)
		(width 0.08382)
		(layer "In2.Cu")
		(net "JTAG_SCM_PLD_JTAGEN")
	)
	(segment
		(start 54.77637 -82.7024)
		(end 53.93817 -81.8642)
		(width 0.08382)
		(layer "In2.Cu")
		(net "JTAG_SCM_PLD_JTAGEN")
	)
	(segment
		(start 24.130254 -80.93202)
		(end 20.261834 -80.93202)
		(width 0.08382)
		(layer "In2.Cu")
		(net "JTAG_SCM_PLD_JTAGEN")
	)
	(segment
		(start 8.0264 -94.894654)
		(end 7.62 -94.488254)
		(width 0.08382)
		(layer "In2.Cu")
		(net "JTAG_SCM_PLD_JTAGEN")
	)
	(segment
		(start 25.34158 -82.143346)
		(end 24.130254 -80.93202)
		(width 0.08382)
		(layer "In2.Cu")
		(net "JTAG_SCM_PLD_JTAGEN")
	)
	(segment
		(start 19.888454 -81.3054)
		(end 18.669 -81.3054)
		(width 0.08382)
		(layer "In2.Cu")
		(net "JTAG_SCM_PLD_JTAGEN")
	)
	(segment
		(start 20.261834 -80.93202)
		(end 19.888454 -81.3054)
		(width 0.08382)
		(layer "In2.Cu")
		(net "JTAG_SCM_PLD_JTAGEN")
	)
	(segment
		(start 48.927258 -82.8548)
		(end 47.793402 -81.720944)
		(width 0.08382)
		(layer "In2.Cu")
		(net "JTAG_SCM_PLD_JTAGEN")
	)
	(segment
		(start 45.828966 -81.720944)
		(end 45.2374 -82.31251)
		(width 0.08382)
		(layer "In2.Cu")
		(net "JTAG_SCM_PLD_JTAGEN")
	)
	(segment
		(start 42.949114 -82.31251)
		(end 42.535094 -82.72653)
		(width 0.08382)
		(layer "In2.Cu")
		(net "JTAG_SCM_PLD_JTAGEN")
	)
	(segment
		(start 52.603146 -81.8642)
		(end 51.612546 -82.8548)
		(width 0.08382)
		(layer "In2.Cu")
		(net "JTAG_SCM_PLD_JTAGEN")
	)
	(segment
		(start 14.81328 -83.2358)
		(end 16.7386 -83.2358)
		(width 0.08382)
		(layer "In2.Cu")
		(net "JTAG_SCM_PLD_JTAGEN")
	)
	(segment
		(start 10.10158 -86.805008)
		(end 10.10158 -86.349332)
		(width 0.08382)
		(layer "In2.Cu")
		(net "JTAG_SCM_PLD_JTAGEN")
	)
	(segment
		(start 57.29351 -82.7024)
		(end 54.77637 -82.7024)
		(width 0.08382)
		(layer "In2.Cu")
		(net "JTAG_SCM_PLD_JTAGEN")
	)
	(segment
		(start 7.62 -94.488254)
		(end 7.62 -89.286588)
		(width 0.08382)
		(layer "In2.Cu")
		(net "JTAG_SCM_PLD_JTAGEN")
	)
	(segment
		(start 53.93817 -81.8642)
		(end 52.603146 -81.8642)
		(width 0.08382)
		(layer "In2.Cu")
		(net "JTAG_SCM_PLD_JTAGEN")
	)
	(segment
		(start 16.7386 -83.2358)
		(end 17.399 -82.5754)
		(width 0.08382)
		(layer "In2.Cu")
		(net "JTAG_SCM_PLD_JTAGEN")
	)
	(segment
		(start 57.4294 -82.56651)
		(end 57.29351 -82.7024)
		(width 0.08382)
		(layer "In2.Cu")
		(net "JTAG_SCM_PLD_JTAGEN")
	)
	(segment
		(start 51.612546 -82.8548)
		(end 48.927258 -82.8548)
		(width 0.08382)
		(layer "In2.Cu")
		(net "JTAG_SCM_PLD_JTAGEN")
	)
	(segment
		(start 32.641794 -81.93786)
		(end 32.1818 -82.397854)
		(width 0.08382)
		(layer "In2.Cu")
		(net "JTAG_SCM_PLD_JTAGEN")
	)
	(segment
		(start 25.34158 -82.628994)
		(end 25.34158 -82.143346)
		(width 0.08382)
		(layer "In2.Cu")
		(net "JTAG_SCM_PLD_JTAGEN")
	)
	(segment
		(start 38.119558 -82.72653)
		(end 37.440108 -82.04708)
		(width 0.08382)
		(layer "In2.Cu")
		(net "JTAG_SCM_PLD_JTAGEN")
	)
	(segment
		(start 10.10158 -86.349332)
		(end 10.321544 -85.818218)
		(width 0.08382)
		(layer "In2.Cu")
		(net "JTAG_SCM_PLD_JTAGEN")
	)
	(segment
		(start 42.535094 -82.72653)
		(end 38.119558 -82.72653)
		(width 0.08382)
		(layer "In2.Cu")
		(net "JTAG_SCM_PLD_JTAGEN")
	)
	(segment
		(start 34.635948 -81.93786)
		(end 32.641794 -81.93786)
		(width 0.08382)
		(layer "In2.Cu")
		(net "JTAG_SCM_PLD_JTAGEN")
	)
	(segment
		(start 18.669 -81.3054)
		(end 17.399 -82.5754)
		(width 0.08382)
		(layer "In2.Cu")
		(net "JTAG_SCM_PLD_JTAGEN")
	)
	(segment
		(start 10.321544 -85.818218)
		(end 13.16482 -83.918552)
		(width 0.08382)
		(layer "In2.Cu")
		(net "JTAG_SCM_PLD_JTAGEN")
	)
	(segment
		(start 13.16482 -83.918552)
		(end 14.81328 -83.2358)
		(width 0.08382)
		(layer "In2.Cu")
		(net "JTAG_SCM_PLD_JTAGEN")
	)
	(segment
		(start 10.287 -95.01505)
		(end 10.02792 -94.75597)
		(width 0.11684)
		(layer "F.Cu")
		(net "JTAG_SCM_CONN_TMS")
	)
	(segment
		(start 7.8994 -94.284546)
		(end 7.8994 -93.068394)
		(width 0.11684)
		(layer "F.Cu")
		(net "JTAG_SCM_CONN_TMS")
	)
	(segment
		(start 10.02792 -94.75597)
		(end 8.370824 -94.75597)
		(width 0.11684)
		(layer "F.Cu")
		(net "JTAG_SCM_CONN_TMS")
	)
	(segment
		(start 6.056122 -91.225116)
		(end 6.050026 -91.225116)
		(width 0.11684)
		(layer "F.Cu")
		(net "JTAG_SCM_CONN_TMS")
	)
	(segment
		(start 7.8994 -93.068394)
		(end 6.056122 -91.225116)
		(width 0.11684)
		(layer "F.Cu")
		(net "JTAG_SCM_CONN_TMS")
	)
	(segment
		(start 8.370824 -94.75597)
		(end 7.8994 -94.284546)
		(width 0.11684)
		(layer "F.Cu")
		(net "JTAG_SCM_CONN_TMS")
	)
	(segment
		(start 9.620504 -102.25405)
		(end 8.75157 -101.385116)
		(width 0.11684)
		(layer "F.Cu")
		(net "JTAG_SCM_CONN_TDO")
	)
	(segment
		(start 8.75157 -101.385116)
		(end 6.050026 -101.385116)
		(width 0.11684)
		(layer "F.Cu")
		(net "JTAG_SCM_CONN_TDO")
	)
	(segment
		(start 10.287 -102.25405)
		(end 9.620504 -102.25405)
		(width 0.11684)
		(layer "F.Cu")
		(net "JTAG_SCM_CONN_TDO")
	)
	(segment
		(start 9.976104 -99.67595)
		(end 9.804654 -99.8474)
		(width 0.11684)
		(layer "F.Cu")
		(net "JTAG_SCM_CONN_TDI")
	)
	(segment
		(start 9.459214 -99.8474)
		(end 9.311386 -99.786186)
		(width 0.11684)
		(layer "F.Cu")
		(net "JTAG_SCM_CONN_TDI")
	)
	(segment
		(start 7.010146 -98.845116)
		(end 6.050026 -98.845116)
		(width 0.11684)
		(layer "F.Cu")
		(net "JTAG_SCM_CONN_TDI")
	)
	(segment
		(start 9.311386 -99.786186)
		(end 8.3058 -98.7806)
		(width 0.11684)
		(layer "F.Cu")
		(net "JTAG_SCM_CONN_TDI")
	)
	(segment
		(start 9.804654 -99.8474)
		(end 9.459214 -99.8474)
		(width 0.11684)
		(layer "F.Cu")
		(net "JTAG_SCM_CONN_TDI")
	)
	(segment
		(start 10.287 -99.67595)
		(end 9.976104 -99.67595)
		(width 0.11684)
		(layer "F.Cu")
		(net "JTAG_SCM_CONN_TDI")
	)
	(segment
		(start 7.074662 -98.7806)
		(end 7.010146 -98.845116)
		(width 0.11684)
		(layer "F.Cu")
		(net "JTAG_SCM_CONN_TDI")
	)
	(segment
		(start 8.3058 -98.7806)
		(end 7.074662 -98.7806)
		(width 0.11684)
		(layer "F.Cu")
		(net "JTAG_SCM_CONN_TDI")
	)
	(segment
		(start 9.4996 -91.4146)
		(end 9.53135 -91.4146)
		(width 0.11684)
		(layer "F.Cu")
		(net "JTAG_SCM_CONN_TCK")
	)
	(segment
		(start 9.53135 -91.4146)
		(end 10.287 -90.65895)
		(width 0.11684)
		(layer "F.Cu")
		(net "JTAG_SCM_CONN_TCK")
	)
	(via
		(at 9.4996 -91.4146)
		(size 0.508)
		(drill 0.254)
		(layers "F.Cu" "B.Cu")
		(net "JTAG_SCM_CONN_TCK")
	)
	(segment
		(start 8.382 -90.297)
		(end 9.4996 -91.4146)
		(width 0.11684)
		(layer "B.Cu")
		(net "JTAG_SCM_CONN_TCK")
	)
	(segment
		(start 8.382 -89.535)
		(end 8.382 -90.297)
		(width 0.11684)
		(layer "B.Cu")
		(net "JTAG_SCM_CONN_TCK")
	)
	(segment
		(start 6.050026 -87.203026)
		(end 8.382 -89.535)
		(width 0.11684)
		(layer "B.Cu")
		(net "JTAG_SCM_CONN_TCK")
	)
	(segment
		(start 6.050026 -86.145116)
		(end 6.050026 -87.203026)
		(width 0.11684)
		(layer "B.Cu")
		(net "JTAG_SCM_CONN_TCK")
	)
	(segment
		(start 59.4487 -94.856046)
		(end 57.940956 -96.36379)
		(width 0.11684)
		(layer "F.Cu")
		(net "IRQ_PCH_TPM_SPI_R_N")
	)
	(segment
		(start 57.940956 -96.36379)
		(end 57.5691 -96.36379)
		(width 0.11684)
		(layer "F.Cu")
		(net "IRQ_PCH_TPM_SPI_R_N")
	)
	(segment
		(start 60.591954 -94.856046)
		(end 59.4487 -94.856046)
		(width 0.11684)
		(layer "F.Cu")
		(net "IRQ_PCH_TPM_SPI_R_N")
	)
	(segment
		(start 57.58561 -92.66301)
		(end 57.58561 -94.5896)
		(width 0.11684)
		(layer "F.Cu")
		(net "FM_TPM_PRSNT_0_N")
	)
	(segment
		(start 48.0949 -56.971184)
		(end 48.499776 -56.566308)
		(width 0.11684)
		(layer "F.Cu")
		(net "FM_TPM_PRSNT_0_N")
	)
	(segment
		(start 57.58434 -92.66301)
		(end 57.58561 -92.66301)
		(width 0.11684)
		(layer "F.Cu")
		(net "FM_TPM_PRSNT_0_N")
	)
	(segment
		(start 57.886346 -94.5896)
		(end 57.58561 -94.5896)
		(width 0.11684)
		(layer "F.Cu")
		(net "FM_TPM_PRSNT_0_N")
	)
	(segment
		(start 58.039 -94.074742)
		(end 58.039 -94.436946)
		(width 0.11684)
		(layer "F.Cu")
		(net "FM_TPM_PRSNT_0_N")
	)
	(segment
		(start 58.039 -94.436946)
		(end 57.886346 -94.5896)
		(width 0.11684)
		(layer "F.Cu")
		(net "FM_TPM_PRSNT_0_N")
	)
	(segment
		(start 58.257694 -93.856048)
		(end 58.039 -94.074742)
		(width 0.11684)
		(layer "F.Cu")
		(net "FM_TPM_PRSNT_0_N")
	)
	(segment
		(start 60.591954 -93.856048)
		(end 58.257694 -93.856048)
		(width 0.11684)
		(layer "F.Cu")
		(net "FM_TPM_PRSNT_0_N")
	)
	(via
		(at 30.7848 -91.2368)
		(size 0.508)
		(drill 0.254)
		(layers "F.Cu" "B.Cu")
		(net "FM_TPM_PRSNT_0_N")
	)
	(via
		(at 48.499776 -56.566308)
		(size 0.4572)
		(drill 0.254)
		(layers "F.Cu" "B.Cu")
		(net "FM_TPM_PRSNT_0_N")
	)
	(via
		(at 31.0388 -90.5256)
		(size 0.6604)
		(drill 0.3302)
		(layers "F.Cu" "B.Cu")
		(net "FM_TPM_PRSNT_0_N")
	)
	(via
		(at 57.58434 -92.66301)
		(size 0.508)
		(drill 0.254)
		(layers "F.Cu" "B.Cu")
		(net "FM_TPM_PRSNT_0_N")
	)
	(segment
		(start 30.31998 -89.37117)
		(end 30.31998 -89.80678)
		(width 0.11684)
		(layer "B.Cu")
		(net "FM_TPM_PRSNT_0_N")
	)
	(segment
		(start 31.0388 -90.9828)
		(end 31.0388 -90.5256)
		(width 0.11684)
		(layer "B.Cu")
		(net "FM_TPM_PRSNT_0_N")
	)
	(segment
		(start 30.7848 -91.2368)
		(end 31.0388 -90.9828)
		(width 0.11684)
		(layer "B.Cu")
		(net "FM_TPM_PRSNT_0_N")
	)
	(segment
		(start 30.31998 -89.80678)
		(end 31.0388 -90.5256)
		(width 0.11684)
		(layer "B.Cu")
		(net "FM_TPM_PRSNT_0_N")
	)
	(segment
		(start 51.98237 -90.11793)
		(end 49.96307 -90.11793)
		(width 0.08382)
		(layer "In2.Cu")
		(net "FM_TPM_PRSNT_0_N")
	)
	(segment
		(start 31.623 -91.2368)
		(end 30.7848 -91.2368)
		(width 0.08382)
		(layer "In2.Cu")
		(net "FM_TPM_PRSNT_0_N")
	)
	(segment
		(start 49.96307 -90.11793)
		(end 47.19447 -92.88653)
		(width 0.08382)
		(layer "In2.Cu")
		(net "FM_TPM_PRSNT_0_N")
	)
	(segment
		(start 33.27273 -92.88653)
		(end 31.623 -91.2368)
		(width 0.08382)
		(layer "In2.Cu")
		(net "FM_TPM_PRSNT_0_N")
	)
	(segment
		(start 55.32882 -91.62542)
		(end 53.48986 -91.62542)
		(width 0.08382)
		(layer "In2.Cu")
		(net "FM_TPM_PRSNT_0_N")
	)
	(segment
		(start 47.19447 -92.88653)
		(end 33.27273 -92.88653)
		(width 0.08382)
		(layer "In2.Cu")
		(net "FM_TPM_PRSNT_0_N")
	)
	(segment
		(start 57.58434 -92.66301)
		(end 56.36641 -92.66301)
		(width 0.08382)
		(layer "In2.Cu")
		(net "FM_TPM_PRSNT_0_N")
	)
	(segment
		(start 56.36641 -92.66301)
		(end 55.32882 -91.62542)
		(width 0.08382)
		(layer "In2.Cu")
		(net "FM_TPM_PRSNT_0_N")
	)
	(segment
		(start 53.48986 -91.62542)
		(end 51.98237 -90.11793)
		(width 0.08382)
		(layer "In2.Cu")
		(net "FM_TPM_PRSNT_0_N")
	)
	(segment
		(start 54.9529 -55.2831)
		(end 49.898046 -55.2831)
		(width 0.08382)
		(layer "In9.Cu")
		(net "FM_TPM_PRSNT_0_N")
	)
	(segment
		(start 56.45912 -62.85992)
		(end 56.45912 -62.082934)
		(width 0.08382)
		(layer "In9.Cu")
		(net "FM_TPM_PRSNT_0_N")
	)
	(segment
		(start 55.27167 -89.82583)
		(end 55.27167 -86.967822)
		(width 0.08382)
		(layer "In9.Cu")
		(net "FM_TPM_PRSNT_0_N")
	)
	(segment
		(start 57.58053 -92.6592)
		(end 56.3626 -92.6592)
		(width 0.08382)
		(layer "In9.Cu")
		(net "FM_TPM_PRSNT_0_N")
	)
	(segment
		(start 56.3626 -92.6592)
		(end 55.626 -91.9226)
		(width 0.08382)
		(layer "In9.Cu")
		(net "FM_TPM_PRSNT_0_N")
	)
	(segment
		(start 49.671986 -55.92064)
		(end 49.454054 -56.138572)
		(width 0.08382)
		(layer "In9.Cu")
		(net "FM_TPM_PRSNT_0_N")
	)
	(segment
		(start 54.551072 -63.89243)
		(end 55.42661 -63.89243)
		(width 0.08382)
		(layer "In9.Cu")
		(net "FM_TPM_PRSNT_0_N")
	)
	(segment
		(start 55.626 -90.18016)
		(end 55.27167 -89.82583)
		(width 0.08382)
		(layer "In9.Cu")
		(net "FM_TPM_PRSNT_0_N")
	)
	(segment
		(start 55.626 -91.9226)
		(end 55.626 -90.18016)
		(width 0.08382)
		(layer "In9.Cu")
		(net "FM_TPM_PRSNT_0_N")
	)
	(segment
		(start 55.42661 -63.89243)
		(end 56.45912 -62.85992)
		(width 0.08382)
		(layer "In9.Cu")
		(net "FM_TPM_PRSNT_0_N")
	)
	(segment
		(start 54.29123 -65.39357)
		(end 54.29123 -64.152272)
		(width 0.08382)
		(layer "In9.Cu")
		(net "FM_TPM_PRSNT_0_N")
	)
	(segment
		(start 53.250084 -81.748884)
		(end 53.250084 -68.84543)
		(width 0.08382)
		(layer "In9.Cu")
		(net "FM_TPM_PRSNT_0_N")
	)
	(segment
		(start 55.27167 -86.967822)
		(end 55.56758 -86.671912)
		(width 0.08382)
		(layer "In9.Cu")
		(net "FM_TPM_PRSNT_0_N")
	)
	(segment
		(start 56.375046 -61.211206)
		(end 56.375046 -59.93511)
		(width 0.08382)
		(layer "In9.Cu")
		(net "FM_TPM_PRSNT_0_N")
	)
	(segment
		(start 56.45912 -62.082934)
		(end 56.58231 -61.959744)
		(width 0.08382)
		(layer "In9.Cu")
		(net "FM_TPM_PRSNT_0_N")
	)
	(segment
		(start 49.042574 -56.138572)
		(end 48.614838 -56.566308)
		(width 0.08382)
		(layer "In9.Cu")
		(net "FM_TPM_PRSNT_0_N")
	)
	(segment
		(start 53.04282 -66.64198)
		(end 54.29123 -65.39357)
		(width 0.08382)
		(layer "In9.Cu")
		(net "FM_TPM_PRSNT_0_N")
	)
	(segment
		(start 55.56758 -86.671912)
		(end 55.56758 -84.06638)
		(width 0.08382)
		(layer "In9.Cu")
		(net "FM_TPM_PRSNT_0_N")
	)
	(segment
		(start 56.053736 -59.6138)
		(end 55.796688 -59.6138)
		(width 0.08382)
		(layer "In9.Cu")
		(net "FM_TPM_PRSNT_0_N")
	)
	(segment
		(start 56.58231 -61.41847)
		(end 56.375046 -61.211206)
		(width 0.08382)
		(layer "In9.Cu")
		(net "FM_TPM_PRSNT_0_N")
	)
	(segment
		(start 54.29123 -64.152272)
		(end 54.551072 -63.89243)
		(width 0.08382)
		(layer "In9.Cu")
		(net "FM_TPM_PRSNT_0_N")
	)
	(segment
		(start 53.04282 -68.638166)
		(end 53.04282 -66.64198)
		(width 0.08382)
		(layer "In9.Cu")
		(net "FM_TPM_PRSNT_0_N")
	)
	(segment
		(start 49.671986 -55.50916)
		(end 49.671986 -55.92064)
		(width 0.08382)
		(layer "In9.Cu")
		(net "FM_TPM_PRSNT_0_N")
	)
	(segment
		(start 55.56758 -84.06638)
		(end 53.250084 -81.748884)
		(width 0.08382)
		(layer "In9.Cu")
		(net "FM_TPM_PRSNT_0_N")
	)
	(segment
		(start 56.58231 -61.959744)
		(end 56.58231 -61.41847)
		(width 0.08382)
		(layer "In9.Cu")
		(net "FM_TPM_PRSNT_0_N")
	)
	(segment
		(start 55.318152 -55.648352)
		(end 54.9529 -55.2831)
		(width 0.08382)
		(layer "In9.Cu")
		(net "FM_TPM_PRSNT_0_N")
	)
	(segment
		(start 57.58434 -92.66301)
		(end 57.58053 -92.6592)
		(width 0.08382)
		(layer "In9.Cu")
		(net "FM_TPM_PRSNT_0_N")
	)
	(segment
		(start 55.796688 -59.6138)
		(end 55.318152 -59.135264)
		(width 0.08382)
		(layer "In9.Cu")
		(net "FM_TPM_PRSNT_0_N")
	)
	(segment
		(start 55.318152 -59.135264)
		(end 55.318152 -55.648352)
		(width 0.08382)
		(layer "In9.Cu")
		(net "FM_TPM_PRSNT_0_N")
	)
	(segment
		(start 48.614838 -56.566308)
		(end 48.499776 -56.566308)
		(width 0.08382)
		(layer "In9.Cu")
		(net "FM_TPM_PRSNT_0_N")
	)
	(segment
		(start 53.250084 -68.84543)
		(end 53.04282 -68.638166)
		(width 0.08382)
		(layer "In9.Cu")
		(net "FM_TPM_PRSNT_0_N")
	)
	(segment
		(start 56.375046 -59.93511)
		(end 56.053736 -59.6138)
		(width 0.08382)
		(layer "In9.Cu")
		(net "FM_TPM_PRSNT_0_N")
	)
	(segment
		(start 49.454054 -56.138572)
		(end 49.042574 -56.138572)
		(width 0.08382)
		(layer "In9.Cu")
		(net "FM_TPM_PRSNT_0_N")
	)
	(segment
		(start 49.898046 -55.2831)
		(end 49.671986 -55.50916)
		(width 0.08382)
		(layer "In9.Cu")
		(net "FM_TPM_PRSNT_0_N")
	)
	(segment
		(start 54.562756 -36.902644)
		(end 54.562756 -36.2458)
		(width 0.11684)
		(layer "F.Cu")
		(net "V_VGAVS_R")
	)
	(segment
		(start 54.562756 -36.2458)
		(end 54.562756 -35.560254)
		(width 0.11684)
		(layer "F.Cu")
		(net "V_VGAVS_R")
	)
	(segment
		(start 54.494938 -40.971216)
		(end 54.099714 -40.575992)
		(width 0.11684)
		(layer "F.Cu")
		(net "V_VGAVS_R")
	)
	(segment
		(start 54.562756 -35.560254)
		(end 54.040278 -35.037776)
		(width 0.11684)
		(layer "F.Cu")
		(net "V_VGAVS_R")
	)
	(segment
		(start 54.099714 -40.575992)
		(end 54.099714 -37.365686)
		(width 0.11684)
		(layer "F.Cu")
		(net "V_VGAVS_R")
	)
	(segment
		(start 54.099714 -37.365686)
		(end 54.562756 -36.902644)
		(width 0.11684)
		(layer "F.Cu")
		(net "V_VGAVS_R")
	)
	(via
		(at 54.562756 -36.2458)
		(size 0.762)
		(drill 0.381)
		(layers "F.Cu" "B.Cu")
		(net "V_VGAVS_R")
	)
	(via
		(at 41.91 -6.223)
		(size 0.6604)
		(drill 0.3302)
		(layers "F.Cu" "B.Cu")
		(net "V_VGAVS_BUF_R")
	)
	(segment
		(start 42.785538 -5.47116)
		(end 42.668698 -5.588)
		(width 0.11684)
		(layer "B.Cu")
		(net "V_VGAVS_BUF_R")
	)
	(segment
		(start 41.91 -5.715)
		(end 41.91 -6.223)
		(width 0.11684)
		(layer "B.Cu")
		(net "V_VGAVS_BUF_R")
	)
	(segment
		(start 42.037 -5.588)
		(end 41.91 -5.715)
		(width 0.11684)
		(layer "B.Cu")
		(net "V_VGAVS_BUF_R")
	)
	(segment
		(start 41.91 -6.223)
		(end 41.92905 -6.20395)
		(width 0.11684)
		(layer "B.Cu")
		(net "V_VGAVS_BUF_R")
	)
	(segment
		(start 42.668698 -5.588)
		(end 42.037 -5.588)
		(width 0.11684)
		(layer "B.Cu")
		(net "V_VGAVS_BUF_R")
	)
	(segment
		(start 42.785538 -5.014722)
		(end 42.785538 -5.47116)
		(width 0.11684)
		(layer "B.Cu")
		(net "V_VGAVS_BUF_R")
	)
	(segment
		(start 41.92905 -6.20395)
		(end 43.053 -6.20395)
		(width 0.11684)
		(layer "B.Cu")
		(net "V_VGAVS_BUF_R")
	)
	(segment
		(start 33.877758 -25.888696)
		(end 33.39084 -26.375614)
		(width 0.11684)
		(layer "F.Cu")
		(net "V_VGAVS_BUF")
	)
	(segment
		(start 31.362396 -27.669998)
		(end 30.663896 -27.669998)
		(width 0.11684)
		(layer "F.Cu")
		(net "V_VGAVS_BUF")
	)
	(segment
		(start 33.2232 -26.780236)
		(end 32.977836 -27.372564)
		(width 0.11684)
		(layer "F.Cu")
		(net "V_VGAVS_BUF")
	)
	(segment
		(start 32.977836 -27.372564)
		(end 32.794448 -27.555952)
		(width 0.11684)
		(layer "F.Cu")
		(net "V_VGAVS_BUF")
	)
	(segment
		(start 34.52622 -25.619964)
		(end 33.877758 -25.888696)
		(width 0.11684)
		(layer "F.Cu")
		(net "V_VGAVS_BUF")
	)
	(segment
		(start 32.519112 -27.669998)
		(end 32.137604 -27.669998)
		(width 0.11684)
		(layer "F.Cu")
		(net "V_VGAVS_BUF")
	)
	(segment
		(start 33.39084 -26.375614)
		(end 33.2232 -26.780236)
		(width 0.11684)
		(layer "F.Cu")
		(net "V_VGAVS_BUF")
	)
	(segment
		(start 32.794448 -27.555952)
		(end 32.519112 -27.669998)
		(width 0.11684)
		(layer "F.Cu")
		(net "V_VGAVS_BUF")
	)
	(segment
		(start 34.625026 -25.619964)
		(end 34.52622 -25.619964)
		(width 0.11684)
		(layer "F.Cu")
		(net "V_VGAVS_BUF")
	)
	(segment
		(start 32.137604 -27.669998)
		(end 31.362396 -27.669998)
		(width 0.11684)
		(layer "F.Cu")
		(net "V_VGAVS_BUF")
	)
	(via
		(at 43.053 -8.128)
		(size 0.6604)
		(drill 0.3302)
		(layers "F.Cu" "B.Cu")
		(net "V_VGAVS_BUF")
	)
	(via
		(at 35.8394 -21.971)
		(size 0.508)
		(drill 0.254)
		(layers "F.Cu" "B.Cu")
		(net "V_VGAVS_BUF")
	)
	(via
		(at 30.663896 -27.669998)
		(size 0.508)
		(drill 0.254)
		(layers "F.Cu" "B.Cu")
		(net "V_VGAVS_BUF")
	)
	(segment
		(start 37.34562 -21.65858)
		(end 37.7952 -21.209)
		(width 0.11684)
		(layer "B.Cu")
		(net "V_VGAVS_BUF")
	)
	(segment
		(start 29.58465 -27.7622)
		(end 30.571694 -27.7622)
		(width 0.11684)
		(layer "B.Cu")
		(net "V_VGAVS_BUF")
	)
	(segment
		(start 35.8394 -21.971)
		(end 36.15182 -21.65858)
		(width 0.11684)
		(layer "B.Cu")
		(net "V_VGAVS_BUF")
	)
	(segment
		(start 37.15258 -17.59458)
		(end 37.15258 -13.520674)
		(width 0.11684)
		(layer "B.Cu")
		(net "V_VGAVS_BUF")
	)
	(segment
		(start 41.529254 -9.144)
		(end 42.037 -9.144)
		(width 0.11684)
		(layer "B.Cu")
		(net "V_VGAVS_BUF")
	)
	(segment
		(start 37.7952 -18.2372)
		(end 37.15258 -17.59458)
		(width 0.11684)
		(layer "B.Cu")
		(net "V_VGAVS_BUF")
	)
	(segment
		(start 30.571694 -27.7622)
		(end 30.663896 -27.669998)
		(width 0.11684)
		(layer "B.Cu")
		(net "V_VGAVS_BUF")
	)
	(segment
		(start 43.053 -7.00405)
		(end 43.053 -8.128)
		(width 0.11684)
		(layer "B.Cu")
		(net "V_VGAVS_BUF")
	)
	(segment
		(start 37.15258 -13.520674)
		(end 41.529254 -9.144)
		(width 0.11684)
		(layer "B.Cu")
		(net "V_VGAVS_BUF")
	)
	(segment
		(start 42.037 -9.144)
		(end 43.053 -8.128)
		(width 0.11684)
		(layer "B.Cu")
		(net "V_VGAVS_BUF")
	)
	(segment
		(start 37.7952 -21.209)
		(end 37.7952 -18.2372)
		(width 0.11684)
		(layer "B.Cu")
		(net "V_VGAVS_BUF")
	)
	(segment
		(start 36.15182 -21.65858)
		(end 37.34562 -21.65858)
		(width 0.11684)
		(layer "B.Cu")
		(net "V_VGAVS_BUF")
	)
	(segment
		(start 35.795204 -21.971)
		(end 35.8394 -21.971)
		(width 0.08382)
		(layer "In2.Cu")
		(net "V_VGAVS_BUF")
	)
	(segment
		(start 34.194242 -23.571962)
		(end 35.795204 -21.971)
		(width 0.08382)
		(layer "In2.Cu")
		(net "V_VGAVS_BUF")
	)
	(segment
		(start 33.792668 -24.541226)
		(end 34.194242 -23.571962)
		(width 0.08382)
		(layer "In2.Cu")
		(net "V_VGAVS_BUF")
	)
	(segment
		(start 30.663896 -27.669998)
		(end 33.792668 -24.541226)
		(width 0.08382)
		(layer "In2.Cu")
		(net "V_VGAVS_BUF")
	)
	(segment
		(start 53.52034 -33.09366)
		(end 53.681884 -32.932116)
		(width 0.11684)
		(layer "F.Cu")
		(net "V_VGAVS")
	)
	(segment
		(start 53.52034 -34.045144)
		(end 53.52034 -33.09366)
		(width 0.11684)
		(layer "F.Cu")
		(net "V_VGAVS")
	)
	(segment
		(start 53.712872 -34.237676)
		(end 53.52034 -34.045144)
		(width 0.11684)
		(layer "F.Cu")
		(net "V_VGAVS")
	)
	(segment
		(start 53.681884 -32.932116)
		(end 54.032658 -32.932116)
		(width 0.11684)
		(layer "F.Cu")
		(net "V_VGAVS")
	)
	(segment
		(start 54.040278 -34.237676)
		(end 53.712872 -34.237676)
		(width 0.11684)
		(layer "F.Cu")
		(net "V_VGAVS")
	)
	(via
		(at 54.032658 -32.932116)
		(size 0.508)
		(drill 0.254)
		(layers "F.Cu" "B.Cu")
		(net "V_VGAVS")
	)
	(via
		(at 44.6278 -19.36623)
		(size 0.508)
		(drill 0.254)
		(layers "F.Cu" "B.Cu")
		(net "V_VGAVS")
	)
	(via
		(at 46.863 -3.937)
		(size 0.6604)
		(drill 0.3302)
		(layers "F.Cu" "B.Cu")
		(net "V_VGAVS")
	)
	(segment
		(start 51.816 -12.022836)
		(end 51.816 -8.89)
		(width 0.11684)
		(layer "B.Cu")
		(net "V_VGAVS")
	)
	(segment
		(start 44.6278 -18.564352)
		(end 46.859952 -16.3322)
		(width 0.11684)
		(layer "B.Cu")
		(net "V_VGAVS")
	)
	(segment
		(start 51.816 -8.89)
		(end 46.863 -3.937)
		(width 0.11684)
		(layer "B.Cu")
		(net "V_VGAVS")
	)
	(segment
		(start 43.65244 -2.6924)
		(end 45.6184 -2.6924)
		(width 0.11684)
		(layer "B.Cu")
		(net "V_VGAVS")
	)
	(segment
		(start 43.5356 -3.214878)
		(end 43.5356 -2.80924)
		(width 0.11684)
		(layer "B.Cu")
		(net "V_VGAVS")
	)
	(segment
		(start 44.6278 -19.36623)
		(end 44.6278 -18.564352)
		(width 0.11684)
		(layer "B.Cu")
		(net "V_VGAVS")
	)
	(segment
		(start 47.506636 -16.3322)
		(end 51.816 -12.022836)
		(width 0.11684)
		(layer "B.Cu")
		(net "V_VGAVS")
	)
	(segment
		(start 45.6184 -2.6924)
		(end 46.863 -3.937)
		(width 0.11684)
		(layer "B.Cu")
		(net "V_VGAVS")
	)
	(segment
		(start 46.859952 -16.3322)
		(end 47.506636 -16.3322)
		(width 0.11684)
		(layer "B.Cu")
		(net "V_VGAVS")
	)
	(segment
		(start 43.5356 -2.80924)
		(end 43.65244 -2.6924)
		(width 0.11684)
		(layer "B.Cu")
		(net "V_VGAVS")
	)
	(segment
		(start 52.9082 -30.7086)
		(end 52.71516 -30.51556)
		(width 0.10668)
		(layer "In4.Cu")
		(net "V_VGAVS")
	)
	(segment
		(start 52.130706 -28.321)
		(end 50.91303 -28.321)
		(width 0.10668)
		(layer "In4.Cu")
		(net "V_VGAVS")
	)
	(segment
		(start 47.534322 -24.0792)
		(end 44.6278 -21.172678)
		(width 0.10668)
		(layer "In4.Cu")
		(net "V_VGAVS")
	)
	(segment
		(start 53.652674 -30.861762)
		(end 53.283104 -30.7086)
		(width 0.10668)
		(layer "In4.Cu")
		(net "V_VGAVS")
	)
	(segment
		(start 54.51094 -31.720028)
		(end 53.652674 -30.861762)
		(width 0.10668)
		(layer "In4.Cu")
		(net "V_VGAVS")
	)
	(segment
		(start 48.856138 -26.264108)
		(end 48.856138 -24.458168)
		(width 0.10668)
		(layer "In4.Cu")
		(net "V_VGAVS")
	)
	(segment
		(start 52.71516 -30.51556)
		(end 52.71516 -28.905454)
		(width 0.10668)
		(layer "In4.Cu")
		(net "V_VGAVS")
	)
	(segment
		(start 48.47717 -24.0792)
		(end 47.534322 -24.0792)
		(width 0.10668)
		(layer "In4.Cu")
		(net "V_VGAVS")
	)
	(segment
		(start 48.856138 -24.458168)
		(end 48.47717 -24.0792)
		(width 0.10668)
		(layer "In4.Cu")
		(net "V_VGAVS")
	)
	(segment
		(start 53.283104 -30.7086)
		(end 52.9082 -30.7086)
		(width 0.10668)
		(layer "In4.Cu")
		(net "V_VGAVS")
	)
	(segment
		(start 44.6278 -21.172678)
		(end 44.6278 -19.36623)
		(width 0.10668)
		(layer "In4.Cu")
		(net "V_VGAVS")
	)
	(segment
		(start 50.91303 -28.321)
		(end 48.856138 -26.264108)
		(width 0.10668)
		(layer "In4.Cu")
		(net "V_VGAVS")
	)
	(segment
		(start 54.51094 -32.453834)
		(end 54.51094 -31.720028)
		(width 0.10668)
		(layer "In4.Cu")
		(net "V_VGAVS")
	)
	(segment
		(start 52.71516 -28.905454)
		(end 52.130706 -28.321)
		(width 0.10668)
		(layer "In4.Cu")
		(net "V_VGAVS")
	)
	(segment
		(start 54.032658 -32.932116)
		(end 54.51094 -32.453834)
		(width 0.10668)
		(layer "In4.Cu")
		(net "V_VGAVS")
	)
	(segment
		(start 56.4388 -35.271964)
		(end 56.4388 -37.008054)
		(width 0.11684)
		(layer "F.Cu")
		(net "V_VGAHS_R")
	)
	(segment
		(start 55.517796 -38.585902)
		(end 54.889908 -39.21379)
		(width 0.11684)
		(layer "F.Cu")
		(net "V_VGAHS_R")
	)
	(segment
		(start 56.204612 -35.037776)
		(end 56.4388 -35.271964)
		(width 0.11684)
		(layer "F.Cu")
		(net "V_VGAHS_R")
	)
	(segment
		(start 56.4388 -37.008054)
		(end 55.517796 -37.929058)
		(width 0.11684)
		(layer "F.Cu")
		(net "V_VGAHS_R")
	)
	(segment
		(start 55.517796 -37.929058)
		(end 55.517796 -38.585902)
		(width 0.11684)
		(layer "F.Cu")
		(net "V_VGAHS_R")
	)
	(segment
		(start 54.889908 -39.7764)
		(end 54.494938 -40.17137)
		(width 0.11684)
		(layer "F.Cu")
		(net "V_VGAHS_R")
	)
	(segment
		(start 54.889908 -39.21379)
		(end 54.889908 -39.7764)
		(width 0.11684)
		(layer "F.Cu")
		(net "V_VGAHS_R")
	)
	(via
		(at 38.354 -6.33095)
		(size 0.6604)
		(drill 0.3302)
		(layers "F.Cu" "B.Cu")
		(net "V_VGAHS_BUF_R")
	)
	(segment
		(start 37.578538 -5.014722)
		(end 37.578538 -5.555488)
		(width 0.11684)
		(layer "B.Cu")
		(net "V_VGAHS_BUF_R")
	)
	(segment
		(start 37.578538 -5.555488)
		(end 38.354 -6.33095)
		(width 0.11684)
		(layer "B.Cu")
		(net "V_VGAHS_BUF_R")
	)
	(segment
		(start 38.354 -6.33095)
		(end 39.497 -6.33095)
		(width 0.11684)
		(layer "B.Cu")
		(net "V_VGAHS_BUF_R")
	)
	(segment
		(start 31.362396 -27.169872)
		(end 32.137604 -27.169872)
		(width 0.11684)
		(layer "F.Cu")
		(net "V_VGAHS_BUF")
	)
	(segment
		(start 33.41624 -24.31796)
		(end 34.114232 -23.619968)
		(width 0.11684)
		(layer "F.Cu")
		(net "V_VGAHS_BUF")
	)
	(segment
		(start 33.41624 -25.845516)
		(end 33.41624 -24.31796)
		(width 0.11684)
		(layer "F.Cu")
		(net "V_VGAHS_BUF")
	)
	(segment
		(start 34.625026 -23.619968)
		(end 35.739832 -23.619968)
		(width 0.11684)
		(layer "F.Cu")
		(net "V_VGAHS_BUF")
	)
	(segment
		(start 32.82696 -26.434796)
		(end 33.41624 -25.845516)
		(width 0.11684)
		(layer "F.Cu")
		(net "V_VGAHS_BUF")
	)
	(segment
		(start 35.739832 -23.619968)
		(end 36.1696 -23.1902)
		(width 0.11684)
		(layer "F.Cu")
		(net "V_VGAHS_BUF")
	)
	(segment
		(start 32.650684 -27.039316)
		(end 32.82696 -26.613866)
		(width 0.11684)
		(layer "F.Cu")
		(net "V_VGAHS_BUF")
	)
	(segment
		(start 32.520128 -27.169872)
		(end 32.650684 -27.039316)
		(width 0.11684)
		(layer "F.Cu")
		(net "V_VGAHS_BUF")
	)
	(segment
		(start 32.137604 -27.169872)
		(end 32.520128 -27.169872)
		(width 0.11684)
		(layer "F.Cu")
		(net "V_VGAHS_BUF")
	)
	(segment
		(start 34.114232 -23.619968)
		(end 34.625026 -23.619968)
		(width 0.11684)
		(layer "F.Cu")
		(net "V_VGAHS_BUF")
	)
	(segment
		(start 32.82696 -26.613866)
		(end 32.82696 -26.434796)
		(width 0.11684)
		(layer "F.Cu")
		(net "V_VGAHS_BUF")
	)
	(via
		(at 36.1696 -23.1902)
		(size 0.508)
		(drill 0.254)
		(layers "F.Cu" "B.Cu")
		(net "V_VGAHS_BUF")
	)
	(via
		(at 37.1348 -7.13105)
		(size 0.6604)
		(drill 0.3302)
		(layers "F.Cu" "B.Cu")
		(net "V_VGAHS_BUF")
	)
	(segment
		(start 35.2044 -17.526)
		(end 35.6362 -17.0942)
		(width 0.11684)
		(layer "B.Cu")
		(net "V_VGAHS_BUF")
	)
	(segment
		(start 34.22142 -10.04443)
		(end 37.1348 -7.13105)
		(width 0.11684)
		(layer "B.Cu")
		(net "V_VGAHS_BUF")
	)
	(segment
		(start 35.687 -23.1902)
		(end 36.1696 -23.1902)
		(width 0.11684)
		(layer "B.Cu")
		(net "V_VGAHS_BUF")
	)
	(segment
		(start 35.19932 -22.70252)
		(end 35.687 -23.1902)
		(width 0.11684)
		(layer "B.Cu")
		(net "V_VGAHS_BUF")
	)
	(segment
		(start 35.6362 -13.9192)
		(end 34.22142 -12.50442)
		(width 0.11684)
		(layer "B.Cu")
		(net "V_VGAHS_BUF")
	)
	(segment
		(start 35.49015 -21.57984)
		(end 35.19932 -21.87067)
		(width 0.11684)
		(layer "B.Cu")
		(net "V_VGAHS_BUF")
	)
	(segment
		(start 34.22142 -12.50442)
		(end 34.22142 -10.04443)
		(width 0.11684)
		(layer "B.Cu")
		(net "V_VGAHS_BUF")
	)
	(segment
		(start 35.2044 -18.694146)
		(end 35.2044 -17.526)
		(width 0.11684)
		(layer "B.Cu")
		(net "V_VGAHS_BUF")
	)
	(segment
		(start 35.49015 -19.9898)
		(end 35.49015 -21.57984)
		(width 0.11684)
		(layer "B.Cu")
		(net "V_VGAHS_BUF")
	)
	(segment
		(start 39.497 -7.13105)
		(end 37.1348 -7.13105)
		(width 0.11684)
		(layer "B.Cu")
		(net "V_VGAHS_BUF")
	)
	(segment
		(start 35.49015 -18.979896)
		(end 35.2044 -18.694146)
		(width 0.11684)
		(layer "B.Cu")
		(net "V_VGAHS_BUF")
	)
	(segment
		(start 35.6362 -17.0942)
		(end 35.6362 -13.9192)
		(width 0.11684)
		(layer "B.Cu")
		(net "V_VGAHS_BUF")
	)
	(segment
		(start 35.49015 -19.9898)
		(end 35.49015 -18.979896)
		(width 0.11684)
		(layer "B.Cu")
		(net "V_VGAHS_BUF")
	)
	(segment
		(start 35.19932 -21.87067)
		(end 35.19932 -22.70252)
		(width 0.11684)
		(layer "B.Cu")
		(net "V_VGAHS_BUF")
	)
	(segment
		(start 56.204612 -34.237676)
		(end 56.204612 -33.602676)
		(width 0.11684)
		(layer "F.Cu")
		(net "V_VGAHS")
	)
	(via
		(at 48.387 -4.572)
		(size 0.6604)
		(drill 0.3302)
		(layers "F.Cu" "B.Cu")
		(net "V_VGAHS")
	)
	(via
		(at 56.204612 -33.602676)
		(size 0.508)
		(drill 0.254)
		(layers "F.Cu" "B.Cu")
		(net "V_VGAHS")
	)
	(via
		(at 45.2628 -19.34083)
		(size 0.508)
		(drill 0.254)
		(layers "F.Cu" "B.Cu")
		(net "V_VGAHS")
	)
	(segment
		(start 52.3748 -8.5598)
		(end 52.3748 -12.204192)
		(width 0.11684)
		(layer "B.Cu")
		(net "V_VGAHS")
	)
	(segment
		(start 52.3748 -12.204192)
		(end 47.687992 -16.891)
		(width 0.11684)
		(layer "B.Cu")
		(net "V_VGAHS")
	)
	(segment
		(start 48.387 -4.572)
		(end 52.3748 -8.5598)
		(width 0.11684)
		(layer "B.Cu")
		(net "V_VGAHS")
	)
	(segment
		(start 47.687992 -16.891)
		(end 47.0916 -16.891)
		(width 0.11684)
		(layer "B.Cu")
		(net "V_VGAHS")
	)
	(segment
		(start 38.3286 -2.4384)
		(end 38.3286 -3.214878)
		(width 0.11684)
		(layer "B.Cu")
		(net "V_VGAHS")
	)
	(segment
		(start 45.8978 -2.0828)
		(end 38.6842 -2.0828)
		(width 0.11684)
		(layer "B.Cu")
		(net "V_VGAHS")
	)
	(segment
		(start 48.387 -4.572)
		(end 45.8978 -2.0828)
		(width 0.11684)
		(layer "B.Cu")
		(net "V_VGAHS")
	)
	(segment
		(start 47.0916 -16.891)
		(end 45.2628 -18.7198)
		(width 0.11684)
		(layer "B.Cu")
		(net "V_VGAHS")
	)
	(segment
		(start 38.6842 -2.0828)
		(end 38.3286 -2.4384)
		(width 0.11684)
		(layer "B.Cu")
		(net "V_VGAHS")
	)
	(segment
		(start 45.2628 -18.7198)
		(end 45.2628 -19.34083)
		(width 0.11684)
		(layer "B.Cu")
		(net "V_VGAHS")
	)
	(segment
		(start 47.436278 -22.234398)
		(end 47.18177 -22.234398)
		(width 0.10668)
		(layer "In4.Cu")
		(net "V_VGAHS")
	)
	(segment
		(start 55.6768 -32.1564)
		(end 53.721 -30.2006)
		(width 0.10668)
		(layer "In4.Cu")
		(net "V_VGAHS")
	)
	(segment
		(start 53.721 -30.2006)
		(end 53.37556 -30.2006)
		(width 0.10668)
		(layer "In4.Cu")
		(net "V_VGAHS")
	)
	(segment
		(start 46.69663 -22.46503)
		(end 45.2628 -21.0312)
		(width 0.10668)
		(layer "In4.Cu")
		(net "V_VGAHS")
	)
	(segment
		(start 53.3908 -28.2448)
		(end 52.8574 -27.7114)
		(width 0.10668)
		(layer "In4.Cu")
		(net "V_VGAHS")
	)
	(segment
		(start 51.029108 -27.7114)
		(end 49.403 -26.085292)
		(width 0.10668)
		(layer "In4.Cu")
		(net "V_VGAHS")
	)
	(segment
		(start 47.385986 -22.899878)
		(end 47.616618 -22.669246)
		(width 0.10668)
		(layer "In4.Cu")
		(net "V_VGAHS")
	)
	(segment
		(start 53.22824 -30.05328)
		(end 53.22824 -29.06776)
		(width 0.10668)
		(layer "In4.Cu")
		(net "V_VGAHS")
	)
	(segment
		(start 49.403 -26.085292)
		(end 49.403 -24.2316)
		(width 0.10668)
		(layer "In4.Cu")
		(net "V_VGAHS")
	)
	(segment
		(start 56.204612 -33.602676)
		(end 55.6768 -33.074864)
		(width 0.10668)
		(layer "In4.Cu")
		(net "V_VGAHS")
	)
	(segment
		(start 47.752 -23.5204)
		(end 47.385986 -23.154386)
		(width 0.10668)
		(layer "In4.Cu")
		(net "V_VGAHS")
	)
	(segment
		(start 53.22824 -29.06776)
		(end 53.3908 -28.9052)
		(width 0.10668)
		(layer "In4.Cu")
		(net "V_VGAHS")
	)
	(segment
		(start 49.403 -24.2316)
		(end 48.6918 -23.5204)
		(width 0.10668)
		(layer "In4.Cu")
		(net "V_VGAHS")
	)
	(segment
		(start 47.18177 -22.234398)
		(end 46.951138 -22.46503)
		(width 0.10668)
		(layer "In4.Cu")
		(net "V_VGAHS")
	)
	(segment
		(start 45.2628 -21.0312)
		(end 45.2628 -19.34083)
		(width 0.10668)
		(layer "In4.Cu")
		(net "V_VGAHS")
	)
	(segment
		(start 47.616618 -22.414738)
		(end 47.436278 -22.234398)
		(width 0.10668)
		(layer "In4.Cu")
		(net "V_VGAHS")
	)
	(segment
		(start 46.951138 -22.46503)
		(end 46.69663 -22.46503)
		(width 0.10668)
		(layer "In4.Cu")
		(net "V_VGAHS")
	)
	(segment
		(start 55.6768 -33.074864)
		(end 55.6768 -32.1564)
		(width 0.10668)
		(layer "In4.Cu")
		(net "V_VGAHS")
	)
	(segment
		(start 53.3908 -28.9052)
		(end 53.3908 -28.2448)
		(width 0.10668)
		(layer "In4.Cu")
		(net "V_VGAHS")
	)
	(segment
		(start 47.616618 -22.669246)
		(end 47.616618 -22.414738)
		(width 0.10668)
		(layer "In4.Cu")
		(net "V_VGAHS")
	)
	(segment
		(start 53.37556 -30.2006)
		(end 53.22824 -30.05328)
		(width 0.10668)
		(layer "In4.Cu")
		(net "V_VGAHS")
	)
	(segment
		(start 52.8574 -27.7114)
		(end 51.029108 -27.7114)
		(width 0.10668)
		(layer "In4.Cu")
		(net "V_VGAHS")
	)
	(segment
		(start 47.385986 -23.154386)
		(end 47.385986 -22.899878)
		(width 0.10668)
		(layer "In4.Cu")
		(net "V_VGAHS")
	)
	(segment
		(start 48.6918 -23.5204)
		(end 47.752 -23.5204)
		(width 0.10668)
		(layer "In4.Cu")
		(net "V_VGAHS")
	)
	(segment
		(start 47.911258 -63.771018)
		(end 47.911258 -63.19647)
		(width 0.11684)
		(layer "F.Cu")
		(net "V_DACR_R")
	)
	(segment
		(start 46.5709 -65.425066)
		(end 46.586394 -65.409572)
		(width 0.11684)
		(layer "F.Cu")
		(net "V_DACR_R")
	)
	(segment
		(start 47.911258 -63.19647)
		(end 47.738284 -63.023496)
		(width 0.11684)
		(layer "F.Cu")
		(net "V_DACR_R")
	)
	(segment
		(start 46.631352 -64.239394)
		(end 47.444152 -64.239394)
		(width 0.11684)
		(layer "F.Cu")
		(net "V_DACR_R")
	)
	(segment
		(start 47.595282 -64.086994)
		(end 47.911258 -63.771018)
		(width 0.11684)
		(layer "F.Cu")
		(net "V_DACR_R")
	)
	(segment
		(start 49.147222 -60.758578)
		(end 49.147222 -59.623452)
		(width 0.11684)
		(layer "F.Cu")
		(net "V_DACR_R")
	)
	(segment
		(start 49.147222 -59.623452)
		(end 48.895 -59.37123)
		(width 0.11684)
		(layer "F.Cu")
		(net "V_DACR_R")
	)
	(segment
		(start 47.738284 -62.167516)
		(end 49.147222 -60.758578)
		(width 0.11684)
		(layer "F.Cu")
		(net "V_DACR_R")
	)
	(segment
		(start 47.738284 -63.023496)
		(end 47.738284 -62.167516)
		(width 0.11684)
		(layer "F.Cu")
		(net "V_DACR_R")
	)
	(segment
		(start 47.594266 -64.08928)
		(end 47.595282 -64.086994)
		(width 0.11684)
		(layer "F.Cu")
		(net "V_DACR_R")
	)
	(segment
		(start 47.444152 -64.239394)
		(end 47.594266 -64.08928)
		(width 0.11684)
		(layer "F.Cu")
		(net "V_DACR_R")
	)
	(segment
		(start 46.586394 -65.409572)
		(end 46.586394 -64.896746)
		(width 0.11684)
		(layer "F.Cu")
		(net "V_DACR_R")
	)
	(segment
		(start 46.586902 -64.334644)
		(end 46.586902 -64.283844)
		(width 0.11684)
		(layer "F.Cu")
		(net "V_DACR_R")
	)
	(segment
		(start 46.586902 -64.896238)
		(end 46.586902 -64.334644)
		(width 0.11684)
		(layer "F.Cu")
		(net "V_DACR_R")
	)
	(segment
		(start 46.5709 -65.83807)
		(end 46.5709 -65.425066)
		(width 0.11684)
		(layer "F.Cu")
		(net "V_DACR_R")
	)
	(segment
		(start 46.586902 -64.283844)
		(end 46.631352 -64.239394)
		(width 0.11684)
		(layer "F.Cu")
		(net "V_DACR_R")
	)
	(segment
		(start 46.586394 -64.896746)
		(end 46.586902 -64.896238)
		(width 0.11684)
		(layer "F.Cu")
		(net "V_DACR_R")
	)
	(segment
		(start 32.142684 -31.619952)
		(end 32.37357 -31.619952)
		(width 0.11684)
		(layer "F.Cu")
		(net "V_DACR_IO")
	)
	(segment
		(start 31.097728 -31.614872)
		(end 31.362396 -31.614872)
		(width 0.11684)
		(layer "F.Cu")
		(net "V_DACR_IO")
	)
	(segment
		(start 32.37357 -31.619952)
		(end 32.562038 -31.80842)
		(width 0.11684)
		(layer "F.Cu")
		(net "V_DACR_IO")
	)
	(segment
		(start 33.136586 -31.80842)
		(end 33.325054 -31.619952)
		(width 0.11684)
		(layer "F.Cu")
		(net "V_DACR_IO")
	)
	(segment
		(start 32.137604 -31.614872)
		(end 31.362396 -31.614872)
		(width 0.11684)
		(layer "F.Cu")
		(net "V_DACR_IO")
	)
	(segment
		(start 31.34995 -33.274)
		(end 30.37078 -33.274)
		(width 0.11684)
		(layer "F.Cu")
		(net "V_DACR_IO")
	)
	(segment
		(start 30.22346 -33.42132)
		(end 30.22346 -32.86506)
		(width 0.11684)
		(layer "F.Cu")
		(net "V_DACR_IO")
	)
	(segment
		(start 29.9974 -32.639)
		(end 30.0736 -32.639)
		(width 0.11684)
		(layer "F.Cu")
		(net "V_DACR_IO")
	)
	(segment
		(start 32.137604 -31.614872)
		(end 32.142684 -31.619952)
		(width 0.11684)
		(layer "F.Cu")
		(net "V_DACR_IO")
	)
	(segment
		(start 30.0736 -32.639)
		(end 31.097728 -31.614872)
		(width 0.11684)
		(layer "F.Cu")
		(net "V_DACR_IO")
	)
	(segment
		(start 32.562038 -31.80842)
		(end 33.136586 -31.80842)
		(width 0.11684)
		(layer "F.Cu")
		(net "V_DACR_IO")
	)
	(segment
		(start 30.22346 -32.86506)
		(end 29.9974 -32.639)
		(width 0.11684)
		(layer "F.Cu")
		(net "V_DACR_IO")
	)
	(segment
		(start 30.37078 -33.274)
		(end 30.22346 -33.42132)
		(width 0.11684)
		(layer "F.Cu")
		(net "V_DACR_IO")
	)
	(segment
		(start 33.325054 -31.619952)
		(end 34.625026 -31.619952)
		(width 0.11684)
		(layer "F.Cu")
		(net "V_DACR_IO")
	)
	(via
		(at 30.22346 -32.648144)
		(size 0.6604)
		(drill 0.3302)
		(layers "F.Cu" "B.Cu")
		(net "V_DACR_IO")
	)
	(via
		(at 30.22346 -33.42132)
		(size 0.508)
		(drill 0.254)
		(layers "F.Cu" "B.Cu")
		(net "V_DACR_IO")
	)
	(segment
		(start 31.369 -32.53105)
		(end 30.340554 -32.53105)
		(width 0.11684)
		(layer "B.Cu")
		(net "V_DACR_IO")
	)
	(segment
		(start 30.340554 -32.53105)
		(end 30.22346 -32.648144)
		(width 0.11684)
		(layer "B.Cu")
		(net "V_DACR_IO")
	)
	(segment
		(start 30.22346 -32.648144)
		(end 30.22346 -33.42132)
		(width 0.11684)
		(layer "B.Cu")
		(net "V_DACR_IO")
	)
	(segment
		(start 46.7868 -67.2846)
		(end 46.7868 -66.85407)
		(width 0.11684)
		(layer "F.Cu")
		(net "V_DACR")
	)
	(segment
		(start 46.7868 -66.85407)
		(end 46.5709 -66.63817)
		(width 0.11684)
		(layer "F.Cu")
		(net "V_DACR")
	)
	(segment
		(start 28.5242 -32.639)
		(end 27.7368 -32.639)
		(width 0.11684)
		(layer "F.Cu")
		(net "V_DACR")
	)
	(via
		(at 27.7368 -32.639)
		(size 0.508)
		(drill 0.254)
		(layers "F.Cu" "B.Cu")
		(net "V_DACR")
	)
	(via
		(at 28.3464 -66.73342)
		(size 0.508)
		(drill 0.254)
		(layers "F.Cu" "B.Cu")
		(net "V_DACR")
	)
	(via
		(at 46.7868 -67.2846)
		(size 0.508)
		(drill 0.254)
		(layers "F.Cu" "B.Cu")
		(net "V_DACR")
	)
	(segment
		(start 28.42895 -32.639)
		(end 28.575 -32.78505)
		(width 0.11684)
		(layer "B.Cu")
		(net "V_DACR")
	)
	(segment
		(start 27.7368 -32.639)
		(end 28.42895 -32.639)
		(width 0.11684)
		(layer "B.Cu")
		(net "V_DACR")
	)
	(segment
		(start 45.614844 -64.21628)
		(end 46.21022 -64.21628)
		(width 0.08382)
		(layer "In2.Cu")
		(net "V_DACR")
	)
	(segment
		(start 29.11729 -66.4718)
		(end 29.464 -66.12509)
		(width 0.08382)
		(layer "In2.Cu")
		(net "V_DACR")
	)
	(segment
		(start 34.840164 -64.98209)
		(end 35.179254 -64.643)
		(width 0.08382)
		(layer "In2.Cu")
		(net "V_DACR")
	)
	(segment
		(start 46.21022 -64.21628)
		(end 46.789848 -64.795908)
		(width 0.08382)
		(layer "In2.Cu")
		(net "V_DACR")
	)
	(segment
		(start 31.928054 -66.4464)
		(end 33.3756 -66.4464)
		(width 0.08382)
		(layer "In2.Cu")
		(net "V_DACR")
	)
	(segment
		(start 29.464 -66.12509)
		(end 31.606744 -66.12509)
		(width 0.08382)
		(layer "In2.Cu")
		(net "V_DACR")
	)
	(segment
		(start 47.7139 -66.311272)
		(end 47.7139 -66.567812)
		(width 0.08382)
		(layer "In2.Cu")
		(net "V_DACR")
	)
	(segment
		(start 44.67987 -65.151254)
		(end 45.614844 -64.21628)
		(width 0.08382)
		(layer "In2.Cu")
		(net "V_DACR")
	)
	(segment
		(start 42.043096 -64.262)
		(end 42.93235 -65.151254)
		(width 0.08382)
		(layer "In2.Cu")
		(net "V_DACR")
	)
	(segment
		(start 47.018448 -65.96126)
		(end 47.20082 -66.143632)
		(width 0.08382)
		(layer "In2.Cu")
		(net "V_DACR")
	)
	(segment
		(start 47.54626 -66.143632)
		(end 47.7139 -66.311272)
		(width 0.08382)
		(layer "In2.Cu")
		(net "V_DACR")
	)
	(segment
		(start 39.315644 -64.262)
		(end 42.043096 -64.262)
		(width 0.08382)
		(layer "In2.Cu")
		(net "V_DACR")
	)
	(segment
		(start 46.9138 -67.1576)
		(end 46.7868 -67.2846)
		(width 0.08382)
		(layer "In2.Cu")
		(net "V_DACR")
	)
	(segment
		(start 47.7139 -66.567812)
		(end 47.54626 -66.735452)
		(width 0.08382)
		(layer "In2.Cu")
		(net "V_DACR")
	)
	(segment
		(start 47.54626 -66.735452)
		(end 47.08144 -66.735452)
		(width 0.08382)
		(layer "In2.Cu")
		(net "V_DACR")
	)
	(segment
		(start 33.3756 -66.4464)
		(end 34.83991 -64.98209)
		(width 0.08382)
		(layer "In2.Cu")
		(net "V_DACR")
	)
	(segment
		(start 47.20082 -66.143632)
		(end 47.54626 -66.143632)
		(width 0.08382)
		(layer "In2.Cu")
		(net "V_DACR")
	)
	(segment
		(start 47.018448 -65.348358)
		(end 47.018448 -65.96126)
		(width 0.08382)
		(layer "In2.Cu")
		(net "V_DACR")
	)
	(segment
		(start 31.606744 -66.12509)
		(end 31.928054 -66.4464)
		(width 0.08382)
		(layer "In2.Cu")
		(net "V_DACR")
	)
	(segment
		(start 28.60802 -66.4718)
		(end 29.11729 -66.4718)
		(width 0.08382)
		(layer "In2.Cu")
		(net "V_DACR")
	)
	(segment
		(start 42.93235 -65.151254)
		(end 44.67987 -65.151254)
		(width 0.08382)
		(layer "In2.Cu")
		(net "V_DACR")
	)
	(segment
		(start 46.9138 -66.903092)
		(end 46.9138 -67.1576)
		(width 0.08382)
		(layer "In2.Cu")
		(net "V_DACR")
	)
	(segment
		(start 47.08144 -66.735452)
		(end 46.9138 -66.903092)
		(width 0.08382)
		(layer "In2.Cu")
		(net "V_DACR")
	)
	(segment
		(start 38.395402 -64.643)
		(end 39.315644 -64.262)
		(width 0.08382)
		(layer "In2.Cu")
		(net "V_DACR")
	)
	(segment
		(start 28.3464 -66.73342)
		(end 28.60802 -66.4718)
		(width 0.08382)
		(layer "In2.Cu")
		(net "V_DACR")
	)
	(segment
		(start 35.179254 -64.643)
		(end 38.395402 -64.643)
		(width 0.08382)
		(layer "In2.Cu")
		(net "V_DACR")
	)
	(segment
		(start 34.83991 -64.98209)
		(end 34.840164 -64.98209)
		(width 0.08382)
		(layer "In2.Cu")
		(net "V_DACR")
	)
	(segment
		(start 46.789848 -64.795908)
		(end 47.018448 -65.348358)
		(width 0.08382)
		(layer "In2.Cu")
		(net "V_DACR")
	)
	(segment
		(start 22.914102 -52.138834)
		(end 22.914102 -46.00956)
		(width 0.08382)
		(layer "In9.Cu")
		(net "V_DACR")
	)
	(segment
		(start 27.956764 -60.153296)
		(end 27.956764 -59.427364)
		(width 0.08382)
		(layer "In9.Cu")
		(net "V_DACR")
	)
	(segment
		(start 22.914102 -46.00956)
		(end 22.999192 -45.581824)
		(width 0.08382)
		(layer "In9.Cu")
		(net "V_DACR")
	)
	(segment
		(start 27.7622 -34.018982)
		(end 27.7622 -32.6644)
		(width 0.08382)
		(layer "In9.Cu")
		(net "V_DACR")
	)
	(segment
		(start 27.051 -35.498532)
		(end 27.051 -34.730182)
		(width 0.08382)
		(layer "In9.Cu")
		(net "V_DACR")
	)
	(segment
		(start 22.999192 -45.581824)
		(end 23.43912 -44.519596)
		(width 0.08382)
		(layer "In9.Cu")
		(net "V_DACR")
	)
	(segment
		(start 28.76042 -65.20942)
		(end 28.76042 -64.355726)
		(width 0.08382)
		(layer "In9.Cu")
		(net "V_DACR")
	)
	(segment
		(start 22.38629 -52.666646)
		(end 22.914102 -52.138834)
		(width 0.08382)
		(layer "In9.Cu")
		(net "V_DACR")
	)
	(segment
		(start 27.49169 -40.467026)
		(end 27.49169 -35.939222)
		(width 0.08382)
		(layer "In9.Cu")
		(net "V_DACR")
	)
	(segment
		(start 28.3464 -65.62344)
		(end 28.76042 -65.20942)
		(width 0.08382)
		(layer "In9.Cu")
		(net "V_DACR")
	)
	(segment
		(start 28.76042 -64.355726)
		(end 28.15844 -63.753746)
		(width 0.08382)
		(layer "In9.Cu")
		(net "V_DACR")
	)
	(segment
		(start 27.49169 -35.939222)
		(end 27.051 -35.498532)
		(width 0.08382)
		(layer "In9.Cu")
		(net "V_DACR")
	)
	(segment
		(start 26.92908 -58.39968)
		(end 23.55088 -58.39968)
		(width 0.08382)
		(layer "In9.Cu")
		(net "V_DACR")
	)
	(segment
		(start 28.3464 -66.73342)
		(end 28.3464 -65.62344)
		(width 0.08382)
		(layer "In9.Cu")
		(net "V_DACR")
	)
	(segment
		(start 27.051 -34.730182)
		(end 27.7622 -34.018982)
		(width 0.08382)
		(layer "In9.Cu")
		(net "V_DACR")
	)
	(segment
		(start 27.956764 -59.427364)
		(end 26.92908 -58.39968)
		(width 0.08382)
		(layer "In9.Cu")
		(net "V_DACR")
	)
	(segment
		(start 23.43912 -44.519596)
		(end 27.49169 -40.467026)
		(width 0.08382)
		(layer "In9.Cu")
		(net "V_DACR")
	)
	(segment
		(start 22.38629 -57.23509)
		(end 22.38629 -52.666646)
		(width 0.08382)
		(layer "In9.Cu")
		(net "V_DACR")
	)
	(segment
		(start 23.55088 -58.39968)
		(end 22.38629 -57.23509)
		(width 0.08382)
		(layer "In9.Cu")
		(net "V_DACR")
	)
	(segment
		(start 28.15844 -60.354972)
		(end 27.956764 -60.153296)
		(width 0.08382)
		(layer "In9.Cu")
		(net "V_DACR")
	)
	(segment
		(start 27.7622 -32.6644)
		(end 27.7368 -32.639)
		(width 0.08382)
		(layer "In9.Cu")
		(net "V_DACR")
	)
	(segment
		(start 28.15844 -63.753746)
		(end 28.15844 -60.354972)
		(width 0.08382)
		(layer "In9.Cu")
		(net "V_DACR")
	)
	(segment
		(start 45.946314 -63.019686)
		(end 45.946314 -63.585344)
		(width 0.11684)
		(layer "F.Cu")
		(net "V_DACG_R")
	)
	(segment
		(start 48.2092 -59.813444)
		(end 48.2092 -60.7568)
		(width 0.11684)
		(layer "F.Cu")
		(net "V_DACG_R")
	)
	(segment
		(start 45.374814 -64.156844)
		(end 45.062902 -64.156844)
		(width 0.11684)
		(layer "F.Cu")
		(net "V_DACG_R")
	)
	(segment
		(start 45.062902 -65.32499)
		(end 45.256196 -65.518284)
		(width 0.11684)
		(layer "F.Cu")
		(net "V_DACG_R")
	)
	(segment
		(start 48.503586 -58.962544)
		(end 48.503586 -59.519058)
		(width 0.11684)
		(layer "F.Cu")
		(net "V_DACG_R")
	)
	(segment
		(start 45.062902 -64.156844)
		(end 45.062902 -65.32499)
		(width 0.11684)
		(layer "F.Cu")
		(net "V_DACG_R")
	)
	(segment
		(start 48.503586 -59.519058)
		(end 48.2092 -59.813444)
		(width 0.11684)
		(layer "F.Cu")
		(net "V_DACG_R")
	)
	(segment
		(start 46.609 -62.357)
		(end 45.946314 -63.019686)
		(width 0.11684)
		(layer "F.Cu")
		(net "V_DACG_R")
	)
	(segment
		(start 48.2092 -60.7568)
		(end 46.609 -62.357)
		(width 0.11684)
		(layer "F.Cu")
		(net "V_DACG_R")
	)
	(segment
		(start 45.946314 -63.585344)
		(end 45.374814 -64.156844)
		(width 0.11684)
		(layer "F.Cu")
		(net "V_DACG_R")
	)
	(segment
		(start 48.895 -58.57113)
		(end 48.503586 -58.962544)
		(width 0.11684)
		(layer "F.Cu")
		(net "V_DACG_R")
	)
	(via
		(at 46.609 -62.357)
		(size 0.762)
		(drill 0.381)
		(layers "F.Cu" "B.Cu")
		(net "V_DACG_R")
	)
	(segment
		(start 32.36849 -30.615128)
		(end 32.562038 -30.42158)
		(width 0.11684)
		(layer "F.Cu")
		(net "V_DACG_IO")
	)
	(segment
		(start 29.9974 -30.099)
		(end 30.0736 -30.099)
		(width 0.11684)
		(layer "F.Cu")
		(net "V_DACG_IO")
	)
	(segment
		(start 30.589728 -30.615128)
		(end 31.362396 -30.615128)
		(width 0.11684)
		(layer "F.Cu")
		(net "V_DACG_IO")
	)
	(segment
		(start 30.0736 -30.099)
		(end 30.589728 -30.615128)
		(width 0.11684)
		(layer "F.Cu")
		(net "V_DACG_IO")
	)
	(segment
		(start 33.18002 -30.42158)
		(end 33.4772 -30.1244)
		(width 0.11684)
		(layer "F.Cu")
		(net "V_DACG_IO")
	)
	(segment
		(start 32.562038 -30.42158)
		(end 33.18002 -30.42158)
		(width 0.11684)
		(layer "F.Cu")
		(net "V_DACG_IO")
	)
	(segment
		(start 29.9974 -29.591)
		(end 30.24505 -29.34335)
		(width 0.11684)
		(layer "F.Cu")
		(net "V_DACG_IO")
	)
	(segment
		(start 33.4772 -29.845)
		(end 33.702244 -29.619956)
		(width 0.11684)
		(layer "F.Cu")
		(net "V_DACG_IO")
	)
	(segment
		(start 32.137604 -30.615128)
		(end 31.362396 -30.615128)
		(width 0.11684)
		(layer "F.Cu")
		(net "V_DACG_IO")
	)
	(segment
		(start 33.4772 -30.1244)
		(end 33.4772 -29.845)
		(width 0.11684)
		(layer "F.Cu")
		(net "V_DACG_IO")
	)
	(segment
		(start 29.86405 -30.23235)
		(end 29.86405 -31.369)
		(width 0.11684)
		(layer "F.Cu")
		(net "V_DACG_IO")
	)
	(segment
		(start 29.9974 -30.099)
		(end 29.86405 -30.23235)
		(width 0.11684)
		(layer "F.Cu")
		(net "V_DACG_IO")
	)
	(segment
		(start 33.702244 -29.619956)
		(end 34.625026 -29.619956)
		(width 0.11684)
		(layer "F.Cu")
		(net "V_DACG_IO")
	)
	(segment
		(start 32.137604 -30.615128)
		(end 32.36849 -30.615128)
		(width 0.11684)
		(layer "F.Cu")
		(net "V_DACG_IO")
	)
	(segment
		(start 30.24505 -29.34335)
		(end 30.607 -29.34335)
		(width 0.11684)
		(layer "F.Cu")
		(net "V_DACG_IO")
	)
	(segment
		(start 29.9974 -30.099)
		(end 29.9974 -29.591)
		(width 0.11684)
		(layer "F.Cu")
		(net "V_DACG_IO")
	)
	(via
		(at 30.607 -29.34335)
		(size 0.508)
		(drill 0.254)
		(layers "F.Cu" "B.Cu")
		(net "V_DACG_IO")
	)
	(segment
		(start 31.2674 -29.34335)
		(end 30.607 -29.34335)
		(width 0.11684)
		(layer "B.Cu")
		(net "V_DACG_IO")
	)
	(segment
		(start 31.877 -29.95295)
		(end 31.2674 -29.34335)
		(width 0.11684)
		(layer "B.Cu")
		(net "V_DACG_IO")
	)
	(segment
		(start 45.837348 -66.20383)
		(end 45.837348 -65.742566)
		(width 0.11684)
		(layer "F.Cu")
		(net "V_DACG")
	)
	(segment
		(start 28.5242 -30.099)
		(end 27.7368 -30.099)
		(width 0.11684)
		(layer "F.Cu")
		(net "V_DACG")
	)
	(segment
		(start 45.722794 -66.318384)
		(end 45.837348 -66.20383)
		(width 0.11684)
		(layer "F.Cu")
		(net "V_DACG")
	)
	(segment
		(start 45.256196 -66.318384)
		(end 45.722794 -66.318384)
		(width 0.11684)
		(layer "F.Cu")
		(net "V_DACG")
	)
	(segment
		(start 45.837348 -65.742566)
		(end 45.836332 -65.74155)
		(width 0.11684)
		(layer "F.Cu")
		(net "V_DACG")
	)
	(via
		(at 45.836332 -65.74155)
		(size 0.508)
		(drill 0.254)
		(layers "F.Cu" "B.Cu")
		(net "V_DACG")
	)
	(via
		(at 27.7368 -30.099)
		(size 0.508)
		(drill 0.254)
		(layers "F.Cu" "B.Cu")
		(net "V_DACG")
	)
	(via
		(at 27.8892 -67.291712)
		(size 0.508)
		(drill 0.254)
		(layers "F.Cu" "B.Cu")
		(net "V_DACG")
	)
	(segment
		(start 28.30195 -29.95295)
		(end 27.88285 -29.95295)
		(width 0.11684)
		(layer "B.Cu")
		(net "V_DACG")
	)
	(segment
		(start 27.88285 -29.95295)
		(end 27.7368 -30.099)
		(width 0.11684)
		(layer "B.Cu")
		(net "V_DACG")
	)
	(segment
		(start 28.3083 -29.9593)
		(end 28.30195 -29.95295)
		(width 0.11684)
		(layer "B.Cu")
		(net "V_DACG")
	)
	(segment
		(start 28.3464 -29.9593)
		(end 28.3083 -29.9593)
		(width 0.11684)
		(layer "B.Cu")
		(net "V_DACG")
	)
	(segment
		(start 37.676328 -65.23482)
		(end 37.932868 -65.23482)
		(width 0.08382)
		(layer "In2.Cu")
		(net "V_DACG")
	)
	(segment
		(start 38.100508 -65.40246)
		(end 38.100508 -65.72758)
		(width 0.08382)
		(layer "In2.Cu")
		(net "V_DACG")
	)
	(segment
		(start 38.749986 -65.89522)
		(end 39.426896 -65.21831)
		(width 0.08382)
		(layer "In2.Cu")
		(net "V_DACG")
	)
	(segment
		(start 38.100508 -65.72758)
		(end 38.268148 -65.89522)
		(width 0.08382)
		(layer "In2.Cu")
		(net "V_DACG")
	)
	(segment
		(start 45.834808 -65.743074)
		(end 45.836332 -65.74155)
		(width 0.08382)
		(layer "In2.Cu")
		(net "V_DACG")
	)
	(segment
		(start 27.8892 -67.291712)
		(end 29.134562 -67.291712)
		(width 0.08382)
		(layer "In2.Cu")
		(net "V_DACG")
	)
	(segment
		(start 37.341048 -65.89522)
		(end 37.508688 -65.72758)
		(width 0.08382)
		(layer "In2.Cu")
		(net "V_DACG")
	)
	(segment
		(start 29.134562 -67.291712)
		(end 29.709364 -66.71691)
		(width 0.08382)
		(layer "In2.Cu")
		(net "V_DACG")
	)
	(segment
		(start 37.508688 -65.40246)
		(end 37.676328 -65.23482)
		(width 0.08382)
		(layer "In2.Cu")
		(net "V_DACG")
	)
	(segment
		(start 40.555164 -65.21831)
		(end 41.079928 -65.743074)
		(width 0.08382)
		(layer "In2.Cu")
		(net "V_DACG")
	)
	(segment
		(start 31.284164 -66.71691)
		(end 31.605474 -67.03822)
		(width 0.08382)
		(layer "In2.Cu")
		(net "V_DACG")
	)
	(segment
		(start 37.932868 -65.23482)
		(end 38.100508 -65.40246)
		(width 0.08382)
		(layer "In2.Cu")
		(net "V_DACG")
	)
	(segment
		(start 37.508688 -65.72758)
		(end 37.508688 -65.40246)
		(width 0.08382)
		(layer "In2.Cu")
		(net "V_DACG")
	)
	(segment
		(start 38.268148 -65.89522)
		(end 38.749986 -65.89522)
		(width 0.08382)
		(layer "In2.Cu")
		(net "V_DACG")
	)
	(segment
		(start 33.620964 -67.03822)
		(end 34.763964 -65.89522)
		(width 0.08382)
		(layer "In2.Cu")
		(net "V_DACG")
	)
	(segment
		(start 29.709364 -66.71691)
		(end 31.284164 -66.71691)
		(width 0.08382)
		(layer "In2.Cu")
		(net "V_DACG")
	)
	(segment
		(start 34.763964 -65.89522)
		(end 37.341048 -65.89522)
		(width 0.08382)
		(layer "In2.Cu")
		(net "V_DACG")
	)
	(segment
		(start 39.426896 -65.21831)
		(end 40.555164 -65.21831)
		(width 0.08382)
		(layer "In2.Cu")
		(net "V_DACG")
	)
	(segment
		(start 41.079928 -65.743074)
		(end 45.834808 -65.743074)
		(width 0.08382)
		(layer "In2.Cu")
		(net "V_DACG")
	)
	(segment
		(start 31.605474 -67.03822)
		(end 33.620964 -67.03822)
		(width 0.08382)
		(layer "In2.Cu")
		(net "V_DACG")
	)
	(segment
		(start 22.93747 -44.184062)
		(end 26.89987 -40.221662)
		(width 0.08382)
		(layer "In9.Cu")
		(net "V_DACG")
	)
	(segment
		(start 27.17038 -33.773618)
		(end 27.17038 -32.393636)
		(width 0.08382)
		(layer "In9.Cu")
		(net "V_DACG")
	)
	(segment
		(start 26.45918 -35.743896)
		(end 26.45918 -34.484818)
		(width 0.08382)
		(layer "In9.Cu")
		(net "V_DACG")
	)
	(segment
		(start 27.7368 -31.827216)
		(end 27.7368 -30.099)
		(width 0.08382)
		(layer "In9.Cu")
		(net "V_DACG")
	)
	(segment
		(start 21.82876 -51.268884)
		(end 21.82876 -51.012344)
		(width 0.08382)
		(layer "In9.Cu")
		(net "V_DACG")
	)
	(segment
		(start 22.154642 -51.436524)
		(end 21.9964 -51.436524)
		(width 0.08382)
		(layer "In9.Cu")
		(net "V_DACG")
	)
	(segment
		(start 21.79447 -52.421282)
		(end 22.322282 -51.89347)
		(width 0.08382)
		(layer "In9.Cu")
		(net "V_DACG")
	)
	(segment
		(start 26.45918 -34.484818)
		(end 27.17038 -33.773618)
		(width 0.08382)
		(layer "In9.Cu")
		(net "V_DACG")
	)
	(segment
		(start 26.89987 -36.184586)
		(end 26.45918 -35.743896)
		(width 0.08382)
		(layer "In9.Cu")
		(net "V_DACG")
	)
	(segment
		(start 27.8892 -67.291712)
		(end 27.750008 -67.15252)
		(width 0.08382)
		(layer "In9.Cu")
		(net "V_DACG")
	)
	(segment
		(start 27.17038 -32.393636)
		(end 27.7368 -31.827216)
		(width 0.08382)
		(layer "In9.Cu")
		(net "V_DACG")
	)
	(segment
		(start 27.750008 -67.15252)
		(end 27.750008 -66.365374)
		(width 0.08382)
		(layer "In9.Cu")
		(net "V_DACG")
	)
	(segment
		(start 22.322282 -51.89347)
		(end 22.322282 -51.604164)
		(width 0.08382)
		(layer "In9.Cu")
		(net "V_DACG")
	)
	(segment
		(start 27.750008 -66.365374)
		(end 27.56662 -66.181986)
		(width 0.08382)
		(layer "In9.Cu")
		(net "V_DACG")
	)
	(segment
		(start 27.56662 -60.600336)
		(end 27.364944 -60.39866)
		(width 0.08382)
		(layer "In9.Cu")
		(net "V_DACG")
	)
	(segment
		(start 21.79447 -57.480454)
		(end 21.79447 -52.421282)
		(width 0.08382)
		(layer "In9.Cu")
		(net "V_DACG")
	)
	(segment
		(start 27.364944 -60.39866)
		(end 27.364944 -59.70016)
		(width 0.08382)
		(layer "In9.Cu")
		(net "V_DACG")
	)
	(segment
		(start 21.9964 -51.436524)
		(end 21.82876 -51.268884)
		(width 0.08382)
		(layer "In9.Cu")
		(net "V_DACG")
	)
	(segment
		(start 27.56662 -66.181986)
		(end 27.56662 -60.600336)
		(width 0.08382)
		(layer "In9.Cu")
		(net "V_DACG")
	)
	(segment
		(start 21.82876 -51.012344)
		(end 21.9964 -50.844704)
		(width 0.08382)
		(layer "In9.Cu")
		(net "V_DACG")
	)
	(segment
		(start 26.656284 -58.9915)
		(end 23.305516 -58.9915)
		(width 0.08382)
		(layer "In9.Cu")
		(net "V_DACG")
	)
	(segment
		(start 22.322282 -50.677064)
		(end 22.322282 -45.946314)
		(width 0.08382)
		(layer "In9.Cu")
		(net "V_DACG")
	)
	(segment
		(start 26.89987 -40.221662)
		(end 26.89987 -36.184586)
		(width 0.08382)
		(layer "In9.Cu")
		(net "V_DACG")
	)
	(segment
		(start 27.364944 -59.70016)
		(end 26.656284 -58.9915)
		(width 0.08382)
		(layer "In9.Cu")
		(net "V_DACG")
	)
	(segment
		(start 22.154642 -50.844704)
		(end 22.322282 -50.677064)
		(width 0.08382)
		(layer "In9.Cu")
		(net "V_DACG")
	)
	(segment
		(start 22.4282 -45.413168)
		(end 22.93747 -44.184062)
		(width 0.08382)
		(layer "In9.Cu")
		(net "V_DACG")
	)
	(segment
		(start 21.9964 -50.844704)
		(end 22.154642 -50.844704)
		(width 0.08382)
		(layer "In9.Cu")
		(net "V_DACG")
	)
	(segment
		(start 22.322282 -51.604164)
		(end 22.154642 -51.436524)
		(width 0.08382)
		(layer "In9.Cu")
		(net "V_DACG")
	)
	(segment
		(start 22.322282 -45.946314)
		(end 22.4282 -45.413168)
		(width 0.08382)
		(layer "In9.Cu")
		(net "V_DACG")
	)
	(segment
		(start 23.305516 -58.9915)
		(end 21.79447 -57.480454)
		(width 0.08382)
		(layer "In9.Cu")
		(net "V_DACG")
	)
	(segment
		(start 47.699676 -58.166508)
		(end 48.216566 -58.166508)
		(width 0.11684)
		(layer "F.Cu")
		(net "V_DACB_R")
	)
	(segment
		(start 48.699928 -57.966356)
		(end 48.895 -57.771284)
		(width 0.11684)
		(layer "F.Cu")
		(net "V_DACB_R")
	)
	(segment
		(start 48.216566 -58.166508)
		(end 48.699928 -57.966356)
		(width 0.11684)
		(layer "F.Cu")
		(net "V_DACB_R")
	)
	(via
		(at 47.699676 -58.166508)
		(size 0.4572)
		(drill 0.254)
		(layers "F.Cu" "B.Cu")
		(net "V_DACB_R")
	)
	(segment
		(start 44.0944 -61.60135)
		(end 45.085 -61.60135)
		(width 0.11684)
		(layer "B.Cu")
		(net "V_DACB_R")
	)
	(segment
		(start 47.699676 -58.166508)
		(end 47.310802 -59.105038)
		(width 0.11684)
		(layer "B.Cu")
		(net "V_DACB_R")
	)
	(segment
		(start 46.947328 -59.468512)
		(end 46.010576 -59.856624)
		(width 0.11684)
		(layer "B.Cu")
		(net "V_DACB_R")
	)
	(segment
		(start 47.310802 -59.105038)
		(end 46.947328 -59.468512)
		(width 0.11684)
		(layer "B.Cu")
		(net "V_DACB_R")
	)
	(segment
		(start 45.637704 -60.229496)
		(end 45.085 -61.56325)
		(width 0.11684)
		(layer "B.Cu")
		(net "V_DACB_R")
	)
	(segment
		(start 46.010576 -59.856624)
		(end 45.637704 -60.229496)
		(width 0.11684)
		(layer "B.Cu")
		(net "V_DACB_R")
	)
	(segment
		(start 45.085 -61.56325)
		(end 45.085 -61.60135)
		(width 0.11684)
		(layer "B.Cu")
		(net "V_DACB_R")
	)
	(segment
		(start 31.115 -28.194)
		(end 31.32455 -28.194)
		(width 0.11684)
		(layer "F.Cu")
		(net "V_DACB_IO")
	)
	(segment
		(start 31.0642 -29.6418)
		(end 31.34995 -29.35605)
		(width 0.11684)
		(layer "F.Cu")
		(net "V_DACB_IO")
	)
	(segment
		(start 31.34995 -29.35605)
		(end 31.34995 -28.956)
		(width 0.11684)
		(layer "F.Cu")
		(net "V_DACB_IO")
	)
	(segment
		(start 31.362396 -30.115002)
		(end 31.18104 -30.115002)
		(width 0.11684)
		(layer "F.Cu")
		(net "V_DACB_IO")
	)
	(segment
		(start 30.7848 -28.5242)
		(end 31.115 -28.194)
		(width 0.11684)
		(layer "F.Cu")
		(net "V_DACB_IO")
	)
	(segment
		(start 29.9974 -28.5242)
		(end 30.7848 -28.5242)
		(width 0.11684)
		(layer "F.Cu")
		(net "V_DACB_IO")
	)
	(segment
		(start 31.362396 -30.115002)
		(end 32.137604 -30.115002)
		(width 0.11684)
		(layer "F.Cu")
		(net "V_DACB_IO")
	)
	(segment
		(start 32.606996 -29.115004)
		(end 32.606996 -29.775404)
		(width 0.11684)
		(layer "F.Cu")
		(net "V_DACB_IO")
	)
	(segment
		(start 34.625026 -27.61996)
		(end 34.10204 -27.61996)
		(width 0.11684)
		(layer "F.Cu")
		(net "V_DACB_IO")
	)
	(segment
		(start 32.267398 -30.115002)
		(end 32.137604 -30.115002)
		(width 0.11684)
		(layer "F.Cu")
		(net "V_DACB_IO")
	)
	(segment
		(start 31.0642 -29.998162)
		(end 31.0642 -29.6418)
		(width 0.11684)
		(layer "F.Cu")
		(net "V_DACB_IO")
	)
	(segment
		(start 31.32455 -28.194)
		(end 31.32455 -28.9306)
		(width 0.11684)
		(layer "F.Cu")
		(net "V_DACB_IO")
	)
	(segment
		(start 32.606996 -29.775404)
		(end 32.267398 -30.115002)
		(width 0.11684)
		(layer "F.Cu")
		(net "V_DACB_IO")
	)
	(segment
		(start 31.18104 -30.115002)
		(end 31.0642 -29.998162)
		(width 0.11684)
		(layer "F.Cu")
		(net "V_DACB_IO")
	)
	(segment
		(start 31.32455 -28.9306)
		(end 31.34995 -28.956)
		(width 0.11684)
		(layer "F.Cu")
		(net "V_DACB_IO")
	)
	(segment
		(start 34.10204 -27.61996)
		(end 32.606996 -29.115004)
		(width 0.11684)
		(layer "F.Cu")
		(net "V_DACB_IO")
	)
	(via
		(at 31.32455 -28.194)
		(size 0.508)
		(drill 0.254)
		(layers "F.Cu" "B.Cu")
		(net "V_DACB_IO")
	)
	(segment
		(start 31.32455 -28.455366)
		(end 31.32455 -28.194)
		(width 0.11684)
		(layer "B.Cu")
		(net "V_DACB_IO")
	)
	(segment
		(start 32.441134 -29.57195)
		(end 31.32455 -28.455366)
		(width 0.11684)
		(layer "B.Cu")
		(net "V_DACB_IO")
	)
	(segment
		(start 32.893 -29.57195)
		(end 32.441134 -29.57195)
		(width 0.11684)
		(layer "B.Cu")
		(net "V_DACB_IO")
	)
	(segment
		(start 27.7749 -28.68168)
		(end 27.7749 -29.337254)
		(width 0.11684)
		(layer "F.Cu")
		(net "V_DACB")
	)
	(segment
		(start 28.5242 -28.5242)
		(end 27.93238 -28.5242)
		(width 0.11684)
		(layer "F.Cu")
		(net "V_DACB")
	)
	(segment
		(start 27.93238 -28.5242)
		(end 27.7749 -28.68168)
		(width 0.11684)
		(layer "F.Cu")
		(net "V_DACB")
	)
	(via
		(at 27.7749 -29.337254)
		(size 0.508)
		(drill 0.254)
		(layers "F.Cu" "B.Cu")
		(net "V_DACB")
	)
	(via
		(at 45.680884 -64.8081)
		(size 0.508)
		(drill 0.254)
		(layers "F.Cu" "B.Cu")
		(net "V_DACB")
	)
	(via
		(at 27.2288 -67.31)
		(size 0.508)
		(drill 0.254)
		(layers "F.Cu" "B.Cu")
		(net "V_DACB")
	)
	(via
		(at 45.657516 -63.5381)
		(size 0.6604)
		(drill 0.3302)
		(layers "F.Cu" "B.Cu")
		(net "V_DACB")
	)
	(segment
		(start 45.085 -62.40145)
		(end 45.484034 -63.364618)
		(width 0.11684)
		(layer "B.Cu")
		(net "V_DACB")
	)
	(segment
		(start 29.31795 -29.95295)
		(end 29.242004 -29.95295)
		(width 0.11684)
		(layer "B.Cu")
		(net "V_DACB")
	)
	(segment
		(start 45.484034 -63.364618)
		(end 45.657516 -63.5381)
		(width 0.11684)
		(layer "B.Cu")
		(net "V_DACB")
	)
	(segment
		(start 29.242004 -29.95295)
		(end 28.499054 -29.21)
		(width 0.11684)
		(layer "B.Cu")
		(net "V_DACB")
	)
	(segment
		(start 29.3243 -29.9593)
		(end 29.31795 -29.95295)
		(width 0.11684)
		(layer "B.Cu")
		(net "V_DACB")
	)
	(segment
		(start 29.3624 -29.9593)
		(end 29.3243 -29.9593)
		(width 0.11684)
		(layer "B.Cu")
		(net "V_DACB")
	)
	(segment
		(start 27.902154 -29.21)
		(end 27.7749 -29.337254)
		(width 0.11684)
		(layer "B.Cu")
		(net "V_DACB")
	)
	(segment
		(start 45.657516 -63.5381)
		(end 45.657516 -64.784732)
		(width 0.11684)
		(layer "B.Cu")
		(net "V_DACB")
	)
	(segment
		(start 45.657516 -64.784732)
		(end 45.680884 -64.8081)
		(width 0.11684)
		(layer "B.Cu")
		(net "V_DACB")
	)
	(segment
		(start 28.499054 -29.21)
		(end 27.902154 -29.21)
		(width 0.11684)
		(layer "B.Cu")
		(net "V_DACB")
	)
	(segment
		(start 27.2796 -67.331082)
		(end 27.408378 -67.641724)
		(width 0.08382)
		(layer "In2.Cu")
		(net "V_DACB")
	)
	(segment
		(start 46.426628 -65.988438)
		(end 46.426628 -65.584324)
		(width 0.08382)
		(layer "In2.Cu")
		(net "V_DACB")
	)
	(segment
		(start 27.408378 -67.641724)
		(end 28.063444 -68.29679)
		(width 0.08382)
		(layer "In2.Cu")
		(net "V_DACB")
	)
	(segment
		(start 27.2288 -67.31)
		(end 27.2796 -67.331082)
		(width 0.08382)
		(layer "In2.Cu")
		(net "V_DACB")
	)
	(segment
		(start 39.204646 -66.3702)
		(end 46.044866 -66.3702)
		(width 0.08382)
		(layer "In2.Cu")
		(net "V_DACB")
	)
	(segment
		(start 39.087806 -66.48704)
		(end 39.204646 -66.3702)
		(width 0.08382)
		(layer "In2.Cu")
		(net "V_DACB")
	)
	(segment
		(start 46.426628 -65.584324)
		(end 46.278292 -65.226184)
		(width 0.08382)
		(layer "In2.Cu")
		(net "V_DACB")
	)
	(segment
		(start 28.063444 -68.29679)
		(end 33.302956 -68.29679)
		(width 0.08382)
		(layer "In2.Cu")
		(net "V_DACB")
	)
	(segment
		(start 33.302956 -68.29679)
		(end 35.112706 -66.48704)
		(width 0.08382)
		(layer "In2.Cu")
		(net "V_DACB")
	)
	(segment
		(start 46.278292 -65.226184)
		(end 45.860208 -64.8081)
		(width 0.08382)
		(layer "In2.Cu")
		(net "V_DACB")
	)
	(segment
		(start 45.860208 -64.8081)
		(end 45.680884 -64.8081)
		(width 0.08382)
		(layer "In2.Cu")
		(net "V_DACB")
	)
	(segment
		(start 46.044866 -66.3702)
		(end 46.426628 -65.988438)
		(width 0.08382)
		(layer "In2.Cu")
		(net "V_DACB")
	)
	(segment
		(start 35.112706 -66.48704)
		(end 39.087806 -66.48704)
		(width 0.08382)
		(layer "In2.Cu")
		(net "V_DACB")
	)
	(segment
		(start 26.76652 -59.93892)
		(end 26.41092 -59.58332)
		(width 0.08382)
		(layer "In9.Cu")
		(net "V_DACB")
	)
	(segment
		(start 23.060152 -59.58332)
		(end 21.20265 -57.725818)
		(width 0.08382)
		(layer "In9.Cu")
		(net "V_DACB")
	)
	(segment
		(start 26.9748 -62.5602)
		(end 26.9748 -60.8457)
		(width 0.08382)
		(layer "In9.Cu")
		(net "V_DACB")
	)
	(segment
		(start 26.60269 -62.93231)
		(end 26.9748 -62.5602)
		(width 0.08382)
		(layer "In9.Cu")
		(net "V_DACB")
	)
	(segment
		(start 26.60269 -66.816478)
		(end 26.60269 -62.93231)
		(width 0.08382)
		(layer "In9.Cu")
		(net "V_DACB")
	)
	(segment
		(start 26.30805 -39.976298)
		(end 26.30805 -36.42995)
		(width 0.08382)
		(layer "In9.Cu")
		(net "V_DACB")
	)
	(segment
		(start 26.9748 -60.8457)
		(end 26.76652 -60.63742)
		(width 0.08382)
		(layer "In9.Cu")
		(net "V_DACB")
	)
	(segment
		(start 26.57856 -32.148272)
		(end 27.14498 -31.581852)
		(width 0.08382)
		(layer "In9.Cu")
		(net "V_DACB")
	)
	(segment
		(start 27.2288 -67.31)
		(end 27.096212 -67.31)
		(width 0.08382)
		(layer "In9.Cu")
		(net "V_DACB")
	)
	(segment
		(start 21.730462 -45.887894)
		(end 21.858986 -45.240448)
		(width 0.08382)
		(layer "In9.Cu")
		(net "V_DACB")
	)
	(segment
		(start 26.41092 -59.58332)
		(end 23.060152 -59.58332)
		(width 0.08382)
		(layer "In9.Cu")
		(net "V_DACB")
	)
	(segment
		(start 21.858986 -45.240448)
		(end 22.435566 -43.848782)
		(width 0.08382)
		(layer "In9.Cu")
		(net "V_DACB")
	)
	(segment
		(start 27.661362 -29.337254)
		(end 27.7749 -29.337254)
		(width 0.08382)
		(layer "In9.Cu")
		(net "V_DACB")
	)
	(segment
		(start 27.14498 -31.581852)
		(end 27.14498 -29.853636)
		(width 0.08382)
		(layer "In9.Cu")
		(net "V_DACB")
	)
	(segment
		(start 21.20265 -57.725818)
		(end 21.20265 -50.66411)
		(width 0.08382)
		(layer "In9.Cu")
		(net "V_DACB")
	)
	(segment
		(start 25.70861 -35.83051)
		(end 25.70861 -33.29559)
		(width 0.08382)
		(layer "In9.Cu")
		(net "V_DACB")
	)
	(segment
		(start 26.30805 -36.42995)
		(end 25.70861 -35.83051)
		(width 0.08382)
		(layer "In9.Cu")
		(net "V_DACB")
	)
	(segment
		(start 25.70861 -33.29559)
		(end 26.57856 -32.42564)
		(width 0.08382)
		(layer "In9.Cu")
		(net "V_DACB")
	)
	(segment
		(start 21.20265 -50.66411)
		(end 21.730462 -49.389792)
		(width 0.08382)
		(layer "In9.Cu")
		(net "V_DACB")
	)
	(segment
		(start 26.57856 -32.42564)
		(end 26.57856 -32.148272)
		(width 0.08382)
		(layer "In9.Cu")
		(net "V_DACB")
	)
	(segment
		(start 21.730462 -49.389792)
		(end 21.730462 -45.887894)
		(width 0.08382)
		(layer "In9.Cu")
		(net "V_DACB")
	)
	(segment
		(start 27.14498 -29.853636)
		(end 27.661362 -29.337254)
		(width 0.08382)
		(layer "In9.Cu")
		(net "V_DACB")
	)
	(segment
		(start 27.096212 -67.31)
		(end 26.60269 -66.816478)
		(width 0.08382)
		(layer "In9.Cu")
		(net "V_DACB")
	)
	(segment
		(start 22.435566 -43.848782)
		(end 26.30805 -39.976298)
		(width 0.08382)
		(layer "In9.Cu")
		(net "V_DACB")
	)
	(segment
		(start 26.76652 -60.63742)
		(end 26.76652 -59.93892)
		(width 0.08382)
		(layer "In9.Cu")
		(net "V_DACB")
	)
	(segment
		(start 26.67762 -24.4602)
		(end 26.67762 -26.38298)
		(width 0.11684)
		(layer "F.Cu")
		(net "V_BMC_LS_DDC_SDA_R")
	)
	(segment
		(start 32.893 -25.6286)
		(end 32.351472 -26.170128)
		(width 0.11684)
		(layer "F.Cu")
		(net "V_BMC_LS_DDC_SDA_R")
	)
	(segment
		(start 34.625026 -21.619972)
		(end 34.133028 -21.619972)
		(width 0.11684)
		(layer "F.Cu")
		(net "V_BMC_LS_DDC_SDA_R")
	)
	(segment
		(start 26.777188 -24.219408)
		(end 26.1112 -22.61108)
		(width 0.11684)
		(layer "F.Cu")
		(net "V_BMC_LS_DDC_SDA_R")
	)
	(segment
		(start 30.01645 -26.650696)
		(end 30.01645 -27.3304)
		(width 0.11684)
		(layer "F.Cu")
		(net "V_BMC_LS_DDC_SDA_R")
	)
	(segment
		(start 26.67762 -24.4602)
		(end 26.777188 -24.219408)
		(width 0.11684)
		(layer "F.Cu")
		(net "V_BMC_LS_DDC_SDA_R")
	)
	(segment
		(start 32.137604 -26.170128)
		(end 31.362396 -26.170128)
		(width 0.11684)
		(layer "F.Cu")
		(net "V_BMC_LS_DDC_SDA_R")
	)
	(segment
		(start 32.893 -24.003)
		(end 32.893 -25.6286)
		(width 0.11684)
		(layer "F.Cu")
		(net "V_BMC_LS_DDC_SDA_R")
	)
	(segment
		(start 30.497018 -26.170128)
		(end 30.01645 -26.650696)
		(width 0.11684)
		(layer "F.Cu")
		(net "V_BMC_LS_DDC_SDA_R")
	)
	(segment
		(start 34.133028 -21.619972)
		(end 33.4264 -22.3266)
		(width 0.11684)
		(layer "F.Cu")
		(net "V_BMC_LS_DDC_SDA_R")
	)
	(segment
		(start 29.55925 -27.7876)
		(end 30.01645 -27.3304)
		(width 0.11684)
		(layer "F.Cu")
		(net "V_BMC_LS_DDC_SDA_R")
	)
	(segment
		(start 27.73045 -26.8224)
		(end 28.21305 -27.305)
		(width 0.11684)
		(layer "F.Cu")
		(net "V_BMC_LS_DDC_SDA_R")
	)
	(segment
		(start 31.362396 -26.170128)
		(end 30.497018 -26.170128)
		(width 0.11684)
		(layer "F.Cu")
		(net "V_BMC_LS_DDC_SDA_R")
	)
	(segment
		(start 27.11704 -26.8224)
		(end 27.73045 -26.8224)
		(width 0.11684)
		(layer "F.Cu")
		(net "V_BMC_LS_DDC_SDA_R")
	)
	(segment
		(start 26.1112 -22.61108)
		(end 26.1112 -22.37105)
		(width 0.11684)
		(layer "F.Cu")
		(net "V_BMC_LS_DDC_SDA_R")
	)
	(segment
		(start 26.67762 -26.38298)
		(end 27.11704 -26.8224)
		(width 0.11684)
		(layer "F.Cu")
		(net "V_BMC_LS_DDC_SDA_R")
	)
	(segment
		(start 33.4264 -22.3266)
		(end 33.4264 -23.4696)
		(width 0.11684)
		(layer "F.Cu")
		(net "V_BMC_LS_DDC_SDA_R")
	)
	(segment
		(start 32.351472 -26.170128)
		(end 32.137604 -26.170128)
		(width 0.11684)
		(layer "F.Cu")
		(net "V_BMC_LS_DDC_SDA_R")
	)
	(segment
		(start 28.69565 -27.7876)
		(end 29.55925 -27.7876)
		(width 0.11684)
		(layer "F.Cu")
		(net "V_BMC_LS_DDC_SDA_R")
	)
	(segment
		(start 28.21305 -27.305)
		(end 28.69565 -27.7876)
		(width 0.11684)
		(layer "F.Cu")
		(net "V_BMC_LS_DDC_SDA_R")
	)
	(segment
		(start 33.4264 -23.4696)
		(end 32.893 -24.003)
		(width 0.11684)
		(layer "F.Cu")
		(net "V_BMC_LS_DDC_SDA_R")
	)
	(via
		(at 26.67762 -24.4602)
		(size 0.762)
		(drill 0.381)
		(layers "F.Cu" "B.Cu")
		(net "V_BMC_LS_DDC_SDA_R")
	)
	(segment
		(start 26.1112 -21.469096)
		(end 25.86863 -21.226526)
		(width 0.11684)
		(layer "F.Cu")
		(net "V_BMC_LS_DDC_SDA")
	)
	(segment
		(start 26.63698 -18.57502)
		(end 26.543 -18.669)
		(width 0.11684)
		(layer "F.Cu")
		(net "V_BMC_LS_DDC_SDA")
	)
	(segment
		(start 26.1112 -21.57095)
		(end 26.1112 -21.469096)
		(width 0.11684)
		(layer "F.Cu")
		(net "V_BMC_LS_DDC_SDA")
	)
	(segment
		(start 28.89504 -18.908014)
		(end 28.562046 -18.57502)
		(width 0.11684)
		(layer "F.Cu")
		(net "V_BMC_LS_DDC_SDA")
	)
	(segment
		(start 26.162 -18.669)
		(end 26.543 -18.669)
		(width 0.11684)
		(layer "F.Cu")
		(net "V_BMC_LS_DDC_SDA")
	)
	(segment
		(start 27.1272 -21.57095)
		(end 26.1112 -21.57095)
		(width 0.11684)
		(layer "F.Cu")
		(net "V_BMC_LS_DDC_SDA")
	)
	(segment
		(start 25.86863 -21.226526)
		(end 25.86863 -18.96237)
		(width 0.11684)
		(layer "F.Cu")
		(net "V_BMC_LS_DDC_SDA")
	)
	(segment
		(start 25.86863 -18.96237)
		(end 26.162 -18.669)
		(width 0.11684)
		(layer "F.Cu")
		(net "V_BMC_LS_DDC_SDA")
	)
	(segment
		(start 28.562046 -18.57502)
		(end 26.63698 -18.57502)
		(width 0.11684)
		(layer "F.Cu")
		(net "V_BMC_LS_DDC_SDA")
	)
	(via
		(at 26.543 -18.669)
		(size 0.508)
		(drill 0.254)
		(layers "F.Cu" "B.Cu")
		(net "V_BMC_LS_DDC_SDA")
	)
	(segment
		(start 32.3596 -22.4282)
		(end 32.3596 -25.553162)
		(width 0.11684)
		(layer "F.Cu")
		(net "V_BMC_LS_DDC_SCL_R")
	)
	(segment
		(start 30.254448 -25.670002)
		(end 30.01645 -25.908)
		(width 0.11684)
		(layer "F.Cu")
		(net "V_BMC_LS_DDC_SCL_R")
	)
	(segment
		(start 32.137604 -25.670002)
		(end 31.362396 -25.670002)
		(width 0.11684)
		(layer "F.Cu")
		(net "V_BMC_LS_DDC_SCL_R")
	)
	(segment
		(start 28.21305 -25.908)
		(end 28.67025 -25.4508)
		(width 0.11684)
		(layer "F.Cu")
		(net "V_BMC_LS_DDC_SCL_R")
	)
	(segment
		(start 31.362396 -25.670002)
		(end 30.254448 -25.670002)
		(width 0.11684)
		(layer "F.Cu")
		(net "V_BMC_LS_DDC_SCL_R")
	)
	(segment
		(start 32.24276 -25.670002)
		(end 32.137604 -25.670002)
		(width 0.11684)
		(layer "F.Cu")
		(net "V_BMC_LS_DDC_SCL_R")
	)
	(segment
		(start 28.21305 -25.908)
		(end 28.21305 -26.5684)
		(width 0.11684)
		(layer "F.Cu")
		(net "V_BMC_LS_DDC_SCL_R")
	)
	(segment
		(start 29.55925 -25.4508)
		(end 30.01645 -25.908)
		(width 0.11684)
		(layer "F.Cu")
		(net "V_BMC_LS_DDC_SCL_R")
	)
	(segment
		(start 32.3596 -25.553162)
		(end 32.24276 -25.670002)
		(width 0.11684)
		(layer "F.Cu")
		(net "V_BMC_LS_DDC_SCL_R")
	)
	(segment
		(start 34.167826 -20.619974)
		(end 32.3596 -22.4282)
		(width 0.11684)
		(layer "F.Cu")
		(net "V_BMC_LS_DDC_SCL_R")
	)
	(segment
		(start 34.625026 -20.619974)
		(end 34.167826 -20.619974)
		(width 0.11684)
		(layer "F.Cu")
		(net "V_BMC_LS_DDC_SCL_R")
	)
	(segment
		(start 28.67025 -25.4508)
		(end 29.55925 -25.4508)
		(width 0.11684)
		(layer "F.Cu")
		(net "V_BMC_LS_DDC_SCL_R")
	)
	(via
		(at 28.21305 -26.5684)
		(size 0.508)
		(drill 0.254)
		(layers "F.Cu" "B.Cu")
		(net "V_BMC_LS_DDC_SCL_R")
	)
	(via
		(at 32.893 -23.23465)
		(size 0.508)
		(drill 0.254)
		(layers "F.Cu" "B.Cu")
		(net "V_BMC_LS_DDC_SCL_R")
	)
	(segment
		(start 33.6296 -23.23465)
		(end 32.893 -23.23465)
		(width 0.11684)
		(layer "B.Cu")
		(net "V_BMC_LS_DDC_SCL_R")
	)
	(segment
		(start 32.766 -24.30653)
		(end 32.893 -24.17953)
		(width 0.08382)
		(layer "In2.Cu")
		(net "V_BMC_LS_DDC_SCL_R")
	)
	(segment
		(start 28.39847 -24.30653)
		(end 32.766 -24.30653)
		(width 0.08382)
		(layer "In2.Cu")
		(net "V_BMC_LS_DDC_SCL_R")
	)
	(segment
		(start 28.21305 -26.5684)
		(end 28.21305 -24.49195)
		(width 0.08382)
		(layer "In2.Cu")
		(net "V_BMC_LS_DDC_SCL_R")
	)
	(segment
		(start 28.21305 -24.49195)
		(end 28.39847 -24.30653)
		(width 0.08382)
		(layer "In2.Cu")
		(net "V_BMC_LS_DDC_SCL_R")
	)
	(segment
		(start 32.893 -24.17953)
		(end 32.893 -23.23465)
		(width 0.08382)
		(layer "In2.Cu")
		(net "V_BMC_LS_DDC_SCL_R")
	)
	(segment
		(start 31.371032 -20.207986)
		(end 31.42996 -20.266914)
		(width 0.11684)
		(layer "F.Cu")
		(net "V_BMC_LS_DDC_SCL")
	)
	(segment
		(start 30.79496 -20.207986)
		(end 31.371032 -20.207986)
		(width 0.11684)
		(layer "F.Cu")
		(net "V_BMC_LS_DDC_SCL")
	)
	(via
		(at 33.782 -20.0406)
		(size 0.6604)
		(drill 0.3302)
		(layers "F.Cu" "B.Cu")
		(net "V_BMC_LS_DDC_SCL")
	)
	(via
		(at 31.42996 -20.266914)
		(size 0.508)
		(drill 0.254)
		(layers "F.Cu" "B.Cu")
		(net "V_BMC_LS_DDC_SCL")
	)
	(segment
		(start 33.782 -20.0406)
		(end 33.2994 -20.0406)
		(width 0.11684)
		(layer "B.Cu")
		(net "V_BMC_LS_DDC_SCL")
	)
	(segment
		(start 33.705546 -21.182584)
		(end 33.61055 -21.4122)
		(width 0.11684)
		(layer "B.Cu")
		(net "V_BMC_LS_DDC_SCL")
	)
	(segment
		(start 33.073086 -20.266914)
		(end 31.42996 -20.266914)
		(width 0.11684)
		(layer "B.Cu")
		(net "V_BMC_LS_DDC_SCL")
	)
	(segment
		(start 33.782 -20.0406)
		(end 33.8836 -20.1422)
		(width 0.11684)
		(layer "B.Cu")
		(net "V_BMC_LS_DDC_SCL")
	)
	(segment
		(start 33.8836 -21.00453)
		(end 33.705546 -21.182584)
		(width 0.11684)
		(layer "B.Cu")
		(net "V_BMC_LS_DDC_SCL")
	)
	(segment
		(start 33.8836 -20.1422)
		(end 33.8836 -21.00453)
		(width 0.11684)
		(layer "B.Cu")
		(net "V_BMC_LS_DDC_SCL")
	)
	(segment
		(start 33.6296 -21.43125)
		(end 33.61055 -21.4122)
		(width 0.11684)
		(layer "B.Cu")
		(net "V_BMC_LS_DDC_SCL")
	)
	(segment
		(start 33.6296 -22.43455)
		(end 33.6296 -21.43125)
		(width 0.11684)
		(layer "B.Cu")
		(net "V_BMC_LS_DDC_SCL")
	)
	(segment
		(start 33.2994 -20.0406)
		(end 33.073086 -20.266914)
		(width 0.11684)
		(layer "B.Cu")
		(net "V_BMC_LS_DDC_SCL")
	)
	(segment
		(start 32.0548 -19.759676)
		(end 32.0548 -20.17395)
		(width 0.11684)
		(layer "F.Cu")
		(net "V_BMC_DDC_SDA")
	)
	(segment
		(start 30.79496 -18.908014)
		(end 30.987746 -19.1008)
		(width 0.11684)
		(layer "F.Cu")
		(net "V_BMC_DDC_SDA")
	)
	(segment
		(start 59.29503 -39.37127)
		(end 59.690254 -38.976046)
		(width 0.11684)
		(layer "F.Cu")
		(net "V_BMC_DDC_SDA")
	)
	(segment
		(start 32.84855 -20.17395)
		(end 33.31464 -20.64004)
		(width 0.11684)
		(layer "F.Cu")
		(net "V_BMC_DDC_SDA")
	)
	(segment
		(start 30.987746 -19.1008)
		(end 31.395924 -19.1008)
		(width 0.11684)
		(layer "F.Cu")
		(net "V_BMC_DDC_SDA")
	)
	(segment
		(start 33.31464 -20.64004)
		(end 33.39338 -20.64004)
		(width 0.11684)
		(layer "F.Cu")
		(net "V_BMC_DDC_SDA")
	)
	(segment
		(start 31.395924 -19.1008)
		(end 32.0548 -19.759676)
		(width 0.11684)
		(layer "F.Cu")
		(net "V_BMC_DDC_SDA")
	)
	(segment
		(start 32.0548 -20.17395)
		(end 32.84855 -20.17395)
		(width 0.11684)
		(layer "F.Cu")
		(net "V_BMC_DDC_SDA")
	)
	(via
		(at 59.690254 -38.976046)
		(size 0.4572)
		(drill 0.254)
		(layers "F.Cu" "B.Cu")
		(net "V_BMC_DDC_SDA")
	)
	(via
		(at 36.8554 -22.1996)
		(size 0.508)
		(drill 0.254)
		(layers "F.Cu" "B.Cu")
		(net "V_BMC_DDC_SDA")
	)
	(via
		(at 33.39338 -20.64004)
		(size 0.508)
		(drill 0.254)
		(layers "F.Cu" "B.Cu")
		(net "V_BMC_DDC_SDA")
	)
	(segment
		(start 57.670954 -23.187406)
		(end 57.490868 -23.00732)
		(width 0.10668)
		(layer "In4.Cu")
		(net "V_BMC_DDC_SDA")
	)
	(segment
		(start 52.828444 -21.287232)
		(end 52.828444 -21.032724)
		(width 0.10668)
		(layer "In4.Cu")
		(net "V_BMC_DDC_SDA")
	)
	(segment
		(start 42.054526 -21.79574)
		(end 38.054788 -21.79574)
		(width 0.10668)
		(layer "In4.Cu")
		(net "V_BMC_DDC_SDA")
	)
	(segment
		(start 42.053764 -20.310094)
		(end 41.873424 -20.490434)
		(width 0.10668)
		(layer "In4.Cu")
		(net "V_BMC_DDC_SDA")
	)
	(segment
		(start 42.936922 -20.938744)
		(end 42.308272 -20.310094)
		(width 0.10668)
		(layer "In4.Cu")
		(net "V_BMC_DDC_SDA")
	)
	(segment
		(start 36.8554 -22.1996)
		(end 36.718494 -22.1996)
		(width 0.10668)
		(layer "In4.Cu")
		(net "V_BMC_DDC_SDA")
	)
	(segment
		(start 37.650928 -22.1996)
		(end 36.8554 -22.1996)
		(width 0.10668)
		(layer "In4.Cu")
		(net "V_BMC_DDC_SDA")
	)
	(segment
		(start 59.690254 -38.976046)
		(end 59.690254 -37.312346)
		(width 0.10668)
		(layer "In4.Cu")
		(net "V_BMC_DDC_SDA")
	)
	(segment
		(start 64.578484 -33.959038)
		(end 64.578484 -33.389824)
		(width 0.10668)
		(layer "In4.Cu")
		(net "V_BMC_DDC_SDA")
	)
	(segment
		(start 60.393834 -36.51758)
		(end 59.87034 -36.51758)
		(width 0.10668)
		(layer "In4.Cu")
		(net "V_BMC_DDC_SDA")
	)
	(segment
		(start 51.632358 -22.737826)
		(end 51.632358 -22.483318)
		(width 0.10668)
		(layer "In4.Cu")
		(net "V_BMC_DDC_SDA")
	)
	(segment
		(start 59.87034 -37.13226)
		(end 60.393834 -37.13226)
		(width 0.10668)
		(layer "In4.Cu")
		(net "V_BMC_DDC_SDA")
	)
	(segment
		(start 43.37177 -20.758404)
		(end 43.19143 -20.938744)
		(width 0.10668)
		(layer "In4.Cu")
		(net "V_BMC_DDC_SDA")
	)
	(segment
		(start 57.056274 -23.187406)
		(end 57.056274 -23.944834)
		(width 0.10668)
		(layer "In4.Cu")
		(net "V_BMC_DDC_SDA")
	)
	(segment
		(start 57.23636 -23.00732)
		(end 57.056274 -23.187406)
		(width 0.10668)
		(layer "In4.Cu")
		(net "V_BMC_DDC_SDA")
	)
	(segment
		(start 64.578484 -33.389824)
		(end 63.771526 -32.582866)
		(width 0.10668)
		(layer "In4.Cu")
		(net "V_BMC_DDC_SDA")
	)
	(segment
		(start 59.690254 -36.048442)
		(end 60.752736 -34.98596)
		(width 0.10668)
		(layer "In4.Cu")
		(net "V_BMC_DDC_SDA")
	)
	(segment
		(start 44.064682 -18.299176)
		(end 42.74312 -19.620738)
		(width 0.10668)
		(layer "In4.Cu")
		(net "V_BMC_DDC_SDA")
	)
	(segment
		(start 57.670954 -23.944834)
		(end 57.670954 -23.187406)
		(width 0.10668)
		(layer "In4.Cu")
		(net "V_BMC_DDC_SDA")
	)
	(segment
		(start 52.393596 -20.852384)
		(end 51.19751 -22.04847)
		(width 0.10668)
		(layer "In4.Cu")
		(net "V_BMC_DDC_SDA")
	)
	(segment
		(start 36.718494 -22.1996)
		(end 36.030154 -21.51126)
		(width 0.10668)
		(layer "In4.Cu")
		(net "V_BMC_DDC_SDA")
	)
	(segment
		(start 34.2646 -21.51126)
		(end 33.39338 -20.64004)
		(width 0.10668)
		(layer "In4.Cu")
		(net "V_BMC_DDC_SDA")
	)
	(segment
		(start 59.690254 -37.312346)
		(end 59.87034 -37.13226)
		(width 0.10668)
		(layer "In4.Cu")
		(net "V_BMC_DDC_SDA")
	)
	(segment
		(start 38.054788 -21.79574)
		(end 37.650928 -22.1996)
		(width 0.10668)
		(layer "In4.Cu")
		(net "V_BMC_DDC_SDA")
	)
	(segment
		(start 53.74132 -22.92096)
		(end 51.815492 -22.92096)
		(width 0.10668)
		(layer "In4.Cu")
		(net "V_BMC_DDC_SDA")
	)
	(segment
		(start 41.873424 -20.490434)
		(end 41.873424 -20.744942)
		(width 0.10668)
		(layer "In4.Cu")
		(net "V_BMC_DDC_SDA")
	)
	(segment
		(start 47.751238 -20.28952)
		(end 45.760894 -18.299176)
		(width 0.10668)
		(layer "In4.Cu")
		(net "V_BMC_DDC_SDA")
	)
	(segment
		(start 63.59398 -29.27858)
		(end 61.54674 -27.23134)
		(width 0.10668)
		(layer "In4.Cu")
		(net "V_BMC_DDC_SDA")
	)
	(segment
		(start 36.030154 -21.51126)
		(end 34.2646 -21.51126)
		(width 0.10668)
		(layer "In4.Cu")
		(net "V_BMC_DDC_SDA")
	)
	(segment
		(start 42.308272 -20.310094)
		(end 42.053764 -20.310094)
		(width 0.10668)
		(layer "In4.Cu")
		(net "V_BMC_DDC_SDA")
	)
	(segment
		(start 63.59398 -30.75178)
		(end 63.59398 -29.27858)
		(width 0.10668)
		(layer "In4.Cu")
		(net "V_BMC_DDC_SDA")
	)
	(segment
		(start 63.771526 -32.582866)
		(end 63.771526 -30.929326)
		(width 0.10668)
		(layer "In4.Cu")
		(net "V_BMC_DDC_SDA")
	)
	(segment
		(start 42.74312 -19.620738)
		(end 42.74312 -19.875246)
		(width 0.10668)
		(layer "In4.Cu")
		(net "V_BMC_DDC_SDA")
	)
	(segment
		(start 60.752736 -34.98596)
		(end 63.551562 -34.98596)
		(width 0.10668)
		(layer "In4.Cu")
		(net "V_BMC_DDC_SDA")
	)
	(segment
		(start 42.488358 -22.078696)
		(end 42.337482 -22.078696)
		(width 0.10668)
		(layer "In4.Cu")
		(net "V_BMC_DDC_SDA")
	)
	(segment
		(start 61.42101 -26.92781)
		(end 60.66028 -26.16708)
		(width 0.10668)
		(layer "In4.Cu")
		(net "V_BMC_DDC_SDA")
	)
	(segment
		(start 50.943002 -22.04847)
		(end 49.184052 -20.28952)
		(width 0.10668)
		(layer "In4.Cu")
		(net "V_BMC_DDC_SDA")
	)
	(segment
		(start 52.828444 -21.032724)
		(end 52.648104 -20.852384)
		(width 0.10668)
		(layer "In4.Cu")
		(net "V_BMC_DDC_SDA")
	)
	(segment
		(start 52.648104 -20.852384)
		(end 52.393596 -20.852384)
		(width 0.10668)
		(layer "In4.Cu")
		(net "V_BMC_DDC_SDA")
	)
	(segment
		(start 60.66028 -25.32126)
		(end 60.39104 -25.05202)
		(width 0.10668)
		(layer "In4.Cu")
		(net "V_BMC_DDC_SDA")
	)
	(segment
		(start 59.690254 -36.337494)
		(end 59.690254 -36.048442)
		(width 0.10668)
		(layer "In4.Cu")
		(net "V_BMC_DDC_SDA")
	)
	(segment
		(start 43.37177 -20.503896)
		(end 43.37177 -20.758404)
		(width 0.10668)
		(layer "In4.Cu")
		(net "V_BMC_DDC_SDA")
	)
	(segment
		(start 59.93257 -25.05202)
		(end 59.00547 -24.12492)
		(width 0.10668)
		(layer "In4.Cu")
		(net "V_BMC_DDC_SDA")
	)
	(segment
		(start 54.94528 -24.12492)
		(end 53.74132 -22.92096)
		(width 0.10668)
		(layer "In4.Cu")
		(net "V_BMC_DDC_SDA")
	)
	(segment
		(start 51.19751 -22.04847)
		(end 50.943002 -22.04847)
		(width 0.10668)
		(layer "In4.Cu")
		(net "V_BMC_DDC_SDA")
	)
	(segment
		(start 41.873424 -20.744942)
		(end 42.77233 -21.643848)
		(width 0.10668)
		(layer "In4.Cu")
		(net "V_BMC_DDC_SDA")
	)
	(segment
		(start 60.66028 -26.16708)
		(end 60.66028 -25.32126)
		(width 0.10668)
		(layer "In4.Cu")
		(net "V_BMC_DDC_SDA")
	)
	(segment
		(start 42.77233 -21.643848)
		(end 42.77233 -21.794724)
		(width 0.10668)
		(layer "In4.Cu")
		(net "V_BMC_DDC_SDA")
	)
	(segment
		(start 42.337482 -22.078696)
		(end 42.054526 -21.79574)
		(width 0.10668)
		(layer "In4.Cu")
		(net "V_BMC_DDC_SDA")
	)
	(segment
		(start 49.184052 -20.28952)
		(end 47.751238 -20.28952)
		(width 0.10668)
		(layer "In4.Cu")
		(net "V_BMC_DDC_SDA")
	)
	(segment
		(start 57.490868 -23.00732)
		(end 57.23636 -23.00732)
		(width 0.10668)
		(layer "In4.Cu")
		(net "V_BMC_DDC_SDA")
	)
	(segment
		(start 56.876188 -24.12492)
		(end 54.94528 -24.12492)
		(width 0.10668)
		(layer "In4.Cu")
		(net "V_BMC_DDC_SDA")
	)
	(segment
		(start 59.87034 -36.51758)
		(end 59.690254 -36.337494)
		(width 0.10668)
		(layer "In4.Cu")
		(net "V_BMC_DDC_SDA")
	)
	(segment
		(start 60.57392 -36.697666)
		(end 60.393834 -36.51758)
		(width 0.10668)
		(layer "In4.Cu")
		(net "V_BMC_DDC_SDA")
	)
	(segment
		(start 61.54674 -27.23134)
		(end 61.42101 -26.92781)
		(width 0.10668)
		(layer "In4.Cu")
		(net "V_BMC_DDC_SDA")
	)
	(segment
		(start 60.393834 -37.13226)
		(end 60.57392 -36.952174)
		(width 0.10668)
		(layer "In4.Cu")
		(net "V_BMC_DDC_SDA")
	)
	(segment
		(start 63.551562 -34.98596)
		(end 64.578484 -33.959038)
		(width 0.10668)
		(layer "In4.Cu")
		(net "V_BMC_DDC_SDA")
	)
	(segment
		(start 60.39104 -25.05202)
		(end 59.93257 -25.05202)
		(width 0.10668)
		(layer "In4.Cu")
		(net "V_BMC_DDC_SDA")
	)
	(segment
		(start 60.57392 -36.952174)
		(end 60.57392 -36.697666)
		(width 0.10668)
		(layer "In4.Cu")
		(net "V_BMC_DDC_SDA")
	)
	(segment
		(start 51.815492 -22.92096)
		(end 51.632358 -22.737826)
		(width 0.10668)
		(layer "In4.Cu")
		(net "V_BMC_DDC_SDA")
	)
	(segment
		(start 59.00547 -24.12492)
		(end 57.85104 -24.12492)
		(width 0.10668)
		(layer "In4.Cu")
		(net "V_BMC_DDC_SDA")
	)
	(segment
		(start 42.74312 -19.875246)
		(end 43.37177 -20.503896)
		(width 0.10668)
		(layer "In4.Cu")
		(net "V_BMC_DDC_SDA")
	)
	(segment
		(start 51.632358 -22.483318)
		(end 52.828444 -21.287232)
		(width 0.10668)
		(layer "In4.Cu")
		(net "V_BMC_DDC_SDA")
	)
	(segment
		(start 43.19143 -20.938744)
		(end 42.936922 -20.938744)
		(width 0.10668)
		(layer "In4.Cu")
		(net "V_BMC_DDC_SDA")
	)
	(segment
		(start 42.77233 -21.794724)
		(end 42.488358 -22.078696)
		(width 0.10668)
		(layer "In4.Cu")
		(net "V_BMC_DDC_SDA")
	)
	(segment
		(start 45.760894 -18.299176)
		(end 44.064682 -18.299176)
		(width 0.10668)
		(layer "In4.Cu")
		(net "V_BMC_DDC_SDA")
	)
	(segment
		(start 57.85104 -24.12492)
		(end 57.670954 -23.944834)
		(width 0.10668)
		(layer "In4.Cu")
		(net "V_BMC_DDC_SDA")
	)
	(segment
		(start 57.056274 -23.944834)
		(end 56.876188 -24.12492)
		(width 0.10668)
		(layer "In4.Cu")
		(net "V_BMC_DDC_SDA")
	)
	(segment
		(start 63.771526 -30.929326)
		(end 63.59398 -30.75178)
		(width 0.10668)
		(layer "In4.Cu")
		(net "V_BMC_DDC_SDA")
	)
	(segment
		(start 28.912566 -20.207986)
		(end 28.89504 -20.207986)
		(width 0.11684)
		(layer "F.Cu")
		(net "V_BMC_DDC_SCL")
	)
	(segment
		(start 32.8422 -20.9931)
		(end 32.27578 -21.55952)
		(width 0.11684)
		(layer "F.Cu")
		(net "V_BMC_DDC_SCL")
	)
	(segment
		(start 28.89504 -20.207986)
		(end 28.194 -20.207986)
		(width 0.11684)
		(layer "F.Cu")
		(net "V_BMC_DDC_SCL")
	)
	(segment
		(start 59.29503 -40.17137)
		(end 59.690254 -39.776146)
		(width 0.11684)
		(layer "F.Cu")
		(net "V_BMC_DDC_SCL")
	)
	(segment
		(start 30.250892 -20.3962)
		(end 29.10078 -20.3962)
		(width 0.11684)
		(layer "F.Cu")
		(net "V_BMC_DDC_SCL")
	)
	(segment
		(start 28.194 -20.207986)
		(end 28.081986 -20.32)
		(width 0.11684)
		(layer "F.Cu")
		(net "V_BMC_DDC_SCL")
	)
	(segment
		(start 32.27578 -21.55952)
		(end 31.414212 -21.55952)
		(width 0.11684)
		(layer "F.Cu")
		(net "V_BMC_DDC_SCL")
	)
	(segment
		(start 28.081986 -20.32)
		(end 27.32405 -20.32)
		(width 0.11684)
		(layer "F.Cu")
		(net "V_BMC_DDC_SCL")
	)
	(segment
		(start 31.414212 -21.55952)
		(end 30.250892 -20.3962)
		(width 0.11684)
		(layer "F.Cu")
		(net "V_BMC_DDC_SCL")
	)
	(segment
		(start 29.10078 -20.3962)
		(end 28.912566 -20.207986)
		(width 0.11684)
		(layer "F.Cu")
		(net "V_BMC_DDC_SCL")
	)
	(via
		(at 59.690254 -39.776146)
		(size 0.4572)
		(drill 0.254)
		(layers "F.Cu" "B.Cu")
		(net "V_BMC_DDC_SCL")
	)
	(via
		(at 32.8422 -20.9931)
		(size 0.508)
		(drill 0.254)
		(layers "F.Cu" "B.Cu")
		(net "V_BMC_DDC_SCL")
	)
	(segment
		(start 64.284606 -31.19374)
		(end 64.755522 -30.722824)
		(width 0.10668)
		(layer "In4.Cu")
		(net "V_BMC_DDC_SCL")
	)
	(segment
		(start 61.6712 -25.13076)
		(end 60.99048 -24.45004)
		(width 0.10668)
		(layer "In4.Cu")
		(net "V_BMC_DDC_SCL")
	)
	(segment
		(start 45.973492 -17.786096)
		(end 42.456608 -17.786096)
		(width 0.10668)
		(layer "In4.Cu")
		(net "V_BMC_DDC_SCL")
	)
	(segment
		(start 64.755522 -30.722824)
		(end 64.755522 -29.043122)
		(width 0.10668)
		(layer "In4.Cu")
		(net "V_BMC_DDC_SCL")
	)
	(segment
		(start 52.68722 -20.15998)
		(end 49.806606 -20.15998)
		(width 0.10668)
		(layer "In4.Cu")
		(net "V_BMC_DDC_SCL")
	)
	(segment
		(start 61.886338 -26.654252)
		(end 61.6712 -26.439114)
		(width 0.10668)
		(layer "In4.Cu")
		(net "V_BMC_DDC_SCL")
	)
	(segment
		(start 33.19018 -20.0914)
		(end 32.8422 -20.43938)
		(width 0.10668)
		(layer "In4.Cu")
		(net "V_BMC_DDC_SCL")
	)
	(segment
		(start 41.68394 -19.95424)
		(end 40.35552 -21.28266)
		(width 0.10668)
		(layer "In4.Cu")
		(net "V_BMC_DDC_SCL")
	)
	(segment
		(start 36.242752 -20.99818)
		(end 34.477452 -20.99818)
		(width 0.10668)
		(layer "In4.Cu")
		(net "V_BMC_DDC_SCL")
	)
	(segment
		(start 40.35552 -21.28266)
		(end 36.527232 -21.28266)
		(width 0.10668)
		(layer "In4.Cu")
		(net "V_BMC_DDC_SCL")
	)
	(segment
		(start 65.091564 -34.171636)
		(end 65.091564 -33.177226)
		(width 0.10668)
		(layer "In4.Cu")
		(net "V_BMC_DDC_SCL")
	)
	(segment
		(start 49.423066 -19.77644)
		(end 47.963836 -19.77644)
		(width 0.10668)
		(layer "In4.Cu")
		(net "V_BMC_DDC_SCL")
	)
	(segment
		(start 60.056268 -24.45004)
		(end 59.1185 -23.512272)
		(width 0.10668)
		(layer "In4.Cu")
		(net "V_BMC_DDC_SCL")
	)
	(segment
		(start 41.68394 -18.558764)
		(end 41.68394 -19.95424)
		(width 0.10668)
		(layer "In4.Cu")
		(net "V_BMC_DDC_SCL")
	)
	(segment
		(start 49.806606 -20.15998)
		(end 49.423066 -19.77644)
		(width 0.10668)
		(layer "In4.Cu")
		(net "V_BMC_DDC_SCL")
	)
	(segment
		(start 47.963836 -19.77644)
		(end 45.973492 -17.786096)
		(width 0.10668)
		(layer "In4.Cu")
		(net "V_BMC_DDC_SCL")
	)
	(segment
		(start 59.1185 -23.512272)
		(end 59.1185 -23.18766)
		(width 0.10668)
		(layer "In4.Cu")
		(net "V_BMC_DDC_SCL")
	)
	(segment
		(start 34.477452 -20.99818)
		(end 33.570672 -20.0914)
		(width 0.10668)
		(layer "In4.Cu")
		(net "V_BMC_DDC_SCL")
	)
	(segment
		(start 61.6712 -26.439114)
		(end 61.6712 -25.13076)
		(width 0.10668)
		(layer "In4.Cu")
		(net "V_BMC_DDC_SCL")
	)
	(segment
		(start 63.339218 -28.29814)
		(end 62.021466 -26.980388)
		(width 0.10668)
		(layer "In4.Cu")
		(net "V_BMC_DDC_SCL")
	)
	(segment
		(start 42.456608 -17.786096)
		(end 41.68394 -18.558764)
		(width 0.10668)
		(layer "In4.Cu")
		(net "V_BMC_DDC_SCL")
	)
	(segment
		(start 64.01054 -28.29814)
		(end 63.339218 -28.29814)
		(width 0.10668)
		(layer "In4.Cu")
		(net "V_BMC_DDC_SCL")
	)
	(segment
		(start 54.98592 -22.45868)
		(end 52.68722 -20.15998)
		(width 0.10668)
		(layer "In4.Cu")
		(net "V_BMC_DDC_SCL")
	)
	(segment
		(start 65.091564 -33.177226)
		(end 64.284606 -32.370268)
		(width 0.10668)
		(layer "In4.Cu")
		(net "V_BMC_DDC_SCL")
	)
	(segment
		(start 36.527232 -21.28266)
		(end 36.242752 -20.99818)
		(width 0.10668)
		(layer "In4.Cu")
		(net "V_BMC_DDC_SCL")
	)
	(segment
		(start 58.38952 -22.45868)
		(end 54.98592 -22.45868)
		(width 0.10668)
		(layer "In4.Cu")
		(net "V_BMC_DDC_SCL")
	)
	(segment
		(start 62.021466 -26.980388)
		(end 61.886338 -26.654252)
		(width 0.10668)
		(layer "In4.Cu")
		(net "V_BMC_DDC_SCL")
	)
	(segment
		(start 60.99048 -24.45004)
		(end 60.056268 -24.45004)
		(width 0.10668)
		(layer "In4.Cu")
		(net "V_BMC_DDC_SCL")
	)
	(segment
		(start 59.690254 -39.776146)
		(end 59.690254 -39.572946)
		(width 0.10668)
		(layer "In4.Cu")
		(net "V_BMC_DDC_SCL")
	)
	(segment
		(start 59.690254 -39.572946)
		(end 65.091564 -34.171636)
		(width 0.10668)
		(layer "In4.Cu")
		(net "V_BMC_DDC_SCL")
	)
	(segment
		(start 64.755522 -29.043122)
		(end 64.01054 -28.29814)
		(width 0.10668)
		(layer "In4.Cu")
		(net "V_BMC_DDC_SCL")
	)
	(segment
		(start 32.8422 -20.43938)
		(end 32.8422 -20.9931)
		(width 0.10668)
		(layer "In4.Cu")
		(net "V_BMC_DDC_SCL")
	)
	(segment
		(start 59.1185 -23.18766)
		(end 58.38952 -22.45868)
		(width 0.10668)
		(layer "In4.Cu")
		(net "V_BMC_DDC_SCL")
	)
	(segment
		(start 64.284606 -32.370268)
		(end 64.284606 -31.19374)
		(width 0.10668)
		(layer "In4.Cu")
		(net "V_BMC_DDC_SCL")
	)
	(segment
		(start 33.570672 -20.0914)
		(end 33.19018 -20.0914)
		(width 0.10668)
		(layer "In4.Cu")
		(net "V_BMC_DDC_SCL")
	)
	(segment
		(start 30.66796 -19.685)
		(end 30.79496 -19.558)
		(width 0.11684)
		(layer "F.Cu")
		(net "V_BMC_DDC_LS_GATE")
	)
	(segment
		(start 28.89504 -19.558)
		(end 29.02204 -19.685)
		(width 0.11684)
		(layer "F.Cu")
		(net "V_BMC_DDC_LS_GATE")
	)
	(segment
		(start 28.194 -19.558)
		(end 28.89504 -19.558)
		(width 0.11684)
		(layer "F.Cu")
		(net "V_BMC_DDC_LS_GATE")
	)
	(segment
		(start 29.02204 -19.685)
		(end 30.66796 -19.685)
		(width 0.11684)
		(layer "F.Cu")
		(net "V_BMC_DDC_LS_GATE")
	)
	(via
		(at 28.194 -19.558)
		(size 0.508)
		(drill 0.254)
		(layers "F.Cu" "B.Cu")
		(net "V_BMC_DDC_LS_GATE")
	)
	(segment
		(start 26.933144 -19.955764)
		(end 27.796236 -19.955764)
		(width 0.11684)
		(layer "B.Cu")
		(net "V_BMC_DDC_LS_GATE")
	)
	(segment
		(start 27.796236 -19.955764)
		(end 28.194 -19.558)
		(width 0.11684)
		(layer "B.Cu")
		(net "V_BMC_DDC_LS_GATE")
	)
	(segment
		(start 35.88512 -63.02248)
		(end 37.481256 -61.426344)
		(width 0.11684)
		(layer "F.Cu")
		(net "USB_OC0_REAR_R_N")
	)
	(segment
		(start 39.435786 -60.861194)
		(end 39.620698 -60.584334)
		(width 0.11684)
		(layer "F.Cu")
		(net "USB_OC0_REAR_R_N")
	)
	(segment
		(start 37.481256 -61.426344)
		(end 38.04666 -61.426344)
		(width 0.11684)
		(layer "F.Cu")
		(net "USB_OC0_REAR_R_N")
	)
	(segment
		(start 14.88948 -103.829866)
		(end 13.777214 -102.7176)
		(width 0.11684)
		(layer "F.Cu")
		(net "USB_OC0_REAR_R_N")
	)
	(segment
		(start 13.777214 -102.7176)
		(end 11.21918 -102.7176)
		(width 0.11684)
		(layer "F.Cu")
		(net "USB_OC0_REAR_R_N")
	)
	(segment
		(start 41.40962 -59.52744)
		(end 41.40962 -59.27598)
		(width 0.11684)
		(layer "F.Cu")
		(net "USB_OC0_REAR_R_N")
	)
	(segment
		(start 10.78738 -102.2858)
		(end 10.78738 -98.365564)
		(width 0.11684)
		(layer "F.Cu")
		(net "USB_OC0_REAR_R_N")
	)
	(segment
		(start 10.78738 -98.365564)
		(end 11.134344 -98.0186)
		(width 0.11684)
		(layer "F.Cu")
		(net "USB_OC0_REAR_R_N")
	)
	(segment
		(start 45.300646 -56.5658)
		(end 45.695108 -56.171338)
		(width 0.11684)
		(layer "F.Cu")
		(net "USB_OC0_REAR_R_N")
	)
	(segment
		(start 38.537388 -61.223144)
		(end 39.073836 -61.223144)
		(width 0.11684)
		(layer "F.Cu")
		(net "USB_OC0_REAR_R_N")
	)
	(segment
		(start 39.073836 -61.223144)
		(end 39.435786 -60.861194)
		(width 0.11684)
		(layer "F.Cu")
		(net "USB_OC0_REAR_R_N")
	)
	(segment
		(start 10.71753 -97.4344)
		(end 10.84453 -97.5614)
		(width 0.11684)
		(layer "F.Cu")
		(net "USB_OC0_REAR_R_N")
	)
	(segment
		(start 14.478 -96.266)
		(end 14.478 -96.690434)
		(width 0.11684)
		(layer "F.Cu")
		(net "USB_OC0_REAR_R_N")
	)
	(segment
		(start 10.84453 -97.728786)
		(end 11.134344 -98.0186)
		(width 0.11684)
		(layer "F.Cu")
		(net "USB_OC0_REAR_R_N")
	)
	(segment
		(start 40.46982 -60.46724)
		(end 41.40962 -59.52744)
		(width 0.11684)
		(layer "F.Cu")
		(net "USB_OC0_REAR_R_N")
	)
	(segment
		(start 15.156942 -95.587058)
		(end 14.478 -96.266)
		(width 0.11684)
		(layer "F.Cu")
		(net "USB_OC0_REAR_R_N")
	)
	(segment
		(start 11.21918 -102.7176)
		(end 10.78738 -102.2858)
		(width 0.11684)
		(layer "F.Cu")
		(net "USB_OC0_REAR_R_N")
	)
	(segment
		(start 46.46295 -23.368)
		(end 45.8724 -23.368)
		(width 0.11684)
		(layer "F.Cu")
		(net "USB_OC0_REAR_R_N")
	)
	(segment
		(start 14.478 -96.690434)
		(end 13.149834 -98.0186)
		(width 0.11684)
		(layer "F.Cu")
		(net "USB_OC0_REAR_R_N")
	)
	(segment
		(start 13.149834 -98.0186)
		(end 11.134344 -98.0186)
		(width 0.11684)
		(layer "F.Cu")
		(net "USB_OC0_REAR_R_N")
	)
	(segment
		(start 45.8724 -23.368)
		(end 45.6946 -23.1902)
		(width 0.11684)
		(layer "F.Cu")
		(net "USB_OC0_REAR_R_N")
	)
	(segment
		(start 38.04666 -61.426344)
		(end 38.537388 -61.223144)
		(width 0.11684)
		(layer "F.Cu")
		(net "USB_OC0_REAR_R_N")
	)
	(segment
		(start 10.84453 -97.5614)
		(end 10.84453 -97.728786)
		(width 0.11684)
		(layer "F.Cu")
		(net "USB_OC0_REAR_R_N")
	)
	(segment
		(start 7.874 -95.0976)
		(end 10.2108 -97.4344)
		(width 0.11684)
		(layer "F.Cu")
		(net "USB_OC0_REAR_R_N")
	)
	(segment
		(start 15.459456 -95.587058)
		(end 15.156942 -95.587058)
		(width 0.11684)
		(layer "F.Cu")
		(net "USB_OC0_REAR_R_N")
	)
	(segment
		(start 35.88512 -65.10274)
		(end 35.88512 -63.02248)
		(width 0.11684)
		(layer "F.Cu")
		(net "USB_OC0_REAR_R_N")
	)
	(segment
		(start 39.903146 -60.46724)
		(end 40.46982 -60.46724)
		(width 0.11684)
		(layer "F.Cu")
		(net "USB_OC0_REAR_R_N")
	)
	(segment
		(start 44.1198 -56.5658)
		(end 45.300646 -56.5658)
		(width 0.11684)
		(layer "F.Cu")
		(net "USB_OC0_REAR_R_N")
	)
	(segment
		(start 39.620698 -60.584334)
		(end 39.903146 -60.46724)
		(width 0.11684)
		(layer "F.Cu")
		(net "USB_OC0_REAR_R_N")
	)
	(segment
		(start 10.2108 -97.4344)
		(end 10.71753 -97.4344)
		(width 0.11684)
		(layer "F.Cu")
		(net "USB_OC0_REAR_R_N")
	)
	(segment
		(start 41.40962 -59.27598)
		(end 44.1198 -56.5658)
		(width 0.11684)
		(layer "F.Cu")
		(net "USB_OC0_REAR_R_N")
	)
	(segment
		(start 6.6802 -95.0976)
		(end 7.874 -95.0976)
		(width 0.11684)
		(layer "F.Cu")
		(net "USB_OC0_REAR_R_N")
	)
	(via
		(at 14.88948 -103.829866)
		(size 0.508)
		(drill 0.254)
		(layers "F.Cu" "B.Cu")
		(net "USB_OC0_REAR_R_N")
	)
	(via
		(at 45.6946 -23.1902)
		(size 0.508)
		(drill 0.254)
		(layers "F.Cu" "B.Cu")
		(net "USB_OC0_REAR_R_N")
	)
	(via
		(at 6.6802 -95.0976)
		(size 0.508)
		(drill 0.254)
		(layers "F.Cu" "B.Cu")
		(net "USB_OC0_REAR_R_N")
	)
	(via
		(at 35.88512 -65.10274)
		(size 0.508)
		(drill 0.254)
		(layers "F.Cu" "B.Cu")
		(net "USB_OC0_REAR_R_N")
	)
	(via
		(at 30.2768 -98.9838)
		(size 0.508)
		(drill 0.254)
		(layers "F.Cu" "B.Cu")
		(net "USB_OC0_REAR_R_N")
	)
	(segment
		(start 33.49498 -18.415)
		(end 34.10585 -19.02587)
		(width 0.08382)
		(layer "In2.Cu")
		(net "USB_OC0_REAR_R_N")
	)
	(segment
		(start 37.718492 -19.02587)
		(end 39.48684 -20.794218)
		(width 0.08382)
		(layer "In2.Cu")
		(net "USB_OC0_REAR_R_N")
	)
	(segment
		(start 6.615176 -85.202776)
		(end 6.234176 -85.202776)
		(width 0.08382)
		(layer "In2.Cu")
		(net "USB_OC0_REAR_R_N")
	)
	(segment
		(start 24.617172 -19.74088)
		(end 24.713946 -19.837654)
		(width 0.08382)
		(layer "In2.Cu")
		(net "USB_OC0_REAR_R_N")
	)
	(segment
		(start 10.91438 -22.86)
		(end 11.42238 -22.352)
		(width 0.08382)
		(layer "In2.Cu")
		(net "USB_OC0_REAR_R_N")
	)
	(segment
		(start 4.445 -87.4776)
		(end 4.7498 -87.1728)
		(width 0.08382)
		(layer "In2.Cu")
		(net "USB_OC0_REAR_R_N")
	)
	(segment
		(start 27.096974 -19.837654)
		(end 27.852878 -19.08175)
		(width 0.08382)
		(layer "In2.Cu")
		(net "USB_OC0_REAR_R_N")
	)
	(segment
		(start 4.7498 -87.1728)
		(end 6.5786 -87.1728)
		(width 0.08382)
		(layer "In2.Cu")
		(net "USB_OC0_REAR_R_N")
	)
	(segment
		(start 27.852878 -19.08175)
		(end 28.36418 -19.08175)
		(width 0.08382)
		(layer "In2.Cu")
		(net "USB_OC0_REAR_R_N")
	)
	(segment
		(start 22.4282 -101.1174)
		(end 22.7584 -101.4476)
		(width 0.08382)
		(layer "In2.Cu")
		(net "USB_OC0_REAR_R_N")
	)
	(segment
		(start 11.42238 -22.352)
		(end 14.986 -22.352)
		(width 0.08382)
		(layer "In2.Cu")
		(net "USB_OC0_REAR_R_N")
	)
	(segment
		(start 9.016492 -27.551634)
		(end 10.91438 -25.653746)
		(width 0.08382)
		(layer "In2.Cu")
		(net "USB_OC0_REAR_R_N")
	)
	(segment
		(start 34.10585 -19.02587)
		(end 37.718492 -19.02587)
		(width 0.08382)
		(layer "In2.Cu")
		(net "USB_OC0_REAR_R_N")
	)
	(segment
		(start 6.99643 -27.55138)
		(end 6.996684 -27.551634)
		(width 0.08382)
		(layer "In2.Cu")
		(net "USB_OC0_REAR_R_N")
	)
	(segment
		(start 39.48684 -20.794218)
		(end 44.853098 -20.794218)
		(width 0.08382)
		(layer "In2.Cu")
		(net "USB_OC0_REAR_R_N")
	)
	(segment
		(start 7.0612 -85.6488)
		(end 6.615176 -85.202776)
		(width 0.08382)
		(layer "In2.Cu")
		(net "USB_OC0_REAR_R_N")
	)
	(segment
		(start 18.314924 -101.10724)
		(end 19.49704 -99.925124)
		(width 0.08382)
		(layer "In2.Cu")
		(net "USB_OC0_REAR_R_N")
	)
	(segment
		(start 6.427978 -27.55138)
		(end 6.99643 -27.55138)
		(width 0.08382)
		(layer "In2.Cu")
		(net "USB_OC0_REAR_R_N")
	)
	(segment
		(start 22.7584 -101.4476)
		(end 23.1902 -101.4476)
		(width 0.08382)
		(layer "In2.Cu")
		(net "USB_OC0_REAR_R_N")
	)
	(segment
		(start 28.1686 -100.838)
		(end 30.0228 -98.9838)
		(width 0.08382)
		(layer "In2.Cu")
		(net "USB_OC0_REAR_R_N")
	)
	(segment
		(start 6.6802 -95.0976)
		(end 5.207 -95.0976)
		(width 0.08382)
		(layer "In2.Cu")
		(net "USB_OC0_REAR_R_N")
	)
	(segment
		(start 16.79956 -101.10724)
		(end 18.314924 -101.10724)
		(width 0.08382)
		(layer "In2.Cu")
		(net "USB_OC0_REAR_R_N")
	)
	(segment
		(start 44.853098 -20.794218)
		(end 45.6946 -21.63572)
		(width 0.08382)
		(layer "In2.Cu")
		(net "USB_OC0_REAR_R_N")
	)
	(segment
		(start 2.766822 -31.212536)
		(end 6.427978 -27.55138)
		(width 0.08382)
		(layer "In2.Cu")
		(net "USB_OC0_REAR_R_N")
	)
	(segment
		(start 5.52958 -84.49818)
		(end 5.52958 -80.658716)
		(width 0.08382)
		(layer "In2.Cu")
		(net "USB_OC0_REAR_R_N")
	)
	(segment
		(start 30.0228 -98.9838)
		(end 30.2768 -98.9838)
		(width 0.08382)
		(layer "In2.Cu")
		(net "USB_OC0_REAR_R_N")
	)
	(segment
		(start 21.617178 -99.925124)
		(end 22.4282 -100.736146)
		(width 0.08382)
		(layer "In2.Cu")
		(net "USB_OC0_REAR_R_N")
	)
	(segment
		(start 5.52958 -80.658716)
		(end 2.766822 -77.895958)
		(width 0.08382)
		(layer "In2.Cu")
		(net "USB_OC0_REAR_R_N")
	)
	(segment
		(start 4.445 -94.3356)
		(end 4.445 -87.4776)
		(width 0.08382)
		(layer "In2.Cu")
		(net "USB_OC0_REAR_R_N")
	)
	(segment
		(start 17.59712 -19.74088)
		(end 24.617172 -19.74088)
		(width 0.08382)
		(layer "In2.Cu")
		(net "USB_OC0_REAR_R_N")
	)
	(segment
		(start 22.4282 -100.736146)
		(end 22.4282 -101.1174)
		(width 0.08382)
		(layer "In2.Cu")
		(net "USB_OC0_REAR_R_N")
	)
	(segment
		(start 2.766822 -77.895958)
		(end 2.766822 -31.212536)
		(width 0.08382)
		(layer "In2.Cu")
		(net "USB_OC0_REAR_R_N")
	)
	(segment
		(start 19.49704 -99.925124)
		(end 21.617178 -99.925124)
		(width 0.08382)
		(layer "In2.Cu")
		(net "USB_OC0_REAR_R_N")
	)
	(segment
		(start 14.88948 -103.829866)
		(end 14.88948 -103.01732)
		(width 0.08382)
		(layer "In2.Cu")
		(net "USB_OC0_REAR_R_N")
	)
	(segment
		(start 6.5786 -87.1728)
		(end 7.0612 -86.6902)
		(width 0.08382)
		(layer "In2.Cu")
		(net "USB_OC0_REAR_R_N")
	)
	(segment
		(start 29.244544 -19.962114)
		(end 30.96514 -19.962114)
		(width 0.08382)
		(layer "In2.Cu")
		(net "USB_OC0_REAR_R_N")
	)
	(segment
		(start 14.986 -22.352)
		(end 17.59712 -19.74088)
		(width 0.08382)
		(layer "In2.Cu")
		(net "USB_OC0_REAR_R_N")
	)
	(segment
		(start 10.91438 -25.653746)
		(end 10.91438 -22.86)
		(width 0.08382)
		(layer "In2.Cu")
		(net "USB_OC0_REAR_R_N")
	)
	(segment
		(start 23.7998 -100.838)
		(end 28.1686 -100.838)
		(width 0.08382)
		(layer "In2.Cu")
		(net "USB_OC0_REAR_R_N")
	)
	(segment
		(start 7.0612 -86.6902)
		(end 7.0612 -85.6488)
		(width 0.08382)
		(layer "In2.Cu")
		(net "USB_OC0_REAR_R_N")
	)
	(segment
		(start 28.36418 -19.08175)
		(end 29.244544 -19.962114)
		(width 0.08382)
		(layer "In2.Cu")
		(net "USB_OC0_REAR_R_N")
	)
	(segment
		(start 23.1902 -101.4476)
		(end 23.7998 -100.838)
		(width 0.08382)
		(layer "In2.Cu")
		(net "USB_OC0_REAR_R_N")
	)
	(segment
		(start 14.88948 -103.01732)
		(end 16.79956 -101.10724)
		(width 0.08382)
		(layer "In2.Cu")
		(net "USB_OC0_REAR_R_N")
	)
	(segment
		(start 30.96514 -19.962114)
		(end 32.512254 -18.415)
		(width 0.08382)
		(layer "In2.Cu")
		(net "USB_OC0_REAR_R_N")
	)
	(segment
		(start 32.512254 -18.415)
		(end 33.49498 -18.415)
		(width 0.08382)
		(layer "In2.Cu")
		(net "USB_OC0_REAR_R_N")
	)
	(segment
		(start 6.234176 -85.202776)
		(end 5.52958 -84.49818)
		(width 0.08382)
		(layer "In2.Cu")
		(net "USB_OC0_REAR_R_N")
	)
	(segment
		(start 24.713946 -19.837654)
		(end 27.096974 -19.837654)
		(width 0.08382)
		(layer "In2.Cu")
		(net "USB_OC0_REAR_R_N")
	)
	(segment
		(start 45.6946 -21.63572)
		(end 45.6946 -23.1902)
		(width 0.08382)
		(layer "In2.Cu")
		(net "USB_OC0_REAR_R_N")
	)
	(segment
		(start 6.996684 -27.551634)
		(end 9.016492 -27.551634)
		(width 0.08382)
		(layer "In2.Cu")
		(net "USB_OC0_REAR_R_N")
	)
	(segment
		(start 5.207 -95.0976)
		(end 4.445 -94.3356)
		(width 0.08382)
		(layer "In2.Cu")
		(net "USB_OC0_REAR_R_N")
	)
	(segment
		(start 31.41726 -84.736686)
		(end 32.385 -83.768946)
		(width 0.10668)
		(layer "In4.Cu")
		(net "USB_OC0_REAR_R_N")
	)
	(segment
		(start 32.385 -82.43316)
		(end 32.385 -81.864454)
		(width 0.10668)
		(layer "In4.Cu")
		(net "USB_OC0_REAR_R_N")
	)
	(segment
		(start 36.374578 -68.685918)
		(end 35.58286 -67.8942)
		(width 0.10668)
		(layer "In4.Cu")
		(net "USB_OC0_REAR_R_N")
	)
	(segment
		(start 31.5722 -94.91472)
		(end 32.37484 -94.11208)
		(width 0.10668)
		(layer "In4.Cu")
		(net "USB_OC0_REAR_R_N")
	)
	(segment
		(start 33.06826 -73.984612)
		(end 34.17951 -72.873362)
		(width 0.10668)
		(layer "In4.Cu")
		(net "USB_OC0_REAR_R_N")
	)
	(segment
		(start 32.21482 -87.61222)
		(end 31.41726 -86.81466)
		(width 0.10668)
		(layer "In4.Cu")
		(net "USB_OC0_REAR_R_N")
	)
	(segment
		(start 32.38754 -82.4357)
		(end 32.385 -82.43316)
		(width 0.10668)
		(layer "In4.Cu")
		(net "USB_OC0_REAR_R_N")
	)
	(segment
		(start 35.22091 -72.873362)
		(end 36.467034 -71.627492)
		(width 0.10668)
		(layer "In4.Cu")
		(net "USB_OC0_REAR_R_N")
	)
	(segment
		(start 31.41726 -86.81466)
		(end 31.41726 -84.736686)
		(width 0.10668)
		(layer "In4.Cu")
		(net "USB_OC0_REAR_R_N")
	)
	(segment
		(start 30.607 -98.9838)
		(end 31.5722 -98.0186)
		(width 0.10668)
		(layer "In4.Cu")
		(net "USB_OC0_REAR_R_N")
	)
	(segment
		(start 32.37484 -94.11208)
		(end 32.37484 -90.23604)
		(width 0.10668)
		(layer "In4.Cu")
		(net "USB_OC0_REAR_R_N")
	)
	(segment
		(start 36.467034 -71.627492)
		(end 36.648644 -71.240904)
		(width 0.10668)
		(layer "In4.Cu")
		(net "USB_OC0_REAR_R_N")
	)
	(segment
		(start 32.21482 -90.07602)
		(end 32.21482 -87.61222)
		(width 0.10668)
		(layer "In4.Cu")
		(net "USB_OC0_REAR_R_N")
	)
	(segment
		(start 35.58286 -67.8942)
		(end 35.58286 -65.405)
		(width 0.10668)
		(layer "In4.Cu")
		(net "USB_OC0_REAR_R_N")
	)
	(segment
		(start 33.06826 -81.181194)
		(end 33.06826 -73.984612)
		(width 0.10668)
		(layer "In4.Cu")
		(net "USB_OC0_REAR_R_N")
	)
	(segment
		(start 36.648644 -71.240904)
		(end 36.648644 -69.347842)
		(width 0.10668)
		(layer "In4.Cu")
		(net "USB_OC0_REAR_R_N")
	)
	(segment
		(start 30.2768 -98.9838)
		(end 30.607 -98.9838)
		(width 0.10668)
		(layer "In4.Cu")
		(net "USB_OC0_REAR_R_N")
	)
	(segment
		(start 32.38754 -82.8167)
		(end 32.38754 -82.4357)
		(width 0.10668)
		(layer "In4.Cu")
		(net "USB_OC0_REAR_R_N")
	)
	(segment
		(start 32.37484 -90.23604)
		(end 32.21482 -90.07602)
		(width 0.10668)
		(layer "In4.Cu")
		(net "USB_OC0_REAR_R_N")
	)
	(segment
		(start 32.385 -81.864454)
		(end 33.06826 -81.181194)
		(width 0.10668)
		(layer "In4.Cu")
		(net "USB_OC0_REAR_R_N")
	)
	(segment
		(start 31.5722 -98.0186)
		(end 31.5722 -94.91472)
		(width 0.10668)
		(layer "In4.Cu")
		(net "USB_OC0_REAR_R_N")
	)
	(segment
		(start 32.385 -82.81924)
		(end 32.38754 -82.8167)
		(width 0.10668)
		(layer "In4.Cu")
		(net "USB_OC0_REAR_R_N")
	)
	(segment
		(start 32.385 -83.768946)
		(end 32.385 -82.81924)
		(width 0.10668)
		(layer "In4.Cu")
		(net "USB_OC0_REAR_R_N")
	)
	(segment
		(start 34.17951 -72.873362)
		(end 35.22091 -72.873362)
		(width 0.10668)
		(layer "In4.Cu")
		(net "USB_OC0_REAR_R_N")
	)
	(segment
		(start 35.58286 -65.405)
		(end 35.88512 -65.10274)
		(width 0.10668)
		(layer "In4.Cu")
		(net "USB_OC0_REAR_R_N")
	)
	(segment
		(start 36.648644 -69.347842)
		(end 36.374578 -68.685918)
		(width 0.10668)
		(layer "In4.Cu")
		(net "USB_OC0_REAR_R_N")
	)
	(segment
		(start 47.26305 -24.384)
		(end 47.26305 -23.368)
		(width 0.11684)
		(layer "F.Cu")
		(net "USB_OC0_REAR_N")
	)
	(segment
		(start 48.5394 -24.400764)
		(end 47.279814 -24.400764)
		(width 0.11684)
		(layer "F.Cu")
		(net "USB_OC0_REAR_N")
	)
	(segment
		(start 47.279814 -24.400764)
		(end 47.26305 -24.384)
		(width 0.11684)
		(layer "F.Cu")
		(net "USB_OC0_REAR_N")
	)
	(segment
		(start 50.066194 -24.400764)
		(end 48.5394 -24.400764)
		(width 0.11684)
		(layer "F.Cu")
		(net "USB_OC0_REAR_N")
	)
	(via
		(at 48.5394 -24.400764)
		(size 0.762)
		(drill 0.381)
		(layers "F.Cu" "B.Cu")
		(net "USB_OC0_REAR_N")
	)
	(segment
		(start 50.066194 -23.450804)
		(end 49.00295 -23.450804)
		(width 0.11684)
		(layer "F.Cu")
		(net "USB_OC0_ILIM")
	)
	(segment
		(start 47.904146 -22.352)
		(end 47.26305 -22.352)
		(width 0.11684)
		(layer "F.Cu")
		(net "USB_OC0_ILIM")
	)
	(segment
		(start 49.00295 -23.450804)
		(end 48.491648 -22.939502)
		(width 0.11684)
		(layer "F.Cu")
		(net "USB_OC0_ILIM")
	)
	(segment
		(start 48.491648 -22.939502)
		(end 47.904146 -22.352)
		(width 0.11684)
		(layer "F.Cu")
		(net "USB_OC0_ILIM")
	)
	(via
		(at 48.491648 -22.939502)
		(size 0.762)
		(drill 0.381)
		(layers "F.Cu" "B.Cu")
		(net "USB_OC0_ILIM")
	)
	(segment
		(start 52.3748 -25.9588)
		(end 53.3908 -25.9588)
		(width 0.11684)
		(layer "F.Cu")
		(net "USB_OC0_EN")
	)
	(segment
		(start 53.4924 -25.8572)
		(end 54.389274 -25.8572)
		(width 0.11684)
		(layer "F.Cu")
		(net "USB_OC0_EN")
	)
	(segment
		(start 51.562 -24.5872)
		(end 51.748436 -24.400764)
		(width 0.11684)
		(layer "F.Cu")
		(net "USB_OC0_EN")
	)
	(segment
		(start 54.389274 -25.8572)
		(end 54.44363 -25.911556)
		(width 0.11684)
		(layer "F.Cu")
		(net "USB_OC0_EN")
	)
	(segment
		(start 51.943 -25.9588)
		(end 51.562 -25.5778)
		(width 0.11684)
		(layer "F.Cu")
		(net "USB_OC0_EN")
	)
	(segment
		(start 51.562 -25.5778)
		(end 51.562 -24.5872)
		(width 0.11684)
		(layer "F.Cu")
		(net "USB_OC0_EN")
	)
	(segment
		(start 53.3908 -25.9588)
		(end 53.4924 -25.8572)
		(width 0.11684)
		(layer "F.Cu")
		(net "USB_OC0_EN")
	)
	(segment
		(start 52.3748 -25.9588)
		(end 51.943 -25.9588)
		(width 0.11684)
		(layer "F.Cu")
		(net "USB_OC0_EN")
	)
	(segment
		(start 51.748436 -24.400764)
		(end 52.316126 -24.400764)
		(width 0.11684)
		(layer "F.Cu")
		(net "USB_OC0_EN")
	)
	(segment
		(start 54.44363 -25.911556)
		(end 54.44363 -24.887936)
		(width 0.11684)
		(layer "F.Cu")
		(net "USB_OC0_EN")
	)
	(via
		(at 52.3748 -25.9588)
		(size 0.762)
		(drill 0.381)
		(layers "F.Cu" "B.Cu")
		(net "USB_OC0_EN")
	)
	(segment
		(start 21.4503 -114.07775)
		(end 21.71446 -113.81359)
		(width 0.14224)
		(layer "F.Cu")
		(net "USB_FPNL_DP")
	)
	(segment
		(start 21.4503 -114.468402)
		(end 21.4503 -114.07775)
		(width 0.14224)
		(layer "F.Cu")
		(net "USB_FPNL_DP")
	)
	(segment
		(start 27.038046 -16.3195)
		(end 27.278838 -16.078708)
		(width 0.14224)
		(layer "F.Cu")
		(net "USB_FPNL_DP")
	)
	(segment
		(start 27.870404 -15.992602)
		(end 27.510232 -15.992602)
		(width 0.14224)
		(layer "F.Cu")
		(net "USB_FPNL_DP")
	)
	(segment
		(start 22.744938 -118.25986)
		(end 22.744938 -117.534436)
		(width 0.14224)
		(layer "F.Cu")
		(net "USB_FPNL_DP")
	)
	(segment
		(start 26.21661 -16.3195)
		(end 27.038046 -16.3195)
		(width 0.14224)
		(layer "F.Cu")
		(net "USB_FPNL_DP")
	)
	(segment
		(start 22.629114 -117.418612)
		(end 22.629114 -116.03736)
		(width 0.14224)
		(layer "F.Cu")
		(net "USB_FPNL_DP")
	)
	(segment
		(start 21.726398 -115.13439)
		(end 21.4503 -114.468402)
		(width 0.14224)
		(layer "F.Cu")
		(net "USB_FPNL_DP")
	)
	(segment
		(start 25.95626 -16.05915)
		(end 26.21661 -16.3195)
		(width 0.14224)
		(layer "F.Cu")
		(net "USB_FPNL_DP")
	)
	(segment
		(start 27.510232 -15.992602)
		(end 27.424126 -16.078708)
		(width 0.14224)
		(layer "F.Cu")
		(net "USB_FPNL_DP")
	)
	(segment
		(start 22.629114 -116.03736)
		(end 21.726398 -115.13439)
		(width 0.14224)
		(layer "F.Cu")
		(net "USB_FPNL_DP")
	)
	(segment
		(start 27.278838 -16.078708)
		(end 27.424126 -16.078708)
		(width 0.14224)
		(layer "F.Cu")
		(net "USB_FPNL_DP")
	)
	(segment
		(start 22.744938 -117.534436)
		(end 22.629114 -117.418612)
		(width 0.14224)
		(layer "F.Cu")
		(net "USB_FPNL_DP")
	)
	(via
		(at 25.95626 -16.05915)
		(size 0.508)
		(drill 0.254)
		(layers "F.Cu" "B.Cu")
		(net "USB_FPNL_DP")
	)
	(via
		(at 21.71446 -113.81359)
		(size 0.508)
		(drill 0.254)
		(layers "F.Cu" "B.Cu")
		(net "USB_FPNL_DP")
	)
	(segment
		(start 1.326642 -78.493112)
		(end 4.076446 -81.242916)
		(width 0.1143)
		(layer "In2.Cu")
		(net "USB_FPNL_DP")
	)
	(segment
		(start 5.831078 -26.1112)
		(end 1.326642 -30.615636)
		(width 0.1143)
		(layer "In2.Cu")
		(net "USB_FPNL_DP")
	)
	(segment
		(start 25.732994 -16.282416)
		(end 25.643332 -16.282416)
		(width 0.1143)
		(layer "In2.Cu")
		(net "USB_FPNL_DP")
	)
	(segment
		(start 15.448534 -113.03508)
		(end 19.92503 -114.88928)
		(width 0.1143)
		(layer "In2.Cu")
		(net "USB_FPNL_DP")
	)
	(segment
		(start 3.780536 -85.602318)
		(end 1.77292 -87.609934)
		(width 0.1143)
		(layer "In2.Cu")
		(net "USB_FPNL_DP")
	)
	(segment
		(start 5.258054 -112.1918)
		(end 12.243054 -112.1918)
		(width 0.1143)
		(layer "In2.Cu")
		(net "USB_FPNL_DP")
	)
	(segment
		(start 9.4742 -23.952454)
		(end 7.315454 -26.1112)
		(width 0.1143)
		(layer "In2.Cu")
		(net "USB_FPNL_DP")
	)
	(segment
		(start 19.92503 -114.88928)
		(end 20.939506 -114.88928)
		(width 0.1143)
		(layer "In2.Cu")
		(net "USB_FPNL_DP")
	)
	(segment
		(start 2.460244 -109.39399)
		(end 5.258054 -112.1918)
		(width 0.1143)
		(layer "In2.Cu")
		(net "USB_FPNL_DP")
	)
	(segment
		(start 7.315454 -26.1112)
		(end 5.831078 -26.1112)
		(width 0.1143)
		(layer "In2.Cu")
		(net "USB_FPNL_DP")
	)
	(segment
		(start 1.326642 -30.615636)
		(end 1.326642 -78.493112)
		(width 0.1143)
		(layer "In2.Cu")
		(net "USB_FPNL_DP")
	)
	(segment
		(start 1.77292 -87.609934)
		(end 1.77292 -107.735116)
		(width 0.1143)
		(layer "In2.Cu")
		(net "USB_FPNL_DP")
	)
	(segment
		(start 3.93446 -85.229954)
		(end 3.780536 -85.602318)
		(width 0.1143)
		(layer "In2.Cu")
		(net "USB_FPNL_DP")
	)
	(segment
		(start 21.4376 -114.09045)
		(end 21.71446 -113.81359)
		(width 0.1143)
		(layer "In2.Cu")
		(net "USB_FPNL_DP")
	)
	(segment
		(start 12.243054 -112.1918)
		(end 13.086334 -113.03508)
		(width 0.1143)
		(layer "In2.Cu")
		(net "USB_FPNL_DP")
	)
	(segment
		(start 21.4376 -114.391186)
		(end 21.4376 -114.09045)
		(width 0.1143)
		(layer "In2.Cu")
		(net "USB_FPNL_DP")
	)
	(segment
		(start 24.353012 -15.748)
		(end 14.986 -15.748)
		(width 0.1143)
		(layer "In2.Cu")
		(net "USB_FPNL_DP")
	)
	(segment
		(start 4.076446 -81.242916)
		(end 4.076446 -84.88807)
		(width 0.1143)
		(layer "In2.Cu")
		(net "USB_FPNL_DP")
	)
	(segment
		(start 3.934714 -85.229954)
		(end 3.93446 -85.229954)
		(width 0.1143)
		(layer "In2.Cu")
		(net "USB_FPNL_DP")
	)
	(segment
		(start 13.086334 -113.03508)
		(end 15.448534 -113.03508)
		(width 0.1143)
		(layer "In2.Cu")
		(net "USB_FPNL_DP")
	)
	(segment
		(start 25.95626 -16.05915)
		(end 25.732994 -16.282416)
		(width 0.1143)
		(layer "In2.Cu")
		(net "USB_FPNL_DP")
	)
	(segment
		(start 1.77292 -107.735116)
		(end 2.460244 -109.39399)
		(width 0.1143)
		(layer "In2.Cu")
		(net "USB_FPNL_DP")
	)
	(segment
		(start 9.4742 -21.2598)
		(end 9.4742 -23.952454)
		(width 0.1143)
		(layer "In2.Cu")
		(net "USB_FPNL_DP")
	)
	(segment
		(start 25.643332 -16.282416)
		(end 24.353012 -15.748)
		(width 0.1143)
		(layer "In2.Cu")
		(net "USB_FPNL_DP")
	)
	(segment
		(start 20.939506 -114.88928)
		(end 21.4376 -114.391186)
		(width 0.1143)
		(layer "In2.Cu")
		(net "USB_FPNL_DP")
	)
	(segment
		(start 4.076446 -84.88807)
		(end 3.934714 -85.229954)
		(width 0.1143)
		(layer "In2.Cu")
		(net "USB_FPNL_DP")
	)
	(segment
		(start 14.986 -15.748)
		(end 9.4742 -21.2598)
		(width 0.1143)
		(layer "In2.Cu")
		(net "USB_FPNL_DP")
	)
	(segment
		(start 22.14499 -118.25986)
		(end 22.14499 -117.529864)
		(width 0.14224)
		(layer "F.Cu")
		(net "USB_FPNL_DN")
	)
	(segment
		(start 21.413978 -115.343178)
		(end 21.082 -114.541808)
		(width 0.14224)
		(layer "F.Cu")
		(net "USB_FPNL_DN")
	)
	(segment
		(start 21.082 -114.541808)
		(end 21.082 -114.07013)
		(width 0.14224)
		(layer "F.Cu")
		(net "USB_FPNL_DN")
	)
	(segment
		(start 27.504136 -17.008602)
		(end 27.424126 -16.928592)
		(width 0.14224)
		(layer "F.Cu")
		(net "USB_FPNL_DN")
	)
	(segment
		(start 21.082 -114.07013)
		(end 20.82546 -113.81359)
		(width 0.14224)
		(layer "F.Cu")
		(net "USB_FPNL_DN")
	)
	(segment
		(start 27.025854 -16.6878)
		(end 27.266646 -16.928592)
		(width 0.14224)
		(layer "F.Cu")
		(net "USB_FPNL_DN")
	)
	(segment
		(start 22.260814 -117.41404)
		(end 22.260814 -116.190014)
		(width 0.14224)
		(layer "F.Cu")
		(net "USB_FPNL_DN")
	)
	(segment
		(start 27.870404 -17.008602)
		(end 27.504136 -17.008602)
		(width 0.14224)
		(layer "F.Cu")
		(net "USB_FPNL_DN")
	)
	(segment
		(start 22.260814 -116.190014)
		(end 21.413978 -115.343178)
		(width 0.14224)
		(layer "F.Cu")
		(net "USB_FPNL_DN")
	)
	(segment
		(start 25.95626 -16.94815)
		(end 26.21661 -16.6878)
		(width 0.14224)
		(layer "F.Cu")
		(net "USB_FPNL_DN")
	)
	(segment
		(start 27.266646 -16.928592)
		(end 27.424126 -16.928592)
		(width 0.14224)
		(layer "F.Cu")
		(net "USB_FPNL_DN")
	)
	(segment
		(start 22.14499 -117.529864)
		(end 22.260814 -117.41404)
		(width 0.14224)
		(layer "F.Cu")
		(net "USB_FPNL_DN")
	)
	(segment
		(start 26.21661 -16.6878)
		(end 27.025854 -16.6878)
		(width 0.14224)
		(layer "F.Cu")
		(net "USB_FPNL_DN")
	)
	(via
		(at 25.95626 -16.94815)
		(size 0.508)
		(drill 0.254)
		(layers "F.Cu" "B.Cu")
		(net "USB_FPNL_DN")
	)
	(via
		(at 20.82546 -113.81359)
		(size 0.508)
		(drill 0.254)
		(layers "F.Cu" "B.Cu")
		(net "USB_FPNL_DN")
	)
	(segment
		(start 18.710656 -16.08328)
		(end 18.494756 -16.29918)
		(width 0.1143)
		(layer "In2.Cu")
		(net "USB_FPNL_DN")
	)
	(segment
		(start 17.877282 -113.677954)
		(end 18.142712 -113.567972)
		(width 0.1143)
		(layer "In2.Cu")
		(net "USB_FPNL_DN")
	)
	(segment
		(start 19.271742 -114.035586)
		(end 19.57705 -114.162078)
		(width 0.1143)
		(layer "In2.Cu")
		(net "USB_FPNL_DN")
	)
	(segment
		(start 8.2677 -111.85652)
		(end 10.7569 -111.85652)
		(width 0.1143)
		(layer "In2.Cu")
		(net "USB_FPNL_DN")
	)
	(segment
		(start 4.017518 -85.839554)
		(end 2.1082 -87.748872)
		(width 0.1143)
		(layer "In2.Cu")
		(net "USB_FPNL_DN")
	)
	(segment
		(start 17.572228 -113.551462)
		(end 17.877282 -113.6777)
		(width 0.1143)
		(layer "In2.Cu")
		(net "USB_FPNL_DN")
	)
	(segment
		(start 9.80948 -21.398738)
		(end 9.80948 -24.091392)
		(width 0.1143)
		(layer "In2.Cu")
		(net "USB_FPNL_DN")
	)
	(segment
		(start 19.006058 -114.145568)
		(end 19.271742 -114.035586)
		(width 0.1143)
		(layer "In2.Cu")
		(net "USB_FPNL_DN")
	)
	(segment
		(start 11.4935 -111.85652)
		(end 12.381992 -111.85652)
		(width 0.1143)
		(layer "In2.Cu")
		(net "USB_FPNL_DN")
	)
	(segment
		(start 20.006564 -16.08328)
		(end 19.790664 -16.29918)
		(width 0.1143)
		(layer "In2.Cu")
		(net "USB_FPNL_DN")
	)
	(segment
		(start 19.57705 -114.162078)
		(end 19.686778 -114.427762)
		(width 0.1143)
		(layer "In2.Cu")
		(net "USB_FPNL_DN")
	)
	(segment
		(start 25.95626 -16.94815)
		(end 25.625806 -16.617696)
		(width 0.1143)
		(layer "In2.Cu")
		(net "USB_FPNL_DN")
	)
	(segment
		(start 7.454392 -26.44648)
		(end 5.970016 -26.44648)
		(width 0.1143)
		(layer "In2.Cu")
		(net "USB_FPNL_DN")
	)
	(segment
		(start 11.2903 -111.65332)
		(end 11.4935 -111.85652)
		(width 0.1143)
		(layer "In2.Cu")
		(net "USB_FPNL_DN")
	)
	(segment
		(start 18.558002 -113.959894)
		(end 19.006058 -114.145568)
		(width 0.1143)
		(layer "In2.Cu")
		(net "USB_FPNL_DN")
	)
	(segment
		(start 7.5311 -111.85652)
		(end 7.7343 -111.65332)
		(width 0.1143)
		(layer "In2.Cu")
		(net "USB_FPNL_DN")
	)
	(segment
		(start 17.935956 -16.08328)
		(end 15.124938 -16.08328)
		(width 0.1143)
		(layer "In2.Cu")
		(net "USB_FPNL_DN")
	)
	(segment
		(start 19.991832 -114.554)
		(end 20.800568 -114.554)
		(width 0.1143)
		(layer "In2.Cu")
		(net "USB_FPNL_DN")
	)
	(segment
		(start 5.396992 -111.85652)
		(end 7.5311 -111.85652)
		(width 0.1143)
		(layer "In2.Cu")
		(net "USB_FPNL_DN")
	)
	(segment
		(start 21.467064 -16.08328)
		(end 21.124164 -16.08328)
		(width 0.1143)
		(layer "In2.Cu")
		(net "USB_FPNL_DN")
	)
	(segment
		(start 5.970016 -26.44648)
		(end 1.661922 -30.754574)
		(width 0.1143)
		(layer "In2.Cu")
		(net "USB_FPNL_DN")
	)
	(segment
		(start 17.156938 -113.15954)
		(end 17.462246 -113.286032)
		(width 0.1143)
		(layer "In2.Cu")
		(net "USB_FPNL_DN")
	)
	(segment
		(start 21.124164 -16.08328)
		(end 20.908264 -16.29918)
		(width 0.1143)
		(layer "In2.Cu")
		(net "USB_FPNL_DN")
	)
	(segment
		(start 2.74447 -109.203998)
		(end 5.396992 -111.85652)
		(width 0.1143)
		(layer "In2.Cu")
		(net "USB_FPNL_DN")
	)
	(segment
		(start 4.017518 -85.839808)
		(end 4.017518 -85.839554)
		(width 0.1143)
		(layer "In2.Cu")
		(net "USB_FPNL_DN")
	)
	(segment
		(start 2.1082 -87.748872)
		(end 2.1082 -107.668314)
		(width 0.1143)
		(layer "In2.Cu")
		(net "USB_FPNL_DN")
	)
	(segment
		(start 19.686778 -114.427508)
		(end 19.991832 -114.554)
		(width 0.1143)
		(layer "In2.Cu")
		(net "USB_FPNL_DN")
	)
	(segment
		(start 19.231864 -16.08328)
		(end 18.710656 -16.08328)
		(width 0.1143)
		(layer "In2.Cu")
		(net "USB_FPNL_DN")
	)
	(segment
		(start 4.411726 -84.954872)
		(end 4.065016 -85.79231)
		(width 0.1143)
		(layer "In2.Cu")
		(net "USB_FPNL_DN")
	)
	(segment
		(start 22.025864 -16.29918)
		(end 21.682964 -16.29918)
		(width 0.1143)
		(layer "In2.Cu")
		(net "USB_FPNL_DN")
	)
	(segment
		(start 12.381992 -111.85652)
		(end 13.225272 -112.6998)
		(width 0.1143)
		(layer "In2.Cu")
		(net "USB_FPNL_DN")
	)
	(segment
		(start 20.908264 -16.29918)
		(end 20.565364 -16.29918)
		(width 0.1143)
		(layer "In2.Cu")
		(net "USB_FPNL_DN")
	)
	(segment
		(start 1.661922 -30.754574)
		(end 1.661922 -78.354174)
		(width 0.1143)
		(layer "In2.Cu")
		(net "USB_FPNL_DN")
	)
	(segment
		(start 7.7343 -111.65332)
		(end 8.0645 -111.65332)
		(width 0.1143)
		(layer "In2.Cu")
		(net "USB_FPNL_DN")
	)
	(segment
		(start 25.625806 -16.617696)
		(end 25.57653 -16.617696)
		(width 0.1143)
		(layer "In2.Cu")
		(net "USB_FPNL_DN")
	)
	(segment
		(start 16.891508 -113.269522)
		(end 17.156938 -113.15954)
		(width 0.1143)
		(layer "In2.Cu")
		(net "USB_FPNL_DN")
	)
	(segment
		(start 25.57653 -16.617696)
		(end 24.28621 -16.08328)
		(width 0.1143)
		(layer "In2.Cu")
		(net "USB_FPNL_DN")
	)
	(segment
		(start 18.151856 -16.29918)
		(end 17.935956 -16.08328)
		(width 0.1143)
		(layer "In2.Cu")
		(net "USB_FPNL_DN")
	)
	(segment
		(start 10.9601 -111.65332)
		(end 11.2903 -111.65332)
		(width 0.1143)
		(layer "In2.Cu")
		(net "USB_FPNL_DN")
	)
	(segment
		(start 18.44802 -113.69421)
		(end 18.558002 -113.960148)
		(width 0.1143)
		(layer "In2.Cu")
		(net "USB_FPNL_DN")
	)
	(segment
		(start 15.515336 -112.6998)
		(end 16.891508 -113.269522)
		(width 0.1143)
		(layer "In2.Cu")
		(net "USB_FPNL_DN")
	)
	(segment
		(start 21.682964 -16.29918)
		(end 21.467064 -16.08328)
		(width 0.1143)
		(layer "In2.Cu")
		(net "USB_FPNL_DN")
	)
	(segment
		(start 9.80948 -24.091392)
		(end 7.454392 -26.44648)
		(width 0.1143)
		(layer "In2.Cu")
		(net "USB_FPNL_DN")
	)
	(segment
		(start 17.462246 -113.286032)
		(end 17.572228 -113.551716)
		(width 0.1143)
		(layer "In2.Cu")
		(net "USB_FPNL_DN")
	)
	(segment
		(start 18.494756 -16.29918)
		(end 18.151856 -16.29918)
		(width 0.1143)
		(layer "In2.Cu")
		(net "USB_FPNL_DN")
	)
	(segment
		(start 18.142712 -113.567972)
		(end 18.44802 -113.69421)
		(width 0.1143)
		(layer "In2.Cu")
		(net "USB_FPNL_DN")
	)
	(segment
		(start 15.124938 -16.08328)
		(end 9.80948 -21.398738)
		(width 0.1143)
		(layer "In2.Cu")
		(net "USB_FPNL_DN")
	)
	(segment
		(start 19.790664 -16.29918)
		(end 19.447764 -16.29918)
		(width 0.1143)
		(layer "In2.Cu")
		(net "USB_FPNL_DN")
	)
	(segment
		(start 20.800568 -114.554)
		(end 21.10232 -114.252248)
		(width 0.1143)
		(layer "In2.Cu")
		(net "USB_FPNL_DN")
	)
	(segment
		(start 21.10232 -114.09045)
		(end 20.82546 -113.81359)
		(width 0.1143)
		(layer "In2.Cu")
		(net "USB_FPNL_DN")
	)
	(segment
		(start 20.349464 -16.08328)
		(end 20.006564 -16.08328)
		(width 0.1143)
		(layer "In2.Cu")
		(net "USB_FPNL_DN")
	)
	(segment
		(start 4.065016 -85.79231)
		(end 4.017518 -85.839808)
		(width 0.1143)
		(layer "In2.Cu")
		(net "USB_FPNL_DN")
	)
	(segment
		(start 13.225272 -112.6998)
		(end 15.515336 -112.6998)
		(width 0.1143)
		(layer "In2.Cu")
		(net "USB_FPNL_DN")
	)
	(segment
		(start 8.0645 -111.65332)
		(end 8.2677 -111.85652)
		(width 0.1143)
		(layer "In2.Cu")
		(net "USB_FPNL_DN")
	)
	(segment
		(start 17.572228 -113.551716)
		(end 17.572228 -113.551462)
		(width 0.1143)
		(layer "In2.Cu")
		(net "USB_FPNL_DN")
	)
	(segment
		(start 24.28621 -16.08328)
		(end 22.241764 -16.08328)
		(width 0.1143)
		(layer "In2.Cu")
		(net "USB_FPNL_DN")
	)
	(segment
		(start 21.10232 -114.252248)
		(end 21.10232 -114.09045)
		(width 0.1143)
		(layer "In2.Cu")
		(net "USB_FPNL_DN")
	)
	(segment
		(start 18.558002 -113.960148)
		(end 18.558002 -113.959894)
		(width 0.1143)
		(layer "In2.Cu")
		(net "USB_FPNL_DN")
	)
	(segment
		(start 20.565364 -16.29918)
		(end 20.349464 -16.08328)
		(width 0.1143)
		(layer "In2.Cu")
		(net "USB_FPNL_DN")
	)
	(segment
		(start 17.877282 -113.6777)
		(end 17.877282 -113.677954)
		(width 0.1143)
		(layer "In2.Cu")
		(net "USB_FPNL_DN")
	)
	(segment
		(start 10.7569 -111.85652)
		(end 10.9601 -111.65332)
		(width 0.1143)
		(layer "In2.Cu")
		(net "USB_FPNL_DN")
	)
	(segment
		(start 19.447764 -16.29918)
		(end 19.231864 -16.08328)
		(width 0.1143)
		(layer "In2.Cu")
		(net "USB_FPNL_DN")
	)
	(segment
		(start 1.661922 -78.354174)
		(end 4.411726 -81.103978)
		(width 0.1143)
		(layer "In2.Cu")
		(net "USB_FPNL_DN")
	)
	(segment
		(start 22.241764 -16.08328)
		(end 22.025864 -16.29918)
		(width 0.1143)
		(layer "In2.Cu")
		(net "USB_FPNL_DN")
	)
	(segment
		(start 19.686778 -114.427762)
		(end 19.686778 -114.427508)
		(width 0.1143)
		(layer "In2.Cu")
		(net "USB_FPNL_DN")
	)
	(segment
		(start 2.1082 -107.668314)
		(end 2.74447 -109.203998)
		(width 0.1143)
		(layer "In2.Cu")
		(net "USB_FPNL_DN")
	)
	(segment
		(start 4.411726 -81.103978)
		(end 4.411726 -84.954872)
		(width 0.1143)
		(layer "In2.Cu")
		(net "USB_FPNL_DN")
	)
	(segment
		(start 37.304726 -13.784834)
		(end 38.785292 -11.5697)
		(width 0.14224)
		(layer "F.Cu")
		(net "USB2_01_F_DP")
	)
	(segment
		(start 29.037788 -15.992602)
		(end 29.123894 -16.078708)
		(width 0.14224)
		(layer "F.Cu")
		(net "USB2_01_F_DP")
	)
	(segment
		(start 33.473898 -16.319246)
		(end 34.711132 -16.319246)
		(width 0.14224)
		(layer "F.Cu")
		(net "USB2_01_F_DP")
	)
	(segment
		(start 43.10634 -11.800586)
		(end 43.10634 -13.237718)
		(width 0.14224)
		(layer "F.Cu")
		(net "USB2_01_F_DP")
	)
	(segment
		(start 29.295598 -16.078708)
		(end 29.536136 -16.319246)
		(width 0.14224)
		(layer "F.Cu")
		(net "USB2_01_F_DP")
	)
	(segment
		(start 29.123894 -16.078708)
		(end 29.295598 -16.078708)
		(width 0.14224)
		(layer "F.Cu")
		(net "USB2_01_F_DP")
	)
	(segment
		(start 42.496486 -11.190732)
		(end 43.10634 -11.800586)
		(width 0.14224)
		(layer "F.Cu")
		(net "USB2_01_F_DP")
	)
	(segment
		(start 31.842202 -16.319246)
		(end 32.65805 -15.503398)
		(width 0.14224)
		(layer "F.Cu")
		(net "USB2_01_F_DP")
	)
	(segment
		(start 35.856672 -15.84452)
		(end 37.304726 -14.396466)
		(width 0.14224)
		(layer "F.Cu")
		(net "USB2_01_F_DP")
	)
	(segment
		(start 34.711132 -16.319246)
		(end 35.856672 -15.84452)
		(width 0.14224)
		(layer "F.Cu")
		(net "USB2_01_F_DP")
	)
	(segment
		(start 43.24858 -13.379958)
		(end 43.922188 -13.379958)
		(width 0.14224)
		(layer "F.Cu")
		(net "USB2_01_F_DP")
	)
	(segment
		(start 28.670504 -15.992602)
		(end 29.037788 -15.992602)
		(width 0.14224)
		(layer "F.Cu")
		(net "USB2_01_F_DP")
	)
	(segment
		(start 29.536136 -16.319246)
		(end 31.842202 -16.319246)
		(width 0.14224)
		(layer "F.Cu")
		(net "USB2_01_F_DP")
	)
	(segment
		(start 37.304726 -14.396466)
		(end 37.304726 -13.784834)
		(width 0.14224)
		(layer "F.Cu")
		(net "USB2_01_F_DP")
	)
	(segment
		(start 39.164514 -11.190732)
		(end 42.496486 -11.190732)
		(width 0.14224)
		(layer "F.Cu")
		(net "USB2_01_F_DP")
	)
	(segment
		(start 38.785292 -11.5697)
		(end 39.164514 -11.190732)
		(width 0.14224)
		(layer "F.Cu")
		(net "USB2_01_F_DP")
	)
	(segment
		(start 32.65805 -15.503398)
		(end 33.473898 -16.319246)
		(width 0.14224)
		(layer "F.Cu")
		(net "USB2_01_F_DP")
	)
	(segment
		(start 43.10634 -13.237718)
		(end 43.24858 -13.379958)
		(width 0.14224)
		(layer "F.Cu")
		(net "USB2_01_F_DP")
	)
	(segment
		(start 42.5958 -13.379958)
		(end 41.922192 -13.379958)
		(width 0.14224)
		(layer "F.Cu")
		(net "USB2_01_F_DN")
	)
	(segment
		(start 33.473898 -16.687546)
		(end 34.784538 -16.687546)
		(width 0.14224)
		(layer "F.Cu")
		(net "USB2_01_F_DN")
	)
	(segment
		(start 40.841168 -11.559032)
		(end 41.103296 -11.82116)
		(width 0.14224)
		(layer "F.Cu")
		(net "USB2_01_F_DN")
	)
	(segment
		(start 42.343832 -11.559032)
		(end 42.73804 -11.95324)
		(width 0.14224)
		(layer "F.Cu")
		(net "USB2_01_F_DN")
	)
	(segment
		(start 42.73804 -13.237718)
		(end 42.5958 -13.379958)
		(width 0.14224)
		(layer "F.Cu")
		(net "USB2_01_F_DN")
	)
	(segment
		(start 38.463982 -12.713462)
		(end 39.07155 -11.80465)
		(width 0.14224)
		(layer "F.Cu")
		(net "USB2_01_F_DN")
	)
	(segment
		(start 39.540688 -11.559032)
		(end 39.792656 -11.811)
		(width 0.14224)
		(layer "F.Cu")
		(net "USB2_01_F_DN")
	)
	(segment
		(start 41.103296 -11.82116)
		(end 41.4528 -11.82116)
		(width 0.14224)
		(layer "F.Cu")
		(net "USB2_01_F_DN")
	)
	(segment
		(start 37.673026 -13.896848)
		(end 37.97808 -13.440156)
		(width 0.14224)
		(layer "F.Cu")
		(net "USB2_01_F_DN")
	)
	(segment
		(start 39.07155 -11.80465)
		(end 39.317168 -11.559032)
		(width 0.14224)
		(layer "F.Cu")
		(net "USB2_01_F_DN")
	)
	(segment
		(start 34.784538 -16.687546)
		(end 35.424872 -16.422116)
		(width 0.14224)
		(layer "F.Cu")
		(net "USB2_01_F_DN")
	)
	(segment
		(start 31.842202 -16.687546)
		(end 32.65805 -17.503394)
		(width 0.14224)
		(layer "F.Cu")
		(net "USB2_01_F_DN")
	)
	(segment
		(start 36.06546 -16.15694)
		(end 37.673026 -14.549374)
		(width 0.14224)
		(layer "F.Cu")
		(net "USB2_01_F_DN")
	)
	(segment
		(start 29.540708 -16.687546)
		(end 31.842202 -16.687546)
		(width 0.14224)
		(layer "F.Cu")
		(net "USB2_01_F_DN")
	)
	(segment
		(start 40.414448 -11.559032)
		(end 40.841168 -11.559032)
		(width 0.14224)
		(layer "F.Cu")
		(net "USB2_01_F_DN")
	)
	(segment
		(start 41.714928 -11.559032)
		(end 42.343832 -11.559032)
		(width 0.14224)
		(layer "F.Cu")
		(net "USB2_01_F_DN")
	)
	(segment
		(start 38.525704 -13.023596)
		(end 38.463982 -12.713462)
		(width 0.14224)
		(layer "F.Cu")
		(net "USB2_01_F_DN")
	)
	(segment
		(start 35.424872 -16.422116)
		(end 35.425126 -16.422116)
		(width 0.14224)
		(layer "F.Cu")
		(net "USB2_01_F_DN")
	)
	(segment
		(start 37.97808 -13.440156)
		(end 38.288468 -13.378688)
		(width 0.14224)
		(layer "F.Cu")
		(net "USB2_01_F_DN")
	)
	(segment
		(start 38.288468 -13.378688)
		(end 38.525704 -13.023596)
		(width 0.14224)
		(layer "F.Cu")
		(net "USB2_01_F_DN")
	)
	(segment
		(start 39.792656 -11.811)
		(end 40.16248 -11.811)
		(width 0.14224)
		(layer "F.Cu")
		(net "USB2_01_F_DN")
	)
	(segment
		(start 29.299662 -16.928592)
		(end 29.540708 -16.687546)
		(width 0.14224)
		(layer "F.Cu")
		(net "USB2_01_F_DN")
	)
	(segment
		(start 29.123894 -16.928592)
		(end 29.299662 -16.928592)
		(width 0.14224)
		(layer "F.Cu")
		(net "USB2_01_F_DN")
	)
	(segment
		(start 32.65805 -17.503394)
		(end 33.473898 -16.687546)
		(width 0.14224)
		(layer "F.Cu")
		(net "USB2_01_F_DN")
	)
	(segment
		(start 37.673026 -14.549374)
		(end 37.673026 -13.896848)
		(width 0.14224)
		(layer "F.Cu")
		(net "USB2_01_F_DN")
	)
	(segment
		(start 40.16248 -11.811)
		(end 40.414448 -11.559032)
		(width 0.14224)
		(layer "F.Cu")
		(net "USB2_01_F_DN")
	)
	(segment
		(start 29.043884 -17.008602)
		(end 29.123894 -16.928592)
		(width 0.14224)
		(layer "F.Cu")
		(net "USB2_01_F_DN")
	)
	(segment
		(start 28.670504 -17.008602)
		(end 29.043884 -17.008602)
		(width 0.14224)
		(layer "F.Cu")
		(net "USB2_01_F_DN")
	)
	(segment
		(start 42.73804 -11.95324)
		(end 42.73804 -13.237718)
		(width 0.14224)
		(layer "F.Cu")
		(net "USB2_01_F_DN")
	)
	(segment
		(start 35.425126 -16.422116)
		(end 36.06546 -16.15694)
		(width 0.14224)
		(layer "F.Cu")
		(net "USB2_01_F_DN")
	)
	(segment
		(start 39.317168 -11.559032)
		(end 39.540688 -11.559032)
		(width 0.14224)
		(layer "F.Cu")
		(net "USB2_01_F_DN")
	)
	(segment
		(start 41.4528 -11.82116)
		(end 41.714928 -11.559032)
		(width 0.14224)
		(layer "F.Cu")
		(net "USB2_01_F_DN")
	)
	(via
		(at 55.68188 -78.12532)
		(size 0.6604)
		(drill 0.3302)
		(layers "F.Cu" "B.Cu")
		(net "TP_BIOS_MUX0_PIN14")
	)
	(segment
		(start 54.36489 -78.98511)
		(end 55.22468 -78.12532)
		(width 0.11684)
		(layer "B.Cu")
		(net "TP_BIOS_MUX0_PIN14")
	)
	(segment
		(start 55.22468 -78.12532)
		(end 55.68188 -78.12532)
		(width 0.11684)
		(layer "B.Cu")
		(net "TP_BIOS_MUX0_PIN14")
	)
	(segment
		(start 51.861466 -78.98511)
		(end 54.36489 -78.98511)
		(width 0.11684)
		(layer "B.Cu")
		(net "TP_BIOS_MUX0_PIN14")
	)
	(via
		(at 53.53558 -79.635096)
		(size 0.6604)
		(drill 0.3302)
		(layers "F.Cu" "B.Cu")
		(net "TP_BIOS_MUX0_PIN13")
	)
	(segment
		(start 51.861466 -79.635096)
		(end 53.53558 -79.635096)
		(width 0.11684)
		(layer "B.Cu")
		(net "TP_BIOS_MUX0_PIN13")
	)
	(via
		(at 55.499 -80.9752)
		(size 0.6604)
		(drill 0.3302)
		(layers "F.Cu" "B.Cu")
		(net "TP_BIOS_MUX0_PIN12")
	)
	(segment
		(start 54.199282 -80.57769)
		(end 53.863494 -80.241902)
		(width 0.11684)
		(layer "B.Cu")
		(net "TP_BIOS_MUX0_PIN12")
	)
	(segment
		(start 53.863494 -80.241902)
		(end 51.9049 -80.241902)
		(width 0.11684)
		(layer "B.Cu")
		(net "TP_BIOS_MUX0_PIN12")
	)
	(segment
		(start 51.9049 -80.241902)
		(end 51.861466 -80.285336)
		(width 0.11684)
		(layer "B.Cu")
		(net "TP_BIOS_MUX0_PIN12")
	)
	(segment
		(start 54.26964 -80.747362)
		(end 54.199282 -80.57769)
		(width 0.11684)
		(layer "B.Cu")
		(net "TP_BIOS_MUX0_PIN12")
	)
	(segment
		(start 54.26964 -80.858106)
		(end 54.26964 -80.747362)
		(width 0.11684)
		(layer "B.Cu")
		(net "TP_BIOS_MUX0_PIN12")
	)
	(segment
		(start 54.386734 -80.9752)
		(end 54.26964 -80.858106)
		(width 0.11684)
		(layer "B.Cu")
		(net "TP_BIOS_MUX0_PIN12")
	)
	(segment
		(start 55.499 -80.9752)
		(end 54.386734 -80.9752)
		(width 0.11684)
		(layer "B.Cu")
		(net "TP_BIOS_MUX0_PIN12")
	)
	(segment
		(start 83.312 -16.9418)
		(end 82.996786 -17.257014)
		(width 0.11684)
		(layer "F.Cu")
		(net "TP_ID_BUF")
	)
	(segment
		(start 82.996786 -17.257014)
		(end 82.55508 -17.257014)
		(width 0.11684)
		(layer "F.Cu")
		(net "TP_ID_BUF")
	)
	(segment
		(start 83.312 -15.7734)
		(end 83.312 -16.9418)
		(width 0.11684)
		(layer "F.Cu")
		(net "TP_ID_BUF")
	)
	(via
		(at 83.312 -15.7734)
		(size 0.762)
		(drill 0.381)
		(layers "F.Cu" "B.Cu")
		(net "TP_ID_BUF")
	)
	(segment
		(start 40.781986 -71.91756)
		(end 40.3225 -72.377046)
		(width 0.11684)
		(layer "F.Cu")
		(net "SYS_PWRBTN_N")
	)
	(segment
		(start 40.781986 -71.447406)
		(end 40.781986 -71.91756)
		(width 0.11684)
		(layer "F.Cu")
		(net "SYS_PWRBTN_N")
	)
	(via
		(at 26.797 -106.2228)
		(size 0.508)
		(drill 0.254)
		(layers "F.Cu" "B.Cu")
		(net "SYS_PWRBTN_N")
	)
	(via
		(at 40.3225 -72.377046)
		(size 0.508)
		(drill 0.254)
		(layers "F.Cu" "B.Cu")
		(net "SYS_PWRBTN_N")
	)
	(via
		(at 35.0266 -101.473)
		(size 0.508)
		(drill 0.254)
		(layers "F.Cu" "B.Cu")
		(net "SYS_PWRBTN_N")
	)
	(via
		(at 27.0637 -109.63402)
		(size 0.6604)
		(drill 0.3302)
		(layers "F.Cu" "B.Cu")
		(net "SYS_PWRBTN_N")
	)
	(segment
		(start 27.0637 -109.63402)
		(end 27.0637 -107.0737)
		(width 0.11684)
		(layer "B.Cu")
		(net "SYS_PWRBTN_N")
	)
	(segment
		(start 27.0637 -109.63402)
		(end 26.01722 -109.63402)
		(width 0.11684)
		(layer "B.Cu")
		(net "SYS_PWRBTN_N")
	)
	(segment
		(start 27.0637 -109.63402)
		(end 27.0637 -110.121954)
		(width 0.11684)
		(layer "B.Cu")
		(net "SYS_PWRBTN_N")
	)
	(segment
		(start 27.0637 -110.121954)
		(end 28.95346 -112.011714)
		(width 0.11684)
		(layer "B.Cu")
		(net "SYS_PWRBTN_N")
	)
	(segment
		(start 25.654 -107.860084)
		(end 25.654 -106.88955)
		(width 0.11684)
		(layer "B.Cu")
		(net "SYS_PWRBTN_N")
	)
	(segment
		(start 25.64638 -109.26318)
		(end 25.64638 -107.867704)
		(width 0.11684)
		(layer "B.Cu")
		(net "SYS_PWRBTN_N")
	)
	(segment
		(start 26.797 -106.807)
		(end 26.797 -106.2228)
		(width 0.11684)
		(layer "B.Cu")
		(net "SYS_PWRBTN_N")
	)
	(segment
		(start 24.611076 -106.88955)
		(end 24.590756 -106.90987)
		(width 0.11684)
		(layer "B.Cu")
		(net "SYS_PWRBTN_N")
	)
	(segment
		(start 25.64638 -107.867704)
		(end 25.654 -107.860084)
		(width 0.11684)
		(layer "B.Cu")
		(net "SYS_PWRBTN_N")
	)
	(segment
		(start 28.95346 -116.360194)
		(end 28.144978 -117.168676)
		(width 0.11684)
		(layer "B.Cu")
		(net "SYS_PWRBTN_N")
	)
	(segment
		(start 28.144978 -117.168676)
		(end 28.144978 -118.25986)
		(width 0.11684)
		(layer "B.Cu")
		(net "SYS_PWRBTN_N")
	)
	(segment
		(start 25.654 -106.88955)
		(end 24.611076 -106.88955)
		(width 0.11684)
		(layer "B.Cu")
		(net "SYS_PWRBTN_N")
	)
	(segment
		(start 28.95346 -112.011714)
		(end 28.95346 -116.360194)
		(width 0.11684)
		(layer "B.Cu")
		(net "SYS_PWRBTN_N")
	)
	(segment
		(start 27.0637 -107.0737)
		(end 26.797 -106.807)
		(width 0.11684)
		(layer "B.Cu")
		(net "SYS_PWRBTN_N")
	)
	(segment
		(start 26.01722 -109.63402)
		(end 25.64638 -109.26318)
		(width 0.11684)
		(layer "B.Cu")
		(net "SYS_PWRBTN_N")
	)
	(segment
		(start 34.1122 -96.432624)
		(end 34.1122 -98.0948)
		(width 0.10668)
		(layer "In4.Cu")
		(net "SYS_PWRBTN_N")
	)
	(segment
		(start 35.0266 -89.883996)
		(end 34.9377 -89.972896)
		(width 0.10668)
		(layer "In4.Cu")
		(net "SYS_PWRBTN_N")
	)
	(segment
		(start 38.634162 -80.325722)
		(end 38.6334 -80.326484)
		(width 0.10668)
		(layer "In4.Cu")
		(net "SYS_PWRBTN_N")
	)
	(segment
		(start 36.65474 -86.43366)
		(end 36.65474 -88.23706)
		(width 0.10668)
		(layer "In4.Cu")
		(net "SYS_PWRBTN_N")
	)
	(segment
		(start 38.634162 -75.789282)
		(end 38.634162 -80.325722)
		(width 0.10668)
		(layer "In4.Cu")
		(net "SYS_PWRBTN_N")
	)
	(segment
		(start 37.2618 -85.8266)
		(end 36.65474 -86.43366)
		(width 0.10668)
		(layer "In4.Cu")
		(net "SYS_PWRBTN_N")
	)
	(segment
		(start 34.9377 -89.972896)
		(end 34.9377 -92.300044)
		(width 0.10668)
		(layer "In4.Cu")
		(net "SYS_PWRBTN_N")
	)
	(segment
		(start 40.3225 -72.377046)
		(end 39.5859 -73.113646)
		(width 0.10668)
		(layer "In4.Cu")
		(net "SYS_PWRBTN_N")
	)
	(segment
		(start 39.5859 -74.837544)
		(end 38.634162 -75.789282)
		(width 0.10668)
		(layer "In4.Cu")
		(net "SYS_PWRBTN_N")
	)
	(segment
		(start 34.3281 -96.216724)
		(end 34.1122 -96.432624)
		(width 0.10668)
		(layer "In4.Cu")
		(net "SYS_PWRBTN_N")
	)
	(segment
		(start 37.2618 -81.863946)
		(end 37.2618 -85.8266)
		(width 0.10668)
		(layer "In4.Cu")
		(net "SYS_PWRBTN_N")
	)
	(segment
		(start 34.1122 -98.0948)
		(end 34.798508 -98.781108)
		(width 0.10668)
		(layer "In4.Cu")
		(net "SYS_PWRBTN_N")
	)
	(segment
		(start 35.0266 -89.8652)
		(end 35.0266 -89.883996)
		(width 0.10668)
		(layer "In4.Cu")
		(net "SYS_PWRBTN_N")
	)
	(segment
		(start 34.798508 -98.781108)
		(end 34.798508 -101.244908)
		(width 0.10668)
		(layer "In4.Cu")
		(net "SYS_PWRBTN_N")
	)
	(segment
		(start 38.6334 -80.492346)
		(end 37.2618 -81.863946)
		(width 0.10668)
		(layer "In4.Cu")
		(net "SYS_PWRBTN_N")
	)
	(segment
		(start 38.6334 -80.326484)
		(end 38.6334 -80.492346)
		(width 0.10668)
		(layer "In4.Cu")
		(net "SYS_PWRBTN_N")
	)
	(segment
		(start 34.9377 -92.300044)
		(end 34.3281 -92.909644)
		(width 0.10668)
		(layer "In4.Cu")
		(net "SYS_PWRBTN_N")
	)
	(segment
		(start 34.798508 -101.244908)
		(end 35.0266 -101.473)
		(width 0.10668)
		(layer "In4.Cu")
		(net "SYS_PWRBTN_N")
	)
	(segment
		(start 39.5859 -73.113646)
		(end 39.5859 -74.837544)
		(width 0.10668)
		(layer "In4.Cu")
		(net "SYS_PWRBTN_N")
	)
	(segment
		(start 36.65474 -88.23706)
		(end 35.0266 -89.8652)
		(width 0.10668)
		(layer "In4.Cu")
		(net "SYS_PWRBTN_N")
	)
	(segment
		(start 34.3281 -92.909644)
		(end 34.3281 -96.216724)
		(width 0.10668)
		(layer "In4.Cu")
		(net "SYS_PWRBTN_N")
	)
	(segment
		(start 32.757872 -104.83215)
		(end 32.116522 -105.4735)
		(width 0.08382)
		(layer "In9.Cu")
		(net "SYS_PWRBTN_N")
	)
	(segment
		(start 28.015946 -106.5022)
		(end 27.787346 -106.7308)
		(width 0.08382)
		(layer "In9.Cu")
		(net "SYS_PWRBTN_N")
	)
	(segment
		(start 30.338522 -105.4735)
		(end 29.309822 -106.5022)
		(width 0.08382)
		(layer "In9.Cu")
		(net "SYS_PWRBTN_N")
	)
	(segment
		(start 35.0266 -103.475536)
		(end 33.669986 -104.83215)
		(width 0.08382)
		(layer "In9.Cu")
		(net "SYS_PWRBTN_N")
	)
	(segment
		(start 29.309822 -106.5022)
		(end 28.015946 -106.5022)
		(width 0.08382)
		(layer "In9.Cu")
		(net "SYS_PWRBTN_N")
	)
	(segment
		(start 32.116522 -105.4735)
		(end 30.338522 -105.4735)
		(width 0.08382)
		(layer "In9.Cu")
		(net "SYS_PWRBTN_N")
	)
	(segment
		(start 35.0266 -101.473)
		(end 35.0266 -103.475536)
		(width 0.08382)
		(layer "In9.Cu")
		(net "SYS_PWRBTN_N")
	)
	(segment
		(start 27.305 -106.7308)
		(end 26.797 -106.2228)
		(width 0.08382)
		(layer "In9.Cu")
		(net "SYS_PWRBTN_N")
	)
	(segment
		(start 27.787346 -106.7308)
		(end 27.305 -106.7308)
		(width 0.08382)
		(layer "In9.Cu")
		(net "SYS_PWRBTN_N")
	)
	(segment
		(start 33.669986 -104.83215)
		(end 32.757872 -104.83215)
		(width 0.08382)
		(layer "In9.Cu")
		(net "SYS_PWRBTN_N")
	)
	(via
		(at 5.8674 -67.1322)
		(size 0.6604)
		(drill 0.3302)
		(layers "F.Cu" "B.Cu")
		(net "SW_P3V3_AUX_SW")
	)
	(via
		(at 9.0424 -61.2648)
		(size 0.508)
		(drill 0.254)
		(layers "F.Cu" "B.Cu")
		(net "SW_P3V3_AUX_FLT")
	)
	(via
		(at 9.677654 -60.8838)
		(size 0.6604)
		(drill 0.3302)
		(layers "F.Cu" "B.Cu")
		(net "SW_P3V3_AUX_FLT")
	)
	(via
		(at 9.0424 -60.5028)
		(size 0.508)
		(drill 0.254)
		(layers "F.Cu" "B.Cu")
		(net "SW_P3V3_AUX_FLT")
	)
	(segment
		(start 7.84225 -67.183)
		(end 8.82015 -67.183)
		(width 0.254)
		(layer "F.Cu")
		(net "SW_P3V3_AUX_BST")
	)
	(via
		(at 83.3374 -74.6252)
		(size 0.762)
		(drill 0.381)
		(layers "F.Cu" "B.Cu")
		(net "SW_P1V2_AUX_FLT")
	)
	(via
		(at 18.183606 -30.0355)
		(size 0.762)
		(drill 0.381)
		(layers "F.Cu" "B.Cu")
		(net "SW_P1V0_AUX_SW")
	)
	(via
		(at 21.844 -37.5158)
		(size 0.762)
		(drill 0.381)
		(layers "F.Cu" "B.Cu")
		(net "SW_P1V0_AUX_FLT")
	)
	(segment
		(start 65.39357 -96.35617)
		(end 64.81191 -96.35617)
		(width 0.11684)
		(layer "F.Cu")
		(net "SPI_TPM_CS_N_R")
	)
	(segment
		(start 68.1228 -99.0854)
		(end 65.39357 -96.35617)
		(width 0.11684)
		(layer "F.Cu")
		(net "SPI_TPM_CS_N_R")
	)
	(segment
		(start 67.789044 -97.877122)
		(end 68.1228 -98.210878)
		(width 0.11684)
		(layer "F.Cu")
		(net "SPI_TPM_CS_N_R")
	)
	(segment
		(start 68.1228 -98.210878)
		(end 68.1228 -99.0854)
		(width 0.11684)
		(layer "F.Cu")
		(net "SPI_TPM_CS_N_R")
	)
	(via
		(at 68.1228 -99.0854)
		(size 0.762)
		(drill 0.381)
		(layers "F.Cu" "B.Cu")
		(net "SPI_TPM_CS_N_R")
	)
	(segment
		(start 35.82543 -90.248486)
		(end 35.82543 -89.65438)
		(width 0.11684)
		(layer "F.Cu")
		(net "SPI_PCH_MUXED_IO3")
	)
	(segment
		(start 35.82543 -89.65438)
		(end 35.55365 -89.3826)
		(width 0.11684)
		(layer "F.Cu")
		(net "SPI_PCH_MUXED_IO3")
	)
	(via
		(at 35.82543 -90.248486)
		(size 0.508)
		(drill 0.254)
		(layers "F.Cu" "B.Cu")
		(net "SPI_PCH_MUXED_IO3")
	)
	(via
		(at 43.3832 -80.6704)
		(size 0.508)
		(drill 0.254)
		(layers "F.Cu" "B.Cu")
		(net "SPI_PCH_MUXED_IO3")
	)
	(segment
		(start 43.3832 -80.6704)
		(end 44.4246 -81.7118)
		(width 0.11684)
		(layer "B.Cu")
		(net "SPI_PCH_MUXED_IO3")
	)
	(segment
		(start 45.085 -81.585308)
		(end 46.019466 -81.585308)
		(width 0.11684)
		(layer "B.Cu")
		(net "SPI_PCH_MUXED_IO3")
	)
	(segment
		(start 44.4246 -81.7118)
		(end 44.958508 -81.7118)
		(width 0.11684)
		(layer "B.Cu")
		(net "SPI_PCH_MUXED_IO3")
	)
	(segment
		(start 44.958508 -81.7118)
		(end 45.085 -81.585308)
		(width 0.11684)
		(layer "B.Cu")
		(net "SPI_PCH_MUXED_IO3")
	)
	(segment
		(start 36.83 -88.920574)
		(end 36.83 -89.204038)
		(width 0.08382)
		(layer "In9.Cu")
		(net "SPI_PCH_MUXED_IO3")
	)
	(segment
		(start 38.26891 -90.05189)
		(end 37.745162 -90.05189)
		(width 0.08382)
		(layer "In9.Cu")
		(net "SPI_PCH_MUXED_IO3")
	)
	(segment
		(start 36.930076 -88.820498)
		(end 36.83 -88.920574)
		(width 0.08382)
		(layer "In9.Cu")
		(net "SPI_PCH_MUXED_IO3")
	)
	(segment
		(start 37.292788 -90.504264)
		(end 36.081208 -90.504264)
		(width 0.08382)
		(layer "In9.Cu")
		(net "SPI_PCH_MUXED_IO3")
	)
	(segment
		(start 37.745162 -90.05189)
		(end 37.292788 -90.504264)
		(width 0.08382)
		(layer "In9.Cu")
		(net "SPI_PCH_MUXED_IO3")
	)
	(segment
		(start 43.3832 -81.3308)
		(end 37.21735 -87.49665)
		(width 0.08382)
		(layer "In9.Cu")
		(net "SPI_PCH_MUXED_IO3")
	)
	(segment
		(start 43.3832 -80.6704)
		(end 43.3832 -81.3308)
		(width 0.08382)
		(layer "In9.Cu")
		(net "SPI_PCH_MUXED_IO3")
	)
	(segment
		(start 37.21735 -88.736678)
		(end 37.13353 -88.820498)
		(width 0.08382)
		(layer "In9.Cu")
		(net "SPI_PCH_MUXED_IO3")
	)
	(segment
		(start 36.081208 -90.504264)
		(end 35.82543 -90.248486)
		(width 0.08382)
		(layer "In9.Cu")
		(net "SPI_PCH_MUXED_IO3")
	)
	(segment
		(start 36.91382 -89.287858)
		(end 38.259258 -89.287858)
		(width 0.08382)
		(layer "In9.Cu")
		(net "SPI_PCH_MUXED_IO3")
	)
	(segment
		(start 36.83 -89.204038)
		(end 36.91382 -89.287858)
		(width 0.08382)
		(layer "In9.Cu")
		(net "SPI_PCH_MUXED_IO3")
	)
	(segment
		(start 37.13353 -88.820498)
		(end 36.930076 -88.820498)
		(width 0.08382)
		(layer "In9.Cu")
		(net "SPI_PCH_MUXED_IO3")
	)
	(segment
		(start 38.4556 -89.4842)
		(end 38.4556 -89.8652)
		(width 0.08382)
		(layer "In9.Cu")
		(net "SPI_PCH_MUXED_IO3")
	)
	(segment
		(start 37.21735 -87.49665)
		(end 37.21735 -88.736678)
		(width 0.08382)
		(layer "In9.Cu")
		(net "SPI_PCH_MUXED_IO3")
	)
	(segment
		(start 38.259258 -89.287858)
		(end 38.4556 -89.4842)
		(width 0.08382)
		(layer "In9.Cu")
		(net "SPI_PCH_MUXED_IO3")
	)
	(segment
		(start 38.4556 -89.8652)
		(end 38.26891 -90.05189)
		(width 0.08382)
		(layer "In9.Cu")
		(net "SPI_PCH_MUXED_IO3")
	)
	(segment
		(start 45.129958 -102.242112)
		(end 45.822616 -102.242112)
		(width 0.11684)
		(layer "F.Cu")
		(net "SPI_PCH_MUXED_IO2")
	)
	(segment
		(start 45.969174 -105.878884)
		(end 45.822616 -106.025442)
		(width 0.11684)
		(layer "F.Cu")
		(net "SPI_PCH_MUXED_IO2")
	)
	(segment
		(start 49.459642 -105.377234)
		(end 49.041558 -105.377234)
		(width 0.11684)
		(layer "F.Cu")
		(net "SPI_PCH_MUXED_IO2")
	)
	(segment
		(start 45.129958 -101.741732)
		(end 44.9834 -101.88829)
		(width 0.11684)
		(layer "F.Cu")
		(net "SPI_PCH_MUXED_IO2")
	)
	(segment
		(start 44.9834 -103.096314)
		(end 45.129958 -103.242872)
		(width 0.11684)
		(layer "F.Cu")
		(net "SPI_PCH_MUXED_IO2")
	)
	(segment
		(start 45.969174 -101.213158)
		(end 45.969174 -101.595174)
		(width 0.11684)
		(layer "F.Cu")
		(net "SPI_PCH_MUXED_IO2")
	)
	(segment
		(start 49.6062 -105.230676)
		(end 49.459642 -105.377234)
		(width 0.11684)
		(layer "F.Cu")
		(net "SPI_PCH_MUXED_IO2")
	)
	(segment
		(start 45.822616 -103.242872)
		(end 45.969174 -103.38943)
		(width 0.11684)
		(layer "F.Cu")
		(net "SPI_PCH_MUXED_IO2")
	)
	(segment
		(start 48.518572 -106.025188)
		(end 48.102012 -105.608628)
		(width 0.11684)
		(layer "F.Cu")
		(net "SPI_PCH_MUXED_IO2")
	)
	(segment
		(start 45.822616 -104.524302)
		(end 45.969174 -104.67086)
		(width 0.11684)
		(layer "F.Cu")
		(net "SPI_PCH_MUXED_IO2")
	)
	(segment
		(start 44.266358 -106.025442)
		(end 44.1198 -106.172)
		(width 0.11684)
		(layer "F.Cu")
		(net "SPI_PCH_MUXED_IO2")
	)
	(segment
		(start 45.969174 -104.878124)
		(end 45.822616 -105.024682)
		(width 0.11684)
		(layer "F.Cu")
		(net "SPI_PCH_MUXED_IO2")
	)
	(segment
		(start 46.115732 -101.0666)
		(end 45.969174 -101.213158)
		(width 0.11684)
		(layer "F.Cu")
		(net "SPI_PCH_MUXED_IO2")
	)
	(segment
		(start 44.266358 -106.525822)
		(end 45.822616 -106.525822)
		(width 0.11684)
		(layer "F.Cu")
		(net "SPI_PCH_MUXED_IO2")
	)
	(segment
		(start 44.9834 -101.88829)
		(end 44.9834 -102.095554)
		(width 0.11684)
		(layer "F.Cu")
		(net "SPI_PCH_MUXED_IO2")
	)
	(segment
		(start 45.969174 -103.38943)
		(end 45.969174 -103.877364)
		(width 0.11684)
		(layer "F.Cu")
		(net "SPI_PCH_MUXED_IO2")
	)
	(segment
		(start 47.544228 -107.303824)
		(end 47.964598 -107.724194)
		(width 0.11684)
		(layer "F.Cu")
		(net "SPI_PCH_MUXED_IO2")
	)
	(segment
		(start 45.969174 -105.67162)
		(end 45.969174 -105.878884)
		(width 0.11684)
		(layer "F.Cu")
		(net "SPI_PCH_MUXED_IO2")
	)
	(segment
		(start 47.985426 -102.61473)
		(end 47.463456 -103.1367)
		(width 0.11684)
		(layer "F.Cu")
		(net "SPI_PCH_MUXED_IO2")
	)
	(segment
		(start 45.822616 -102.242112)
		(end 45.969174 -102.38867)
		(width 0.11684)
		(layer "F.Cu")
		(net "SPI_PCH_MUXED_IO2")
	)
	(segment
		(start 47.463456 -103.1367)
		(end 47.463456 -104.06634)
		(width 0.11684)
		(layer "F.Cu")
		(net "SPI_PCH_MUXED_IO2")
	)
	(segment
		(start 44.266358 -105.525062)
		(end 45.822616 -105.525062)
		(width 0.11684)
		(layer "F.Cu")
		(net "SPI_PCH_MUXED_IO2")
	)
	(segment
		(start 44.1198 -106.379264)
		(end 44.266358 -106.525822)
		(width 0.11684)
		(layer "F.Cu")
		(net "SPI_PCH_MUXED_IO2")
	)
	(segment
		(start 44.121832 -104.379776)
		(end 44.266358 -104.524302)
		(width 0.11684)
		(layer "F.Cu")
		(net "SPI_PCH_MUXED_IO2")
	)
	(segment
		(start 49.041558 -105.377234)
		(end 48.895 -105.523792)
		(width 0.11684)
		(layer "F.Cu")
		(net "SPI_PCH_MUXED_IO2")
	)
	(segment
		(start 44.1198 -106.172)
		(end 44.1198 -106.379264)
		(width 0.11684)
		(layer "F.Cu")
		(net "SPI_PCH_MUXED_IO2")
	)
	(segment
		(start 47.084234 -107.693206)
		(end 46.616112 -107.693206)
		(width 0.11684)
		(layer "F.Cu")
		(net "SPI_PCH_MUXED_IO2")
	)
	(segment
		(start 45.129958 -102.742492)
		(end 44.9834 -102.88905)
		(width 0.11684)
		(layer "F.Cu")
		(net "SPI_PCH_MUXED_IO2")
	)
	(segment
		(start 45.822616 -102.742492)
		(end 45.129958 -102.742492)
		(width 0.11684)
		(layer "F.Cu")
		(net "SPI_PCH_MUXED_IO2")
	)
	(segment
		(start 48.895 -105.523792)
		(end 48.895 -105.908348)
		(width 0.11684)
		(layer "F.Cu")
		(net "SPI_PCH_MUXED_IO2")
	)
	(segment
		(start 47.53991 -108.148882)
		(end 47.084234 -107.693206)
		(width 0.11684)
		(layer "F.Cu")
		(net "SPI_PCH_MUXED_IO2")
	)
	(segment
		(start 48.728122 -102.61473)
		(end 47.985426 -102.61473)
		(width 0.11684)
		(layer "F.Cu")
		(net "SPI_PCH_MUXED_IO2")
	)
	(segment
		(start 48.27397 -104.876854)
		(end 49.459642 -104.876854)
		(width 0.11684)
		(layer "F.Cu")
		(net "SPI_PCH_MUXED_IO2")
	)
	(segment
		(start 45.969174 -103.877364)
		(end 45.822616 -104.023922)
		(width 0.11684)
		(layer "F.Cu")
		(net "SPI_PCH_MUXED_IO2")
	)
	(segment
		(start 44.1198 -105.17124)
		(end 44.1198 -105.378504)
		(width 0.11684)
		(layer "F.Cu")
		(net "SPI_PCH_MUXED_IO2")
	)
	(segment
		(start 45.822616 -101.741732)
		(end 45.129958 -101.741732)
		(width 0.11684)
		(layer "F.Cu")
		(net "SPI_PCH_MUXED_IO2")
	)
	(segment
		(start 45.969174 -101.595174)
		(end 45.822616 -101.741732)
		(width 0.11684)
		(layer "F.Cu")
		(net "SPI_PCH_MUXED_IO2")
	)
	(segment
		(start 45.822616 -105.024682)
		(end 44.266358 -105.024682)
		(width 0.11684)
		(layer "F.Cu")
		(net "SPI_PCH_MUXED_IO2")
	)
	(segment
		(start 45.969174 -104.67086)
		(end 45.969174 -104.878124)
		(width 0.11684)
		(layer "F.Cu")
		(net "SPI_PCH_MUXED_IO2")
	)
	(segment
		(start 45.822616 -106.525822)
		(end 45.969174 -106.67238)
		(width 0.11684)
		(layer "F.Cu")
		(net "SPI_PCH_MUXED_IO2")
	)
	(segment
		(start 49.459642 -104.876854)
		(end 49.6062 -105.023412)
		(width 0.11684)
		(layer "F.Cu")
		(net "SPI_PCH_MUXED_IO2")
	)
	(segment
		(start 45.822616 -106.025442)
		(end 44.266358 -106.025442)
		(width 0.11684)
		(layer "F.Cu")
		(net "SPI_PCH_MUXED_IO2")
	)
	(segment
		(start 45.969174 -107.393232)
		(end 45.6692 -107.693206)
		(width 0.11684)
		(layer "F.Cu")
		(net "SPI_PCH_MUXED_IO2")
	)
	(segment
		(start 44.266358 -105.024682)
		(end 44.1198 -105.17124)
		(width 0.11684)
		(layer "F.Cu")
		(net "SPI_PCH_MUXED_IO2")
	)
	(segment
		(start 46.616112 -107.693206)
		(end 46.469554 -107.546648)
		(width 0.11684)
		(layer "F.Cu")
		(net "SPI_PCH_MUXED_IO2")
	)
	(segment
		(start 47.544228 -106.963972)
		(end 47.544228 -107.303824)
		(width 0.11684)
		(layer "F.Cu")
		(net "SPI_PCH_MUXED_IO2")
	)
	(segment
		(start 44.4754 -108.32465)
		(end 45.037756 -108.32465)
		(width 0.11684)
		(layer "F.Cu")
		(net "SPI_PCH_MUXED_IO2")
	)
	(segment
		(start 46.469554 -101.213158)
		(end 46.322996 -101.0666)
		(width 0.11684)
		(layer "F.Cu")
		(net "SPI_PCH_MUXED_IO2")
	)
	(segment
		(start 48.102012 -105.608628)
		(end 47.832772 -105.608628)
		(width 0.11684)
		(layer "F.Cu")
		(net "SPI_PCH_MUXED_IO2")
	)
	(segment
		(start 46.469554 -107.546648)
		(end 46.469554 -101.213158)
		(width 0.11684)
		(layer "F.Cu")
		(net "SPI_PCH_MUXED_IO2")
	)
	(segment
		(start 44.1198 -105.378504)
		(end 44.266358 -105.525062)
		(width 0.11684)
		(layer "F.Cu")
		(net "SPI_PCH_MUXED_IO2")
	)
	(segment
		(start 47.642018 -105.799382)
		(end 47.642018 -106.068622)
		(width 0.11684)
		(layer "F.Cu")
		(net "SPI_PCH_MUXED_IO2")
	)
	(segment
		(start 47.957994 -106.384598)
		(end 47.957994 -106.550206)
		(width 0.11684)
		(layer "F.Cu")
		(net "SPI_PCH_MUXED_IO2")
	)
	(segment
		(start 47.964598 -107.889802)
		(end 47.705518 -108.148882)
		(width 0.11684)
		(layer "F.Cu")
		(net "SPI_PCH_MUXED_IO2")
	)
	(segment
		(start 48.77816 -106.025188)
		(end 48.518572 -106.025188)
		(width 0.11684)
		(layer "F.Cu")
		(net "SPI_PCH_MUXED_IO2")
	)
	(segment
		(start 47.642018 -106.068622)
		(end 47.957994 -106.384598)
		(width 0.11684)
		(layer "F.Cu")
		(net "SPI_PCH_MUXED_IO2")
	)
	(segment
		(start 47.832772 -105.608628)
		(end 47.642018 -105.799382)
		(width 0.11684)
		(layer "F.Cu")
		(net "SPI_PCH_MUXED_IO2")
	)
	(segment
		(start 45.822616 -105.525062)
		(end 45.969174 -105.67162)
		(width 0.11684)
		(layer "F.Cu")
		(net "SPI_PCH_MUXED_IO2")
	)
	(segment
		(start 45.969174 -102.38867)
		(end 45.969174 -102.595934)
		(width 0.11684)
		(layer "F.Cu")
		(net "SPI_PCH_MUXED_IO2")
	)
	(segment
		(start 45.129958 -103.242872)
		(end 45.822616 -103.242872)
		(width 0.11684)
		(layer "F.Cu")
		(net "SPI_PCH_MUXED_IO2")
	)
	(segment
		(start 47.957994 -106.550206)
		(end 47.544228 -106.963972)
		(width 0.11684)
		(layer "F.Cu")
		(net "SPI_PCH_MUXED_IO2")
	)
	(segment
		(start 45.969174 -106.67238)
		(end 45.969174 -107.393232)
		(width 0.11684)
		(layer "F.Cu")
		(net "SPI_PCH_MUXED_IO2")
	)
	(segment
		(start 47.964598 -107.724194)
		(end 47.964598 -107.889802)
		(width 0.11684)
		(layer "F.Cu")
		(net "SPI_PCH_MUXED_IO2")
	)
	(segment
		(start 46.322996 -101.0666)
		(end 46.115732 -101.0666)
		(width 0.11684)
		(layer "F.Cu")
		(net "SPI_PCH_MUXED_IO2")
	)
	(segment
		(start 44.9834 -102.88905)
		(end 44.9834 -103.096314)
		(width 0.11684)
		(layer "F.Cu")
		(net "SPI_PCH_MUXED_IO2")
	)
	(segment
		(start 47.705518 -108.148882)
		(end 47.53991 -108.148882)
		(width 0.11684)
		(layer "F.Cu")
		(net "SPI_PCH_MUXED_IO2")
	)
	(segment
		(start 44.312078 -104.023922)
		(end 44.121832 -104.214168)
		(width 0.11684)
		(layer "F.Cu")
		(net "SPI_PCH_MUXED_IO2")
	)
	(segment
		(start 47.463456 -104.06634)
		(end 48.27397 -104.876854)
		(width 0.11684)
		(layer "F.Cu")
		(net "SPI_PCH_MUXED_IO2")
	)
	(segment
		(start 44.121832 -104.214168)
		(end 44.121832 -104.379776)
		(width 0.11684)
		(layer "F.Cu")
		(net "SPI_PCH_MUXED_IO2")
	)
	(segment
		(start 49.6062 -105.023412)
		(end 49.6062 -105.230676)
		(width 0.11684)
		(layer "F.Cu")
		(net "SPI_PCH_MUXED_IO2")
	)
	(segment
		(start 44.266358 -104.524302)
		(end 45.822616 -104.524302)
		(width 0.11684)
		(layer "F.Cu")
		(net "SPI_PCH_MUXED_IO2")
	)
	(segment
		(start 45.969174 -102.595934)
		(end 45.822616 -102.742492)
		(width 0.11684)
		(layer "F.Cu")
		(net "SPI_PCH_MUXED_IO2")
	)
	(segment
		(start 45.822616 -104.023922)
		(end 44.312078 -104.023922)
		(width 0.11684)
		(layer "F.Cu")
		(net "SPI_PCH_MUXED_IO2")
	)
	(segment
		(start 48.895 -105.908348)
		(end 48.77816 -106.025188)
		(width 0.11684)
		(layer "F.Cu")
		(net "SPI_PCH_MUXED_IO2")
	)
	(segment
		(start 44.9834 -102.095554)
		(end 45.129958 -102.242112)
		(width 0.11684)
		(layer "F.Cu")
		(net "SPI_PCH_MUXED_IO2")
	)
	(segment
		(start 45.037756 -108.32465)
		(end 45.6692 -107.693206)
		(width 0.11684)
		(layer "F.Cu")
		(net "SPI_PCH_MUXED_IO2")
	)
	(via
		(at 45.6692 -107.693206)
		(size 0.762)
		(drill 0.381)
		(layers "F.Cu" "B.Cu")
		(net "SPI_PCH_MUXED_IO2")
	)
	(via
		(at 48.728122 -102.61473)
		(size 0.508)
		(drill 0.254)
		(layers "F.Cu" "B.Cu")
		(net "SPI_PCH_MUXED_IO2")
	)
	(segment
		(start 48.734218 -102.61473)
		(end 48.728122 -102.61473)
		(width 0.11684)
		(layer "B.Cu")
		(net "SPI_PCH_MUXED_IO2")
	)
	(segment
		(start 46.811184 -102.02799)
		(end 48.171862 -102.02799)
		(width 0.11684)
		(layer "B.Cu")
		(net "SPI_PCH_MUXED_IO2")
	)
	(segment
		(start 48.734218 -102.590346)
		(end 48.734218 -102.61473)
		(width 0.11684)
		(layer "B.Cu")
		(net "SPI_PCH_MUXED_IO2")
	)
	(segment
		(start 48.171862 -102.02799)
		(end 48.734218 -102.590346)
		(width 0.11684)
		(layer "B.Cu")
		(net "SPI_PCH_MUXED_IO2")
	)
	(segment
		(start 45.2882 -90.556842)
		(end 45.2882 -91.984068)
		(width 0.11684)
		(layer "F.Cu")
		(net "SPI_PCH_MUXED_IO1")
	)
	(segment
		(start 44.5516 -87.477346)
		(end 44.353988 -87.279734)
		(width 0.11684)
		(layer "F.Cu")
		(net "SPI_PCH_MUXED_IO1")
	)
	(segment
		(start 44.3103 -95.231458)
		(end 48.0187 -95.231458)
		(width 0.11684)
		(layer "F.Cu")
		(net "SPI_PCH_MUXED_IO1")
	)
	(segment
		(start 44.203874 -98.6536)
		(end 43.934634 -98.6536)
		(width 0.11684)
		(layer "F.Cu")
		(net "SPI_PCH_MUXED_IO1")
	)
	(segment
		(start 46.4566 -93.740478)
		(end 46.6471 -93.930978)
		(width 0.11684)
		(layer "F.Cu")
		(net "SPI_PCH_MUXED_IO1")
	)
	(segment
		(start 48.2092 -94.121478)
		(end 48.2092 -94.390718)
		(width 0.11684)
		(layer "F.Cu")
		(net "SPI_PCH_MUXED_IO1")
	)
	(segment
		(start 44.353988 -87.279734)
		(end 43.948604 -87.279734)
		(width 0.11684)
		(layer "F.Cu")
		(net "SPI_PCH_MUXED_IO1")
	)
	(segment
		(start 43.553634 -97.0788)
		(end 43.284394 -97.0788)
		(width 0.11684)
		(layer "F.Cu")
		(net "SPI_PCH_MUXED_IO1")
	)
	(segment
		(start 46.672246 -90.373708)
		(end 45.471334 -90.373708)
		(width 0.11684)
		(layer "F.Cu")
		(net "SPI_PCH_MUXED_IO1")
	)
	(segment
		(start 45.2882 -88.5444)
		(end 45.2882 -89.565734)
		(width 0.11684)
		(layer "F.Cu")
		(net "SPI_PCH_MUXED_IO1")
	)
	(segment
		(start 46.85538 -90.190574)
		(end 46.672246 -90.373708)
		(width 0.11684)
		(layer "F.Cu")
		(net "SPI_PCH_MUXED_IO1")
	)
	(segment
		(start 48.0187 -93.280738)
		(end 46.6471 -93.280738)
		(width 0.11684)
		(layer "F.Cu")
		(net "SPI_PCH_MUXED_IO1")
	)
	(segment
		(start 44.394374 -98.4631)
		(end 44.203874 -98.6536)
		(width 0.11684)
		(layer "F.Cu")
		(net "SPI_PCH_MUXED_IO1")
	)
	(segment
		(start 46.4566 -93.471238)
		(end 46.4566 -93.740478)
		(width 0.11684)
		(layer "F.Cu")
		(net "SPI_PCH_MUXED_IO1")
	)
	(segment
		(start 43.744134 -97.2693)
		(end 43.553634 -97.0788)
		(width 0.11684)
		(layer "F.Cu")
		(net "SPI_PCH_MUXED_IO1")
	)
	(segment
		(start 45.471334 -89.748868)
		(end 46.672246 -89.748868)
		(width 0.11684)
		(layer "F.Cu")
		(net "SPI_PCH_MUXED_IO1")
	)
	(segment
		(start 43.284394 -97.0788)
		(end 43.093894 -97.2693)
		(width 0.11684)
		(layer "F.Cu")
		(net "SPI_PCH_MUXED_IO1")
	)
	(segment
		(start 45.2882 -91.984068)
		(end 45.93463 -92.630498)
		(width 0.11684)
		(layer "F.Cu")
		(net "SPI_PCH_MUXED_IO1")
	)
	(segment
		(start 45.93463 -92.630498)
		(end 48.0187 -92.630498)
		(width 0.11684)
		(layer "F.Cu")
		(net "SPI_PCH_MUXED_IO1")
	)
	(segment
		(start 46.85538 -89.932002)
		(end 46.85538 -90.190574)
		(width 0.11684)
		(layer "F.Cu")
		(net "SPI_PCH_MUXED_IO1")
	)
	(segment
		(start 43.093894 -97.2693)
		(end 43.093894 -99.51974)
		(width 0.11684)
		(layer "F.Cu")
		(net "SPI_PCH_MUXED_IO1")
	)
	(segment
		(start 44.5516 -87.8078)
		(end 44.5516 -87.477346)
		(width 0.11684)
		(layer "F.Cu")
		(net "SPI_PCH_MUXED_IO1")
	)
	(segment
		(start 43.934634 -98.6536)
		(end 43.744134 -98.4631)
		(width 0.11684)
		(layer "F.Cu")
		(net "SPI_PCH_MUXED_IO1")
	)
	(segment
		(start 48.2092 -94.390718)
		(end 48.0187 -94.581218)
		(width 0.11684)
		(layer "F.Cu")
		(net "SPI_PCH_MUXED_IO1")
	)
	(segment
		(start 48.0187 -92.630498)
		(end 48.2092 -92.820998)
		(width 0.11684)
		(layer "F.Cu")
		(net "SPI_PCH_MUXED_IO1")
	)
	(segment
		(start 45.2882 -89.565734)
		(end 45.471334 -89.748868)
		(width 0.11684)
		(layer "F.Cu")
		(net "SPI_PCH_MUXED_IO1")
	)
	(segment
		(start 48.2092 -92.820998)
		(end 48.2092 -93.090238)
		(width 0.11684)
		(layer "F.Cu")
		(net "SPI_PCH_MUXED_IO1")
	)
	(segment
		(start 44.77512 -96.9772)
		(end 44.394374 -97.357946)
		(width 0.11684)
		(layer "F.Cu")
		(net "SPI_PCH_MUXED_IO1")
	)
	(segment
		(start 48.0187 -93.930978)
		(end 48.2092 -94.121478)
		(width 0.11684)
		(layer "F.Cu")
		(net "SPI_PCH_MUXED_IO1")
	)
	(segment
		(start 46.672246 -89.748868)
		(end 46.85538 -89.932002)
		(width 0.11684)
		(layer "F.Cu")
		(net "SPI_PCH_MUXED_IO1")
	)
	(segment
		(start 44.1452 -94.797118)
		(end 44.1452 -95.066358)
		(width 0.11684)
		(layer "F.Cu")
		(net "SPI_PCH_MUXED_IO1")
	)
	(segment
		(start 48.2092 -96.621346)
		(end 47.853346 -96.9772)
		(width 0.11684)
		(layer "F.Cu")
		(net "SPI_PCH_MUXED_IO1")
	)
	(segment
		(start 48.0187 -94.581218)
		(end 44.3611 -94.581218)
		(width 0.11684)
		(layer "F.Cu")
		(net "SPI_PCH_MUXED_IO1")
	)
	(segment
		(start 46.6471 -93.280738)
		(end 46.4566 -93.471238)
		(width 0.11684)
		(layer "F.Cu")
		(net "SPI_PCH_MUXED_IO1")
	)
	(segment
		(start 45.471334 -90.373708)
		(end 45.2882 -90.556842)
		(width 0.11684)
		(layer "F.Cu")
		(net "SPI_PCH_MUXED_IO1")
	)
	(segment
		(start 44.1452 -95.066358)
		(end 44.3103 -95.231458)
		(width 0.11684)
		(layer "F.Cu")
		(net "SPI_PCH_MUXED_IO1")
	)
	(segment
		(start 45.2882 -88.5444)
		(end 44.5516 -87.8078)
		(width 0.11684)
		(layer "F.Cu")
		(net "SPI_PCH_MUXED_IO1")
	)
	(segment
		(start 43.744134 -98.4631)
		(end 43.744134 -97.2693)
		(width 0.11684)
		(layer "F.Cu")
		(net "SPI_PCH_MUXED_IO1")
	)
	(segment
		(start 43.093894 -99.51974)
		(end 43.210734 -99.63658)
		(width 0.11684)
		(layer "F.Cu")
		(net "SPI_PCH_MUXED_IO1")
	)
	(segment
		(start 44.3611 -94.581218)
		(end 44.1452 -94.797118)
		(width 0.11684)
		(layer "F.Cu")
		(net "SPI_PCH_MUXED_IO1")
	)
	(segment
		(start 44.394374 -97.357946)
		(end 44.394374 -98.4631)
		(width 0.11684)
		(layer "F.Cu")
		(net "SPI_PCH_MUXED_IO1")
	)
	(segment
		(start 43.210734 -99.63658)
		(end 48.2854 -99.63658)
		(width 0.11684)
		(layer "F.Cu")
		(net "SPI_PCH_MUXED_IO1")
	)
	(segment
		(start 48.2092 -93.090238)
		(end 48.0187 -93.280738)
		(width 0.11684)
		(layer "F.Cu")
		(net "SPI_PCH_MUXED_IO1")
	)
	(segment
		(start 48.0187 -95.231458)
		(end 48.2092 -95.421958)
		(width 0.11684)
		(layer "F.Cu")
		(net "SPI_PCH_MUXED_IO1")
	)
	(segment
		(start 47.853346 -96.9772)
		(end 44.77512 -96.9772)
		(width 0.11684)
		(layer "F.Cu")
		(net "SPI_PCH_MUXED_IO1")
	)
	(segment
		(start 46.6471 -93.930978)
		(end 48.0187 -93.930978)
		(width 0.11684)
		(layer "F.Cu")
		(net "SPI_PCH_MUXED_IO1")
	)
	(segment
		(start 48.2092 -95.421958)
		(end 48.2092 -96.621346)
		(width 0.11684)
		(layer "F.Cu")
		(net "SPI_PCH_MUXED_IO1")
	)
	(via
		(at 45.2882 -88.5444)
		(size 0.762)
		(drill 0.381)
		(layers "F.Cu" "B.Cu")
		(net "SPI_PCH_MUXED_IO1")
	)
	(via
		(at 48.2854 -99.63658)
		(size 0.508)
		(drill 0.254)
		(layers "F.Cu" "B.Cu")
		(net "SPI_PCH_MUXED_IO1")
	)
	(segment
		(start 47.420022 -100.077778)
		(end 47.86122 -99.63658)
		(width 0.11684)
		(layer "B.Cu")
		(net "SPI_PCH_MUXED_IO1")
	)
	(segment
		(start 46.811184 -100.077778)
		(end 47.420022 -100.077778)
		(width 0.11684)
		(layer "B.Cu")
		(net "SPI_PCH_MUXED_IO1")
	)
	(segment
		(start 47.86122 -99.63658)
		(end 48.2854 -99.63658)
		(width 0.11684)
		(layer "B.Cu")
		(net "SPI_PCH_MUXED_IO1")
	)
	(segment
		(start 38.030404 -106.471466)
		(end 38.01237 -106.4895)
		(width 0.11684)
		(layer "F.Cu")
		(net "SPI_PCH_MUXED_IO0")
	)
	(segment
		(start 40.396922 -105.335324)
		(end 40.003984 -105.598214)
		(width 0.11684)
		(layer "F.Cu")
		(net "SPI_PCH_MUXED_IO0")
	)
	(segment
		(start 41.1734 -105.156)
		(end 40.510714 -105.288334)
		(width 0.11684)
		(layer "F.Cu")
		(net "SPI_PCH_MUXED_IO0")
	)
	(segment
		(start 40.003984 -105.598214)
		(end 38.058344 -106.403902)
		(width 0.11684)
		(layer "F.Cu")
		(net "SPI_PCH_MUXED_IO0")
	)
	(segment
		(start 38.058344 -106.403902)
		(end 38.030404 -106.471466)
		(width 0.11684)
		(layer "F.Cu")
		(net "SPI_PCH_MUXED_IO0")
	)
	(segment
		(start 40.510714 -105.288334)
		(end 40.396922 -105.335324)
		(width 0.11684)
		(layer "F.Cu")
		(net "SPI_PCH_MUXED_IO0")
	)
	(via
		(at 41.1734 -105.156)
		(size 0.508)
		(drill 0.254)
		(layers "F.Cu" "B.Cu")
		(net "SPI_PCH_MUXED_IO0")
	)
	(via
		(at 44.839382 -79.768446)
		(size 0.508)
		(drill 0.254)
		(layers "F.Cu" "B.Cu")
		(net "SPI_PCH_MUXED_IO0")
	)
	(segment
		(start 44.972732 -79.635096)
		(end 44.839382 -79.768446)
		(width 0.11684)
		(layer "B.Cu")
		(net "SPI_PCH_MUXED_IO0")
	)
	(segment
		(start 46.019466 -79.635096)
		(end 44.972732 -79.635096)
		(width 0.11684)
		(layer "B.Cu")
		(net "SPI_PCH_MUXED_IO0")
	)
	(segment
		(start 46.37024 -94.163896)
		(end 46.37024 -92.782644)
		(width 0.10668)
		(layer "In4.Cu")
		(net "SPI_PCH_MUXED_IO0")
	)
	(segment
		(start 45.3136 -82.642456)
		(end 45.3136 -80.7212)
		(width 0.10668)
		(layer "In4.Cu")
		(net "SPI_PCH_MUXED_IO0")
	)
	(segment
		(start 46.37024 -92.782644)
		(end 44.84116 -91.253564)
		(width 0.10668)
		(layer "In4.Cu")
		(net "SPI_PCH_MUXED_IO0")
	)
	(segment
		(start 45.3136 -80.7212)
		(end 44.839382 -80.246982)
		(width 0.10668)
		(layer "In4.Cu")
		(net "SPI_PCH_MUXED_IO0")
	)
	(segment
		(start 44.84116 -83.114896)
		(end 45.3136 -82.642456)
		(width 0.10668)
		(layer "In4.Cu")
		(net "SPI_PCH_MUXED_IO0")
	)
	(segment
		(start 44.839382 -80.246982)
		(end 44.839382 -79.768446)
		(width 0.10668)
		(layer "In4.Cu")
		(net "SPI_PCH_MUXED_IO0")
	)
	(segment
		(start 43.59148 -96.942656)
		(end 46.37024 -94.163896)
		(width 0.10668)
		(layer "In4.Cu")
		(net "SPI_PCH_MUXED_IO0")
	)
	(segment
		(start 44.84116 -91.253564)
		(end 44.84116 -83.114896)
		(width 0.10668)
		(layer "In4.Cu")
		(net "SPI_PCH_MUXED_IO0")
	)
	(segment
		(start 41.1734 -105.156)
		(end 41.1734 -101.294946)
		(width 0.10668)
		(layer "In4.Cu")
		(net "SPI_PCH_MUXED_IO0")
	)
	(segment
		(start 41.1734 -101.294946)
		(end 43.59148 -98.876866)
		(width 0.10668)
		(layer "In4.Cu")
		(net "SPI_PCH_MUXED_IO0")
	)
	(segment
		(start 43.59148 -98.876866)
		(end 43.59148 -96.942656)
		(width 0.10668)
		(layer "In4.Cu")
		(net "SPI_PCH_MUXED_IO0")
	)
	(segment
		(start 40.250618 -87.393018)
		(end 40.78732 -87.393018)
		(width 0.11684)
		(layer "F.Cu")
		(net "SPI_PCH_MUXED_CS0_N")
	)
	(segment
		(start 40.78732 -87.393018)
		(end 40.900604 -87.279734)
		(width 0.11684)
		(layer "F.Cu")
		(net "SPI_PCH_MUXED_CS0_N")
	)
	(via
		(at 40.250618 -87.393018)
		(size 0.508)
		(drill 0.254)
		(layers "F.Cu" "B.Cu")
		(net "SPI_PCH_MUXED_CS0_N")
	)
	(via
		(at 48.133 -93.7006)
		(size 0.6604)
		(drill 0.3302)
		(layers "F.Cu" "B.Cu")
		(net "SPI_PCH_MUXED_CS0_N")
	)
	(segment
		(start 48.133 -92.065094)
		(end 48.133 -93.7006)
		(width 0.11684)
		(layer "B.Cu")
		(net "SPI_PCH_MUXED_CS0_N")
	)
	(segment
		(start 48.26 -97.789746)
		(end 47.167546 -98.8822)
		(width 0.11684)
		(layer "B.Cu")
		(net "SPI_PCH_MUXED_CS0_N")
	)
	(segment
		(start 43.355006 -98.8822)
		(end 42.037254 -99.427792)
		(width 0.11684)
		(layer "B.Cu")
		(net "SPI_PCH_MUXED_CS0_N")
	)
	(segment
		(start 46.972728 -89.263728)
		(end 48.133 -92.065094)
		(width 0.11684)
		(layer "B.Cu")
		(net "SPI_PCH_MUXED_CS0_N")
	)
	(segment
		(start 47.167546 -98.8822)
		(end 43.355006 -98.8822)
		(width 0.11684)
		(layer "B.Cu")
		(net "SPI_PCH_MUXED_CS0_N")
	)
	(segment
		(start 41.772586 -87.65413)
		(end 45.36313 -87.65413)
		(width 0.11684)
		(layer "B.Cu")
		(net "SPI_PCH_MUXED_CS0_N")
	)
	(segment
		(start 41.084246 -87.15756)
		(end 41.411652 -87.293196)
		(width 0.11684)
		(layer "B.Cu")
		(net "SPI_PCH_MUXED_CS0_N")
	)
	(segment
		(start 40.250618 -87.393018)
		(end 40.486076 -87.15756)
		(width 0.11684)
		(layer "B.Cu")
		(net "SPI_PCH_MUXED_CS0_N")
	)
	(segment
		(start 48.26 -93.8276)
		(end 48.26 -97.789746)
		(width 0.11684)
		(layer "B.Cu")
		(net "SPI_PCH_MUXED_CS0_N")
	)
	(segment
		(start 48.133 -93.7006)
		(end 48.26 -93.8276)
		(width 0.11684)
		(layer "B.Cu")
		(net "SPI_PCH_MUXED_CS0_N")
	)
	(segment
		(start 42.037254 -99.427792)
		(end 40.969184 -99.427792)
		(width 0.11684)
		(layer "B.Cu")
		(net "SPI_PCH_MUXED_CS0_N")
	)
	(segment
		(start 41.411652 -87.293196)
		(end 41.772586 -87.65413)
		(width 0.11684)
		(layer "B.Cu")
		(net "SPI_PCH_MUXED_CS0_N")
	)
	(segment
		(start 45.36313 -87.65413)
		(end 46.972728 -89.263728)
		(width 0.11684)
		(layer "B.Cu")
		(net "SPI_PCH_MUXED_CS0_N")
	)
	(segment
		(start 40.486076 -87.15756)
		(end 41.084246 -87.15756)
		(width 0.11684)
		(layer "B.Cu")
		(net "SPI_PCH_MUXED_CS0_N")
	)
	(segment
		(start 36.719256 -107.33405)
		(end 37.101526 -106.95178)
		(width 0.11684)
		(layer "F.Cu")
		(net "SPI_PCH_MUXED_CLK")
	)
	(segment
		(start 38.227254 -106.95178)
		(end 40.77716 -105.895648)
		(width 0.11684)
		(layer "F.Cu")
		(net "SPI_PCH_MUXED_CLK")
	)
	(segment
		(start 36.322 -107.33405)
		(end 36.719256 -107.33405)
		(width 0.11684)
		(layer "F.Cu")
		(net "SPI_PCH_MUXED_CLK")
	)
	(segment
		(start 37.101526 -106.95178)
		(end 38.227254 -106.95178)
		(width 0.11684)
		(layer "F.Cu")
		(net "SPI_PCH_MUXED_CLK")
	)
	(via
		(at 40.77716 -105.895648)
		(size 0.508)
		(drill 0.254)
		(layers "F.Cu" "B.Cu")
		(net "SPI_PCH_MUXED_CLK")
	)
	(via
		(at 52.991512 -82.46491)
		(size 0.508)
		(drill 0.254)
		(layers "F.Cu" "B.Cu")
		(net "SPI_PCH_MUXED_CLK")
	)
	(via
		(at 50.1904 -105.5116)
		(size 0.508)
		(drill 0.254)
		(layers "F.Cu" "B.Cu")
		(net "SPI_PCH_MUXED_CLK")
	)
	(segment
		(start 52.761896 -82.235294)
		(end 51.861466 -82.235294)
		(width 0.11684)
		(layer "B.Cu")
		(net "SPI_PCH_MUXED_CLK")
	)
	(segment
		(start 52.991512 -82.46491)
		(end 52.761896 -82.235294)
		(width 0.11684)
		(layer "B.Cu")
		(net "SPI_PCH_MUXED_CLK")
	)
	(segment
		(start 45.362876 -105.88498)
		(end 40.787828 -105.88498)
		(width 0.08382)
		(layer "In2.Cu")
		(net "SPI_PCH_MUXED_CLK")
	)
	(segment
		(start 40.787828 -105.88498)
		(end 40.77716 -105.895648)
		(width 0.08382)
		(layer "In2.Cu")
		(net "SPI_PCH_MUXED_CLK")
	)
	(segment
		(start 47.635414 -106.68889)
		(end 46.166786 -106.68889)
		(width 0.08382)
		(layer "In2.Cu")
		(net "SPI_PCH_MUXED_CLK")
	)
	(segment
		(start 46.166786 -106.68889)
		(end 45.362876 -105.88498)
		(width 0.08382)
		(layer "In2.Cu")
		(net "SPI_PCH_MUXED_CLK")
	)
	(segment
		(start 48.431704 -105.8926)
		(end 47.635414 -106.68889)
		(width 0.08382)
		(layer "In2.Cu")
		(net "SPI_PCH_MUXED_CLK")
	)
	(segment
		(start 50.1904 -105.5116)
		(end 49.8094 -105.8926)
		(width 0.08382)
		(layer "In2.Cu")
		(net "SPI_PCH_MUXED_CLK")
	)
	(segment
		(start 49.8094 -105.8926)
		(end 48.431704 -105.8926)
		(width 0.08382)
		(layer "In2.Cu")
		(net "SPI_PCH_MUXED_CLK")
	)
	(segment
		(start 54.8386 -94.681294)
		(end 54.8386 -96.121728)
		(width 0.10668)
		(layer "In4.Cu")
		(net "SPI_PCH_MUXED_CLK")
	)
	(segment
		(start 51.388518 -104.731058)
		(end 50.607976 -105.5116)
		(width 0.10668)
		(layer "In4.Cu")
		(net "SPI_PCH_MUXED_CLK")
	)
	(segment
		(start 52.26685 -102.611174)
		(end 51.388518 -104.731058)
		(width 0.10668)
		(layer "In4.Cu")
		(net "SPI_PCH_MUXED_CLK")
	)
	(segment
		(start 52.991512 -82.46491)
		(end 52.991512 -90.221308)
		(width 0.10668)
		(layer "In4.Cu")
		(net "SPI_PCH_MUXED_CLK")
	)
	(segment
		(start 52.991512 -90.221308)
		(end 54.8386 -94.681294)
		(width 0.10668)
		(layer "In4.Cu")
		(net "SPI_PCH_MUXED_CLK")
	)
	(segment
		(start 50.607976 -105.5116)
		(end 50.1904 -105.5116)
		(width 0.10668)
		(layer "In4.Cu")
		(net "SPI_PCH_MUXED_CLK")
	)
	(segment
		(start 52.26685 -102.330758)
		(end 52.26685 -102.611174)
		(width 0.10668)
		(layer "In4.Cu")
		(net "SPI_PCH_MUXED_CLK")
	)
	(segment
		(start 54.8386 -96.121728)
		(end 52.26685 -102.330758)
		(width 0.10668)
		(layer "In4.Cu")
		(net "SPI_PCH_MUXED_CLK")
	)
	(segment
		(start 34.938462 -93.859096)
		(end 35.055302 -93.742256)
		(width 0.11684)
		(layer "F.Cu")
		(net "SPI_PCH_IO3_FLASH_R1")
	)
	(segment
		(start 34.32175 -88.0364)
		(end 33.5534 -88.0364)
		(width 0.11684)
		(layer "F.Cu")
		(net "SPI_PCH_IO3_FLASH_R1")
	)
	(segment
		(start 33.0708 -90.594434)
		(end 33.0708 -93.742256)
		(width 0.11684)
		(layer "F.Cu")
		(net "SPI_PCH_IO3_FLASH_R1")
	)
	(segment
		(start 34.75355 -88.4682)
		(end 34.32175 -88.0364)
		(width 0.11684)
		(layer "F.Cu")
		(net "SPI_PCH_IO3_FLASH_R1")
	)
	(segment
		(start 34.75355 -88.4682)
		(end 34.75355 -89.3826)
		(width 0.11684)
		(layer "F.Cu")
		(net "SPI_PCH_IO3_FLASH_R1")
	)
	(segment
		(start 33.0708 -89.603326)
		(end 33.253934 -89.78646)
		(width 0.11684)
		(layer "F.Cu")
		(net "SPI_PCH_IO3_FLASH_R1")
	)
	(segment
		(start 33.0708 -88.4428)
		(end 33.0708 -89.603326)
		(width 0.11684)
		(layer "F.Cu")
		(net "SPI_PCH_IO3_FLASH_R1")
	)
	(segment
		(start 33.63976 -89.78646)
		(end 33.7566 -89.9033)
		(width 0.11684)
		(layer "F.Cu")
		(net "SPI_PCH_IO3_FLASH_R1")
	)
	(segment
		(start 33.4772 -88.0364)
		(end 33.0708 -88.4428)
		(width 0.11684)
		(layer "F.Cu")
		(net "SPI_PCH_IO3_FLASH_R1")
	)
	(segment
		(start 35.055302 -93.742256)
		(end 35.055302 -92.760038)
		(width 0.11684)
		(layer "F.Cu")
		(net "SPI_PCH_IO3_FLASH_R1")
	)
	(segment
		(start 33.253934 -89.78646)
		(end 33.63976 -89.78646)
		(width 0.11684)
		(layer "F.Cu")
		(net "SPI_PCH_IO3_FLASH_R1")
	)
	(segment
		(start 33.0708 -93.742256)
		(end 33.18764 -93.859096)
		(width 0.11684)
		(layer "F.Cu")
		(net "SPI_PCH_IO3_FLASH_R1")
	)
	(segment
		(start 33.5534 -88.0364)
		(end 33.4772 -88.0364)
		(width 0.11684)
		(layer "F.Cu")
		(net "SPI_PCH_IO3_FLASH_R1")
	)
	(segment
		(start 33.253934 -90.4113)
		(end 33.0708 -90.594434)
		(width 0.11684)
		(layer "F.Cu")
		(net "SPI_PCH_IO3_FLASH_R1")
	)
	(segment
		(start 33.63976 -90.4113)
		(end 33.253934 -90.4113)
		(width 0.11684)
		(layer "F.Cu")
		(net "SPI_PCH_IO3_FLASH_R1")
	)
	(segment
		(start 33.7566 -89.9033)
		(end 33.7566 -90.29446)
		(width 0.11684)
		(layer "F.Cu")
		(net "SPI_PCH_IO3_FLASH_R1")
	)
	(segment
		(start 33.18764 -93.859096)
		(end 34.938462 -93.859096)
		(width 0.11684)
		(layer "F.Cu")
		(net "SPI_PCH_IO3_FLASH_R1")
	)
	(segment
		(start 33.7566 -90.29446)
		(end 33.63976 -90.4113)
		(width 0.11684)
		(layer "F.Cu")
		(net "SPI_PCH_IO3_FLASH_R1")
	)
	(via
		(at 33.5534 -88.0364)
		(size 0.762)
		(drill 0.381)
		(layers "F.Cu" "B.Cu")
		(net "SPI_PCH_IO3_FLASH_R1")
	)
	(segment
		(start 42.8244 -106.492548)
		(end 43.0149 -106.302048)
		(width 0.11684)
		(layer "F.Cu")
		(net "SPI_PCH_IO2_FLASH_R1")
	)
	(segment
		(start 43.54576 -105.651808)
		(end 42.81424 -105.651808)
		(width 0.11684)
		(layer "F.Cu")
		(net "SPI_PCH_IO2_FLASH_R1")
	)
	(segment
		(start 43.54576 -106.302048)
		(end 43.6626 -106.185208)
		(width 0.11684)
		(layer "F.Cu")
		(net "SPI_PCH_IO2_FLASH_R1")
	)
	(segment
		(start 43.6626 -105.768648)
		(end 43.54576 -105.651808)
		(width 0.11684)
		(layer "F.Cu")
		(net "SPI_PCH_IO2_FLASH_R1")
	)
	(segment
		(start 43.504104 -107.599734)
		(end 43.109134 -107.599734)
		(width 0.11684)
		(layer "F.Cu")
		(net "SPI_PCH_IO2_FLASH_R1")
	)
	(segment
		(start 42.6974 -104.244394)
		(end 42.827194 -104.1146)
		(width 0.11684)
		(layer "F.Cu")
		(net "SPI_PCH_IO2_FLASH_R1")
	)
	(segment
		(start 43.945302 -103.654098)
		(end 43.945302 -103.060246)
		(width 0.11684)
		(layer "F.Cu")
		(net "SPI_PCH_IO2_FLASH_R1")
	)
	(segment
		(start 43.4848 -104.1146)
		(end 43.945302 -103.654098)
		(width 0.11684)
		(layer "F.Cu")
		(net "SPI_PCH_IO2_FLASH_R1")
	)
	(segment
		(start 43.504104 -107.599734)
		(end 43.556174 -107.547664)
		(width 0.11684)
		(layer "F.Cu")
		(net "SPI_PCH_IO2_FLASH_R1")
	)
	(segment
		(start 43.556174 -107.547664)
		(end 44.452286 -107.547664)
		(width 0.11684)
		(layer "F.Cu")
		(net "SPI_PCH_IO2_FLASH_R1")
	)
	(segment
		(start 42.6974 -105.534968)
		(end 42.6974 -104.244394)
		(width 0.11684)
		(layer "F.Cu")
		(net "SPI_PCH_IO2_FLASH_R1")
	)
	(segment
		(start 42.8244 -107.315)
		(end 42.8244 -106.492548)
		(width 0.11684)
		(layer "F.Cu")
		(net "SPI_PCH_IO2_FLASH_R1")
	)
	(segment
		(start 44.452286 -107.547664)
		(end 44.4754 -107.52455)
		(width 0.11684)
		(layer "F.Cu")
		(net "SPI_PCH_IO2_FLASH_R1")
	)
	(segment
		(start 43.0149 -106.302048)
		(end 43.54576 -106.302048)
		(width 0.11684)
		(layer "F.Cu")
		(net "SPI_PCH_IO2_FLASH_R1")
	)
	(segment
		(start 43.6626 -106.185208)
		(end 43.6626 -105.768648)
		(width 0.11684)
		(layer "F.Cu")
		(net "SPI_PCH_IO2_FLASH_R1")
	)
	(segment
		(start 42.827194 -104.1146)
		(end 43.4848 -104.1146)
		(width 0.11684)
		(layer "F.Cu")
		(net "SPI_PCH_IO2_FLASH_R1")
	)
	(segment
		(start 43.109134 -107.599734)
		(end 42.8244 -107.315)
		(width 0.11684)
		(layer "F.Cu")
		(net "SPI_PCH_IO2_FLASH_R1")
	)
	(segment
		(start 42.81424 -105.651808)
		(end 42.6974 -105.534968)
		(width 0.11684)
		(layer "F.Cu")
		(net "SPI_PCH_IO2_FLASH_R1")
	)
	(segment
		(start 44.3738 -90.2208)
		(end 44.3738 -88.50503)
		(width 0.11684)
		(layer "F.Cu")
		(net "SPI_PCH_IO1_FLASH_R1")
	)
	(segment
		(start 44.3738 -88.50503)
		(end 43.948604 -88.079834)
		(width 0.11684)
		(layer "F.Cu")
		(net "SPI_PCH_IO1_FLASH_R1")
	)
	(segment
		(start 43.945302 -92.760038)
		(end 43.945302 -90.649298)
		(width 0.11684)
		(layer "F.Cu")
		(net "SPI_PCH_IO1_FLASH_R1")
	)
	(segment
		(start 43.945302 -90.649298)
		(end 44.3738 -90.2208)
		(width 0.11684)
		(layer "F.Cu")
		(net "SPI_PCH_IO1_FLASH_R1")
	)
	(segment
		(start 37.21227 -106.03103)
		(end 37.235384 -106.054144)
		(width 0.11684)
		(layer "F.Cu")
		(net "SPI_PCH_IO0_FLASH_R1")
	)
	(segment
		(start 36.325302 -103.835708)
		(end 37.21227 -105.97769)
		(width 0.11684)
		(layer "F.Cu")
		(net "SPI_PCH_IO0_FLASH_R1")
	)
	(segment
		(start 37.235384 -106.054144)
		(end 37.235384 -106.466386)
		(width 0.11684)
		(layer "F.Cu")
		(net "SPI_PCH_IO0_FLASH_R1")
	)
	(segment
		(start 37.21227 -105.97769)
		(end 37.21227 -106.03103)
		(width 0.11684)
		(layer "F.Cu")
		(net "SPI_PCH_IO0_FLASH_R1")
	)
	(segment
		(start 36.325302 -103.060246)
		(end 36.325302 -103.835708)
		(width 0.11684)
		(layer "F.Cu")
		(net "SPI_PCH_IO0_FLASH_R1")
	)
	(segment
		(start 37.235384 -106.466386)
		(end 37.21227 -106.4895)
		(width 0.11684)
		(layer "F.Cu")
		(net "SPI_PCH_IO0_FLASH_R1")
	)
	(segment
		(start 41.916604 -88.079834)
		(end 42.932604 -88.079834)
		(width 0.11684)
		(layer "F.Cu")
		(net "SPI_PCH_CS0_FLASH_R1_N")
	)
	(segment
		(start 43.574208 -88.687402)
		(end 42.96664 -88.079834)
		(width 0.11684)
		(layer "F.Cu")
		(net "SPI_PCH_CS0_FLASH_R1_N")
	)
	(segment
		(start 40.900604 -88.079834)
		(end 41.916604 -88.079834)
		(width 0.11684)
		(layer "F.Cu")
		(net "SPI_PCH_CS0_FLASH_R1_N")
	)
	(segment
		(start 42.96664 -88.079834)
		(end 42.932604 -88.079834)
		(width 0.11684)
		(layer "F.Cu")
		(net "SPI_PCH_CS0_FLASH_R1_N")
	)
	(segment
		(start 43.574208 -89.164922)
		(end 43.574208 -88.687402)
		(width 0.11684)
		(layer "F.Cu")
		(net "SPI_PCH_CS0_FLASH_R1_N")
	)
	(segment
		(start 42.675302 -92.760038)
		(end 42.675302 -91.335098)
		(width 0.11684)
		(layer "F.Cu")
		(net "SPI_PCH_CS0_FLASH_R1_N")
	)
	(segment
		(start 42.675302 -91.335098)
		(end 43.574208 -89.164922)
		(width 0.11684)
		(layer "F.Cu")
		(net "SPI_PCH_CS0_FLASH_R1_N")
	)
	(segment
		(start 36.16325 -106.3752)
		(end 36.322 -106.53395)
		(width 0.11684)
		(layer "F.Cu")
		(net "SPI_PCH_CLK_FLASH_R1")
	)
	(segment
		(start 35.0266 -106.3752)
		(end 36.16325 -106.3752)
		(width 0.11684)
		(layer "F.Cu")
		(net "SPI_PCH_CLK_FLASH_R1")
	)
	(segment
		(start 34.772854 -104.2924)
		(end 34.772854 -106.121454)
		(width 0.11684)
		(layer "F.Cu")
		(net "SPI_PCH_CLK_FLASH_R1")
	)
	(segment
		(start 35.055302 -103.060246)
		(end 35.055302 -104.009952)
		(width 0.11684)
		(layer "F.Cu")
		(net "SPI_PCH_CLK_FLASH_R1")
	)
	(segment
		(start 34.772854 -106.121454)
		(end 35.0266 -106.3752)
		(width 0.11684)
		(layer "F.Cu")
		(net "SPI_PCH_CLK_FLASH_R1")
	)
	(segment
		(start 35.055302 -104.009952)
		(end 34.772854 -104.2924)
		(width 0.11684)
		(layer "F.Cu")
		(net "SPI_PCH_CLK_FLASH_R1")
	)
	(segment
		(start 20.701 -43.30065)
		(end 22.815296 -43.30065)
		(width 0.11684)
		(layer "F.Cu")
		(net "RST_SPI_FLASH_N")
	)
	(segment
		(start 70.961504 -24.134826)
		(end 70.6882 -24.134826)
		(width 0.11684)
		(layer "F.Cu")
		(net "RST_SPI_FLASH_N")
	)
	(segment
		(start 60.094876 -40.17137)
		(end 60.4901 -39.776146)
		(width 0.11684)
		(layer "F.Cu")
		(net "RST_SPI_FLASH_N")
	)
	(segment
		(start 22.815296 -43.30065)
		(end 24.3713 -41.744646)
		(width 0.11684)
		(layer "F.Cu")
		(net "RST_SPI_FLASH_N")
	)
	(segment
		(start 24.3713 -41.744646)
		(end 24.3713 -38.8366)
		(width 0.11684)
		(layer "F.Cu")
		(net "RST_SPI_FLASH_N")
	)
	(segment
		(start 71.40829 -23.68804)
		(end 70.961504 -24.134826)
		(width 0.11684)
		(layer "F.Cu")
		(net "RST_SPI_FLASH_N")
	)
	(via
		(at 70.6882 -24.134826)
		(size 0.508)
		(drill 0.254)
		(layers "F.Cu" "B.Cu")
		(net "RST_SPI_FLASH_N")
	)
	(via
		(at 24.3713 -38.8366)
		(size 0.508)
		(drill 0.254)
		(layers "F.Cu" "B.Cu")
		(net "RST_SPI_FLASH_N")
	)
	(via
		(at 60.4901 -39.776146)
		(size 0.4572)
		(drill 0.254)
		(layers "F.Cu" "B.Cu")
		(net "RST_SPI_FLASH_N")
	)
	(via
		(at 28.1813 -20.8407)
		(size 0.508)
		(drill 0.254)
		(layers "F.Cu" "B.Cu")
		(net "RST_SPI_FLASH_N")
	)
	(segment
		(start 39.80942 -24.278844)
		(end 39.80942 -21.953982)
		(width 0.08382)
		(layer "In2.Cu")
		(net "RST_SPI_FLASH_N")
	)
	(segment
		(start 45.72 -25.4)
		(end 45.593 -25.527)
		(width 0.08382)
		(layer "In2.Cu")
		(net "RST_SPI_FLASH_N")
	)
	(segment
		(start 68.65366 -23.18766)
		(end 65.786 -20.32)
		(width 0.08382)
		(layer "In2.Cu")
		(net "RST_SPI_FLASH_N")
	)
	(segment
		(start 68.65366 -23.65756)
		(end 68.65366 -23.18766)
		(width 0.08382)
		(layer "In2.Cu")
		(net "RST_SPI_FLASH_N")
	)
	(segment
		(start 46.09465 -24.31415)
		(end 45.72 -24.6888)
		(width 0.08382)
		(layer "In2.Cu")
		(net "RST_SPI_FLASH_N")
	)
	(segment
		(start 62.551564 -20.32)
		(end 61.535564 -21.336)
		(width 0.08382)
		(layer "In2.Cu")
		(net "RST_SPI_FLASH_N")
	)
	(segment
		(start 69.130926 -24.134826)
		(end 68.65366 -23.65756)
		(width 0.08382)
		(layer "In2.Cu")
		(net "RST_SPI_FLASH_N")
	)
	(segment
		(start 40.803576 -25.273)
		(end 39.80942 -24.278844)
		(width 0.08382)
		(layer "In2.Cu")
		(net "RST_SPI_FLASH_N")
	)
	(segment
		(start 57.653174 -22.19833)
		(end 51.030124 -22.19833)
		(width 0.08382)
		(layer "In2.Cu")
		(net "RST_SPI_FLASH_N")
	)
	(segment
		(start 61.535564 -21.336)
		(end 60.051442 -21.336)
		(width 0.08382)
		(layer "In2.Cu")
		(net "RST_SPI_FLASH_N")
	)
	(segment
		(start 31.56839 -21.46681)
		(end 30.893258 -21.46681)
		(width 0.08382)
		(layer "In2.Cu")
		(net "RST_SPI_FLASH_N")
	)
	(segment
		(start 51.030124 -22.19833)
		(end 48.914304 -24.31415)
		(width 0.08382)
		(layer "In2.Cu")
		(net "RST_SPI_FLASH_N")
	)
	(segment
		(start 57.861454 -21.99005)
		(end 57.653174 -22.19833)
		(width 0.08382)
		(layer "In2.Cu")
		(net "RST_SPI_FLASH_N")
	)
	(segment
		(start 44.3484 -25.527)
		(end 44.0944 -25.273)
		(width 0.08382)
		(layer "In2.Cu")
		(net "RST_SPI_FLASH_N")
	)
	(segment
		(start 30.267148 -20.8407)
		(end 28.1813 -20.8407)
		(width 0.08382)
		(layer "In2.Cu")
		(net "RST_SPI_FLASH_N")
	)
	(segment
		(start 39.80942 -21.953982)
		(end 37.473128 -19.61769)
		(width 0.08382)
		(layer "In2.Cu")
		(net "RST_SPI_FLASH_N")
	)
	(segment
		(start 45.72 -24.6888)
		(end 45.72 -25.4)
		(width 0.08382)
		(layer "In2.Cu")
		(net "RST_SPI_FLASH_N")
	)
	(segment
		(start 45.593 -25.527)
		(end 44.3484 -25.527)
		(width 0.08382)
		(layer "In2.Cu")
		(net "RST_SPI_FLASH_N")
	)
	(segment
		(start 60.051442 -21.336)
		(end 59.397392 -21.99005)
		(width 0.08382)
		(layer "In2.Cu")
		(net "RST_SPI_FLASH_N")
	)
	(segment
		(start 59.397392 -21.99005)
		(end 57.861454 -21.99005)
		(width 0.08382)
		(layer "In2.Cu")
		(net "RST_SPI_FLASH_N")
	)
	(segment
		(start 70.6882 -24.134826)
		(end 69.130926 -24.134826)
		(width 0.08382)
		(layer "In2.Cu")
		(net "RST_SPI_FLASH_N")
	)
	(segment
		(start 30.893258 -21.46681)
		(end 30.267148 -20.8407)
		(width 0.08382)
		(layer "In2.Cu")
		(net "RST_SPI_FLASH_N")
	)
	(segment
		(start 48.914304 -24.31415)
		(end 46.09465 -24.31415)
		(width 0.08382)
		(layer "In2.Cu")
		(net "RST_SPI_FLASH_N")
	)
	(segment
		(start 65.786 -20.32)
		(end 62.551564 -20.32)
		(width 0.08382)
		(layer "In2.Cu")
		(net "RST_SPI_FLASH_N")
	)
	(segment
		(start 37.473128 -19.61769)
		(end 33.41751 -19.61769)
		(width 0.08382)
		(layer "In2.Cu")
		(net "RST_SPI_FLASH_N")
	)
	(segment
		(start 44.0944 -25.273)
		(end 40.803576 -25.273)
		(width 0.08382)
		(layer "In2.Cu")
		(net "RST_SPI_FLASH_N")
	)
	(segment
		(start 33.41751 -19.61769)
		(end 31.56839 -21.46681)
		(width 0.08382)
		(layer "In2.Cu")
		(net "RST_SPI_FLASH_N")
	)
	(segment
		(start 65.4177 -30.169358)
		(end 68.458842 -27.128216)
		(width 0.10668)
		(layer "In7.Cu")
		(net "RST_SPI_FLASH_N")
	)
	(segment
		(start 68.458842 -27.128216)
		(end 68.458842 -26.493216)
		(width 0.10668)
		(layer "In7.Cu")
		(net "RST_SPI_FLASH_N")
	)
	(segment
		(start 63.643256 -34.205672)
		(end 63.643256 -32.722058)
		(width 0.10668)
		(layer "In7.Cu")
		(net "RST_SPI_FLASH_N")
	)
	(segment
		(start 60.4901 -39.776146)
		(end 60.4901 -37.492432)
		(width 0.10668)
		(layer "In7.Cu")
		(net "RST_SPI_FLASH_N")
	)
	(segment
		(start 61.97727 -35.871658)
		(end 63.643256 -34.205672)
		(width 0.10668)
		(layer "In7.Cu")
		(net "RST_SPI_FLASH_N")
	)
	(segment
		(start 70.048374 -24.134826)
		(end 70.6882 -24.134826)
		(width 0.10668)
		(layer "In7.Cu")
		(net "RST_SPI_FLASH_N")
	)
	(segment
		(start 61.97727 -36.005262)
		(end 61.97727 -35.871658)
		(width 0.10668)
		(layer "In7.Cu")
		(net "RST_SPI_FLASH_N")
	)
	(segment
		(start 60.4901 -37.492432)
		(end 61.97727 -36.005262)
		(width 0.10668)
		(layer "In7.Cu")
		(net "RST_SPI_FLASH_N")
	)
	(segment
		(start 68.458842 -26.493216)
		(end 69.48932 -25.462738)
		(width 0.10668)
		(layer "In7.Cu")
		(net "RST_SPI_FLASH_N")
	)
	(segment
		(start 69.48932 -25.462738)
		(end 69.48932 -24.69388)
		(width 0.10668)
		(layer "In7.Cu")
		(net "RST_SPI_FLASH_N")
	)
	(segment
		(start 69.48932 -24.69388)
		(end 70.048374 -24.134826)
		(width 0.10668)
		(layer "In7.Cu")
		(net "RST_SPI_FLASH_N")
	)
	(segment
		(start 65.4177 -30.947614)
		(end 65.4177 -30.169358)
		(width 0.10668)
		(layer "In7.Cu")
		(net "RST_SPI_FLASH_N")
	)
	(segment
		(start 63.643256 -32.722058)
		(end 65.4177 -30.947614)
		(width 0.10668)
		(layer "In7.Cu")
		(net "RST_SPI_FLASH_N")
	)
	(segment
		(start 24.03729 -33.214564)
		(end 24.03729 -35.87369)
		(width 0.08382)
		(layer "In9.Cu")
		(net "RST_SPI_FLASH_N")
	)
	(segment
		(start 24.6888 -38.8366)
		(end 24.3713 -38.8366)
		(width 0.08382)
		(layer "In9.Cu")
		(net "RST_SPI_FLASH_N")
	)
	(segment
		(start 25.98674 -31.265114)
		(end 24.03729 -33.214564)
		(width 0.08382)
		(layer "In9.Cu")
		(net "RST_SPI_FLASH_N")
	)
	(segment
		(start 28.194 -23.8252)
		(end 26.1112 -25.908)
		(width 0.08382)
		(layer "In9.Cu")
		(net "RST_SPI_FLASH_N")
	)
	(segment
		(start 27.813 -21.209)
		(end 27.813 -22.606)
		(width 0.08382)
		(layer "In9.Cu")
		(net "RST_SPI_FLASH_N")
	)
	(segment
		(start 25.019 -38.5064)
		(end 24.6888 -38.8366)
		(width 0.08382)
		(layer "In9.Cu")
		(net "RST_SPI_FLASH_N")
	)
	(segment
		(start 24.03729 -35.87369)
		(end 25.019 -36.8554)
		(width 0.08382)
		(layer "In9.Cu")
		(net "RST_SPI_FLASH_N")
	)
	(segment
		(start 26.1112 -25.908)
		(end 26.1112 -30.16377)
		(width 0.08382)
		(layer "In9.Cu")
		(net "RST_SPI_FLASH_N")
	)
	(segment
		(start 28.1813 -20.8407)
		(end 27.813 -21.209)
		(width 0.08382)
		(layer "In9.Cu")
		(net "RST_SPI_FLASH_N")
	)
	(segment
		(start 25.019 -36.8554)
		(end 25.019 -38.5064)
		(width 0.08382)
		(layer "In9.Cu")
		(net "RST_SPI_FLASH_N")
	)
	(segment
		(start 28.194 -22.987)
		(end 28.194 -23.8252)
		(width 0.08382)
		(layer "In9.Cu")
		(net "RST_SPI_FLASH_N")
	)
	(segment
		(start 26.1112 -30.16377)
		(end 25.98674 -30.28823)
		(width 0.08382)
		(layer "In9.Cu")
		(net "RST_SPI_FLASH_N")
	)
	(segment
		(start 27.813 -22.606)
		(end 28.194 -22.987)
		(width 0.08382)
		(layer "In9.Cu")
		(net "RST_SPI_FLASH_N")
	)
	(segment
		(start 25.98674 -30.28823)
		(end 25.98674 -31.265114)
		(width 0.08382)
		(layer "In9.Cu")
		(net "RST_SPI_FLASH_N")
	)
	(segment
		(start 54.494938 -56.971184)
		(end 54.099714 -56.57596)
		(width 0.11684)
		(layer "F.Cu")
		(net "SPI_BMC_MOSI_IO0_R")
	)
	(via
		(at 54.099714 -56.57596)
		(size 0.4572)
		(drill 0.254)
		(layers "F.Cu" "B.Cu")
		(net "SPI_BMC_MOSI_IO0_R")
	)
	(via
		(at 46.64075 -69.469)
		(size 0.508)
		(drill 0.254)
		(layers "F.Cu" "B.Cu")
		(net "SPI_BMC_MOSI_IO0_R")
	)
	(segment
		(start 54.5338 -59.179206)
		(end 54.5338 -57.010046)
		(width 0.11684)
		(layer "B.Cu")
		(net "SPI_BMC_MOSI_IO0_R")
	)
	(segment
		(start 46.64075 -69.469)
		(end 46.64075 -70.8406)
		(width 0.11684)
		(layer "B.Cu")
		(net "SPI_BMC_MOSI_IO0_R")
	)
	(segment
		(start 46.64075 -70.8406)
		(end 46.56455 -70.9168)
		(width 0.11684)
		(layer "B.Cu")
		(net "SPI_BMC_MOSI_IO0_R")
	)
	(segment
		(start 54.16423 -60.66155)
		(end 54.242208 -60.629292)
		(width 0.11684)
		(layer "B.Cu")
		(net "SPI_BMC_MOSI_IO0_R")
	)
	(segment
		(start 54.248304 -60.61456)
		(end 54.5338 -59.179206)
		(width 0.11684)
		(layer "B.Cu")
		(net "SPI_BMC_MOSI_IO0_R")
	)
	(segment
		(start 54.5338 -57.010046)
		(end 54.099714 -56.57596)
		(width 0.11684)
		(layer "B.Cu")
		(net "SPI_BMC_MOSI_IO0_R")
	)
	(segment
		(start 54.242208 -60.629292)
		(end 54.248304 -60.61456)
		(width 0.11684)
		(layer "B.Cu")
		(net "SPI_BMC_MOSI_IO0_R")
	)
	(segment
		(start 46.4058 -69.13245)
		(end 46.4058 -68.453)
		(width 0.08382)
		(layer "In9.Cu")
		(net "SPI_BMC_MOSI_IO0_R")
	)
	(segment
		(start 50.882042 -63.493904)
		(end 51.09337 -63.282576)
		(width 0.08382)
		(layer "In9.Cu")
		(net "SPI_BMC_MOSI_IO0_R")
	)
	(segment
		(start 46.4058 -68.453)
		(end 46.65091 -68.20789)
		(width 0.08382)
		(layer "In9.Cu")
		(net "SPI_BMC_MOSI_IO0_R")
	)
	(segment
		(start 51.09337 -63.282576)
		(end 51.09337 -62.978792)
		(width 0.08382)
		(layer "In9.Cu")
		(net "SPI_BMC_MOSI_IO0_R")
	)
	(segment
		(start 48.418496 -64.624712)
		(end 49.549304 -63.493904)
		(width 0.08382)
		(layer "In9.Cu")
		(net "SPI_BMC_MOSI_IO0_R")
	)
	(segment
		(start 49.549304 -63.493904)
		(end 50.882042 -63.493904)
		(width 0.08382)
		(layer "In9.Cu")
		(net "SPI_BMC_MOSI_IO0_R")
	)
	(segment
		(start 46.64075 -69.469)
		(end 46.64075 -69.3674)
		(width 0.08382)
		(layer "In9.Cu")
		(net "SPI_BMC_MOSI_IO0_R")
	)
	(segment
		(start 51.09337 -62.978792)
		(end 54.473094 -59.599068)
		(width 0.08382)
		(layer "In9.Cu")
		(net "SPI_BMC_MOSI_IO0_R")
	)
	(segment
		(start 46.65091 -68.20789)
		(end 47.46371 -68.20789)
		(width 0.08382)
		(layer "In9.Cu")
		(net "SPI_BMC_MOSI_IO0_R")
	)
	(segment
		(start 54.099714 -56.846216)
		(end 54.099714 -56.57596)
		(width 0.08382)
		(layer "In9.Cu")
		(net "SPI_BMC_MOSI_IO0_R")
	)
	(segment
		(start 54.473094 -59.599068)
		(end 54.473094 -57.219596)
		(width 0.08382)
		(layer "In9.Cu")
		(net "SPI_BMC_MOSI_IO0_R")
	)
	(segment
		(start 47.46371 -68.20789)
		(end 47.875952 -67.795648)
		(width 0.08382)
		(layer "In9.Cu")
		(net "SPI_BMC_MOSI_IO0_R")
	)
	(segment
		(start 54.473094 -57.219596)
		(end 54.099714 -56.846216)
		(width 0.08382)
		(layer "In9.Cu")
		(net "SPI_BMC_MOSI_IO0_R")
	)
	(segment
		(start 47.875952 -65.93459)
		(end 48.418496 -64.624712)
		(width 0.08382)
		(layer "In9.Cu")
		(net "SPI_BMC_MOSI_IO0_R")
	)
	(segment
		(start 47.875952 -67.795648)
		(end 47.875952 -65.93459)
		(width 0.08382)
		(layer "In9.Cu")
		(net "SPI_BMC_MOSI_IO0_R")
	)
	(segment
		(start 46.64075 -69.3674)
		(end 46.4058 -69.13245)
		(width 0.08382)
		(layer "In9.Cu")
		(net "SPI_BMC_MOSI_IO0_R")
	)
	(segment
		(start 55.295038 -56.171338)
		(end 54.899814 -56.566562)
		(width 0.11684)
		(layer "F.Cu")
		(net "SPI_BMC_MISO_IO1_R")
	)
	(via
		(at 55.118 -59.3852)
		(size 0.6604)
		(drill 0.3302)
		(layers "F.Cu" "B.Cu")
		(net "SPI_BMC_MISO_IO1_R")
	)
	(via
		(at 54.899814 -56.566562)
		(size 0.4572)
		(drill 0.254)
		(layers "F.Cu" "B.Cu")
		(net "SPI_BMC_MISO_IO1_R")
	)
	(segment
		(start 55.311294 -62.931294)
		(end 55.5498 -63.1698)
		(width 0.11684)
		(layer "B.Cu")
		(net "SPI_BMC_MISO_IO1_R")
	)
	(segment
		(start 55.5498 -63.1698)
		(end 55.80634 -63.1698)
		(width 0.11684)
		(layer "B.Cu")
		(net "SPI_BMC_MISO_IO1_R")
	)
	(segment
		(start 55.118 -59.7662)
		(end 55.118 -59.3852)
		(width 0.11684)
		(layer "B.Cu")
		(net "SPI_BMC_MISO_IO1_R")
	)
	(segment
		(start 55.118 -59.3852)
		(end 55.118 -58.675778)
		(width 0.11684)
		(layer "B.Cu")
		(net "SPI_BMC_MISO_IO1_R")
	)
	(segment
		(start 56.1086 -65.36055)
		(end 55.8546 -65.61455)
		(width 0.11684)
		(layer "B.Cu")
		(net "SPI_BMC_MISO_IO1_R")
	)
	(segment
		(start 55.311294 -61.553344)
		(end 55.311294 -62.931294)
		(width 0.11684)
		(layer "B.Cu")
		(net "SPI_BMC_MISO_IO1_R")
	)
	(segment
		(start 55.1688 -61.41085)
		(end 54.883304 -61.41085)
		(width 0.11684)
		(layer "B.Cu")
		(net "SPI_BMC_MISO_IO1_R")
	)
	(segment
		(start 54.7116 -61.239146)
		(end 54.7116 -60.371482)
		(width 0.11684)
		(layer "B.Cu")
		(net "SPI_BMC_MISO_IO1_R")
	)
	(segment
		(start 54.7116 -60.371482)
		(end 54.852316 -60.031884)
		(width 0.11684)
		(layer "B.Cu")
		(net "SPI_BMC_MISO_IO1_R")
	)
	(segment
		(start 56.1086 -63.47206)
		(end 56.1086 -65.36055)
		(width 0.11684)
		(layer "B.Cu")
		(net "SPI_BMC_MISO_IO1_R")
	)
	(segment
		(start 55.80634 -63.1698)
		(end 56.1086 -63.47206)
		(width 0.11684)
		(layer "B.Cu")
		(net "SPI_BMC_MISO_IO1_R")
	)
	(segment
		(start 54.899814 -58.457592)
		(end 54.899814 -56.566562)
		(width 0.11684)
		(layer "B.Cu")
		(net "SPI_BMC_MISO_IO1_R")
	)
	(segment
		(start 54.852316 -60.031884)
		(end 55.118 -59.7662)
		(width 0.11684)
		(layer "B.Cu")
		(net "SPI_BMC_MISO_IO1_R")
	)
	(segment
		(start 55.118 -58.675778)
		(end 54.899814 -58.457592)
		(width 0.11684)
		(layer "B.Cu")
		(net "SPI_BMC_MISO_IO1_R")
	)
	(segment
		(start 54.883304 -61.41085)
		(end 54.7116 -61.239146)
		(width 0.11684)
		(layer "B.Cu")
		(net "SPI_BMC_MISO_IO1_R")
	)
	(segment
		(start 55.1688 -61.41085)
		(end 55.311294 -61.553344)
		(width 0.11684)
		(layer "B.Cu")
		(net "SPI_BMC_MISO_IO1_R")
	)
	(segment
		(start 54.102 -63.627)
		(end 54.102 -65.557908)
		(width 0.11684)
		(layer "F.Cu")
		(net "SPI_BMC_IO3_R")
	)
	(segment
		(start 53.671216 -65.988692)
		(end 53.671216 -66.752216)
		(width 0.11684)
		(layer "F.Cu")
		(net "SPI_BMC_IO3_R")
	)
	(segment
		(start 54.0512 -62.981586)
		(end 54.0512 -61.414914)
		(width 0.11684)
		(layer "F.Cu")
		(net "SPI_BMC_IO3_R")
	)
	(segment
		(start 54.102 -65.557908)
		(end 53.671216 -65.988692)
		(width 0.11684)
		(layer "F.Cu")
		(net "SPI_BMC_IO3_R")
	)
	(segment
		(start 54.102 -63.627)
		(end 54.102 -63.10376)
		(width 0.11684)
		(layer "F.Cu")
		(net "SPI_BMC_IO3_R")
	)
	(segment
		(start 54.356 -68.17995)
		(end 53.213 -69.32295)
		(width 0.11684)
		(layer "F.Cu")
		(net "SPI_BMC_IO3_R")
	)
	(segment
		(start 54.102 -63.10376)
		(end 54.0512 -62.981586)
		(width 0.11684)
		(layer "F.Cu")
		(net "SPI_BMC_IO3_R")
	)
	(segment
		(start 54.0512 -61.414914)
		(end 56.094884 -59.37123)
		(width 0.11684)
		(layer "F.Cu")
		(net "SPI_BMC_IO3_R")
	)
	(segment
		(start 53.671216 -66.752216)
		(end 54.356 -67.437)
		(width 0.11684)
		(layer "F.Cu")
		(net "SPI_BMC_IO3_R")
	)
	(segment
		(start 54.356 -67.437)
		(end 54.356 -68.17995)
		(width 0.11684)
		(layer "F.Cu")
		(net "SPI_BMC_IO3_R")
	)
	(via
		(at 54.102 -63.627)
		(size 0.762)
		(drill 0.381)
		(layers "F.Cu" "B.Cu")
		(net "SPI_BMC_IO3_R")
	)
	(segment
		(start 55.2196 -61.1632)
		(end 55.6006 -60.7822)
		(width 0.11684)
		(layer "F.Cu")
		(net "SPI_BMC_IO2_R")
	)
	(segment
		(start 56.483504 -59.210194)
		(end 56.482234 -59.208924)
		(width 0.11684)
		(layer "F.Cu")
		(net "SPI_BMC_IO2_R")
	)
	(segment
		(start 56.482234 -58.95848)
		(end 56.094884 -58.57113)
		(width 0.11684)
		(layer "F.Cu")
		(net "SPI_BMC_IO2_R")
	)
	(segment
		(start 56.482234 -59.533536)
		(end 56.483504 -59.532266)
		(width 0.11684)
		(layer "F.Cu")
		(net "SPI_BMC_IO2_R")
	)
	(segment
		(start 55.4228 -63.25235)
		(end 55.4228 -62.479428)
		(width 0.11684)
		(layer "F.Cu")
		(net "SPI_BMC_IO2_R")
	)
	(segment
		(start 56.483504 -59.532266)
		(end 56.483504 -59.210194)
		(width 0.11684)
		(layer "F.Cu")
		(net "SPI_BMC_IO2_R")
	)
	(segment
		(start 56.107076 -60.7822)
		(end 56.482234 -60.407042)
		(width 0.11684)
		(layer "F.Cu")
		(net "SPI_BMC_IO2_R")
	)
	(segment
		(start 56.482234 -59.208924)
		(end 56.482234 -58.95848)
		(width 0.11684)
		(layer "F.Cu")
		(net "SPI_BMC_IO2_R")
	)
	(segment
		(start 56.482234 -60.407042)
		(end 56.482234 -59.533536)
		(width 0.11684)
		(layer "F.Cu")
		(net "SPI_BMC_IO2_R")
	)
	(segment
		(start 55.4228 -62.479428)
		(end 55.2196 -61.9887)
		(width 0.11684)
		(layer "F.Cu")
		(net "SPI_BMC_IO2_R")
	)
	(segment
		(start 55.6006 -60.7822)
		(end 56.107076 -60.7822)
		(width 0.11684)
		(layer "F.Cu")
		(net "SPI_BMC_IO2_R")
	)
	(segment
		(start 55.2196 -61.9887)
		(end 55.2196 -61.1632)
		(width 0.11684)
		(layer "F.Cu")
		(net "SPI_BMC_IO2_R")
	)
	(segment
		(start 53.52161 -62.2046)
		(end 53.52161 -61.144658)
		(width 0.11684)
		(layer "F.Cu")
		(net "SPI_BMC_CLK_R")
	)
	(segment
		(start 53.1876 -62.5348)
		(end 53.1876 -62.4586)
		(width 0.11684)
		(layer "F.Cu")
		(net "SPI_BMC_CLK_R")
	)
	(segment
		(start 53.4416 -62.2046)
		(end 53.52161 -62.2046)
		(width 0.11684)
		(layer "F.Cu")
		(net "SPI_BMC_CLK_R")
	)
	(segment
		(start 53.1876 -62.4586)
		(end 53.4416 -62.2046)
		(width 0.11684)
		(layer "F.Cu")
		(net "SPI_BMC_CLK_R")
	)
	(segment
		(start 52.959 -63.363094)
		(end 52.959 -62.7634)
		(width 0.11684)
		(layer "F.Cu")
		(net "SPI_BMC_CLK_R")
	)
	(segment
		(start 53.52161 -61.144658)
		(end 55.295038 -59.37123)
		(width 0.11684)
		(layer "F.Cu")
		(net "SPI_BMC_CLK_R")
	)
	(segment
		(start 52.959 -62.7634)
		(end 53.1876 -62.5348)
		(width 0.11684)
		(layer "F.Cu")
		(net "SPI_BMC_CLK_R")
	)
	(segment
		(start 52.809648 -63.512446)
		(end 52.959 -63.363094)
		(width 0.11684)
		(layer "F.Cu")
		(net "SPI_BMC_CLK_R")
	)
	(segment
		(start 60.325 -87.122)
		(end 60.325 -88.519)
		(width 0.11684)
		(layer "F.Cu")
		(net "SPI_BMC_BOOT_MOSI")
	)
	(segment
		(start 60.01766 -88.82634)
		(end 58.58129 -88.82634)
		(width 0.11684)
		(layer "F.Cu")
		(net "SPI_BMC_BOOT_MOSI")
	)
	(segment
		(start 60.325 -88.519)
		(end 60.01766 -88.82634)
		(width 0.11684)
		(layer "F.Cu")
		(net "SPI_BMC_BOOT_MOSI")
	)
	(segment
		(start 61.44895 -87.122)
		(end 60.325 -87.122)
		(width 0.11684)
		(layer "F.Cu")
		(net "SPI_BMC_BOOT_MOSI")
	)
	(segment
		(start 58.475372 -88.720422)
		(end 58.420254 -88.720422)
		(width 0.11684)
		(layer "F.Cu")
		(net "SPI_BMC_BOOT_MOSI")
	)
	(segment
		(start 40.768524 -76.454)
		(end 40.8559 -76.541376)
		(width 0.11684)
		(layer "F.Cu")
		(net "SPI_BMC_BOOT_MOSI")
	)
	(segment
		(start 58.060082 -88.36025)
		(end 58.039 -88.36025)
		(width 0.11684)
		(layer "F.Cu")
		(net "SPI_BMC_BOOT_MOSI")
	)
	(segment
		(start 61.595 -87.26805)
		(end 61.44895 -87.122)
		(width 0.11684)
		(layer "F.Cu")
		(net "SPI_BMC_BOOT_MOSI")
	)
	(segment
		(start 57.16905 -88.36025)
		(end 56.134 -87.3252)
		(width 0.11684)
		(layer "F.Cu")
		(net "SPI_BMC_BOOT_MOSI")
	)
	(segment
		(start 40.22725 -76.454)
		(end 40.768524 -76.454)
		(width 0.11684)
		(layer "F.Cu")
		(net "SPI_BMC_BOOT_MOSI")
	)
	(segment
		(start 58.58129 -88.82634)
		(end 58.475372 -88.720422)
		(width 0.11684)
		(layer "F.Cu")
		(net "SPI_BMC_BOOT_MOSI")
	)
	(segment
		(start 58.420254 -88.720422)
		(end 58.060082 -88.36025)
		(width 0.11684)
		(layer "F.Cu")
		(net "SPI_BMC_BOOT_MOSI")
	)
	(segment
		(start 58.039 -88.36025)
		(end 57.16905 -88.36025)
		(width 0.11684)
		(layer "F.Cu")
		(net "SPI_BMC_BOOT_MOSI")
	)
	(via
		(at 46.4058 -86.922864)
		(size 0.508)
		(drill 0.254)
		(layers "F.Cu" "B.Cu")
		(net "SPI_BMC_BOOT_MOSI")
	)
	(via
		(at 54.6354 -62.0014)
		(size 0.508)
		(drill 0.254)
		(layers "F.Cu" "B.Cu")
		(net "SPI_BMC_BOOT_MOSI")
	)
	(via
		(at 40.8559 -76.541376)
		(size 0.508)
		(drill 0.254)
		(layers "F.Cu" "B.Cu")
		(net "SPI_BMC_BOOT_MOSI")
	)
	(via
		(at 60.325 -87.122)
		(size 0.762)
		(drill 0.381)
		(layers "F.Cu" "B.Cu")
		(net "SPI_BMC_BOOT_MOSI")
	)
	(via
		(at 56.134 -87.3252)
		(size 0.508)
		(drill 0.254)
		(layers "F.Cu" "B.Cu")
		(net "SPI_BMC_BOOT_MOSI")
	)
	(via
		(at 40.248586 -86.588092)
		(size 0.508)
		(drill 0.254)
		(layers "F.Cu" "B.Cu")
		(net "SPI_BMC_BOOT_MOSI")
	)
	(segment
		(start 37.86886 -82.705702)
		(end 37.86886 -81.57718)
		(width 0.11684)
		(layer "B.Cu")
		(net "SPI_BMC_BOOT_MOSI")
	)
	(segment
		(start 38.424104 -81.021936)
		(end 39.87292 -77.524356)
		(width 0.11684)
		(layer "B.Cu")
		(net "SPI_BMC_BOOT_MOSI")
	)
	(segment
		(start 39.87292 -77.524356)
		(end 40.8559 -76.541376)
		(width 0.11684)
		(layer "B.Cu")
		(net "SPI_BMC_BOOT_MOSI")
	)
	(segment
		(start 37.86886 -81.57718)
		(end 38.424104 -81.021936)
		(width 0.11684)
		(layer "B.Cu")
		(net "SPI_BMC_BOOT_MOSI")
	)
	(segment
		(start 40.248586 -86.588092)
		(end 38.931342 -85.270848)
		(width 0.11684)
		(layer "B.Cu")
		(net "SPI_BMC_BOOT_MOSI")
	)
	(segment
		(start 54.6354 -62.0014)
		(end 54.28107 -62.0014)
		(width 0.11684)
		(layer "B.Cu")
		(net "SPI_BMC_BOOT_MOSI")
	)
	(segment
		(start 38.931342 -85.270848)
		(end 37.86886 -82.705702)
		(width 0.11684)
		(layer "B.Cu")
		(net "SPI_BMC_BOOT_MOSI")
	)
	(segment
		(start 54.28107 -62.0014)
		(end 54.16423 -61.88456)
		(width 0.11684)
		(layer "B.Cu")
		(net "SPI_BMC_BOOT_MOSI")
	)
	(segment
		(start 54.16423 -61.88456)
		(end 54.16423 -61.46165)
		(width 0.11684)
		(layer "B.Cu")
		(net "SPI_BMC_BOOT_MOSI")
	)
	(segment
		(start 48.846486 -86.385654)
		(end 47.599092 -86.385654)
		(width 0.08382)
		(layer "In2.Cu")
		(net "SPI_BMC_BOOT_MOSI")
	)
	(segment
		(start 56.134 -87.3252)
		(end 52.1208 -87.3252)
		(width 0.08382)
		(layer "In2.Cu")
		(net "SPI_BMC_BOOT_MOSI")
	)
	(segment
		(start 47.599092 -86.385654)
		(end 47.061882 -86.922864)
		(width 0.08382)
		(layer "In2.Cu")
		(net "SPI_BMC_BOOT_MOSI")
	)
	(segment
		(start 50.9524 -86.1568)
		(end 49.07534 -86.1568)
		(width 0.08382)
		(layer "In2.Cu")
		(net "SPI_BMC_BOOT_MOSI")
	)
	(segment
		(start 47.061882 -86.922864)
		(end 46.4058 -86.922864)
		(width 0.08382)
		(layer "In2.Cu")
		(net "SPI_BMC_BOOT_MOSI")
	)
	(segment
		(start 49.07534 -86.1568)
		(end 48.846486 -86.385654)
		(width 0.08382)
		(layer "In2.Cu")
		(net "SPI_BMC_BOOT_MOSI")
	)
	(segment
		(start 52.1208 -87.3252)
		(end 50.9524 -86.1568)
		(width 0.08382)
		(layer "In2.Cu")
		(net "SPI_BMC_BOOT_MOSI")
	)
	(segment
		(start 46.4058 -86.922864)
		(end 45.698664 -86.922864)
		(width 0.08382)
		(layer "In9.Cu")
		(net "SPI_BMC_BOOT_MOSI")
	)
	(segment
		(start 55.28691 -63.019686)
		(end 54.990492 -63.316104)
		(width 0.08382)
		(layer "In9.Cu")
		(net "SPI_BMC_BOOT_MOSI")
	)
	(segment
		(start 45.698664 -86.922864)
		(end 44.492164 -85.716364)
		(width 0.08382)
		(layer "In9.Cu")
		(net "SPI_BMC_BOOT_MOSI")
	)
	(segment
		(start 52.74691 -65.596516)
		(end 52.74691 -65.836038)
		(width 0.08382)
		(layer "In9.Cu")
		(net "SPI_BMC_BOOT_MOSI")
	)
	(segment
		(start 46.9138 -86.144354)
		(end 46.4058 -86.652354)
		(width 0.08382)
		(layer "In9.Cu")
		(net "SPI_BMC_BOOT_MOSI")
	)
	(segment
		(start 50.9524 -68.288408)
		(end 50.9524 -73.926954)
		(width 0.08382)
		(layer "In9.Cu")
		(net "SPI_BMC_BOOT_MOSI")
	)
	(segment
		(start 53.727604 -63.316104)
		(end 53.726842 -63.316358)
		(width 0.08382)
		(layer "In9.Cu")
		(net "SPI_BMC_BOOT_MOSI")
	)
	(segment
		(start 50.189892 -75.768454)
		(end 47.834804 -78.123542)
		(width 0.08382)
		(layer "In9.Cu")
		(net "SPI_BMC_BOOT_MOSI")
	)
	(segment
		(start 54.990492 -63.316104)
		(end 53.727604 -63.316104)
		(width 0.08382)
		(layer "In9.Cu")
		(net "SPI_BMC_BOOT_MOSI")
	)
	(segment
		(start 46.4058 -86.652354)
		(end 46.4058 -86.922864)
		(width 0.08382)
		(layer "In9.Cu")
		(net "SPI_BMC_BOOT_MOSI")
	)
	(segment
		(start 51.62931 -67.568318)
		(end 51.307238 -67.89039)
		(width 0.08382)
		(layer "In9.Cu")
		(net "SPI_BMC_BOOT_MOSI")
	)
	(segment
		(start 41.130728 -85.716364)
		(end 40.259 -86.588092)
		(width 0.08382)
		(layer "In9.Cu")
		(net "SPI_BMC_BOOT_MOSI")
	)
	(segment
		(start 52.9336 -65.316608)
		(end 52.74691 -65.596516)
		(width 0.08382)
		(layer "In9.Cu")
		(net "SPI_BMC_BOOT_MOSI")
	)
	(segment
		(start 46.9138 -82.336386)
		(end 46.9138 -86.144354)
		(width 0.08382)
		(layer "In9.Cu")
		(net "SPI_BMC_BOOT_MOSI")
	)
	(segment
		(start 51.21783 -67.89039)
		(end 50.9524 -68.288408)
		(width 0.08382)
		(layer "In9.Cu")
		(net "SPI_BMC_BOOT_MOSI")
	)
	(segment
		(start 52.9336 -64.1096)
		(end 52.9336 -65.316608)
		(width 0.08382)
		(layer "In9.Cu")
		(net "SPI_BMC_BOOT_MOSI")
	)
	(segment
		(start 51.62931 -66.953638)
		(end 51.62931 -67.568318)
		(width 0.08382)
		(layer "In9.Cu")
		(net "SPI_BMC_BOOT_MOSI")
	)
	(segment
		(start 47.724822 -78.389226)
		(end 47.724822 -80.378554)
		(width 0.08382)
		(layer "In9.Cu")
		(net "SPI_BMC_BOOT_MOSI")
	)
	(segment
		(start 47.834804 -78.123542)
		(end 47.724822 -78.389226)
		(width 0.08382)
		(layer "In9.Cu")
		(net "SPI_BMC_BOOT_MOSI")
	)
	(segment
		(start 44.492164 -85.716364)
		(end 41.130728 -85.716364)
		(width 0.08382)
		(layer "In9.Cu")
		(net "SPI_BMC_BOOT_MOSI")
	)
	(segment
		(start 47.724822 -80.378554)
		(end 46.9138 -82.336386)
		(width 0.08382)
		(layer "In9.Cu")
		(net "SPI_BMC_BOOT_MOSI")
	)
	(segment
		(start 54.863746 -62.0014)
		(end 55.28691 -62.424564)
		(width 0.08382)
		(layer "In9.Cu")
		(net "SPI_BMC_BOOT_MOSI")
	)
	(segment
		(start 55.28691 -62.424564)
		(end 55.28691 -63.019686)
		(width 0.08382)
		(layer "In9.Cu")
		(net "SPI_BMC_BOOT_MOSI")
	)
	(segment
		(start 52.74691 -65.836038)
		(end 51.62931 -66.953638)
		(width 0.08382)
		(layer "In9.Cu")
		(net "SPI_BMC_BOOT_MOSI")
	)
	(segment
		(start 40.259 -86.588092)
		(end 40.248586 -86.588092)
		(width 0.08382)
		(layer "In9.Cu")
		(net "SPI_BMC_BOOT_MOSI")
	)
	(segment
		(start 54.6354 -62.0014)
		(end 54.863746 -62.0014)
		(width 0.08382)
		(layer "In9.Cu")
		(net "SPI_BMC_BOOT_MOSI")
	)
	(segment
		(start 50.9524 -73.926954)
		(end 50.189892 -75.768454)
		(width 0.08382)
		(layer "In9.Cu")
		(net "SPI_BMC_BOOT_MOSI")
	)
	(segment
		(start 53.726842 -63.316358)
		(end 52.9336 -64.1096)
		(width 0.08382)
		(layer "In9.Cu")
		(net "SPI_BMC_BOOT_MOSI")
	)
	(segment
		(start 51.307238 -67.89039)
		(end 51.21783 -67.89039)
		(width 0.08382)
		(layer "In9.Cu")
		(net "SPI_BMC_BOOT_MOSI")
	)
	(segment
		(start 57.3151 -85.35416)
		(end 57.56021 -85.10905)
		(width 0.11684)
		(layer "F.Cu")
		(net "SPI_BMC_BOOT_MISO")
	)
	(segment
		(start 40.22725 -75.438)
		(end 40.22725 -74.974704)
		(width 0.11684)
		(layer "F.Cu")
		(net "SPI_BMC_BOOT_MISO")
	)
	(segment
		(start 47.09922 -70.27418)
		(end 47.5488 -69.8246)
		(width 0.11684)
		(layer "F.Cu")
		(net "SPI_BMC_BOOT_MISO")
	)
	(segment
		(start 46.794166 -70.27418)
		(end 47.09922 -70.27418)
		(width 0.11684)
		(layer "F.Cu")
		(net "SPI_BMC_BOOT_MISO")
	)
	(segment
		(start 49.05502 -69.246496)
		(end 49.05502 -68.427092)
		(width 0.11684)
		(layer "F.Cu")
		(net "SPI_BMC_BOOT_MISO")
	)
	(segment
		(start 58.648346 -84.455)
		(end 59.92495 -84.455)
		(width 0.11684)
		(layer "F.Cu")
		(net "SPI_BMC_BOOT_MISO")
	)
	(segment
		(start 49.05502 -68.427092)
		(end 49.120044 -68.362068)
		(width 0.11684)
		(layer "F.Cu")
		(net "SPI_BMC_BOOT_MISO")
	)
	(segment
		(start 47.879 -69.8246)
		(end 48.476916 -69.8246)
		(width 0.11684)
		(layer "F.Cu")
		(net "SPI_BMC_BOOT_MISO")
	)
	(segment
		(start 58.039 -85.10905)
		(end 58.039 -85.064346)
		(width 0.11684)
		(layer "F.Cu")
		(net "SPI_BMC_BOOT_MISO")
	)
	(segment
		(start 40.0558 -74.803254)
		(end 40.0558 -73.4568)
		(width 0.11684)
		(layer "F.Cu")
		(net "SPI_BMC_BOOT_MISO")
	)
	(segment
		(start 45.085 -71.3232)
		(end 45.212 -71.4502)
		(width 0.11684)
		(layer "F.Cu")
		(net "SPI_BMC_BOOT_MISO")
	)
	(segment
		(start 42.1894 -71.3232)
		(end 45.085 -71.3232)
		(width 0.11684)
		(layer "F.Cu")
		(net "SPI_BMC_BOOT_MISO")
	)
	(segment
		(start 58.039 -85.064346)
		(end 58.648346 -84.455)
		(width 0.11684)
		(layer "F.Cu")
		(net "SPI_BMC_BOOT_MISO")
	)
	(segment
		(start 40.0558 -73.4568)
		(end 42.1894 -71.3232)
		(width 0.11684)
		(layer "F.Cu")
		(net "SPI_BMC_BOOT_MISO")
	)
	(segment
		(start 59.92495 -84.455)
		(end 60.579 -85.10905)
		(width 0.11684)
		(layer "F.Cu")
		(net "SPI_BMC_BOOT_MISO")
	)
	(segment
		(start 48.476916 -69.8246)
		(end 49.05502 -69.246496)
		(width 0.11684)
		(layer "F.Cu")
		(net "SPI_BMC_BOOT_MISO")
	)
	(segment
		(start 57.3151 -85.73008)
		(end 57.3151 -85.35416)
		(width 0.11684)
		(layer "F.Cu")
		(net "SPI_BMC_BOOT_MISO")
	)
	(segment
		(start 40.22725 -74.974704)
		(end 40.0558 -74.803254)
		(width 0.11684)
		(layer "F.Cu")
		(net "SPI_BMC_BOOT_MISO")
	)
	(segment
		(start 45.212 -71.4502)
		(end 45.618146 -71.4502)
		(width 0.11684)
		(layer "F.Cu")
		(net "SPI_BMC_BOOT_MISO")
	)
	(segment
		(start 57.56021 -85.10905)
		(end 58.039 -85.10905)
		(width 0.11684)
		(layer "F.Cu")
		(net "SPI_BMC_BOOT_MISO")
	)
	(segment
		(start 45.618146 -71.4502)
		(end 46.794166 -70.27418)
		(width 0.11684)
		(layer "F.Cu")
		(net "SPI_BMC_BOOT_MISO")
	)
	(segment
		(start 47.5488 -69.8246)
		(end 47.879 -69.8246)
		(width 0.11684)
		(layer "F.Cu")
		(net "SPI_BMC_BOOT_MISO")
	)
	(via
		(at 49.120044 -68.362068)
		(size 0.508)
		(drill 0.254)
		(layers "F.Cu" "B.Cu")
		(net "SPI_BMC_BOOT_MISO")
	)
	(via
		(at 47.879 -69.8246)
		(size 0.762)
		(drill 0.381)
		(layers "F.Cu" "B.Cu")
		(net "SPI_BMC_BOOT_MISO")
	)
	(via
		(at 55.8546 -67.8434)
		(size 0.508)
		(drill 0.254)
		(layers "F.Cu" "B.Cu")
		(net "SPI_BMC_BOOT_MISO")
	)
	(via
		(at 57.3151 -85.73008)
		(size 0.508)
		(drill 0.254)
		(layers "F.Cu" "B.Cu")
		(net "SPI_BMC_BOOT_MISO")
	)
	(segment
		(start 55.811674 -66.457322)
		(end 55.8546 -66.41465)
		(width 0.11684)
		(layer "B.Cu")
		(net "SPI_BMC_BOOT_MISO")
	)
	(segment
		(start 55.639462 -67.462654)
		(end 55.81142 -67.290696)
		(width 0.11684)
		(layer "B.Cu")
		(net "SPI_BMC_BOOT_MISO")
	)
	(segment
		(start 55.81142 -66.552572)
		(end 55.811674 -66.457322)
		(width 0.11684)
		(layer "B.Cu")
		(net "SPI_BMC_BOOT_MISO")
	)
	(segment
		(start 55.8546 -67.8434)
		(end 55.639462 -67.628262)
		(width 0.11684)
		(layer "B.Cu")
		(net "SPI_BMC_BOOT_MISO")
	)
	(segment
		(start 55.639462 -67.628262)
		(end 55.639462 -67.462654)
		(width 0.11684)
		(layer "B.Cu")
		(net "SPI_BMC_BOOT_MISO")
	)
	(segment
		(start 55.81142 -67.290696)
		(end 55.81142 -66.552572)
		(width 0.11684)
		(layer "B.Cu")
		(net "SPI_BMC_BOOT_MISO")
	)
	(segment
		(start 55.245 -68.4784)
		(end 54.3052 -68.4784)
		(width 0.08382)
		(layer "In2.Cu")
		(net "SPI_BMC_BOOT_MISO")
	)
	(segment
		(start 54.3052 -68.4784)
		(end 53.38064 -69.40296)
		(width 0.08382)
		(layer "In2.Cu")
		(net "SPI_BMC_BOOT_MISO")
	)
	(segment
		(start 50.78476 -69.40296)
		(end 49.741836 -68.360036)
		(width 0.08382)
		(layer "In2.Cu")
		(net "SPI_BMC_BOOT_MISO")
	)
	(segment
		(start 53.38064 -69.40296)
		(end 50.78476 -69.40296)
		(width 0.08382)
		(layer "In2.Cu")
		(net "SPI_BMC_BOOT_MISO")
	)
	(segment
		(start 55.8546 -67.8688)
		(end 55.245 -68.4784)
		(width 0.08382)
		(layer "In2.Cu")
		(net "SPI_BMC_BOOT_MISO")
	)
	(segment
		(start 55.8546 -67.8434)
		(end 55.8546 -67.8688)
		(width 0.08382)
		(layer "In2.Cu")
		(net "SPI_BMC_BOOT_MISO")
	)
	(segment
		(start 49.122076 -68.360036)
		(end 49.120044 -68.362068)
		(width 0.08382)
		(layer "In2.Cu")
		(net "SPI_BMC_BOOT_MISO")
	)
	(segment
		(start 49.741836 -68.360036)
		(end 49.122076 -68.360036)
		(width 0.08382)
		(layer "In2.Cu")
		(net "SPI_BMC_BOOT_MISO")
	)
	(segment
		(start 57.3151 -83.7819)
		(end 57.3151 -85.73008)
		(width 0.08382)
		(layer "In9.Cu")
		(net "SPI_BMC_BOOT_MISO")
	)
	(segment
		(start 56.515 -82.9818)
		(end 57.3151 -83.7819)
		(width 0.08382)
		(layer "In9.Cu")
		(net "SPI_BMC_BOOT_MISO")
	)
	(segment
		(start 55.162196 -71.298562)
		(end 55.162196 -74.341228)
		(width 0.08382)
		(layer "In9.Cu")
		(net "SPI_BMC_BOOT_MISO")
	)
	(segment
		(start 55.54472 -78.081124)
		(end 56.515 -80.423766)
		(width 0.08382)
		(layer "In9.Cu")
		(net "SPI_BMC_BOOT_MISO")
	)
	(segment
		(start 55.54472 -74.723752)
		(end 55.54472 -78.081124)
		(width 0.08382)
		(layer "In9.Cu")
		(net "SPI_BMC_BOOT_MISO")
	)
	(segment
		(start 55.162196 -74.341228)
		(end 55.54472 -74.723752)
		(width 0.08382)
		(layer "In9.Cu")
		(net "SPI_BMC_BOOT_MISO")
	)
	(segment
		(start 55.8546 -67.8434)
		(end 55.499 -68.199)
		(width 0.08382)
		(layer "In9.Cu")
		(net "SPI_BMC_BOOT_MISO")
	)
	(segment
		(start 56.515 -80.423766)
		(end 56.515 -82.9818)
		(width 0.08382)
		(layer "In9.Cu")
		(net "SPI_BMC_BOOT_MISO")
	)
	(segment
		(start 55.499 -68.199)
		(end 55.499 -70.961758)
		(width 0.08382)
		(layer "In9.Cu")
		(net "SPI_BMC_BOOT_MISO")
	)
	(segment
		(start 55.499 -70.961758)
		(end 55.162196 -71.298562)
		(width 0.08382)
		(layer "In9.Cu")
		(net "SPI_BMC_BOOT_MISO")
	)
	(via
		(at 58.1152 -79.2734)
		(size 0.508)
		(drill 0.254)
		(layers "F.Cu" "B.Cu")
		(net "SPI_BMC_BOOT_CS1_R_N")
	)
	(via
		(at 57.738264 -65.2018)
		(size 0.508)
		(drill 0.254)
		(layers "F.Cu" "B.Cu")
		(net "SPI_BMC_BOOT_CS1_R_N")
	)
	(segment
		(start 57.738264 -65.2018)
		(end 57.738264 -64.312546)
		(width 0.11684)
		(layer "B.Cu")
		(net "SPI_BMC_BOOT_CS1_R_N")
	)
	(segment
		(start 58.98515 -78.97876)
		(end 58.69051 -79.2734)
		(width 0.11684)
		(layer "B.Cu")
		(net "SPI_BMC_BOOT_CS1_R_N")
	)
	(segment
		(start 58.98515 -77.9526)
		(end 58.98515 -78.97876)
		(width 0.11684)
		(layer "B.Cu")
		(net "SPI_BMC_BOOT_CS1_R_N")
	)
	(segment
		(start 57.738264 -64.312546)
		(end 57.687464 -64.261746)
		(width 0.11684)
		(layer "B.Cu")
		(net "SPI_BMC_BOOT_CS1_R_N")
	)
	(segment
		(start 58.69051 -79.2734)
		(end 58.1152 -79.2734)
		(width 0.11684)
		(layer "B.Cu")
		(net "SPI_BMC_BOOT_CS1_R_N")
	)
	(segment
		(start 57.5818 -78.74)
		(end 57.5818 -76.62672)
		(width 0.08382)
		(layer "In9.Cu")
		(net "SPI_BMC_BOOT_CS1_R_N")
	)
	(segment
		(start 57.4802 -66.83248)
		(end 57.4802 -65.459864)
		(width 0.08382)
		(layer "In9.Cu")
		(net "SPI_BMC_BOOT_CS1_R_N")
	)
	(segment
		(start 57.05602 -67.25666)
		(end 57.4802 -66.83248)
		(width 0.08382)
		(layer "In9.Cu")
		(net "SPI_BMC_BOOT_CS1_R_N")
	)
	(segment
		(start 57.4802 -65.459864)
		(end 57.738264 -65.2018)
		(width 0.08382)
		(layer "In9.Cu")
		(net "SPI_BMC_BOOT_CS1_R_N")
	)
	(segment
		(start 57.75706 -70.702678)
		(end 57.05602 -70.001638)
		(width 0.08382)
		(layer "In9.Cu")
		(net "SPI_BMC_BOOT_CS1_R_N")
	)
	(segment
		(start 57.75706 -76.45146)
		(end 57.75706 -70.702678)
		(width 0.08382)
		(layer "In9.Cu")
		(net "SPI_BMC_BOOT_CS1_R_N")
	)
	(segment
		(start 58.1152 -79.2734)
		(end 57.5818 -78.74)
		(width 0.08382)
		(layer "In9.Cu")
		(net "SPI_BMC_BOOT_CS1_R_N")
	)
	(segment
		(start 57.5818 -76.62672)
		(end 57.75706 -76.45146)
		(width 0.08382)
		(layer "In9.Cu")
		(net "SPI_BMC_BOOT_CS1_R_N")
	)
	(segment
		(start 57.05602 -70.001638)
		(end 57.05602 -67.25666)
		(width 0.08382)
		(layer "In9.Cu")
		(net "SPI_BMC_BOOT_CS1_R_N")
	)
	(segment
		(start 46.99 -85.979)
		(end 46.6852 -85.6742)
		(width 0.11684)
		(layer "F.Cu")
		(net "SPI_BMC_BOOT_CS0_R_N")
	)
	(segment
		(start 46.8122 -87.6046)
		(end 46.812454 -87.6046)
		(width 0.11684)
		(layer "F.Cu")
		(net "SPI_BMC_BOOT_CS0_R_N")
	)
	(segment
		(start 41.9608 -81.42605)
		(end 41.9608 -81.878424)
		(width 0.11684)
		(layer "F.Cu")
		(net "SPI_BMC_BOOT_CS0_R_N")
	)
	(segment
		(start 41.95445 -81.884774)
		(end 41.95445 -81.98485)
		(width 0.11684)
		(layer "F.Cu")
		(net "SPI_BMC_BOOT_CS0_R_N")
	)
	(segment
		(start 46.812454 -87.6046)
		(end 46.99 -87.427054)
		(width 0.11684)
		(layer "F.Cu")
		(net "SPI_BMC_BOOT_CS0_R_N")
	)
	(segment
		(start 41.9608 -81.878424)
		(end 41.95445 -81.884774)
		(width 0.11684)
		(layer "F.Cu")
		(net "SPI_BMC_BOOT_CS0_R_N")
	)
	(segment
		(start 41.95445 -81.98485)
		(end 45.6438 -85.6742)
		(width 0.11684)
		(layer "F.Cu")
		(net "SPI_BMC_BOOT_CS0_R_N")
	)
	(segment
		(start 45.6438 -85.6742)
		(end 46.1645 -85.6742)
		(width 0.11684)
		(layer "F.Cu")
		(net "SPI_BMC_BOOT_CS0_R_N")
	)
	(segment
		(start 46.99 -87.427054)
		(end 46.99 -85.979)
		(width 0.11684)
		(layer "F.Cu")
		(net "SPI_BMC_BOOT_CS0_R_N")
	)
	(segment
		(start 46.6852 -87.7316)
		(end 46.8122 -87.6046)
		(width 0.11684)
		(layer "F.Cu")
		(net "SPI_BMC_BOOT_CS0_R_N")
	)
	(segment
		(start 46.6852 -85.6742)
		(end 46.1645 -85.6742)
		(width 0.11684)
		(layer "F.Cu")
		(net "SPI_BMC_BOOT_CS0_R_N")
	)
	(via
		(at 46.6852 -87.7316)
		(size 0.508)
		(drill 0.254)
		(layers "F.Cu" "B.Cu")
		(net "SPI_BMC_BOOT_CS0_R_N")
	)
	(via
		(at 56.134 -61.722)
		(size 0.508)
		(drill 0.254)
		(layers "F.Cu" "B.Cu")
		(net "SPI_BMC_BOOT_CS0_R_N")
	)
	(via
		(at 46.1645 -85.6742)
		(size 0.762)
		(drill 0.381)
		(layers "F.Cu" "B.Cu")
		(net "SPI_BMC_BOOT_CS0_R_N")
	)
	(segment
		(start 56.134 -61.722)
		(end 56.134 -61.390276)
		(width 0.11684)
		(layer "B.Cu")
		(net "SPI_BMC_BOOT_CS0_R_N")
	)
	(segment
		(start 56.134 -61.390276)
		(end 56.316626 -61.20765)
		(width 0.11684)
		(layer "B.Cu")
		(net "SPI_BMC_BOOT_CS0_R_N")
	)
	(segment
		(start 56.316626 -61.20765)
		(end 56.710326 -61.20765)
		(width 0.11684)
		(layer "B.Cu")
		(net "SPI_BMC_BOOT_CS0_R_N")
	)
	(segment
		(start 48.62322 -84.912708)
		(end 48.62322 -81.302606)
		(width 0.08382)
		(layer "In9.Cu")
		(net "SPI_BMC_BOOT_CS0_R_N")
	)
	(segment
		(start 52.8066 -66.446146)
		(end 53.96611 -65.286636)
		(width 0.08382)
		(layer "In9.Cu")
		(net "SPI_BMC_BOOT_CS0_R_N")
	)
	(segment
		(start 52.8066 -72.22363)
		(end 52.8066 -66.446146)
		(width 0.08382)
		(layer "In9.Cu")
		(net "SPI_BMC_BOOT_CS0_R_N")
	)
	(segment
		(start 53.96611 -64.04229)
		(end 54.35219 -63.65621)
		(width 0.08382)
		(layer "In9.Cu")
		(net "SPI_BMC_BOOT_CS0_R_N")
	)
	(segment
		(start 48.433482 -78.002638)
		(end 50.476404 -75.959716)
		(width 0.08382)
		(layer "In9.Cu")
		(net "SPI_BMC_BOOT_CS0_R_N")
	)
	(segment
		(start 56.134 -62.850776)
		(end 56.134 -61.722)
		(width 0.08382)
		(layer "In9.Cu")
		(net "SPI_BMC_BOOT_CS0_R_N")
	)
	(segment
		(start 55.328566 -63.65621)
		(end 56.134 -62.850776)
		(width 0.08382)
		(layer "In9.Cu")
		(net "SPI_BMC_BOOT_CS0_R_N")
	)
	(segment
		(start 53.96611 -65.286636)
		(end 53.96611 -64.04229)
		(width 0.08382)
		(layer "In9.Cu")
		(net "SPI_BMC_BOOT_CS0_R_N")
	)
	(segment
		(start 46.95571 -87.46109)
		(end 46.95571 -86.580218)
		(width 0.08382)
		(layer "In9.Cu")
		(net "SPI_BMC_BOOT_CS0_R_N")
	)
	(segment
		(start 48.62322 -81.302606)
		(end 48.433482 -81.112868)
		(width 0.08382)
		(layer "In9.Cu")
		(net "SPI_BMC_BOOT_CS0_R_N")
	)
	(segment
		(start 50.512218 -75.873356)
		(end 51.848004 -74.53757)
		(width 0.08382)
		(layer "In9.Cu")
		(net "SPI_BMC_BOOT_CS0_R_N")
	)
	(segment
		(start 50.476404 -75.959716)
		(end 50.512218 -75.873356)
		(width 0.08382)
		(layer "In9.Cu")
		(net "SPI_BMC_BOOT_CS0_R_N")
	)
	(segment
		(start 48.433482 -81.112868)
		(end 48.433482 -78.002638)
		(width 0.08382)
		(layer "In9.Cu")
		(net "SPI_BMC_BOOT_CS0_R_N")
	)
	(segment
		(start 54.35219 -63.65621)
		(end 55.328566 -63.65621)
		(width 0.08382)
		(layer "In9.Cu")
		(net "SPI_BMC_BOOT_CS0_R_N")
	)
	(segment
		(start 46.95571 -86.580218)
		(end 48.62322 -84.912708)
		(width 0.08382)
		(layer "In9.Cu")
		(net "SPI_BMC_BOOT_CS0_R_N")
	)
	(segment
		(start 51.848004 -74.53757)
		(end 52.727606 -72.415654)
		(width 0.08382)
		(layer "In9.Cu")
		(net "SPI_BMC_BOOT_CS0_R_N")
	)
	(segment
		(start 52.727606 -72.415654)
		(end 52.8066 -72.22363)
		(width 0.08382)
		(layer "In9.Cu")
		(net "SPI_BMC_BOOT_CS0_R_N")
	)
	(segment
		(start 46.6852 -87.7316)
		(end 46.95571 -87.46109)
		(width 0.08382)
		(layer "In9.Cu")
		(net "SPI_BMC_BOOT_CS0_R_N")
	)
	(segment
		(start 49.25187 -72.117712)
		(end 49.25187 -71.858124)
		(width 0.11684)
		(layer "F.Cu")
		(net "SPI_BMC_BOOT_CLK")
	)
	(segment
		(start 44.018708 -71.755)
		(end 44.906946 -71.755)
		(width 0.11684)
		(layer "F.Cu")
		(net "SPI_BMC_BOOT_CLK")
	)
	(segment
		(start 42.31767 -73.404222)
		(end 42.31767 -73.170034)
		(width 0.11684)
		(layer "F.Cu")
		(net "SPI_BMC_BOOT_CLK")
	)
	(segment
		(start 48.631348 -72.73798)
		(end 49.25187 -72.117712)
		(width 0.11684)
		(layer "F.Cu")
		(net "SPI_BMC_BOOT_CLK")
	)
	(segment
		(start 52.854606 -64.331342)
		(end 53.249576 -65.283334)
		(width 0.11684)
		(layer "F.Cu")
		(net "SPI_BMC_BOOT_CLK")
	)
	(segment
		(start 42.13352 -73.588372)
		(end 42.31767 -73.404222)
		(width 0.11684)
		(layer "F.Cu")
		(net "SPI_BMC_BOOT_CLK")
	)
	(segment
		(start 41.397174 -73.137268)
		(end 41.848278 -73.588372)
		(width 0.11684)
		(layer "F.Cu")
		(net "SPI_BMC_BOOT_CLK")
	)
	(segment
		(start 41.848278 -73.588372)
		(end 42.13352 -73.588372)
		(width 0.11684)
		(layer "F.Cu")
		(net "SPI_BMC_BOOT_CLK")
	)
	(segment
		(start 45.745146 -72.5932)
		(end 46.025054 -72.5932)
		(width 0.11684)
		(layer "F.Cu")
		(net "SPI_BMC_BOOT_CLK")
	)
	(segment
		(start 45.0596 -73.727564)
		(end 44.875958 -73.543922)
		(width 0.11684)
		(layer "F.Cu")
		(net "SPI_BMC_BOOT_CLK")
	)
	(segment
		(start 47.710598 -70.612)
		(end 48.895 -70.612)
		(width 0.11684)
		(layer "F.Cu")
		(net "SPI_BMC_BOOT_CLK")
	)
	(segment
		(start 46.99889 -72.537574)
		(end 45.826426 -73.710038)
		(width 0.11684)
		(layer "F.Cu")
		(net "SPI_BMC_BOOT_CLK")
	)
	(segment
		(start 47.442374 -72.981312)
		(end 47.727616 -72.981312)
		(width 0.11684)
		(layer "F.Cu")
		(net "SPI_BMC_BOOT_CLK")
	)
	(segment
		(start 52.83708 -68.72097)
		(end 52.21605 -69.342)
		(width 0.11684)
		(layer "F.Cu")
		(net "SPI_BMC_BOOT_CLK")
	)
	(segment
		(start 48.488092 -73.4822)
		(end 48.672242 -73.29805)
		(width 0.11684)
		(layer "F.Cu")
		(net "SPI_BMC_BOOT_CLK")
	)
	(segment
		(start 43.264328 -71.9836)
		(end 43.264328 -74.924158)
		(width 0.11684)
		(layer "F.Cu")
		(net "SPI_BMC_BOOT_CLK")
	)
	(segment
		(start 41.840912 -72.433942)
		(end 42.418254 -71.8566)
		(width 0.11684)
		(layer "F.Cu")
		(net "SPI_BMC_BOOT_CLK")
	)
	(segment
		(start 46.431454 -72.1868)
		(end 46.87189 -72.1868)
		(width 0.11684)
		(layer "F.Cu")
		(net "SPI_BMC_BOOT_CLK")
	)
	(segment
		(start 43.264328 -74.924158)
		(end 43.44797 -75.1078)
		(width 0.11684)
		(layer "F.Cu")
		(net "SPI_BMC_BOOT_CLK")
	)
	(segment
		(start 45.826426 -73.9394)
		(end 45.953426 -74.0664)
		(width 0.11684)
		(layer "F.Cu")
		(net "SPI_BMC_BOOT_CLK")
	)
	(segment
		(start 44.906946 -71.755)
		(end 45.745146 -72.5932)
		(width 0.11684)
		(layer "F.Cu")
		(net "SPI_BMC_BOOT_CLK")
	)
	(segment
		(start 43.891708 -71.882)
		(end 44.018708 -71.755)
		(width 0.11684)
		(layer "F.Cu")
		(net "SPI_BMC_BOOT_CLK")
	)
	(segment
		(start 51.44389 -70.034912)
		(end 51.560222 -69.91858)
		(width 0.11684)
		(layer "F.Cu")
		(net "SPI_BMC_BOOT_CLK")
	)
	(segment
		(start 48.808132 -71.673974)
		(end 48.18761 -72.294242)
		(width 0.11684)
		(layer "F.Cu")
		(net "SPI_BMC_BOOT_CLK")
	)
	(segment
		(start 48.631348 -72.997568)
		(end 48.631348 -72.73798)
		(width 0.11684)
		(layer "F.Cu")
		(net "SPI_BMC_BOOT_CLK")
	)
	(segment
		(start 46.357286 -74.0664)
		(end 47.442374 -72.981312)
		(width 0.11684)
		(layer "F.Cu")
		(net "SPI_BMC_BOOT_CLK")
	)
	(segment
		(start 43.44797 -75.1078)
		(end 43.708066 -75.1078)
		(width 0.11684)
		(layer "F.Cu")
		(net "SPI_BMC_BOOT_CLK")
	)
	(segment
		(start 41.656 -76.719938)
		(end 41.656 -75.5396)
		(width 0.11684)
		(layer "F.Cu")
		(net "SPI_BMC_BOOT_CLK")
	)
	(segment
		(start 47.10811 -71.474076)
		(end 47.10811 -71.214488)
		(width 0.11684)
		(layer "F.Cu")
		(net "SPI_BMC_BOOT_CLK")
	)
	(segment
		(start 40.22725 -77.4954)
		(end 40.55745 -77.1652)
		(width 0.11684)
		(layer "F.Cu")
		(net "SPI_BMC_BOOT_CLK")
	)
	(segment
		(start 52.809648 -64.312546)
		(end 52.854606 -64.331342)
		(width 0.11684)
		(layer "F.Cu")
		(net "SPI_BMC_BOOT_CLK")
	)
	(segment
		(start 43.891708 -73.36028)
		(end 43.891708 -71.882)
		(width 0.11684)
		(layer "F.Cu")
		(net "SPI_BMC_BOOT_CLK")
	)
	(segment
		(start 46.025054 -72.5932)
		(end 46.431454 -72.1868)
		(width 0.11684)
		(layer "F.Cu")
		(net "SPI_BMC_BOOT_CLK")
	)
	(segment
		(start 48.672242 -73.29805)
		(end 48.672242 -73.038462)
		(width 0.11684)
		(layer "F.Cu")
		(net "SPI_BMC_BOOT_CLK")
	)
	(segment
		(start 52.21605 -69.627496)
		(end 52.21605 -69.342)
		(width 0.11684)
		(layer "F.Cu")
		(net "SPI_BMC_BOOT_CLK")
	)
	(segment
		(start 41.656 -75.5396)
		(end 40.513 -74.3966)
		(width 0.11684)
		(layer "F.Cu")
		(net "SPI_BMC_BOOT_CLK")
	)
	(segment
		(start 40.513 -74.3966)
		(end 40.513 -73.761854)
		(width 0.11684)
		(layer "F.Cu")
		(net "SPI_BMC_BOOT_CLK")
	)
	(segment
		(start 44.07535 -74.171302)
		(end 44.875958 -74.171302)
		(width 0.11684)
		(layer "F.Cu")
		(net "SPI_BMC_BOOT_CLK")
	)
	(segment
		(start 46.87189 -72.1868)
		(end 46.99889 -72.3138)
		(width 0.11684)
		(layer "F.Cu")
		(net "SPI_BMC_BOOT_CLK")
	)
	(segment
		(start 51.924966 -69.91858)
		(end 52.21605 -69.627496)
		(width 0.11684)
		(layer "F.Cu")
		(net "SPI_BMC_BOOT_CLK")
	)
	(segment
		(start 51.560222 -69.91858)
		(end 51.924966 -69.91858)
		(width 0.11684)
		(layer "F.Cu")
		(net "SPI_BMC_BOOT_CLK")
	)
	(segment
		(start 48.18761 -72.294242)
		(end 47.928022 -72.294242)
		(width 0.11684)
		(layer "F.Cu")
		(net "SPI_BMC_BOOT_CLK")
	)
	(segment
		(start 43.708066 -75.1078)
		(end 43.891708 -74.924158)
		(width 0.11684)
		(layer "F.Cu")
		(net "SPI_BMC_BOOT_CLK")
	)
	(segment
		(start 41.210738 -77.1652)
		(end 41.656 -76.719938)
		(width 0.11684)
		(layer "F.Cu")
		(net "SPI_BMC_BOOT_CLK")
	)
	(segment
		(start 45.953426 -74.0664)
		(end 46.357286 -74.0664)
		(width 0.11684)
		(layer "F.Cu")
		(net "SPI_BMC_BOOT_CLK")
	)
	(segment
		(start 49.472088 -70.034912)
		(end 51.44389 -70.034912)
		(width 0.11684)
		(layer "F.Cu")
		(net "SPI_BMC_BOOT_CLK")
	)
	(segment
		(start 53.249576 -65.283334)
		(end 53.249576 -67.251326)
		(width 0.11684)
		(layer "F.Cu")
		(net "SPI_BMC_BOOT_CLK")
	)
	(segment
		(start 42.31767 -73.170034)
		(end 41.840912 -72.693276)
		(width 0.11684)
		(layer "F.Cu")
		(net "SPI_BMC_BOOT_CLK")
	)
	(segment
		(start 40.513 -73.761854)
		(end 41.137586 -73.137268)
		(width 0.11684)
		(layer "F.Cu")
		(net "SPI_BMC_BOOT_CLK")
	)
	(segment
		(start 52.83708 -68.24726)
		(end 52.83708 -68.72097)
		(width 0.11684)
		(layer "F.Cu")
		(net "SPI_BMC_BOOT_CLK")
	)
	(segment
		(start 44.875958 -74.171302)
		(end 45.0596 -73.98766)
		(width 0.11684)
		(layer "F.Cu")
		(net "SPI_BMC_BOOT_CLK")
	)
	(segment
		(start 48.672242 -73.038462)
		(end 48.631348 -72.997568)
		(width 0.11684)
		(layer "F.Cu")
		(net "SPI_BMC_BOOT_CLK")
	)
	(segment
		(start 45.826426 -73.710038)
		(end 45.826426 -73.9394)
		(width 0.11684)
		(layer "F.Cu")
		(net "SPI_BMC_BOOT_CLK")
	)
	(segment
		(start 48.895 -70.612)
		(end 49.472088 -70.034912)
		(width 0.11684)
		(layer "F.Cu")
		(net "SPI_BMC_BOOT_CLK")
	)
	(segment
		(start 41.840912 -72.693276)
		(end 41.840912 -72.433942)
		(width 0.11684)
		(layer "F.Cu")
		(net "SPI_BMC_BOOT_CLK")
	)
	(segment
		(start 47.727616 -72.981312)
		(end 48.228504 -73.4822)
		(width 0.11684)
		(layer "F.Cu")
		(net "SPI_BMC_BOOT_CLK")
	)
	(segment
		(start 40.55745 -77.1652)
		(end 41.210738 -77.1652)
		(width 0.11684)
		(layer "F.Cu")
		(net "SPI_BMC_BOOT_CLK")
	)
	(segment
		(start 41.137586 -73.137268)
		(end 41.397174 -73.137268)
		(width 0.11684)
		(layer "F.Cu")
		(net "SPI_BMC_BOOT_CLK")
	)
	(segment
		(start 44.07535 -73.543922)
		(end 43.891708 -73.36028)
		(width 0.11684)
		(layer "F.Cu")
		(net "SPI_BMC_BOOT_CLK")
	)
	(segment
		(start 43.891708 -74.354944)
		(end 44.07535 -74.171302)
		(width 0.11684)
		(layer "F.Cu")
		(net "SPI_BMC_BOOT_CLK")
	)
	(segment
		(start 46.99889 -72.3138)
		(end 46.99889 -72.537574)
		(width 0.11684)
		(layer "F.Cu")
		(net "SPI_BMC_BOOT_CLK")
	)
	(segment
		(start 49.06772 -71.673974)
		(end 48.808132 -71.673974)
		(width 0.11684)
		(layer "F.Cu")
		(net "SPI_BMC_BOOT_CLK")
	)
	(segment
		(start 45.0596 -73.98766)
		(end 45.0596 -73.727564)
		(width 0.11684)
		(layer "F.Cu")
		(net "SPI_BMC_BOOT_CLK")
	)
	(segment
		(start 47.10811 -71.214488)
		(end 47.710598 -70.612)
		(width 0.11684)
		(layer "F.Cu")
		(net "SPI_BMC_BOOT_CLK")
	)
	(segment
		(start 44.875958 -73.543922)
		(end 44.07535 -73.543922)
		(width 0.11684)
		(layer "F.Cu")
		(net "SPI_BMC_BOOT_CLK")
	)
	(segment
		(start 47.928022 -72.294242)
		(end 47.10811 -71.474076)
		(width 0.11684)
		(layer "F.Cu")
		(net "SPI_BMC_BOOT_CLK")
	)
	(segment
		(start 42.418254 -71.8566)
		(end 43.137328 -71.8566)
		(width 0.11684)
		(layer "F.Cu")
		(net "SPI_BMC_BOOT_CLK")
	)
	(segment
		(start 43.137328 -71.8566)
		(end 43.264328 -71.9836)
		(width 0.11684)
		(layer "F.Cu")
		(net "SPI_BMC_BOOT_CLK")
	)
	(segment
		(start 43.891708 -74.924158)
		(end 43.891708 -74.354944)
		(width 0.11684)
		(layer "F.Cu")
		(net "SPI_BMC_BOOT_CLK")
	)
	(segment
		(start 48.228504 -73.4822)
		(end 48.488092 -73.4822)
		(width 0.11684)
		(layer "F.Cu")
		(net "SPI_BMC_BOOT_CLK")
	)
	(segment
		(start 53.249576 -67.251326)
		(end 52.83708 -68.24726)
		(width 0.11684)
		(layer "F.Cu")
		(net "SPI_BMC_BOOT_CLK")
	)
	(segment
		(start 49.25187 -71.858124)
		(end 49.06772 -71.673974)
		(width 0.11684)
		(layer "F.Cu")
		(net "SPI_BMC_BOOT_CLK")
	)
	(via
		(at 48.895 -70.612)
		(size 0.762)
		(drill 0.381)
		(layers "F.Cu" "B.Cu")
		(net "SPI_BMC_BOOT_CLK")
	)
	(segment
		(start 66.326258 -76.59878)
		(end 65.67678 -76.59878)
		(width 0.11684)
		(layer "F.Cu")
		(net "SPI_BMC_BIOS_ROM_R_MOSI")
	)
	(segment
		(start 63.839344 -76.495656)
		(end 63.4746 -76.8604)
		(width 0.11684)
		(layer "F.Cu")
		(net "SPI_BMC_BIOS_ROM_R_MOSI")
	)
	(segment
		(start 67.64274 -64.87414)
		(end 67.789552 -65.020952)
		(width 0.11684)
		(layer "F.Cu")
		(net "SPI_BMC_BIOS_ROM_R_MOSI")
	)
	(segment
		(start 66.472816 -75.432158)
		(end 66.472816 -76.452222)
		(width 0.11684)
		(layer "F.Cu")
		(net "SPI_BMC_BIOS_ROM_R_MOSI")
	)
	(segment
		(start 67.474592 -66.251328)
		(end 68.308728 -65.417192)
		(width 0.11684)
		(layer "F.Cu")
		(net "SPI_BMC_BIOS_ROM_R_MOSI")
	)
	(segment
		(start 69.9008 -68.533264)
		(end 69.9008 -70.445884)
		(width 0.11684)
		(layer "F.Cu")
		(net "SPI_BMC_BIOS_ROM_R_MOSI")
	)
	(segment
		(start 68.8594 -67.491864)
		(end 69.066664 -67.491864)
		(width 0.11684)
		(layer "F.Cu")
		(net "SPI_BMC_BIOS_ROM_R_MOSI")
	)
	(segment
		(start 69.559932 -66.998596)
		(end 69.767196 -66.998596)
		(width 0.11684)
		(layer "F.Cu")
		(net "SPI_BMC_BIOS_ROM_R_MOSI")
	)
	(segment
		(start 66.3702 -64.35725)
		(end 66.3702 -65.002664)
		(width 0.11684)
		(layer "F.Cu")
		(net "SPI_BMC_BIOS_ROM_R_MOSI")
	)
	(segment
		(start 68.004436 -66.429636)
		(end 68.004436 -66.6369)
		(width 0.11684)
		(layer "F.Cu")
		(net "SPI_BMC_BIOS_ROM_R_MOSI")
	)
	(segment
		(start 69.370956 -66.288666)
		(end 69.370956 -66.47942)
		(width 0.11684)
		(layer "F.Cu")
		(net "SPI_BMC_BIOS_ROM_R_MOSI")
	)
	(segment
		(start 70.502018 -71.226934)
		(end 69.292216 -72.436736)
		(width 0.11684)
		(layer "F.Cu")
		(net "SPI_BMC_BIOS_ROM_R_MOSI")
	)
	(segment
		(start 66.472816 -76.452222)
		(end 66.326258 -76.59878)
		(width 0.11684)
		(layer "F.Cu")
		(net "SPI_BMC_BIOS_ROM_R_MOSI")
	)
	(segment
		(start 63.839344 -75.911456)
		(end 63.839344 -76.495656)
		(width 0.11684)
		(layer "F.Cu")
		(net "SPI_BMC_BIOS_ROM_R_MOSI")
	)
	(segment
		(start 68.712588 -67.345052)
		(end 68.8594 -67.491864)
		(width 0.11684)
		(layer "F.Cu")
		(net "SPI_BMC_BIOS_ROM_R_MOSI")
	)
	(segment
		(start 51.39182 -75.98918)
		(end 51.39182 -77.32522)
		(width 0.11684)
		(layer "F.Cu")
		(net "SPI_BMC_BIOS_ROM_R_MOSI")
	)
	(segment
		(start 55.969662 -73.8886)
		(end 53.4924 -73.8886)
		(width 0.11684)
		(layer "F.Cu")
		(net "SPI_BMC_BIOS_ROM_R_MOSI")
	)
	(segment
		(start 66.973196 -75.432158)
		(end 66.826638 -75.2856)
		(width 0.11684)
		(layer "F.Cu")
		(net "SPI_BMC_BIOS_ROM_R_MOSI")
	)
	(segment
		(start 68.151248 -66.783712)
		(end 68.358512 -66.783712)
		(width 0.11684)
		(layer "F.Cu")
		(net "SPI_BMC_BIOS_ROM_R_MOSI")
	)
	(segment
		(start 68.662804 -65.580514)
		(end 68.662804 -65.771268)
		(width 0.11684)
		(layer "F.Cu")
		(net "SPI_BMC_BIOS_ROM_R_MOSI")
	)
	(segment
		(start 67.267328 -66.251328)
		(end 67.474592 -66.251328)
		(width 0.11684)
		(layer "F.Cu")
		(net "SPI_BMC_BIOS_ROM_R_MOSI")
	)
	(segment
		(start 51.94681 -77.88021)
		(end 53.81879 -77.88021)
		(width 0.11684)
		(layer "F.Cu")
		(net "SPI_BMC_BIOS_ROM_R_MOSI")
	)
	(segment
		(start 54.961536 -78.33868)
		(end 54.961536 -79.302864)
		(width 0.11684)
		(layer "F.Cu")
		(net "SPI_BMC_BIOS_ROM_R_MOSI")
	)
	(segment
		(start 60.788296 -76.70038)
		(end 60.59678 -76.70038)
		(width 0.11684)
		(layer "F.Cu")
		(net "SPI_BMC_BIOS_ROM_R_MOSI")
	)
	(segment
		(start 67.789552 -65.020952)
		(end 67.789552 -65.228216)
		(width 0.11684)
		(layer "F.Cu")
		(net "SPI_BMC_BIOS_ROM_R_MOSI")
	)
	(segment
		(start 69.292216 -72.436736)
		(end 69.292216 -75.754992)
		(width 0.11684)
		(layer "F.Cu")
		(net "SPI_BMC_BIOS_ROM_R_MOSI")
	)
	(segment
		(start 57.17667 -73.28027)
		(end 56.577992 -73.28027)
		(width 0.11684)
		(layer "F.Cu")
		(net "SPI_BMC_BIOS_ROM_R_MOSI")
	)
	(segment
		(start 66.942208 -65.367408)
		(end 67.435476 -64.87414)
		(width 0.11684)
		(layer "F.Cu")
		(net "SPI_BMC_BIOS_ROM_R_MOSI")
	)
	(segment
		(start 63.4746 -76.8604)
		(end 60.948316 -76.8604)
		(width 0.11684)
		(layer "F.Cu")
		(net "SPI_BMC_BIOS_ROM_R_MOSI")
	)
	(segment
		(start 69.207634 -66.125344)
		(end 69.370956 -66.288666)
		(width 0.11684)
		(layer "F.Cu")
		(net "SPI_BMC_BIOS_ROM_R_MOSI")
	)
	(segment
		(start 53.83657 -77.86243)
		(end 54.485286 -77.86243)
		(width 0.11684)
		(layer "F.Cu")
		(net "SPI_BMC_BIOS_ROM_R_MOSI")
	)
	(segment
		(start 68.153788 -76.89342)
		(end 67.380104 -76.89342)
		(width 0.11684)
		(layer "F.Cu")
		(net "SPI_BMC_BIOS_ROM_R_MOSI")
	)
	(segment
		(start 69.292216 -75.754992)
		(end 68.153788 -76.89342)
		(width 0.11684)
		(layer "F.Cu")
		(net "SPI_BMC_BIOS_ROM_R_MOSI")
	)
	(segment
		(start 69.914008 -67.352672)
		(end 69.42074 -67.84594)
		(width 0.11684)
		(layer "F.Cu")
		(net "SPI_BMC_BIOS_ROM_R_MOSI")
	)
	(segment
		(start 65.67678 -76.59878)
		(end 64.657732 -75.579732)
		(width 0.11684)
		(layer "F.Cu")
		(net "SPI_BMC_BIOS_ROM_R_MOSI")
	)
	(segment
		(start 69.42074 -68.053204)
		(end 69.9008 -68.533264)
		(width 0.11684)
		(layer "F.Cu")
		(net "SPI_BMC_BIOS_ROM_R_MOSI")
	)
	(segment
		(start 69.01688 -66.125344)
		(end 69.207634 -66.125344)
		(width 0.11684)
		(layer "F.Cu")
		(net "SPI_BMC_BIOS_ROM_R_MOSI")
	)
	(segment
		(start 68.499482 -65.417192)
		(end 68.662804 -65.580514)
		(width 0.11684)
		(layer "F.Cu")
		(net "SPI_BMC_BIOS_ROM_R_MOSI")
	)
	(segment
		(start 66.734944 -65.367408)
		(end 66.942208 -65.367408)
		(width 0.11684)
		(layer "F.Cu")
		(net "SPI_BMC_BIOS_ROM_R_MOSI")
	)
	(segment
		(start 67.789552 -65.228216)
		(end 67.120516 -65.897252)
		(width 0.11684)
		(layer "F.Cu")
		(net "SPI_BMC_BIOS_ROM_R_MOSI")
	)
	(segment
		(start 69.767196 -66.998596)
		(end 69.914008 -67.145408)
		(width 0.11684)
		(layer "F.Cu")
		(net "SPI_BMC_BIOS_ROM_R_MOSI")
	)
	(segment
		(start 69.9008 -70.445884)
		(end 70.502018 -71.047102)
		(width 0.11684)
		(layer "F.Cu")
		(net "SPI_BMC_BIOS_ROM_R_MOSI")
	)
	(segment
		(start 64.171068 -75.579732)
		(end 63.839344 -75.911456)
		(width 0.11684)
		(layer "F.Cu")
		(net "SPI_BMC_BIOS_ROM_R_MOSI")
	)
	(segment
		(start 66.826638 -75.2856)
		(end 66.619374 -75.2856)
		(width 0.11684)
		(layer "F.Cu")
		(net "SPI_BMC_BIOS_ROM_R_MOSI")
	)
	(segment
		(start 68.358512 -66.783712)
		(end 69.01688 -66.125344)
		(width 0.11684)
		(layer "F.Cu")
		(net "SPI_BMC_BIOS_ROM_R_MOSI")
	)
	(segment
		(start 64.657732 -75.579732)
		(end 64.171068 -75.579732)
		(width 0.11684)
		(layer "F.Cu")
		(net "SPI_BMC_BIOS_ROM_R_MOSI")
	)
	(segment
		(start 68.004436 -66.6369)
		(end 68.151248 -66.783712)
		(width 0.11684)
		(layer "F.Cu")
		(net "SPI_BMC_BIOS_ROM_R_MOSI")
	)
	(segment
		(start 69.914008 -67.145408)
		(end 69.914008 -67.352672)
		(width 0.11684)
		(layer "F.Cu")
		(net "SPI_BMC_BIOS_ROM_R_MOSI")
	)
	(segment
		(start 69.42074 -67.84594)
		(end 69.42074 -68.053204)
		(width 0.11684)
		(layer "F.Cu")
		(net "SPI_BMC_BIOS_ROM_R_MOSI")
	)
	(segment
		(start 53.81879 -77.88021)
		(end 53.83657 -77.86243)
		(width 0.11684)
		(layer "F.Cu")
		(net "SPI_BMC_BIOS_ROM_R_MOSI")
	)
	(segment
		(start 60.59678 -76.70038)
		(end 57.17667 -73.28027)
		(width 0.11684)
		(layer "F.Cu")
		(net "SPI_BMC_BIOS_ROM_R_MOSI")
	)
	(segment
		(start 68.712588 -67.137788)
		(end 68.712588 -67.345052)
		(width 0.11684)
		(layer "F.Cu")
		(net "SPI_BMC_BIOS_ROM_R_MOSI")
	)
	(segment
		(start 56.577992 -73.28027)
		(end 55.969662 -73.8886)
		(width 0.11684)
		(layer "F.Cu")
		(net "SPI_BMC_BIOS_ROM_R_MOSI")
	)
	(segment
		(start 66.3702 -65.002664)
		(end 66.734944 -65.367408)
		(width 0.11684)
		(layer "F.Cu")
		(net "SPI_BMC_BIOS_ROM_R_MOSI")
	)
	(segment
		(start 67.380104 -76.89342)
		(end 66.973196 -76.486512)
		(width 0.11684)
		(layer "F.Cu")
		(net "SPI_BMC_BIOS_ROM_R_MOSI")
	)
	(segment
		(start 68.308728 -65.417192)
		(end 68.499482 -65.417192)
		(width 0.11684)
		(layer "F.Cu")
		(net "SPI_BMC_BIOS_ROM_R_MOSI")
	)
	(segment
		(start 67.120516 -65.897252)
		(end 67.120516 -66.104516)
		(width 0.11684)
		(layer "F.Cu")
		(net "SPI_BMC_BIOS_ROM_R_MOSI")
	)
	(segment
		(start 70.502018 -71.047102)
		(end 70.502018 -71.226934)
		(width 0.11684)
		(layer "F.Cu")
		(net "SPI_BMC_BIOS_ROM_R_MOSI")
	)
	(segment
		(start 67.435476 -64.87414)
		(end 67.64274 -64.87414)
		(width 0.11684)
		(layer "F.Cu")
		(net "SPI_BMC_BIOS_ROM_R_MOSI")
	)
	(segment
		(start 66.973196 -76.486512)
		(end 66.973196 -75.432158)
		(width 0.11684)
		(layer "F.Cu")
		(net "SPI_BMC_BIOS_ROM_R_MOSI")
	)
	(segment
		(start 68.662804 -65.771268)
		(end 68.004436 -66.429636)
		(width 0.11684)
		(layer "F.Cu")
		(net "SPI_BMC_BIOS_ROM_R_MOSI")
	)
	(segment
		(start 67.120516 -66.104516)
		(end 67.267328 -66.251328)
		(width 0.11684)
		(layer "F.Cu")
		(net "SPI_BMC_BIOS_ROM_R_MOSI")
	)
	(segment
		(start 54.485286 -77.86243)
		(end 54.961536 -78.33868)
		(width 0.11684)
		(layer "F.Cu")
		(net "SPI_BMC_BIOS_ROM_R_MOSI")
	)
	(segment
		(start 69.370956 -66.47942)
		(end 68.712588 -67.137788)
		(width 0.11684)
		(layer "F.Cu")
		(net "SPI_BMC_BIOS_ROM_R_MOSI")
	)
	(segment
		(start 69.066664 -67.491864)
		(end 69.559932 -66.998596)
		(width 0.11684)
		(layer "F.Cu")
		(net "SPI_BMC_BIOS_ROM_R_MOSI")
	)
	(segment
		(start 60.948316 -76.8604)
		(end 60.788296 -76.70038)
		(width 0.11684)
		(layer "F.Cu")
		(net "SPI_BMC_BIOS_ROM_R_MOSI")
	)
	(segment
		(start 66.619374 -75.2856)
		(end 66.472816 -75.432158)
		(width 0.11684)
		(layer "F.Cu")
		(net "SPI_BMC_BIOS_ROM_R_MOSI")
	)
	(segment
		(start 53.4924 -73.8886)
		(end 51.39182 -75.98918)
		(width 0.11684)
		(layer "F.Cu")
		(net "SPI_BMC_BIOS_ROM_R_MOSI")
	)
	(segment
		(start 51.39182 -77.32522)
		(end 51.94681 -77.88021)
		(width 0.11684)
		(layer "F.Cu")
		(net "SPI_BMC_BIOS_ROM_R_MOSI")
	)
	(via
		(at 44.847002 -78.972918)
		(size 0.508)
		(drill 0.254)
		(layers "F.Cu" "B.Cu")
		(net "SPI_BMC_BIOS_ROM_R_MOSI")
	)
	(via
		(at 54.961536 -79.302864)
		(size 0.508)
		(drill 0.254)
		(layers "F.Cu" "B.Cu")
		(net "SPI_BMC_BIOS_ROM_R_MOSI")
	)
	(segment
		(start 44.859194 -78.98511)
		(end 46.019466 -78.98511)
		(width 0.11684)
		(layer "B.Cu")
		(net "SPI_BMC_BIOS_ROM_R_MOSI")
	)
	(segment
		(start 44.847002 -78.972918)
		(end 44.859194 -78.98511)
		(width 0.11684)
		(layer "B.Cu")
		(net "SPI_BMC_BIOS_ROM_R_MOSI")
	)
	(segment
		(start 49.544224 -81.36636)
		(end 48.410368 -80.232504)
		(width 0.08382)
		(layer "In2.Cu")
		(net "SPI_BMC_BIOS_ROM_R_MOSI")
	)
	(segment
		(start 53.063648 -79.298292)
		(end 50.99558 -81.36636)
		(width 0.08382)
		(layer "In2.Cu")
		(net "SPI_BMC_BIOS_ROM_R_MOSI")
	)
	(segment
		(start 45.019722 -78.972918)
		(end 44.847002 -78.972918)
		(width 0.08382)
		(layer "In2.Cu")
		(net "SPI_BMC_BIOS_ROM_R_MOSI")
	)
	(segment
		(start 46.279308 -80.232504)
		(end 45.019722 -78.972918)
		(width 0.08382)
		(layer "In2.Cu")
		(net "SPI_BMC_BIOS_ROM_R_MOSI")
	)
	(segment
		(start 54.956964 -79.298292)
		(end 53.063648 -79.298292)
		(width 0.08382)
		(layer "In2.Cu")
		(net "SPI_BMC_BIOS_ROM_R_MOSI")
	)
	(segment
		(start 54.956964 -79.302864)
		(end 54.956964 -79.298292)
		(width 0.08382)
		(layer "In2.Cu")
		(net "SPI_BMC_BIOS_ROM_R_MOSI")
	)
	(segment
		(start 54.961536 -79.302864)
		(end 54.956964 -79.302864)
		(width 0.08382)
		(layer "In2.Cu")
		(net "SPI_BMC_BIOS_ROM_R_MOSI")
	)
	(segment
		(start 50.99558 -81.36636)
		(end 49.544224 -81.36636)
		(width 0.08382)
		(layer "In2.Cu")
		(net "SPI_BMC_BIOS_ROM_R_MOSI")
	)
	(segment
		(start 48.410368 -80.232504)
		(end 46.279308 -80.232504)
		(width 0.08382)
		(layer "In2.Cu")
		(net "SPI_BMC_BIOS_ROM_R_MOSI")
	)
	(via
		(at 50.20564 -99.28098)
		(size 0.508)
		(drill 0.254)
		(layers "F.Cu" "B.Cu")
		(net "SPI_BMC_BIOS_ROM_R_MISO")
	)
	(via
		(at 60.3758 -65.376298)
		(size 0.508)
		(drill 0.254)
		(layers "F.Cu" "B.Cu")
		(net "SPI_BMC_BIOS_ROM_R_MISO")
	)
	(via
		(at 63.1952 -97.9678)
		(size 0.508)
		(drill 0.254)
		(layers "F.Cu" "B.Cu")
		(net "SPI_BMC_BIOS_ROM_R_MISO")
	)
	(segment
		(start 47.95774 -100.22586)
		(end 47.455836 -100.727764)
		(width 0.11684)
		(layer "B.Cu")
		(net "SPI_BMC_BIOS_ROM_R_MISO")
	)
	(segment
		(start 49.51222 -99.28098)
		(end 48.56734 -100.22586)
		(width 0.11684)
		(layer "B.Cu")
		(net "SPI_BMC_BIOS_ROM_R_MISO")
	)
	(segment
		(start 59.7154 -65.259458)
		(end 59.7154 -64.73825)
		(width 0.11684)
		(layer "B.Cu")
		(net "SPI_BMC_BIOS_ROM_R_MISO")
	)
	(segment
		(start 50.20564 -99.28098)
		(end 49.51222 -99.28098)
		(width 0.11684)
		(layer "B.Cu")
		(net "SPI_BMC_BIOS_ROM_R_MISO")
	)
	(segment
		(start 48.56734 -100.22586)
		(end 47.95774 -100.22586)
		(width 0.11684)
		(layer "B.Cu")
		(net "SPI_BMC_BIOS_ROM_R_MISO")
	)
	(segment
		(start 59.83224 -65.376298)
		(end 59.7154 -65.259458)
		(width 0.11684)
		(layer "B.Cu")
		(net "SPI_BMC_BIOS_ROM_R_MISO")
	)
	(segment
		(start 60.3758 -65.376298)
		(end 59.83224 -65.376298)
		(width 0.11684)
		(layer "B.Cu")
		(net "SPI_BMC_BIOS_ROM_R_MISO")
	)
	(segment
		(start 47.455836 -100.727764)
		(end 46.811184 -100.727764)
		(width 0.11684)
		(layer "B.Cu")
		(net "SPI_BMC_BIOS_ROM_R_MISO")
	)
	(segment
		(start 63.1952 -98.831146)
		(end 63.1952 -97.9678)
		(width 0.08382)
		(layer "In2.Cu")
		(net "SPI_BMC_BIOS_ROM_R_MISO")
	)
	(segment
		(start 55.0545 -99.28098)
		(end 56.1213 -100.34778)
		(width 0.08382)
		(layer "In2.Cu")
		(net "SPI_BMC_BIOS_ROM_R_MISO")
	)
	(segment
		(start 50.20564 -99.28098)
		(end 55.0545 -99.28098)
		(width 0.08382)
		(layer "In2.Cu")
		(net "SPI_BMC_BIOS_ROM_R_MISO")
	)
	(segment
		(start 59.28614 -100.34778)
		(end 59.81192 -100.87356)
		(width 0.08382)
		(layer "In2.Cu")
		(net "SPI_BMC_BIOS_ROM_R_MISO")
	)
	(segment
		(start 56.1213 -100.34778)
		(end 59.28614 -100.34778)
		(width 0.08382)
		(layer "In2.Cu")
		(net "SPI_BMC_BIOS_ROM_R_MISO")
	)
	(segment
		(start 61.152786 -100.87356)
		(end 63.1952 -98.831146)
		(width 0.08382)
		(layer "In2.Cu")
		(net "SPI_BMC_BIOS_ROM_R_MISO")
	)
	(segment
		(start 59.81192 -100.87356)
		(end 61.152786 -100.87356)
		(width 0.08382)
		(layer "In2.Cu")
		(net "SPI_BMC_BIOS_ROM_R_MISO")
	)
	(segment
		(start 66.9798 -74.075544)
		(end 66.62547 -74.429874)
		(width 0.08382)
		(layer "In9.Cu")
		(net "SPI_BMC_BIOS_ROM_R_MISO")
	)
	(segment
		(start 66.62547 -77.291184)
		(end 64.87795 -79.038704)
		(width 0.08382)
		(layer "In9.Cu")
		(net "SPI_BMC_BIOS_ROM_R_MISO")
	)
	(segment
		(start 63.1952 -95.0214)
		(end 63.1952 -97.9678)
		(width 0.08382)
		(layer "In9.Cu")
		(net "SPI_BMC_BIOS_ROM_R_MISO")
	)
	(segment
		(start 60.3758 -65.376298)
		(end 60.582302 -65.5828)
		(width 0.08382)
		(layer "In9.Cu")
		(net "SPI_BMC_BIOS_ROM_R_MISO")
	)
	(segment
		(start 66.62547 -74.429874)
		(end 66.62547 -77.291184)
		(width 0.08382)
		(layer "In9.Cu")
		(net "SPI_BMC_BIOS_ROM_R_MISO")
	)
	(segment
		(start 64.87795 -79.038704)
		(end 64.87795 -79.609696)
		(width 0.08382)
		(layer "In9.Cu")
		(net "SPI_BMC_BIOS_ROM_R_MISO")
	)
	(segment
		(start 63.4238 -94.7928)
		(end 63.1952 -95.0214)
		(width 0.08382)
		(layer "In9.Cu")
		(net "SPI_BMC_BIOS_ROM_R_MISO")
	)
	(segment
		(start 65.3796 -82.7278)
		(end 63.4238 -84.6836)
		(width 0.08382)
		(layer "In9.Cu")
		(net "SPI_BMC_BIOS_ROM_R_MISO")
	)
	(segment
		(start 65.938146 -68.605146)
		(end 67.12331 -69.79031)
		(width 0.08382)
		(layer "In9.Cu")
		(net "SPI_BMC_BIOS_ROM_R_MISO")
	)
	(segment
		(start 66.9798 -71.669148)
		(end 66.9798 -74.075544)
		(width 0.08382)
		(layer "In9.Cu")
		(net "SPI_BMC_BIOS_ROM_R_MISO")
	)
	(segment
		(start 62.535054 -65.5828)
		(end 65.5574 -68.605146)
		(width 0.08382)
		(layer "In9.Cu")
		(net "SPI_BMC_BIOS_ROM_R_MISO")
	)
	(segment
		(start 67.12331 -71.525638)
		(end 66.9798 -71.669148)
		(width 0.08382)
		(layer "In9.Cu")
		(net "SPI_BMC_BIOS_ROM_R_MISO")
	)
	(segment
		(start 60.582302 -65.5828)
		(end 62.535054 -65.5828)
		(width 0.08382)
		(layer "In9.Cu")
		(net "SPI_BMC_BIOS_ROM_R_MISO")
	)
	(segment
		(start 64.87795 -79.609696)
		(end 65.3796 -80.111346)
		(width 0.08382)
		(layer "In9.Cu")
		(net "SPI_BMC_BIOS_ROM_R_MISO")
	)
	(segment
		(start 65.5574 -68.605146)
		(end 65.938146 -68.605146)
		(width 0.08382)
		(layer "In9.Cu")
		(net "SPI_BMC_BIOS_ROM_R_MISO")
	)
	(segment
		(start 65.3796 -80.111346)
		(end 65.3796 -82.7278)
		(width 0.08382)
		(layer "In9.Cu")
		(net "SPI_BMC_BIOS_ROM_R_MISO")
	)
	(segment
		(start 67.12331 -69.79031)
		(end 67.12331 -71.525638)
		(width 0.08382)
		(layer "In9.Cu")
		(net "SPI_BMC_BIOS_ROM_R_MISO")
	)
	(segment
		(start 63.4238 -84.6836)
		(end 63.4238 -94.7928)
		(width 0.08382)
		(layer "In9.Cu")
		(net "SPI_BMC_BIOS_ROM_R_MISO")
	)
	(segment
		(start 60.7314 -64.45885)
		(end 61.0108 -64.73825)
		(width 0.11684)
		(layer "F.Cu")
		(net "SPI_BMC_BIOS_ROM_R_CLK")
	)
	(segment
		(start 61.202824 -66.235326)
		(end 61.204094 -66.236596)
		(width 0.11684)
		(layer "F.Cu")
		(net "SPI_BMC_BIOS_ROM_R_CLK")
	)
	(segment
		(start 61.0108 -64.73825)
		(end 61.0108 -65.9638)
		(width 0.11684)
		(layer "F.Cu")
		(net "SPI_BMC_BIOS_ROM_R_CLK")
	)
	(segment
		(start 61.204094 -67.840606)
		(end 60.781692 -68.263008)
		(width 0.11684)
		(layer "F.Cu")
		(net "SPI_BMC_BIOS_ROM_R_CLK")
	)
	(segment
		(start 61.202824 -66.155824)
		(end 61.202824 -66.235326)
		(width 0.11684)
		(layer "F.Cu")
		(net "SPI_BMC_BIOS_ROM_R_CLK")
	)
	(segment
		(start 61.0108 -65.9638)
		(end 61.202824 -66.155824)
		(width 0.11684)
		(layer "F.Cu")
		(net "SPI_BMC_BIOS_ROM_R_CLK")
	)
	(segment
		(start 61.204094 -66.236596)
		(end 61.204094 -67.840606)
		(width 0.11684)
		(layer "F.Cu")
		(net "SPI_BMC_BIOS_ROM_R_CLK")
	)
	(segment
		(start 60.781692 -68.263008)
		(end 60.781692 -68.2752)
		(width 0.11684)
		(layer "F.Cu")
		(net "SPI_BMC_BIOS_ROM_R_CLK")
	)
	(via
		(at 60.781692 -68.2752)
		(size 0.508)
		(drill 0.254)
		(layers "F.Cu" "B.Cu")
		(net "SPI_BMC_BIOS_ROM_R_CLK")
	)
	(via
		(at 60.118752 -79.049118)
		(size 0.508)
		(drill 0.254)
		(layers "F.Cu" "B.Cu")
		(net "SPI_BMC_BIOS_ROM_R_CLK")
	)
	(segment
		(start 55.6514 -79.839566)
		(end 55.76824 -79.956406)
		(width 0.11684)
		(layer "B.Cu")
		(net "SPI_BMC_BIOS_ROM_R_CLK")
	)
	(segment
		(start 57.055512 -78.6384)
		(end 56.848248 -78.6384)
		(width 0.11684)
		(layer "B.Cu")
		(net "SPI_BMC_BIOS_ROM_R_CLK")
	)
	(segment
		(start 54.294532 -82.640932)
		(end 53.238908 -81.585308)
		(width 0.11684)
		(layer "B.Cu")
		(net "SPI_BMC_BIOS_ROM_R_CLK")
	)
	(segment
		(start 53.238908 -81.585308)
		(end 51.861466 -81.585308)
		(width 0.11684)
		(layer "B.Cu")
		(net "SPI_BMC_BIOS_ROM_R_CLK")
	)
	(segment
		(start 56.70169 -79.309468)
		(end 56.555132 -79.456026)
		(width 0.11684)
		(layer "B.Cu")
		(net "SPI_BMC_BIOS_ROM_R_CLK")
	)
	(segment
		(start 58.92038 -80.645)
		(end 57.81929 -80.645)
		(width 0.11684)
		(layer "B.Cu")
		(net "SPI_BMC_BIOS_ROM_R_CLK")
	)
	(segment
		(start 60.118752 -79.049118)
		(end 60.1218 -79.049118)
		(width 0.11684)
		(layer "B.Cu")
		(net "SPI_BMC_BIOS_ROM_R_CLK")
	)
	(segment
		(start 56.555132 -79.456026)
		(end 55.76824 -79.456026)
		(width 0.11684)
		(layer "B.Cu")
		(net "SPI_BMC_BIOS_ROM_R_CLK")
	)
	(segment
		(start 56.70169 -80.171036)
		(end 56.70169 -81.768442)
		(width 0.11684)
		(layer "B.Cu")
		(net "SPI_BMC_BIOS_ROM_R_CLK")
	)
	(segment
		(start 56.70169 -78.784958)
		(end 56.70169 -79.309468)
		(width 0.11684)
		(layer "B.Cu")
		(net "SPI_BMC_BIOS_ROM_R_CLK")
	)
	(segment
		(start 55.6514 -79.572866)
		(end 55.6514 -79.839566)
		(width 0.11684)
		(layer "B.Cu")
		(net "SPI_BMC_BIOS_ROM_R_CLK")
	)
	(segment
		(start 60.1218 -79.44358)
		(end 58.92038 -80.645)
		(width 0.11684)
		(layer "B.Cu")
		(net "SPI_BMC_BIOS_ROM_R_CLK")
	)
	(segment
		(start 57.555892 -81.915)
		(end 57.348628 -81.915)
		(width 0.11684)
		(layer "B.Cu")
		(net "SPI_BMC_BIOS_ROM_R_CLK")
	)
	(segment
		(start 57.70245 -81.768442)
		(end 57.555892 -81.915)
		(width 0.11684)
		(layer "B.Cu")
		(net "SPI_BMC_BIOS_ROM_R_CLK")
	)
	(segment
		(start 56.48706 -79.956406)
		(end 56.70169 -80.171036)
		(width 0.11684)
		(layer "B.Cu")
		(net "SPI_BMC_BIOS_ROM_R_CLK")
	)
	(segment
		(start 56.555132 -81.915)
		(end 56.159654 -81.915)
		(width 0.11684)
		(layer "B.Cu")
		(net "SPI_BMC_BIOS_ROM_R_CLK")
	)
	(segment
		(start 57.20207 -81.768442)
		(end 57.20207 -78.784958)
		(width 0.11684)
		(layer "B.Cu")
		(net "SPI_BMC_BIOS_ROM_R_CLK")
	)
	(segment
		(start 57.20207 -78.784958)
		(end 57.055512 -78.6384)
		(width 0.11684)
		(layer "B.Cu")
		(net "SPI_BMC_BIOS_ROM_R_CLK")
	)
	(segment
		(start 57.70245 -80.76184)
		(end 57.70245 -81.768442)
		(width 0.11684)
		(layer "B.Cu")
		(net "SPI_BMC_BIOS_ROM_R_CLK")
	)
	(segment
		(start 60.1218 -79.049118)
		(end 60.1218 -79.44358)
		(width 0.11684)
		(layer "B.Cu")
		(net "SPI_BMC_BIOS_ROM_R_CLK")
	)
	(segment
		(start 56.70169 -81.768442)
		(end 56.555132 -81.915)
		(width 0.11684)
		(layer "B.Cu")
		(net "SPI_BMC_BIOS_ROM_R_CLK")
	)
	(segment
		(start 57.81929 -80.645)
		(end 57.70245 -80.76184)
		(width 0.11684)
		(layer "B.Cu")
		(net "SPI_BMC_BIOS_ROM_R_CLK")
	)
	(segment
		(start 57.348628 -81.915)
		(end 57.20207 -81.768442)
		(width 0.11684)
		(layer "B.Cu")
		(net "SPI_BMC_BIOS_ROM_R_CLK")
	)
	(segment
		(start 55.76824 -79.956406)
		(end 56.48706 -79.956406)
		(width 0.11684)
		(layer "B.Cu")
		(net "SPI_BMC_BIOS_ROM_R_CLK")
	)
	(segment
		(start 55.433722 -82.640932)
		(end 54.294532 -82.640932)
		(width 0.11684)
		(layer "B.Cu")
		(net "SPI_BMC_BIOS_ROM_R_CLK")
	)
	(segment
		(start 56.848248 -78.6384)
		(end 56.70169 -78.784958)
		(width 0.11684)
		(layer "B.Cu")
		(net "SPI_BMC_BIOS_ROM_R_CLK")
	)
	(segment
		(start 55.76824 -79.456026)
		(end 55.6514 -79.572866)
		(width 0.11684)
		(layer "B.Cu")
		(net "SPI_BMC_BIOS_ROM_R_CLK")
	)
	(segment
		(start 56.159654 -81.915)
		(end 55.433722 -82.640932)
		(width 0.11684)
		(layer "B.Cu")
		(net "SPI_BMC_BIOS_ROM_R_CLK")
	)
	(segment
		(start 61.68771 -76.54798)
		(end 61.68771 -77.021944)
		(width 0.08382)
		(layer "In9.Cu")
		(net "SPI_BMC_BIOS_ROM_R_CLK")
	)
	(segment
		(start 60.66028 -70.57898)
		(end 60.66028 -72.15378)
		(width 0.08382)
		(layer "In9.Cu")
		(net "SPI_BMC_BIOS_ROM_R_CLK")
	)
	(segment
		(start 60.198 -73.50506)
		(end 60.03036 -73.6727)
		(width 0.08382)
		(layer "In9.Cu")
		(net "SPI_BMC_BIOS_ROM_R_CLK")
	)
	(segment
		(start 62.39129 -72.50176)
		(end 62.57798 -72.68845)
		(width 0.08382)
		(layer "In9.Cu")
		(net "SPI_BMC_BIOS_ROM_R_CLK")
	)
	(segment
		(start 59.97067 -78.07071)
		(end 59.60237 -78.43901)
		(width 0.08382)
		(layer "In9.Cu")
		(net "SPI_BMC_BIOS_ROM_R_CLK")
	)
	(segment
		(start 61.88202 -74.09688)
		(end 62.04966 -74.26452)
		(width 0.08382)
		(layer "In9.Cu")
		(net "SPI_BMC_BIOS_ROM_R_CLK")
	)
	(segment
		(start 60.66028 -72.15378)
		(end 61.00826 -72.50176)
		(width 0.08382)
		(layer "In9.Cu")
		(net "SPI_BMC_BIOS_ROM_R_CLK")
	)
	(segment
		(start 62.38494 -73.50506)
		(end 60.198 -73.50506)
		(width 0.08382)
		(layer "In9.Cu")
		(net "SPI_BMC_BIOS_ROM_R_CLK")
	)
	(segment
		(start 61.99886 -75.7047)
		(end 61.83122 -75.87234)
		(width 0.08382)
		(layer "In9.Cu")
		(net "SPI_BMC_BIOS_ROM_R_CLK")
	)
	(segment
		(start 61.99886 -75.44816)
		(end 61.99886 -75.7047)
		(width 0.08382)
		(layer "In9.Cu")
		(net "SPI_BMC_BIOS_ROM_R_CLK")
	)
	(segment
		(start 62.04966 -74.52106)
		(end 61.88202 -74.6887)
		(width 0.08382)
		(layer "In9.Cu")
		(net "SPI_BMC_BIOS_ROM_R_CLK")
	)
	(segment
		(start 60.204604 -74.6887)
		(end 60.12053 -74.772774)
		(width 0.08382)
		(layer "In9.Cu")
		(net "SPI_BMC_BIOS_ROM_R_CLK")
	)
	(segment
		(start 60.03036 -73.6727)
		(end 60.03036 -73.92924)
		(width 0.08382)
		(layer "In9.Cu")
		(net "SPI_BMC_BIOS_ROM_R_CLK")
	)
	(segment
		(start 61.68771 -77.021944)
		(end 60.638944 -78.07071)
		(width 0.08382)
		(layer "In9.Cu")
		(net "SPI_BMC_BIOS_ROM_R_CLK")
	)
	(segment
		(start 61.80582 -79.73568)
		(end 61.58484 -79.5147)
		(width 0.08382)
		(layer "In9.Cu")
		(net "SPI_BMC_BIOS_ROM_R_CLK")
	)
	(segment
		(start 61.00826 -72.50176)
		(end 62.39129 -72.50176)
		(width 0.08382)
		(layer "In9.Cu")
		(net "SPI_BMC_BIOS_ROM_R_CLK")
	)
	(segment
		(start 60.12053 -74.772774)
		(end 60.12053 -75.196446)
		(width 0.08382)
		(layer "In9.Cu")
		(net "SPI_BMC_BIOS_ROM_R_CLK")
	)
	(segment
		(start 62.57798 -73.31202)
		(end 62.38494 -73.50506)
		(width 0.08382)
		(layer "In9.Cu")
		(net "SPI_BMC_BIOS_ROM_R_CLK")
	)
	(segment
		(start 60.83808 -82.169)
		(end 61.80582 -81.20126)
		(width 0.08382)
		(layer "In9.Cu")
		(net "SPI_BMC_BIOS_ROM_R_CLK")
	)
	(segment
		(start 59.72556 -76.46416)
		(end 61.60389 -76.46416)
		(width 0.08382)
		(layer "In9.Cu")
		(net "SPI_BMC_BIOS_ROM_R_CLK")
	)
	(segment
		(start 59.6392 -75.9968)
		(end 59.6392 -76.3778)
		(width 0.08382)
		(layer "In9.Cu")
		(net "SPI_BMC_BIOS_ROM_R_CLK")
	)
	(segment
		(start 61.60389 -76.46416)
		(end 61.68771 -76.54798)
		(width 0.08382)
		(layer "In9.Cu")
		(net "SPI_BMC_BIOS_ROM_R_CLK")
	)
	(segment
		(start 59.60237 -78.43901)
		(end 59.60237 -81.181702)
		(width 0.08382)
		(layer "In9.Cu")
		(net "SPI_BMC_BIOS_ROM_R_CLK")
	)
	(segment
		(start 59.76366 -75.87234)
		(end 59.6392 -75.9968)
		(width 0.08382)
		(layer "In9.Cu")
		(net "SPI_BMC_BIOS_ROM_R_CLK")
	)
	(segment
		(start 60.12053 -75.196446)
		(end 60.204604 -75.28052)
		(width 0.08382)
		(layer "In9.Cu")
		(net "SPI_BMC_BIOS_ROM_R_CLK")
	)
	(segment
		(start 61.83122 -75.87234)
		(end 59.76366 -75.87234)
		(width 0.08382)
		(layer "In9.Cu")
		(net "SPI_BMC_BIOS_ROM_R_CLK")
	)
	(segment
		(start 60.198 -74.09688)
		(end 61.88202 -74.09688)
		(width 0.08382)
		(layer "In9.Cu")
		(net "SPI_BMC_BIOS_ROM_R_CLK")
	)
	(segment
		(start 60.584334 -79.5147)
		(end 60.118752 -79.049118)
		(width 0.08382)
		(layer "In9.Cu")
		(net "SPI_BMC_BIOS_ROM_R_CLK")
	)
	(segment
		(start 60.638944 -78.07071)
		(end 59.97067 -78.07071)
		(width 0.08382)
		(layer "In9.Cu")
		(net "SPI_BMC_BIOS_ROM_R_CLK")
	)
	(segment
		(start 62.57798 -72.68845)
		(end 62.57798 -73.31202)
		(width 0.08382)
		(layer "In9.Cu")
		(net "SPI_BMC_BIOS_ROM_R_CLK")
	)
	(segment
		(start 61.80582 -81.20126)
		(end 61.80582 -79.73568)
		(width 0.08382)
		(layer "In9.Cu")
		(net "SPI_BMC_BIOS_ROM_R_CLK")
	)
	(segment
		(start 61.83122 -75.28052)
		(end 61.99886 -75.44816)
		(width 0.08382)
		(layer "In9.Cu")
		(net "SPI_BMC_BIOS_ROM_R_CLK")
	)
	(segment
		(start 60.781692 -70.457568)
		(end 60.66028 -70.57898)
		(width 0.08382)
		(layer "In9.Cu")
		(net "SPI_BMC_BIOS_ROM_R_CLK")
	)
	(segment
		(start 59.6392 -76.3778)
		(end 59.72556 -76.46416)
		(width 0.08382)
		(layer "In9.Cu")
		(net "SPI_BMC_BIOS_ROM_R_CLK")
	)
	(segment
		(start 60.589668 -82.169)
		(end 60.83808 -82.169)
		(width 0.08382)
		(layer "In9.Cu")
		(net "SPI_BMC_BIOS_ROM_R_CLK")
	)
	(segment
		(start 59.60237 -81.181702)
		(end 60.589668 -82.169)
		(width 0.08382)
		(layer "In9.Cu")
		(net "SPI_BMC_BIOS_ROM_R_CLK")
	)
	(segment
		(start 60.204604 -75.28052)
		(end 61.83122 -75.28052)
		(width 0.08382)
		(layer "In9.Cu")
		(net "SPI_BMC_BIOS_ROM_R_CLK")
	)
	(segment
		(start 61.88202 -74.6887)
		(end 60.204604 -74.6887)
		(width 0.08382)
		(layer "In9.Cu")
		(net "SPI_BMC_BIOS_ROM_R_CLK")
	)
	(segment
		(start 62.04966 -74.26452)
		(end 62.04966 -74.52106)
		(width 0.08382)
		(layer "In9.Cu")
		(net "SPI_BMC_BIOS_ROM_R_CLK")
	)
	(segment
		(start 61.58484 -79.5147)
		(end 60.584334 -79.5147)
		(width 0.08382)
		(layer "In9.Cu")
		(net "SPI_BMC_BIOS_ROM_R_CLK")
	)
	(segment
		(start 60.781692 -68.2752)
		(end 60.781692 -70.457568)
		(width 0.08382)
		(layer "In9.Cu")
		(net "SPI_BMC_BIOS_ROM_R_CLK")
	)
	(segment
		(start 60.03036 -73.92924)
		(end 60.198 -74.09688)
		(width 0.08382)
		(layer "In9.Cu")
		(net "SPI_BMC_BIOS_ROM_R_CLK")
	)
	(segment
		(start 65.70345 -62.8904)
		(end 65.691512 -62.8904)
		(width 0.11684)
		(layer "F.Cu")
		(net "SPI_BMC_BIOS_ROM_MOSI")
	)
	(segment
		(start 66.3702 -63.55715)
		(end 65.70345 -62.8904)
		(width 0.11684)
		(layer "F.Cu")
		(net "SPI_BMC_BIOS_ROM_MOSI")
	)
	(segment
		(start 58.49493 -56.171338)
		(end 58.099706 -56.566562)
		(width 0.11684)
		(layer "F.Cu")
		(net "SPI_BMC_BIOS_ROM_MOSI")
	)
	(via
		(at 65.691512 -62.8904)
		(size 0.508)
		(drill 0.254)
		(layers "F.Cu" "B.Cu")
		(net "SPI_BMC_BIOS_ROM_MOSI")
	)
	(via
		(at 58.099706 -56.566562)
		(size 0.4572)
		(drill 0.254)
		(layers "F.Cu" "B.Cu")
		(net "SPI_BMC_BIOS_ROM_MOSI")
	)
	(segment
		(start 60.21832 -59.914536)
		(end 60.21832 -58.175652)
		(width 0.08382)
		(layer "In2.Cu")
		(net "SPI_BMC_BIOS_ROM_MOSI")
	)
	(segment
		(start 60.216542 -58.16473)
		(end 59.80557 -57.753758)
		(width 0.08382)
		(layer "In2.Cu")
		(net "SPI_BMC_BIOS_ROM_MOSI")
	)
	(segment
		(start 59.30646 -57.510934)
		(end 59.30646 -57.254648)
		(width 0.08382)
		(layer "In2.Cu")
		(net "SPI_BMC_BIOS_ROM_MOSI")
	)
	(segment
		(start 58.353198 -56.820054)
		(end 58.099706 -56.566562)
		(width 0.08382)
		(layer "In2.Cu")
		(net "SPI_BMC_BIOS_ROM_MOSI")
	)
	(segment
		(start 59.046618 -56.994806)
		(end 58.775092 -56.994806)
		(width 0.08382)
		(layer "In2.Cu")
		(net "SPI_BMC_BIOS_ROM_MOSI")
	)
	(segment
		(start 59.80557 -57.753758)
		(end 59.549284 -57.753758)
		(width 0.08382)
		(layer "In2.Cu")
		(net "SPI_BMC_BIOS_ROM_MOSI")
	)
	(segment
		(start 60.468764 -60.51931)
		(end 60.21832 -59.914536)
		(width 0.08382)
		(layer "In2.Cu")
		(net "SPI_BMC_BIOS_ROM_MOSI")
	)
	(segment
		(start 60.21832 -58.175652)
		(end 60.216542 -58.16473)
		(width 0.08382)
		(layer "In2.Cu")
		(net "SPI_BMC_BIOS_ROM_MOSI")
	)
	(segment
		(start 59.549284 -57.753758)
		(end 59.30646 -57.510934)
		(width 0.08382)
		(layer "In2.Cu")
		(net "SPI_BMC_BIOS_ROM_MOSI")
	)
	(segment
		(start 65.691512 -62.8904)
		(end 60.82411 -60.874656)
		(width 0.08382)
		(layer "In2.Cu")
		(net "SPI_BMC_BIOS_ROM_MOSI")
	)
	(segment
		(start 60.82411 -60.874656)
		(end 60.468764 -60.51931)
		(width 0.08382)
		(layer "In2.Cu")
		(net "SPI_BMC_BIOS_ROM_MOSI")
	)
	(segment
		(start 59.30646 -57.254648)
		(end 59.046618 -56.994806)
		(width 0.08382)
		(layer "In2.Cu")
		(net "SPI_BMC_BIOS_ROM_MOSI")
	)
	(segment
		(start 58.775092 -56.994806)
		(end 58.353198 -56.820054)
		(width 0.08382)
		(layer "In2.Cu")
		(net "SPI_BMC_BIOS_ROM_MOSI")
	)
	(segment
		(start 58.49493 -57.771284)
		(end 58.890154 -58.166508)
		(width 0.11684)
		(layer "F.Cu")
		(net "SPI_BMC_BIOS_ROM_MISO")
	)
	(via
		(at 58.890154 -58.166508)
		(size 0.4572)
		(drill 0.254)
		(layers "F.Cu" "B.Cu")
		(net "SPI_BMC_BIOS_ROM_MISO")
	)
	(segment
		(start 59.3344 -58.610754)
		(end 58.890154 -58.166508)
		(width 0.11684)
		(layer "B.Cu")
		(net "SPI_BMC_BIOS_ROM_MISO")
	)
	(segment
		(start 59.214004 -63.436754)
		(end 59.214004 -59.417966)
		(width 0.11684)
		(layer "B.Cu")
		(net "SPI_BMC_BIOS_ROM_MISO")
	)
	(segment
		(start 59.214004 -59.417966)
		(end 59.3344 -59.29757)
		(width 0.11684)
		(layer "B.Cu")
		(net "SPI_BMC_BIOS_ROM_MISO")
	)
	(segment
		(start 59.3344 -59.29757)
		(end 59.3344 -58.610754)
		(width 0.11684)
		(layer "B.Cu")
		(net "SPI_BMC_BIOS_ROM_MISO")
	)
	(segment
		(start 59.7154 -63.93815)
		(end 59.214004 -63.436754)
		(width 0.11684)
		(layer "B.Cu")
		(net "SPI_BMC_BIOS_ROM_MISO")
	)
	(segment
		(start 60.976256 -63.65875)
		(end 61.552328 -63.082678)
		(width 0.11684)
		(layer "F.Cu")
		(net "SPI_BMC_BIOS_ROM_CLK")
	)
	(segment
		(start 61.2394 -62.35954)
		(end 60.861702 -62.35954)
		(width 0.11684)
		(layer "F.Cu")
		(net "SPI_BMC_BIOS_ROM_CLK")
	)
	(segment
		(start 60.861702 -62.35954)
		(end 59.29503 -60.792868)
		(width 0.11684)
		(layer "F.Cu")
		(net "SPI_BMC_BIOS_ROM_CLK")
	)
	(segment
		(start 61.552328 -62.672468)
		(end 61.2394 -62.35954)
		(width 0.11684)
		(layer "F.Cu")
		(net "SPI_BMC_BIOS_ROM_CLK")
	)
	(segment
		(start 59.29503 -60.792868)
		(end 59.29503 -59.37123)
		(width 0.11684)
		(layer "F.Cu")
		(net "SPI_BMC_BIOS_ROM_CLK")
	)
	(segment
		(start 60.7314 -63.65875)
		(end 60.976256 -63.65875)
		(width 0.11684)
		(layer "F.Cu")
		(net "SPI_BMC_BIOS_ROM_CLK")
	)
	(segment
		(start 61.552328 -63.082678)
		(end 61.552328 -62.672468)
		(width 0.11684)
		(layer "F.Cu")
		(net "SPI_BMC_BIOS_ROM_CLK")
	)
	(via
		(at 61.2394 -62.35954)
		(size 0.762)
		(drill 0.381)
		(layers "F.Cu" "B.Cu")
		(net "SPI_BMC_BIOS_ROM_CLK")
	)
	(segment
		(start 25.781 -65.51295)
		(end 24.765 -65.51295)
		(width 0.11684)
		(layer "F.Cu")
		(net "SPA_SOUT_SW_BUF")
	)
	(segment
		(start 24.718264 -63.65621)
		(end 24.718264 -65.458086)
		(width 0.11684)
		(layer "F.Cu")
		(net "SPA_SOUT_SW_BUF")
	)
	(segment
		(start 24.718264 -65.458086)
		(end 24.7142 -65.46215)
		(width 0.11684)
		(layer "F.Cu")
		(net "SPA_SOUT_SW_BUF")
	)
	(segment
		(start 24.765 -65.51295)
		(end 24.7142 -65.46215)
		(width 0.11684)
		(layer "F.Cu")
		(net "SPA_SOUT_SW_BUF")
	)
	(segment
		(start 55.295038 -40.971216)
		(end 55.690262 -40.575992)
		(width 0.11684)
		(layer "F.Cu")
		(net "UART_BMC_1_TXD")
	)
	(via
		(at 55.690262 -40.575992)
		(size 0.4572)
		(drill 0.254)
		(layers "F.Cu" "B.Cu")
		(net "UART_BMC_1_TXD")
	)
	(via
		(at 56.643778 -39.107618)
		(size 0.6604)
		(drill 0.3302)
		(layers "F.Cu" "B.Cu")
		(net "UART_BMC_1_TXD")
	)
	(segment
		(start 56.975248 -38.604698)
		(end 58.520584 -37.059362)
		(width 0.11684)
		(layer "B.Cu")
		(net "UART_BMC_1_TXD")
	)
	(segment
		(start 60.643262 -32.510984)
		(end 61.876686 -31.27756)
		(width 0.11684)
		(layer "B.Cu")
		(net "UART_BMC_1_TXD")
	)
	(segment
		(start 56.642 -39.107618)
		(end 56.642 -39.114984)
		(width 0.11684)
		(layer "B.Cu")
		(net "UART_BMC_1_TXD")
	)
	(segment
		(start 56.870854 -38.856666)
		(end 56.975248 -38.604698)
		(width 0.11684)
		(layer "B.Cu")
		(net "UART_BMC_1_TXD")
	)
	(segment
		(start 56.642 -39.114984)
		(end 56.566562 -39.114984)
		(width 0.11684)
		(layer "B.Cu")
		(net "UART_BMC_1_TXD")
	)
	(segment
		(start 59.64936 -36.591494)
		(end 60.643262 -35.597592)
		(width 0.11684)
		(layer "B.Cu")
		(net "UART_BMC_1_TXD")
	)
	(segment
		(start 56.642 -39.08552)
		(end 56.870854 -38.856666)
		(width 0.11684)
		(layer "B.Cu")
		(net "UART_BMC_1_TXD")
	)
	(segment
		(start 56.090566 -40.175688)
		(end 55.690262 -40.575992)
		(width 0.11684)
		(layer "B.Cu")
		(net "UART_BMC_1_TXD")
	)
	(segment
		(start 56.642 -39.107618)
		(end 56.642 -39.08552)
		(width 0.11684)
		(layer "B.Cu")
		(net "UART_BMC_1_TXD")
	)
	(segment
		(start 58.520584 -37.059362)
		(end 59.64936 -36.591494)
		(width 0.11684)
		(layer "B.Cu")
		(net "UART_BMC_1_TXD")
	)
	(segment
		(start 56.643778 -39.107618)
		(end 56.642 -39.107618)
		(width 0.11684)
		(layer "B.Cu")
		(net "UART_BMC_1_TXD")
	)
	(segment
		(start 56.090566 -39.59098)
		(end 56.090566 -40.175688)
		(width 0.11684)
		(layer "B.Cu")
		(net "UART_BMC_1_TXD")
	)
	(segment
		(start 56.566562 -39.114984)
		(end 56.090566 -39.59098)
		(width 0.11684)
		(layer "B.Cu")
		(net "UART_BMC_1_TXD")
	)
	(segment
		(start 60.643262 -35.597592)
		(end 60.643262 -32.510984)
		(width 0.11684)
		(layer "B.Cu")
		(net "UART_BMC_1_TXD")
	)
	(segment
		(start 25.07488 -60.19292)
		(end 25.218136 -60.336176)
		(width 0.11684)
		(layer "F.Cu")
		(net "UART_BMC_1_TXD_R")
	)
	(segment
		(start 25.218136 -60.336176)
		(end 25.218136 -60.95619)
		(width 0.11684)
		(layer "F.Cu")
		(net "UART_BMC_1_TXD_R")
	)
	(via
		(at 44.8437 -31.80334)
		(size 0.508)
		(drill 0.254)
		(layers "F.Cu" "B.Cu")
		(net "UART_BMC_1_TXD_R")
	)
	(via
		(at 62.30874 -28.93314)
		(size 0.508)
		(drill 0.254)
		(layers "F.Cu" "B.Cu")
		(net "UART_BMC_1_TXD_R")
	)
	(via
		(at 25.07488 -60.19292)
		(size 0.508)
		(drill 0.254)
		(layers "F.Cu" "B.Cu")
		(net "UART_BMC_1_TXD_R")
	)
	(segment
		(start 62.1792 -29.06268)
		(end 62.1792 -30.174946)
		(width 0.11684)
		(layer "B.Cu")
		(net "UART_BMC_1_TXD_R")
	)
	(segment
		(start 62.1792 -30.174946)
		(end 61.876686 -30.47746)
		(width 0.11684)
		(layer "B.Cu")
		(net "UART_BMC_1_TXD_R")
	)
	(segment
		(start 62.30874 -28.93314)
		(end 62.1792 -29.06268)
		(width 0.11684)
		(layer "B.Cu")
		(net "UART_BMC_1_TXD_R")
	)
	(segment
		(start 48.0568 -32.63646)
		(end 48.0568 -33.18256)
		(width 0.08382)
		(layer "In2.Cu")
		(net "UART_BMC_1_TXD_R")
	)
	(segment
		(start 53.395118 -26.220674)
		(end 59.32805 -26.220674)
		(width 0.08382)
		(layer "In2.Cu")
		(net "UART_BMC_1_TXD_R")
	)
	(segment
		(start 52.43449 -30.38729)
		(end 52.43449 -27.181302)
		(width 0.08382)
		(layer "In2.Cu")
		(net "UART_BMC_1_TXD_R")
	)
	(segment
		(start 54.65318 -32.2326)
		(end 54.1655 -31.74492)
		(width 0.08382)
		(layer "In2.Cu")
		(net "UART_BMC_1_TXD_R")
	)
	(segment
		(start 48.0568 -33.18256)
		(end 49.39284 -34.5186)
		(width 0.08382)
		(layer "In2.Cu")
		(net "UART_BMC_1_TXD_R")
	)
	(segment
		(start 44.8437 -31.80334)
		(end 46.37278 -31.80334)
		(width 0.08382)
		(layer "In2.Cu")
		(net "UART_BMC_1_TXD_R")
	)
	(segment
		(start 54.27472 -34.5186)
		(end 54.65318 -34.14014)
		(width 0.08382)
		(layer "In2.Cu")
		(net "UART_BMC_1_TXD_R")
	)
	(segment
		(start 60.775342 -26.053542)
		(end 62.30874 -27.58694)
		(width 0.08382)
		(layer "In2.Cu")
		(net "UART_BMC_1_TXD_R")
	)
	(segment
		(start 54.65318 -34.14014)
		(end 54.65318 -32.2326)
		(width 0.08382)
		(layer "In2.Cu")
		(net "UART_BMC_1_TXD_R")
	)
	(segment
		(start 46.37278 -31.80334)
		(end 46.967648 -32.398208)
		(width 0.08382)
		(layer "In2.Cu")
		(net "UART_BMC_1_TXD_R")
	)
	(segment
		(start 49.39284 -34.5186)
		(end 54.27472 -34.5186)
		(width 0.08382)
		(layer "In2.Cu")
		(net "UART_BMC_1_TXD_R")
	)
	(segment
		(start 53.79212 -31.74492)
		(end 52.43449 -30.38729)
		(width 0.08382)
		(layer "In2.Cu")
		(net "UART_BMC_1_TXD_R")
	)
	(segment
		(start 47.818548 -32.398208)
		(end 48.0568 -32.63646)
		(width 0.08382)
		(layer "In2.Cu")
		(net "UART_BMC_1_TXD_R")
	)
	(segment
		(start 54.1655 -31.74492)
		(end 53.79212 -31.74492)
		(width 0.08382)
		(layer "In2.Cu")
		(net "UART_BMC_1_TXD_R")
	)
	(segment
		(start 62.30874 -27.58694)
		(end 62.30874 -28.93314)
		(width 0.08382)
		(layer "In2.Cu")
		(net "UART_BMC_1_TXD_R")
	)
	(segment
		(start 59.32805 -26.220674)
		(end 59.495182 -26.053542)
		(width 0.08382)
		(layer "In2.Cu")
		(net "UART_BMC_1_TXD_R")
	)
	(segment
		(start 46.967648 -32.398208)
		(end 47.818548 -32.398208)
		(width 0.08382)
		(layer "In2.Cu")
		(net "UART_BMC_1_TXD_R")
	)
	(segment
		(start 59.495182 -26.053542)
		(end 60.775342 -26.053542)
		(width 0.08382)
		(layer "In2.Cu")
		(net "UART_BMC_1_TXD_R")
	)
	(segment
		(start 52.43449 -27.181302)
		(end 53.395118 -26.220674)
		(width 0.08382)
		(layer "In2.Cu")
		(net "UART_BMC_1_TXD_R")
	)
	(segment
		(start 35.2298 -37.89172)
		(end 35.2298 -40.48506)
		(width 0.10668)
		(layer "In4.Cu")
		(net "UART_BMC_1_TXD_R")
	)
	(segment
		(start 34.7091 -41.00576)
		(end 30.59176 -41.00576)
		(width 0.10668)
		(layer "In4.Cu")
		(net "UART_BMC_1_TXD_R")
	)
	(segment
		(start 22.5425 -50.621438)
		(end 22.29358 -51.223164)
		(width 0.10668)
		(layer "In4.Cu")
		(net "UART_BMC_1_TXD_R")
	)
	(segment
		(start 45.268896 -34.293556)
		(end 44.184316 -34.293556)
		(width 0.10668)
		(layer "In4.Cu")
		(net "UART_BMC_1_TXD_R")
	)
	(segment
		(start 36.34994 -37.6555)
		(end 35.46602 -37.6555)
		(width 0.10668)
		(layer "In4.Cu")
		(net "UART_BMC_1_TXD_R")
	)
	(segment
		(start 43.82262 -33.3248)
		(end 43.53306 -33.03524)
		(width 0.10668)
		(layer "In4.Cu")
		(net "UART_BMC_1_TXD_R")
	)
	(segment
		(start 36.6649 -37.34054)
		(end 36.34994 -37.6555)
		(width 0.10668)
		(layer "In4.Cu")
		(net "UART_BMC_1_TXD_R")
	)
	(segment
		(start 43.82262 -33.93186)
		(end 43.82262 -33.3248)
		(width 0.10668)
		(layer "In4.Cu")
		(net "UART_BMC_1_TXD_R")
	)
	(segment
		(start 23.309326 -44.39158)
		(end 22.5425 -46.243748)
		(width 0.10668)
		(layer "In4.Cu")
		(net "UART_BMC_1_TXD_R")
	)
	(segment
		(start 28.163266 -39.92118)
		(end 27.779726 -39.92118)
		(width 0.10668)
		(layer "In4.Cu")
		(net "UART_BMC_1_TXD_R")
	)
	(segment
		(start 36.99256 -36.0045)
		(end 36.6649 -36.33216)
		(width 0.10668)
		(layer "In4.Cu")
		(net "UART_BMC_1_TXD_R")
	)
	(segment
		(start 22.29358 -51.223164)
		(end 22.29358 -56.933592)
		(width 0.10668)
		(layer "In4.Cu")
		(net "UART_BMC_1_TXD_R")
	)
	(segment
		(start 43.53306 -33.03524)
		(end 43.03522 -33.03524)
		(width 0.10668)
		(layer "In4.Cu")
		(net "UART_BMC_1_TXD_R")
	)
	(segment
		(start 44.184316 -34.293556)
		(end 43.82262 -33.93186)
		(width 0.10668)
		(layer "In4.Cu")
		(net "UART_BMC_1_TXD_R")
	)
	(segment
		(start 35.46602 -37.6555)
		(end 35.2298 -37.89172)
		(width 0.10668)
		(layer "In4.Cu")
		(net "UART_BMC_1_TXD_R")
	)
	(segment
		(start 22.5425 -46.243748)
		(end 22.5425 -50.621438)
		(width 0.10668)
		(layer "In4.Cu")
		(net "UART_BMC_1_TXD_R")
	)
	(segment
		(start 42.81424 -33.25622)
		(end 42.81424 -33.870646)
		(width 0.10668)
		(layer "In4.Cu")
		(net "UART_BMC_1_TXD_R")
	)
	(segment
		(start 40.680386 -36.0045)
		(end 36.99256 -36.0045)
		(width 0.10668)
		(layer "In4.Cu")
		(net "UART_BMC_1_TXD_R")
	)
	(segment
		(start 30.59176 -41.00576)
		(end 29.22905 -39.64305)
		(width 0.10668)
		(layer "In4.Cu")
		(net "UART_BMC_1_TXD_R")
	)
	(segment
		(start 43.03522 -33.03524)
		(end 42.81424 -33.25622)
		(width 0.10668)
		(layer "In4.Cu")
		(net "UART_BMC_1_TXD_R")
	)
	(segment
		(start 45.09897 -31.80334)
		(end 45.7454 -32.44977)
		(width 0.10668)
		(layer "In4.Cu")
		(net "UART_BMC_1_TXD_R")
	)
	(segment
		(start 28.441396 -39.64305)
		(end 28.163266 -39.92118)
		(width 0.10668)
		(layer "In4.Cu")
		(net "UART_BMC_1_TXD_R")
	)
	(segment
		(start 42.81424 -33.870646)
		(end 40.680386 -36.0045)
		(width 0.10668)
		(layer "In4.Cu")
		(net "UART_BMC_1_TXD_R")
	)
	(segment
		(start 22.29358 -56.933592)
		(end 25.07488 -59.714892)
		(width 0.10668)
		(layer "In4.Cu")
		(net "UART_BMC_1_TXD_R")
	)
	(segment
		(start 25.07488 -59.714892)
		(end 25.07488 -60.19292)
		(width 0.10668)
		(layer "In4.Cu")
		(net "UART_BMC_1_TXD_R")
	)
	(segment
		(start 35.2298 -40.48506)
		(end 34.7091 -41.00576)
		(width 0.10668)
		(layer "In4.Cu")
		(net "UART_BMC_1_TXD_R")
	)
	(segment
		(start 36.6649 -36.33216)
		(end 36.6649 -37.34054)
		(width 0.10668)
		(layer "In4.Cu")
		(net "UART_BMC_1_TXD_R")
	)
	(segment
		(start 45.7454 -33.817052)
		(end 45.268896 -34.293556)
		(width 0.10668)
		(layer "In4.Cu")
		(net "UART_BMC_1_TXD_R")
	)
	(segment
		(start 44.8437 -31.80334)
		(end 45.09897 -31.80334)
		(width 0.10668)
		(layer "In4.Cu")
		(net "UART_BMC_1_TXD_R")
	)
	(segment
		(start 29.22905 -39.64305)
		(end 28.441396 -39.64305)
		(width 0.10668)
		(layer "In4.Cu")
		(net "UART_BMC_1_TXD_R")
	)
	(segment
		(start 45.7454 -32.44977)
		(end 45.7454 -33.817052)
		(width 0.10668)
		(layer "In4.Cu")
		(net "UART_BMC_1_TXD_R")
	)
	(segment
		(start 27.779726 -39.92118)
		(end 23.309326 -44.39158)
		(width 0.10668)
		(layer "In4.Cu")
		(net "UART_BMC_1_TXD_R")
	)
	(segment
		(start 20.21205 -65.8368)
		(end 20.21205 -65.500504)
		(width 0.11684)
		(layer "F.Cu")
		(net "SPA_SIN_SW_BUF")
	)
	(segment
		(start 19.155664 -64.782954)
		(end 19.155664 -63.68161)
		(width 0.11684)
		(layer "F.Cu")
		(net "SPA_SIN_SW_BUF")
	)
	(segment
		(start 19.899376 -65.18783)
		(end 19.56054 -65.18783)
		(width 0.11684)
		(layer "F.Cu")
		(net "SPA_SIN_SW_BUF")
	)
	(segment
		(start 20.21205 -65.500504)
		(end 19.899376 -65.18783)
		(width 0.11684)
		(layer "F.Cu")
		(net "SPA_SIN_SW_BUF")
	)
	(segment
		(start 19.56054 -65.18783)
		(end 19.155664 -64.782954)
		(width 0.11684)
		(layer "F.Cu")
		(net "SPA_SIN_SW_BUF")
	)
	(via
		(at 19.56054 -65.18783)
		(size 0.508)
		(drill 0.254)
		(layers "F.Cu" "B.Cu")
		(net "SPA_SIN_SW_BUF")
	)
	(segment
		(start 20.4724 -64.72555)
		(end 20.25015 -64.9478)
		(width 0.11684)
		(layer "B.Cu")
		(net "SPA_SIN_SW_BUF")
	)
	(segment
		(start 20.25015 -64.9478)
		(end 19.80057 -64.9478)
		(width 0.11684)
		(layer "B.Cu")
		(net "SPA_SIN_SW_BUF")
	)
	(segment
		(start 19.80057 -64.9478)
		(end 19.56054 -65.18783)
		(width 0.11684)
		(layer "B.Cu")
		(net "SPA_SIN_SW_BUF")
	)
	(via
		(at 70.66788 -25.78862)
		(size 0.6604)
		(drill 0.3302)
		(layers "F.Cu" "B.Cu")
		(net "SMB_BMC_MM16_R2_SDA")
	)
	(segment
		(start 68.208398 -26.401522)
		(end 69.02704 -25.58288)
		(width 0.11684)
		(layer "B.Cu")
		(net "SMB_BMC_MM16_R2_SDA")
	)
	(segment
		(start 69.02704 -25.58288)
		(end 70.46214 -25.58288)
		(width 0.11684)
		(layer "B.Cu")
		(net "SMB_BMC_MM16_R2_SDA")
	)
	(segment
		(start 71.319136 -25.421082)
		(end 72.082914 -26.18486)
		(width 0.11684)
		(layer "B.Cu")
		(net "SMB_BMC_MM16_R2_SDA")
	)
	(segment
		(start 72.082914 -26.18486)
		(end 72.783446 -26.18486)
		(width 0.11684)
		(layer "B.Cu")
		(net "SMB_BMC_MM16_R2_SDA")
	)
	(segment
		(start 71.035418 -25.421082)
		(end 71.319136 -25.421082)
		(width 0.11684)
		(layer "B.Cu")
		(net "SMB_BMC_MM16_R2_SDA")
	)
	(segment
		(start 70.46214 -25.58288)
		(end 70.66788 -25.78862)
		(width 0.11684)
		(layer "B.Cu")
		(net "SMB_BMC_MM16_R2_SDA")
	)
	(segment
		(start 68.208398 -26.594562)
		(end 68.208398 -26.401522)
		(width 0.11684)
		(layer "B.Cu")
		(net "SMB_BMC_MM16_R2_SDA")
	)
	(segment
		(start 70.66788 -25.78862)
		(end 71.035418 -25.421082)
		(width 0.11684)
		(layer "B.Cu")
		(net "SMB_BMC_MM16_R2_SDA")
	)
	(via
		(at 68.137024 -28.649676)
		(size 0.6604)
		(drill 0.3302)
		(layers "F.Cu" "B.Cu")
		(net "SMB_BMC_MM16_R2_SCL")
	)
	(segment
		(start 68.208398 -27.489404)
		(end 68.231766 -27.512772)
		(width 0.11684)
		(layer "B.Cu")
		(net "SMB_BMC_MM16_R2_SCL")
	)
	(segment
		(start 71.694294 -26.834846)
		(end 72.783446 -26.834846)
		(width 0.11684)
		(layer "B.Cu")
		(net "SMB_BMC_MM16_R2_SCL")
	)
	(segment
		(start 68.137024 -28.019502)
		(end 68.137024 -28.649676)
		(width 0.11684)
		(layer "B.Cu")
		(net "SMB_BMC_MM16_R2_SCL")
	)
	(segment
		(start 68.231766 -27.512772)
		(end 68.231766 -27.92476)
		(width 0.11684)
		(layer "B.Cu")
		(net "SMB_BMC_MM16_R2_SCL")
	)
	(segment
		(start 69.49567 -28.649676)
		(end 71.112126 -27.03322)
		(width 0.11684)
		(layer "B.Cu")
		(net "SMB_BMC_MM16_R2_SCL")
	)
	(segment
		(start 68.231766 -27.92476)
		(end 68.137024 -28.019502)
		(width 0.11684)
		(layer "B.Cu")
		(net "SMB_BMC_MM16_R2_SCL")
	)
	(segment
		(start 71.49592 -27.03322)
		(end 71.694294 -26.834846)
		(width 0.11684)
		(layer "B.Cu")
		(net "SMB_BMC_MM16_R2_SCL")
	)
	(segment
		(start 68.137024 -28.649676)
		(end 69.49567 -28.649676)
		(width 0.11684)
		(layer "B.Cu")
		(net "SMB_BMC_MM16_R2_SCL")
	)
	(segment
		(start 71.112126 -27.03322)
		(end 71.49592 -27.03322)
		(width 0.11684)
		(layer "B.Cu")
		(net "SMB_BMC_MM16_R2_SCL")
	)
	(segment
		(start 54.887876 -33.602676)
		(end 55.184548 -33.602676)
		(width 0.11684)
		(layer "F.Cu")
		(net "SMB_BMC_MM9_SDA")
	)
	(segment
		(start 55.184548 -33.602676)
		(end 55.184548 -34.237676)
		(width 0.11684)
		(layer "F.Cu")
		(net "SMB_BMC_MM9_SDA")
	)
	(segment
		(start 53.7718 -31.267654)
		(end 54.592728 -32.088582)
		(width 0.11684)
		(layer "F.Cu")
		(net "SMB_BMC_MM9_SDA")
	)
	(segment
		(start 53.388006 -31.267654)
		(end 53.7718 -31.267654)
		(width 0.11684)
		(layer "F.Cu")
		(net "SMB_BMC_MM9_SDA")
	)
	(segment
		(start 54.592728 -32.088582)
		(end 54.592728 -33.307528)
		(width 0.11684)
		(layer "F.Cu")
		(net "SMB_BMC_MM9_SDA")
	)
	(segment
		(start 54.592728 -33.307528)
		(end 54.887876 -33.602676)
		(width 0.11684)
		(layer "F.Cu")
		(net "SMB_BMC_MM9_SDA")
	)
	(via
		(at 55.184548 -33.602676)
		(size 0.508)
		(drill 0.254)
		(layers "F.Cu" "B.Cu")
		(net "SMB_BMC_MM9_SDA")
	)
	(via
		(at 43.70324 -110.0074)
		(size 0.6604)
		(drill 0.3302)
		(layers "F.Cu" "B.Cu")
		(net "SMB_BMC_MM9_SDA")
	)
	(via
		(at 42.63771 -108.653834)
		(size 0.508)
		(drill 0.254)
		(layers "F.Cu" "B.Cu")
		(net "SMB_BMC_MM9_SDA")
	)
	(segment
		(start 42.654982 -116.683536)
		(end 42.164 -116.192554)
		(width 0.11684)
		(layer "B.Cu")
		(net "SMB_BMC_MM9_SDA")
	)
	(segment
		(start 42.164 -116.192554)
		(end 42.164 -114.85499)
		(width 0.11684)
		(layer "B.Cu")
		(net "SMB_BMC_MM9_SDA")
	)
	(segment
		(start 42.63771 -108.653834)
		(end 42.841164 -109.145324)
		(width 0.11684)
		(layer "B.Cu")
		(net "SMB_BMC_MM9_SDA")
	)
	(segment
		(start 42.164 -114.85499)
		(end 43.702732 -111.141002)
		(width 0.11684)
		(layer "B.Cu")
		(net "SMB_BMC_MM9_SDA")
	)
	(segment
		(start 43.702732 -111.141002)
		(end 43.70324 -110.23346)
		(width 0.11684)
		(layer "B.Cu")
		(net "SMB_BMC_MM9_SDA")
	)
	(segment
		(start 42.654982 -118.25986)
		(end 42.654982 -116.683536)
		(width 0.11684)
		(layer "B.Cu")
		(net "SMB_BMC_MM9_SDA")
	)
	(segment
		(start 43.70324 -110.23346)
		(end 43.70324 -110.0074)
		(width 0.11684)
		(layer "B.Cu")
		(net "SMB_BMC_MM9_SDA")
	)
	(segment
		(start 42.841164 -109.145324)
		(end 43.70324 -110.0074)
		(width 0.11684)
		(layer "B.Cu")
		(net "SMB_BMC_MM9_SDA")
	)
	(segment
		(start 29.27096 -36.422076)
		(end 29.27096 -34.463736)
		(width 0.10668)
		(layer "In7.Cu")
		(net "SMB_BMC_MM9_SDA")
	)
	(segment
		(start 23.64994 -63.45174)
		(end 23.0378 -62.8396)
		(width 0.10668)
		(layer "In7.Cu")
		(net "SMB_BMC_MM9_SDA")
	)
	(segment
		(start 30.92704 -83.959192)
		(end 29.6672 -82.699352)
		(width 0.10668)
		(layer "In7.Cu")
		(net "SMB_BMC_MM9_SDA")
	)
	(segment
		(start 33.644586 -27.47645)
		(end 33.644586 -26.296874)
		(width 0.10668)
		(layer "In7.Cu")
		(net "SMB_BMC_MM9_SDA")
	)
	(segment
		(start 27.715464 -77.035152)
		(end 27.04846 -76.7588)
		(width 0.10668)
		(layer "In7.Cu")
		(net "SMB_BMC_MM9_SDA")
	)
	(segment
		(start 23.6347 -71.19366)
		(end 23.128478 -71.19366)
		(width 0.10668)
		(layer "In7.Cu")
		(net "SMB_BMC_MM9_SDA")
	)
	(segment
		(start 27.60472 -38.088316)
		(end 29.27096 -36.422076)
		(width 0.10668)
		(layer "In7.Cu")
		(net "SMB_BMC_MM9_SDA")
	)
	(segment
		(start 33.533334 -89.81948)
		(end 33.109662 -89.81948)
		(width 0.10668)
		(layer "In7.Cu")
		(net "SMB_BMC_MM9_SDA")
	)
	(segment
		(start 26.37282 -76.283312)
		(end 26.37282 -74.244962)
		(width 0.10668)
		(layer "In7.Cu")
		(net "SMB_BMC_MM9_SDA")
	)
	(segment
		(start 29.6672 -81.62163)
		(end 28.49626 -80.45069)
		(width 0.10668)
		(layer "In7.Cu")
		(net "SMB_BMC_MM9_SDA")
	)
	(segment
		(start 23.293578 -67.115182)
		(end 23.293578 -66.139822)
		(width 0.10668)
		(layer "In7.Cu")
		(net "SMB_BMC_MM9_SDA")
	)
	(segment
		(start 43.26128 -105.001822)
		(end 41.275 -103.015542)
		(width 0.10668)
		(layer "In7.Cu")
		(net "SMB_BMC_MM9_SDA")
	)
	(segment
		(start 23.293578 -66.139822)
		(end 23.64994 -65.78346)
		(width 0.10668)
		(layer "In7.Cu")
		(net "SMB_BMC_MM9_SDA")
	)
	(segment
		(start 51.91506 -29.25826)
		(end 55.037736 -32.380936)
		(width 0.10668)
		(layer "In7.Cu")
		(net "SMB_BMC_MM9_SDA")
	)
	(segment
		(start 29.6672 -82.699352)
		(end 29.6672 -81.62163)
		(width 0.10668)
		(layer "In7.Cu")
		(net "SMB_BMC_MM9_SDA")
	)
	(segment
		(start 26.37282 -74.244962)
		(end 25.907238 -73.77938)
		(width 0.10668)
		(layer "In7.Cu")
		(net "SMB_BMC_MM9_SDA")
	)
	(segment
		(start 22.78126 -67.6275)
		(end 23.293578 -67.115182)
		(width 0.10668)
		(layer "In7.Cu")
		(net "SMB_BMC_MM9_SDA")
	)
	(segment
		(start 38.68674 -99.906582)
		(end 34.76752 -95.987362)
		(width 0.10668)
		(layer "In7.Cu")
		(net "SMB_BMC_MM9_SDA")
	)
	(segment
		(start 30.92704 -86.067392)
		(end 30.92704 -83.959192)
		(width 0.10668)
		(layer "In7.Cu")
		(net "SMB_BMC_MM9_SDA")
	)
	(segment
		(start 43.26128 -105.00868)
		(end 43.26128 -105.001822)
		(width 0.10668)
		(layer "In7.Cu")
		(net "SMB_BMC_MM9_SDA")
	)
	(segment
		(start 32.7279 -89.437718)
		(end 32.7279 -87.08517)
		(width 0.10668)
		(layer "In7.Cu")
		(net "SMB_BMC_MM9_SDA")
	)
	(segment
		(start 33.109662 -89.81948)
		(end 32.7279 -89.437718)
		(width 0.10668)
		(layer "In7.Cu")
		(net "SMB_BMC_MM9_SDA")
	)
	(segment
		(start 31.383732 -30.507432)
		(end 32.274764 -29.6164)
		(width 0.10668)
		(layer "In7.Cu")
		(net "SMB_BMC_MM9_SDA")
	)
	(segment
		(start 22.78126 -70.846442)
		(end 22.78126 -67.6275)
		(width 0.10668)
		(layer "In7.Cu")
		(net "SMB_BMC_MM9_SDA")
	)
	(segment
		(start 23.90394 -71.4629)
		(end 23.6347 -71.19366)
		(width 0.10668)
		(layer "In7.Cu")
		(net "SMB_BMC_MM9_SDA")
	)
	(segment
		(start 43.3324 -107.959144)
		(end 43.3324 -105.0798)
		(width 0.10668)
		(layer "In7.Cu")
		(net "SMB_BMC_MM9_SDA")
	)
	(segment
		(start 34.76752 -91.053666)
		(end 33.533334 -89.81948)
		(width 0.10668)
		(layer "In7.Cu")
		(net "SMB_BMC_MM9_SDA")
	)
	(segment
		(start 26.848308 -76.7588)
		(end 26.37282 -76.283312)
		(width 0.10668)
		(layer "In7.Cu")
		(net "SMB_BMC_MM9_SDA")
	)
	(segment
		(start 37.147754 -24.9682)
		(end 44.0436 -24.9682)
		(width 0.10668)
		(layer "In7.Cu")
		(net "SMB_BMC_MM9_SDA")
	)
	(segment
		(start 20.93976 -52.223924)
		(end 21.57222 -51.591464)
		(width 0.10668)
		(layer "In7.Cu")
		(net "SMB_BMC_MM9_SDA")
	)
	(segment
		(start 43.3324 -105.0798)
		(end 43.26128 -105.00868)
		(width 0.10668)
		(layer "In7.Cu")
		(net "SMB_BMC_MM9_SDA")
	)
	(segment
		(start 36.978082 -25.137872)
		(end 37.147754 -24.9682)
		(width 0.10668)
		(layer "In7.Cu")
		(net "SMB_BMC_MM9_SDA")
	)
	(segment
		(start 28.49626 -77.815948)
		(end 27.715464 -77.035152)
		(width 0.10668)
		(layer "In7.Cu")
		(net "SMB_BMC_MM9_SDA")
	)
	(segment
		(start 41.275 -103.015542)
		(end 41.275 -101.930454)
		(width 0.10668)
		(layer "In7.Cu")
		(net "SMB_BMC_MM9_SDA")
	)
	(segment
		(start 51.22926 -29.25826)
		(end 51.91506 -29.25826)
		(width 0.10668)
		(layer "In7.Cu")
		(net "SMB_BMC_MM9_SDA")
	)
	(segment
		(start 21.57222 -45.8851)
		(end 22.40788 -43.867578)
		(width 0.10668)
		(layer "In7.Cu")
		(net "SMB_BMC_MM9_SDA")
	)
	(segment
		(start 21.57222 -51.591464)
		(end 21.57222 -45.8851)
		(width 0.10668)
		(layer "In7.Cu")
		(net "SMB_BMC_MM9_SDA")
	)
	(segment
		(start 27.04846 -76.7588)
		(end 26.848308 -76.7588)
		(width 0.10668)
		(layer "In7.Cu")
		(net "SMB_BMC_MM9_SDA")
	)
	(segment
		(start 48.0822 -24.5872)
		(end 49.0728 -25.5778)
		(width 0.10668)
		(layer "In7.Cu")
		(net "SMB_BMC_MM9_SDA")
	)
	(segment
		(start 55.037736 -32.380936)
		(end 55.375048 -32.380936)
		(width 0.10668)
		(layer "In7.Cu")
		(net "SMB_BMC_MM9_SDA")
	)
	(segment
		(start 28.49626 -80.45069)
		(end 28.49626 -77.815948)
		(width 0.10668)
		(layer "In7.Cu")
		(net "SMB_BMC_MM9_SDA")
	)
	(segment
		(start 23.0378 -62.8396)
		(end 23.0378 -59.207146)
		(width 0.10668)
		(layer "In7.Cu")
		(net "SMB_BMC_MM9_SDA")
	)
	(segment
		(start 23.128478 -71.19366)
		(end 22.78126 -70.846442)
		(width 0.10668)
		(layer "In7.Cu")
		(net "SMB_BMC_MM9_SDA")
	)
	(segment
		(start 44.0436 -24.9682)
		(end 44.4246 -24.5872)
		(width 0.10668)
		(layer "In7.Cu")
		(net "SMB_BMC_MM9_SDA")
	)
	(segment
		(start 23.90394 -72.310752)
		(end 23.90394 -71.4629)
		(width 0.10668)
		(layer "In7.Cu")
		(net "SMB_BMC_MM9_SDA")
	)
	(segment
		(start 34.803588 -25.137872)
		(end 36.978082 -25.137872)
		(width 0.10668)
		(layer "In7.Cu")
		(net "SMB_BMC_MM9_SDA")
	)
	(segment
		(start 34.76752 -95.987362)
		(end 34.76752 -91.053666)
		(width 0.10668)
		(layer "In7.Cu")
		(net "SMB_BMC_MM9_SDA")
	)
	(segment
		(start 33.644586 -26.296874)
		(end 34.803588 -25.137872)
		(width 0.10668)
		(layer "In7.Cu")
		(net "SMB_BMC_MM9_SDA")
	)
	(segment
		(start 31.435548 -86.5759)
		(end 30.92704 -86.067392)
		(width 0.10668)
		(layer "In7.Cu")
		(net "SMB_BMC_MM9_SDA")
	)
	(segment
		(start 29.27096 -34.463736)
		(end 29.953966 -32.814514)
		(width 0.10668)
		(layer "In7.Cu")
		(net "SMB_BMC_MM9_SDA")
	)
	(segment
		(start 27.60472 -38.670738)
		(end 27.60472 -38.088316)
		(width 0.10668)
		(layer "In7.Cu")
		(net "SMB_BMC_MM9_SDA")
	)
	(segment
		(start 49.0728 -27.1018)
		(end 51.22926 -29.25826)
		(width 0.10668)
		(layer "In7.Cu")
		(net "SMB_BMC_MM9_SDA")
	)
	(segment
		(start 31.383732 -31.658052)
		(end 31.383732 -30.507432)
		(width 0.10668)
		(layer "In7.Cu")
		(net "SMB_BMC_MM9_SDA")
	)
	(segment
		(start 30.452568 -32.589216)
		(end 31.383732 -31.658052)
		(width 0.10668)
		(layer "In7.Cu")
		(net "SMB_BMC_MM9_SDA")
	)
	(segment
		(start 49.0728 -25.5778)
		(end 49.0728 -27.1018)
		(width 0.10668)
		(layer "In7.Cu")
		(net "SMB_BMC_MM9_SDA")
	)
	(segment
		(start 23.64994 -65.78346)
		(end 23.64994 -63.45174)
		(width 0.10668)
		(layer "In7.Cu")
		(net "SMB_BMC_MM9_SDA")
	)
	(segment
		(start 20.93976 -57.109106)
		(end 20.93976 -52.223924)
		(width 0.10668)
		(layer "In7.Cu")
		(net "SMB_BMC_MM9_SDA")
	)
	(segment
		(start 29.953966 -32.814514)
		(end 30.179264 -32.589216)
		(width 0.10668)
		(layer "In7.Cu")
		(net "SMB_BMC_MM9_SDA")
	)
	(segment
		(start 25.372568 -73.77938)
		(end 23.90394 -72.310752)
		(width 0.10668)
		(layer "In7.Cu")
		(net "SMB_BMC_MM9_SDA")
	)
	(segment
		(start 22.40788 -43.867578)
		(end 27.60472 -38.670738)
		(width 0.10668)
		(layer "In7.Cu")
		(net "SMB_BMC_MM9_SDA")
	)
	(segment
		(start 32.7279 -87.08517)
		(end 32.21863 -86.5759)
		(width 0.10668)
		(layer "In7.Cu")
		(net "SMB_BMC_MM9_SDA")
	)
	(segment
		(start 55.644288 -33.142936)
		(end 55.184548 -33.602676)
		(width 0.10668)
		(layer "In7.Cu")
		(net "SMB_BMC_MM9_SDA")
	)
	(segment
		(start 41.275 -101.930454)
		(end 39.251128 -99.906582)
		(width 0.10668)
		(layer "In7.Cu")
		(net "SMB_BMC_MM9_SDA")
	)
	(segment
		(start 32.21863 -86.5759)
		(end 31.435548 -86.5759)
		(width 0.10668)
		(layer "In7.Cu")
		(net "SMB_BMC_MM9_SDA")
	)
	(segment
		(start 25.907238 -73.77938)
		(end 25.372568 -73.77938)
		(width 0.10668)
		(layer "In7.Cu")
		(net "SMB_BMC_MM9_SDA")
	)
	(segment
		(start 30.179264 -32.589216)
		(end 30.452568 -32.589216)
		(width 0.10668)
		(layer "In7.Cu")
		(net "SMB_BMC_MM9_SDA")
	)
	(segment
		(start 55.375048 -32.380936)
		(end 55.644288 -32.650176)
		(width 0.10668)
		(layer "In7.Cu")
		(net "SMB_BMC_MM9_SDA")
	)
	(segment
		(start 32.274764 -28.846272)
		(end 33.644586 -27.47645)
		(width 0.10668)
		(layer "In7.Cu")
		(net "SMB_BMC_MM9_SDA")
	)
	(segment
		(start 42.63771 -108.653834)
		(end 43.3324 -107.959144)
		(width 0.10668)
		(layer "In7.Cu")
		(net "SMB_BMC_MM9_SDA")
	)
	(segment
		(start 23.0378 -59.207146)
		(end 20.93976 -57.109106)
		(width 0.10668)
		(layer "In7.Cu")
		(net "SMB_BMC_MM9_SDA")
	)
	(segment
		(start 55.644288 -32.650176)
		(end 55.644288 -33.142936)
		(width 0.10668)
		(layer "In7.Cu")
		(net "SMB_BMC_MM9_SDA")
	)
	(segment
		(start 39.251128 -99.906582)
		(end 38.68674 -99.906582)
		(width 0.10668)
		(layer "In7.Cu")
		(net "SMB_BMC_MM9_SDA")
	)
	(segment
		(start 32.274764 -29.6164)
		(end 32.274764 -28.846272)
		(width 0.10668)
		(layer "In7.Cu")
		(net "SMB_BMC_MM9_SDA")
	)
	(segment
		(start 44.4246 -24.5872)
		(end 48.0822 -24.5872)
		(width 0.10668)
		(layer "In7.Cu")
		(net "SMB_BMC_MM9_SDA")
	)
	(via
		(at 44.40682 -108.673392)
		(size 0.6604)
		(drill 0.3302)
		(layers "F.Cu" "B.Cu")
		(net "SMB_BMC_MM9_SCL")
	)
	(via
		(at 43.82262 -106.9213)
		(size 0.508)
		(drill 0.254)
		(layers "F.Cu" "B.Cu")
		(net "SMB_BMC_MM9_SCL")
	)
	(via
		(at 54.040278 -32.274256)
		(size 0.508)
		(drill 0.254)
		(layers "F.Cu" "B.Cu")
		(net "SMB_BMC_MM9_SCL")
	)
	(segment
		(start 54.553612 -32.78759)
		(end 54.553612 -33.78708)
		(width 0.11684)
		(layer "B.Cu")
		(net "SMB_BMC_MM9_SCL")
	)
	(segment
		(start 43.25493 -114.857784)
		(end 43.25493 -118.460012)
		(width 0.11684)
		(layer "B.Cu")
		(net "SMB_BMC_MM9_SCL")
	)
	(segment
		(start 43.053 -114.655854)
		(end 43.25493 -114.857784)
		(width 0.11684)
		(layer "B.Cu")
		(net "SMB_BMC_MM9_SCL")
	)
	(segment
		(start 44.40682 -110.509558)
		(end 43.053 -113.77803)
		(width 0.11684)
		(layer "B.Cu")
		(net "SMB_BMC_MM9_SCL")
	)
	(segment
		(start 44.40682 -107.5055)
		(end 44.40682 -108.673392)
		(width 0.11684)
		(layer "B.Cu")
		(net "SMB_BMC_MM9_SCL")
	)
	(segment
		(start 54.040278 -31.618428)
		(end 54.040278 -32.274256)
		(width 0.11684)
		(layer "B.Cu")
		(net "SMB_BMC_MM9_SCL")
	)
	(segment
		(start 53.68798 -31.26613)
		(end 54.040278 -31.618428)
		(width 0.11684)
		(layer "B.Cu")
		(net "SMB_BMC_MM9_SCL")
	)
	(segment
		(start 43.82262 -106.9213)
		(end 44.40682 -107.5055)
		(width 0.11684)
		(layer "B.Cu")
		(net "SMB_BMC_MM9_SCL")
	)
	(segment
		(start 54.483 -33.857692)
		(end 54.483 -34.27095)
		(width 0.11684)
		(layer "B.Cu")
		(net "SMB_BMC_MM9_SCL")
	)
	(segment
		(start 54.553612 -33.78708)
		(end 54.483 -33.857692)
		(width 0.11684)
		(layer "B.Cu")
		(net "SMB_BMC_MM9_SCL")
	)
	(segment
		(start 54.040278 -32.274256)
		(end 54.553612 -32.78759)
		(width 0.11684)
		(layer "B.Cu")
		(net "SMB_BMC_MM9_SCL")
	)
	(segment
		(start 43.053 -113.77803)
		(end 43.053 -114.655854)
		(width 0.11684)
		(layer "B.Cu")
		(net "SMB_BMC_MM9_SCL")
	)
	(segment
		(start 44.40682 -108.673392)
		(end 44.40682 -110.509558)
		(width 0.11684)
		(layer "B.Cu")
		(net "SMB_BMC_MM9_SCL")
	)
	(segment
		(start 37.27704 -25.842214)
		(end 35.111182 -25.842214)
		(width 0.10668)
		(layer "In7.Cu")
		(net "SMB_BMC_MM9_SCL")
	)
	(segment
		(start 39.963598 -99.571302)
		(end 40.507412 -99.027488)
		(width 0.10668)
		(layer "In7.Cu")
		(net "SMB_BMC_MM9_SCL")
	)
	(segment
		(start 38.848538 -99.571302)
		(end 39.963598 -99.571302)
		(width 0.10668)
		(layer "In7.Cu")
		(net "SMB_BMC_MM9_SCL")
	)
	(segment
		(start 50.2666 -30.0736)
		(end 50.2666 -28.854146)
		(width 0.10668)
		(layer "In7.Cu")
		(net "SMB_BMC_MM9_SCL")
	)
	(segment
		(start 24.57958 -63.717678)
		(end 24.57958 -66.336418)
		(width 0.10668)
		(layer "In7.Cu")
		(net "SMB_BMC_MM9_SCL")
	)
	(segment
		(start 40.709088 -99.027488)
		(end 40.852344 -99.170744)
		(width 0.10668)
		(layer "In7.Cu")
		(net "SMB_BMC_MM9_SCL")
	)
	(segment
		(start 40.507412 -99.027488)
		(end 40.709088 -99.027488)
		(width 0.10668)
		(layer "In7.Cu")
		(net "SMB_BMC_MM9_SCL")
	)
	(segment
		(start 43.07332 -26.96972)
		(end 41.74236 -25.63876)
		(width 0.10668)
		(layer "In7.Cu")
		(net "SMB_BMC_MM9_SCL")
	)
	(segment
		(start 42.232072 -100.550472)
		(end 42.232072 -100.752148)
		(width 0.10668)
		(layer "In7.Cu")
		(net "SMB_BMC_MM9_SCL")
	)
	(segment
		(start 34.413444 -85.725)
		(end 35.860482 -87.172038)
		(width 0.10668)
		(layer "In7.Cu")
		(net "SMB_BMC_MM9_SCL")
	)
	(segment
		(start 35.111182 -25.842214)
		(end 34.315146 -26.63825)
		(width 0.10668)
		(layer "In7.Cu")
		(net "SMB_BMC_MM9_SCL")
	)
	(segment
		(start 28.459176 -73.645268)
		(end 28.70454 -73.890632)
		(width 0.10668)
		(layer "In7.Cu")
		(net "SMB_BMC_MM9_SCL")
	)
	(segment
		(start 33.37814 -85.048852)
		(end 34.054288 -85.725)
		(width 0.10668)
		(layer "In7.Cu")
		(net "SMB_BMC_MM9_SCL")
	)
	(segment
		(start 25.07488 -62.243462)
		(end 25.07488 -63.222378)
		(width 0.10668)
		(layer "In7.Cu")
		(net "SMB_BMC_MM9_SCL")
	)
	(segment
		(start 48.382174 -26.96972)
		(end 43.07332 -26.96972)
		(width 0.10668)
		(layer "In7.Cu")
		(net "SMB_BMC_MM9_SCL")
	)
	(segment
		(start 40.852344 -99.37242)
		(end 40.30853 -99.916234)
		(width 0.10668)
		(layer "In7.Cu")
		(net "SMB_BMC_MM9_SCL")
	)
	(segment
		(start 31.1912 -37.378386)
		(end 31.070042 -37.67074)
		(width 0.10668)
		(layer "In7.Cu")
		(net "SMB_BMC_MM9_SCL")
	)
	(segment
		(start 27.088084 -73.645268)
		(end 28.459176 -73.645268)
		(width 0.10668)
		(layer "In7.Cu")
		(net "SMB_BMC_MM9_SCL")
	)
	(segment
		(start 42.088816 -100.407216)
		(end 42.232072 -100.550472)
		(width 0.10668)
		(layer "In7.Cu")
		(net "SMB_BMC_MM9_SCL")
	)
	(segment
		(start 42.232072 -100.752148)
		(end 41.688258 -101.295962)
		(width 0.10668)
		(layer "In7.Cu")
		(net "SMB_BMC_MM9_SCL")
	)
	(segment
		(start 52.578 -30.555946)
		(end 50.748946 -30.555946)
		(width 0.10668)
		(layer "In7.Cu")
		(net "SMB_BMC_MM9_SCL")
	)
	(segment
		(start 28.70454 -73.890632)
		(end 28.70454 -76.234544)
		(width 0.10668)
		(layer "In7.Cu")
		(net "SMB_BMC_MM9_SCL")
	)
	(segment
		(start 28.70454 -76.234544)
		(end 29.7688 -77.298804)
		(width 0.10668)
		(layer "In7.Cu")
		(net "SMB_BMC_MM9_SCL")
	)
	(segment
		(start 30.45968 -78.996794)
		(end 30.45968 -80.11668)
		(width 0.10668)
		(layer "In7.Cu")
		(net "SMB_BMC_MM9_SCL")
	)
	(segment
		(start 39.406576 -90.086942)
		(end 39.406576 -94.070424)
		(width 0.10668)
		(layer "In7.Cu")
		(net "SMB_BMC_MM9_SCL")
	)
	(segment
		(start 40.30853 -99.916234)
		(end 40.30853 -100.11791)
		(width 0.10668)
		(layer "In7.Cu")
		(net "SMB_BMC_MM9_SCL")
	)
	(segment
		(start 43.82262 -103.632)
		(end 43.82262 -106.9213)
		(width 0.10668)
		(layer "In7.Cu")
		(net "SMB_BMC_MM9_SCL")
	)
	(segment
		(start 37.338 -98.060764)
		(end 38.848538 -99.571302)
		(width 0.10668)
		(layer "In7.Cu")
		(net "SMB_BMC_MM9_SCL")
	)
	(segment
		(start 29.7688 -78.16596)
		(end 30.36062 -78.75778)
		(width 0.10668)
		(layer "In7.Cu")
		(net "SMB_BMC_MM9_SCL")
	)
	(segment
		(start 37.338 -96.139)
		(end 37.338 -98.060764)
		(width 0.10668)
		(layer "In7.Cu")
		(net "SMB_BMC_MM9_SCL")
	)
	(segment
		(start 31.070042 -37.67074)
		(end 29.604462 -39.13632)
		(width 0.10668)
		(layer "In7.Cu")
		(net "SMB_BMC_MM9_SCL")
	)
	(segment
		(start 32.4612 -82.1182)
		(end 32.4612 -83.704176)
		(width 0.10668)
		(layer "In7.Cu")
		(net "SMB_BMC_MM9_SCL")
	)
	(segment
		(start 25.619202 -72.025256)
		(end 25.72639 -72.283574)
		(width 0.10668)
		(layer "In7.Cu")
		(net "SMB_BMC_MM9_SCL")
	)
	(segment
		(start 36.491672 -87.172038)
		(end 39.406576 -90.086942)
		(width 0.10668)
		(layer "In7.Cu")
		(net "SMB_BMC_MM9_SCL")
	)
	(segment
		(start 37.480494 -25.63876)
		(end 37.27704 -25.842214)
		(width 0.10668)
		(layer "In7.Cu")
		(net "SMB_BMC_MM9_SCL")
	)
	(segment
		(start 41.516808 -99.911408)
		(end 41.516808 -100.087684)
		(width 0.10668)
		(layer "In7.Cu")
		(net "SMB_BMC_MM9_SCL")
	)
	(segment
		(start 41.343326 -100.95103)
		(end 41.88714 -100.407216)
		(width 0.10668)
		(layer "In7.Cu")
		(net "SMB_BMC_MM9_SCL")
	)
	(segment
		(start 32.054292 -30.785308)
		(end 32.054292 -31.935928)
		(width 0.10668)
		(layer "In7.Cu")
		(net "SMB_BMC_MM9_SCL")
	)
	(segment
		(start 24.01062 -61.179202)
		(end 25.07488 -62.243462)
		(width 0.10668)
		(layer "In7.Cu")
		(net "SMB_BMC_MM9_SCL")
	)
	(segment
		(start 39.406576 -94.070424)
		(end 37.338 -96.139)
		(width 0.10668)
		(layer "In7.Cu")
		(net "SMB_BMC_MM9_SCL")
	)
	(segment
		(start 23.195788 -44.39539)
		(end 22.50186 -46.070774)
		(width 0.10668)
		(layer "In7.Cu")
		(net "SMB_BMC_MM9_SCL")
	)
	(segment
		(start 41.74236 -25.63876)
		(end 37.480494 -25.63876)
		(width 0.10668)
		(layer "In7.Cu")
		(net "SMB_BMC_MM9_SCL")
	)
	(segment
		(start 41.146476 -99.768152)
		(end 41.373552 -99.768152)
		(width 0.10668)
		(layer "In7.Cu")
		(net "SMB_BMC_MM9_SCL")
	)
	(segment
		(start 34.315146 -28.821634)
		(end 33.006792 -30.129988)
		(width 0.10668)
		(layer "In7.Cu")
		(net "SMB_BMC_MM9_SCL")
	)
	(segment
		(start 22.50186 -46.070774)
		(end 22.50186 -52.064158)
		(width 0.10668)
		(layer "In7.Cu")
		(net "SMB_BMC_MM9_SCL")
	)
	(segment
		(start 41.373552 -99.768152)
		(end 41.516808 -99.911408)
		(width 0.10668)
		(layer "In7.Cu")
		(net "SMB_BMC_MM9_SCL")
	)
	(segment
		(start 24.223218 -66.69278)
		(end 24.223218 -67.07378)
		(width 0.10668)
		(layer "In7.Cu")
		(net "SMB_BMC_MM9_SCL")
	)
	(segment
		(start 40.998394 -100.807774)
		(end 41.14165 -100.95103)
		(width 0.10668)
		(layer "In7.Cu")
		(net "SMB_BMC_MM9_SCL")
	)
	(segment
		(start 25.72639 -72.283574)
		(end 27.088084 -73.645268)
		(width 0.10668)
		(layer "In7.Cu")
		(net "SMB_BMC_MM9_SCL")
	)
	(segment
		(start 50.2666 -28.854146)
		(end 48.382174 -26.96972)
		(width 0.10668)
		(layer "In7.Cu")
		(net "SMB_BMC_MM9_SCL")
	)
	(segment
		(start 33.37814 -84.621116)
		(end 33.37814 -85.048852)
		(width 0.10668)
		(layer "In7.Cu")
		(net "SMB_BMC_MM9_SCL")
	)
	(segment
		(start 34.315146 -26.63825)
		(end 34.315146 -28.821634)
		(width 0.10668)
		(layer "In7.Cu")
		(net "SMB_BMC_MM9_SCL")
	)
	(segment
		(start 41.688258 -101.497638)
		(end 43.82262 -103.632)
		(width 0.10668)
		(layer "In7.Cu")
		(net "SMB_BMC_MM9_SCL")
	)
	(segment
		(start 40.451786 -100.261166)
		(end 40.653462 -100.261166)
		(width 0.10668)
		(layer "In7.Cu")
		(net "SMB_BMC_MM9_SCL")
	)
	(segment
		(start 54.040278 -32.274256)
		(end 54.040278 -32.018224)
		(width 0.10668)
		(layer "In7.Cu")
		(net "SMB_BMC_MM9_SCL")
	)
	(segment
		(start 24.82088 -70.978522)
		(end 25.442926 -71.600568)
		(width 0.10668)
		(layer "In7.Cu")
		(net "SMB_BMC_MM9_SCL")
	)
	(segment
		(start 24.57958 -66.336418)
		(end 24.223218 -66.69278)
		(width 0.10668)
		(layer "In7.Cu")
		(net "SMB_BMC_MM9_SCL")
	)
	(segment
		(start 32.709612 -30.129988)
		(end 32.054292 -30.785308)
		(width 0.10668)
		(layer "In7.Cu")
		(net "SMB_BMC_MM9_SCL")
	)
	(segment
		(start 24.01062 -58.85942)
		(end 24.01062 -61.179202)
		(width 0.10668)
		(layer "In7.Cu")
		(net "SMB_BMC_MM9_SCL")
	)
	(segment
		(start 40.653462 -100.261166)
		(end 41.146476 -99.768152)
		(width 0.10668)
		(layer "In7.Cu")
		(net "SMB_BMC_MM9_SCL")
	)
	(segment
		(start 21.8694 -52.696618)
		(end 21.8694 -56.7182)
		(width 0.10668)
		(layer "In7.Cu")
		(net "SMB_BMC_MM9_SCL")
	)
	(segment
		(start 24.82088 -67.671442)
		(end 24.82088 -70.978522)
		(width 0.10668)
		(layer "In7.Cu")
		(net "SMB_BMC_MM9_SCL")
	)
	(segment
		(start 40.30853 -100.11791)
		(end 40.451786 -100.261166)
		(width 0.10668)
		(layer "In7.Cu")
		(net "SMB_BMC_MM9_SCL")
	)
	(segment
		(start 33.006792 -30.129988)
		(end 32.709612 -30.129988)
		(width 0.10668)
		(layer "In7.Cu")
		(net "SMB_BMC_MM9_SCL")
	)
	(segment
		(start 34.054288 -85.725)
		(end 34.413444 -85.725)
		(width 0.10668)
		(layer "In7.Cu")
		(net "SMB_BMC_MM9_SCL")
	)
	(segment
		(start 40.852344 -99.170744)
		(end 40.852344 -99.37242)
		(width 0.10668)
		(layer "In7.Cu")
		(net "SMB_BMC_MM9_SCL")
	)
	(segment
		(start 21.8694 -56.7182)
		(end 24.01062 -58.85942)
		(width 0.10668)
		(layer "In7.Cu")
		(net "SMB_BMC_MM9_SCL")
	)
	(segment
		(start 32.054292 -31.935928)
		(end 31.1912 -32.79902)
		(width 0.10668)
		(layer "In7.Cu")
		(net "SMB_BMC_MM9_SCL")
	)
	(segment
		(start 30.45968 -80.11668)
		(end 32.4612 -82.1182)
		(width 0.10668)
		(layer "In7.Cu")
		(net "SMB_BMC_MM9_SCL")
	)
	(segment
		(start 54.040278 -32.018224)
		(end 52.578 -30.555946)
		(width 0.10668)
		(layer "In7.Cu")
		(net "SMB_BMC_MM9_SCL")
	)
	(segment
		(start 29.604462 -39.13632)
		(end 28.454858 -39.13632)
		(width 0.10668)
		(layer "In7.Cu")
		(net "SMB_BMC_MM9_SCL")
	)
	(segment
		(start 40.998394 -100.606098)
		(end 40.998394 -100.807774)
		(width 0.10668)
		(layer "In7.Cu")
		(net "SMB_BMC_MM9_SCL")
	)
	(segment
		(start 31.1912 -32.79902)
		(end 31.1912 -37.378386)
		(width 0.10668)
		(layer "In7.Cu")
		(net "SMB_BMC_MM9_SCL")
	)
	(segment
		(start 32.4612 -83.704176)
		(end 33.37814 -84.621116)
		(width 0.10668)
		(layer "In7.Cu")
		(net "SMB_BMC_MM9_SCL")
	)
	(segment
		(start 41.516808 -100.087684)
		(end 40.998394 -100.606098)
		(width 0.10668)
		(layer "In7.Cu")
		(net "SMB_BMC_MM9_SCL")
	)
	(segment
		(start 41.688258 -101.295962)
		(end 41.688258 -101.497638)
		(width 0.10668)
		(layer "In7.Cu")
		(net "SMB_BMC_MM9_SCL")
	)
	(segment
		(start 30.36062 -78.75778)
		(end 30.45968 -78.996794)
		(width 0.10668)
		(layer "In7.Cu")
		(net "SMB_BMC_MM9_SCL")
	)
	(segment
		(start 25.442926 -71.600568)
		(end 25.619202 -72.025256)
		(width 0.10668)
		(layer "In7.Cu")
		(net "SMB_BMC_MM9_SCL")
	)
	(segment
		(start 25.07488 -63.222378)
		(end 24.57958 -63.717678)
		(width 0.10668)
		(layer "In7.Cu")
		(net "SMB_BMC_MM9_SCL")
	)
	(segment
		(start 50.748946 -30.555946)
		(end 50.2666 -30.0736)
		(width 0.10668)
		(layer "In7.Cu")
		(net "SMB_BMC_MM9_SCL")
	)
	(segment
		(start 41.88714 -100.407216)
		(end 42.088816 -100.407216)
		(width 0.10668)
		(layer "In7.Cu")
		(net "SMB_BMC_MM9_SCL")
	)
	(segment
		(start 35.860482 -87.172038)
		(end 36.491672 -87.172038)
		(width 0.10668)
		(layer "In7.Cu")
		(net "SMB_BMC_MM9_SCL")
	)
	(segment
		(start 22.50186 -52.064158)
		(end 21.8694 -52.696618)
		(width 0.10668)
		(layer "In7.Cu")
		(net "SMB_BMC_MM9_SCL")
	)
	(segment
		(start 24.223218 -67.07378)
		(end 24.82088 -67.671442)
		(width 0.10668)
		(layer "In7.Cu")
		(net "SMB_BMC_MM9_SCL")
	)
	(segment
		(start 29.7688 -77.298804)
		(end 29.7688 -78.16596)
		(width 0.10668)
		(layer "In7.Cu")
		(net "SMB_BMC_MM9_SCL")
	)
	(segment
		(start 28.454858 -39.13632)
		(end 23.195788 -44.39539)
		(width 0.10668)
		(layer "In7.Cu")
		(net "SMB_BMC_MM9_SCL")
	)
	(segment
		(start 41.14165 -100.95103)
		(end 41.343326 -100.95103)
		(width 0.10668)
		(layer "In7.Cu")
		(net "SMB_BMC_MM9_SCL")
	)
	(segment
		(start 55.184548 -35.037776)
		(end 55.8292 -35.682428)
		(width 0.11684)
		(layer "F.Cu")
		(net "SMB_BMC_MM9_R_SDA")
	)
	(segment
		(start 55.8292 -36.3855)
		(end 55.8292 -36.8554)
		(width 0.11684)
		(layer "F.Cu")
		(net "SMB_BMC_MM9_R_SDA")
	)
	(segment
		(start 54.860698 -37.823902)
		(end 54.860698 -38.535356)
		(width 0.11684)
		(layer "F.Cu")
		(net "SMB_BMC_MM9_R_SDA")
	)
	(segment
		(start 55.8292 -36.8554)
		(end 54.860698 -37.823902)
		(width 0.11684)
		(layer "F.Cu")
		(net "SMB_BMC_MM9_R_SDA")
	)
	(segment
		(start 55.8292 -35.682428)
		(end 55.8292 -36.3855)
		(width 0.11684)
		(layer "F.Cu")
		(net "SMB_BMC_MM9_R_SDA")
	)
	(segment
		(start 54.860698 -38.535356)
		(end 54.494938 -38.901116)
		(width 0.11684)
		(layer "F.Cu")
		(net "SMB_BMC_MM9_R_SDA")
	)
	(segment
		(start 54.494938 -38.901116)
		(end 54.494938 -39.37127)
		(width 0.11684)
		(layer "F.Cu")
		(net "SMB_BMC_MM9_R_SDA")
	)
	(via
		(at 55.8292 -36.3855)
		(size 0.762)
		(drill 0.381)
		(layers "F.Cu" "B.Cu")
		(net "SMB_BMC_MM9_R_SDA")
	)
	(segment
		(start 53.695092 -41.771316)
		(end 53.299868 -41.376092)
		(width 0.11684)
		(layer "F.Cu")
		(net "SMB_BMC_MM9_R_SCL")
	)
	(via
		(at 53.6702 -38.3794)
		(size 0.6604)
		(drill 0.3302)
		(layers "F.Cu" "B.Cu")
		(net "SMB_BMC_MM9_R_SCL")
	)
	(via
		(at 53.299868 -41.376092)
		(size 0.4572)
		(drill 0.254)
		(layers "F.Cu" "B.Cu")
		(net "SMB_BMC_MM9_R_SCL")
	)
	(segment
		(start 53.299868 -41.376092)
		(end 53.450744 -41.011856)
		(width 0.11684)
		(layer "B.Cu")
		(net "SMB_BMC_MM9_R_SCL")
	)
	(segment
		(start 53.6956 -40.767)
		(end 53.6956 -38.8874)
		(width 0.11684)
		(layer "B.Cu")
		(net "SMB_BMC_MM9_R_SCL")
	)
	(segment
		(start 54.513226 -37.030914)
		(end 53.81244 -37.7317)
		(width 0.11684)
		(layer "B.Cu")
		(net "SMB_BMC_MM9_R_SCL")
	)
	(segment
		(start 53.81244 -37.7317)
		(end 53.81244 -38.035992)
		(width 0.11684)
		(layer "B.Cu")
		(net "SMB_BMC_MM9_R_SCL")
	)
	(segment
		(start 53.6956 -38.8874)
		(end 53.6702 -38.826186)
		(width 0.11684)
		(layer "B.Cu")
		(net "SMB_BMC_MM9_R_SCL")
	)
	(segment
		(start 54.5846 -35.73018)
		(end 54.65572 -35.9029)
		(width 0.11684)
		(layer "B.Cu")
		(net "SMB_BMC_MM9_R_SCL")
	)
	(segment
		(start 53.6702 -38.826186)
		(end 53.6702 -38.3794)
		(width 0.11684)
		(layer "B.Cu")
		(net "SMB_BMC_MM9_R_SCL")
	)
	(segment
		(start 54.65572 -36.686998)
		(end 54.513226 -37.030914)
		(width 0.11684)
		(layer "B.Cu")
		(net "SMB_BMC_MM9_R_SCL")
	)
	(segment
		(start 54.483 -35.07105)
		(end 54.5846 -35.17265)
		(width 0.11684)
		(layer "B.Cu")
		(net "SMB_BMC_MM9_R_SCL")
	)
	(segment
		(start 53.450744 -41.011856)
		(end 53.6956 -40.767)
		(width 0.11684)
		(layer "B.Cu")
		(net "SMB_BMC_MM9_R_SCL")
	)
	(segment
		(start 53.81244 -38.035992)
		(end 53.6702 -38.3794)
		(width 0.11684)
		(layer "B.Cu")
		(net "SMB_BMC_MM9_R_SCL")
	)
	(segment
		(start 54.5846 -35.17265)
		(end 54.5846 -35.73018)
		(width 0.11684)
		(layer "B.Cu")
		(net "SMB_BMC_MM9_R_SCL")
	)
	(segment
		(start 54.65572 -35.9029)
		(end 54.65572 -36.686998)
		(width 0.11684)
		(layer "B.Cu")
		(net "SMB_BMC_MM9_R_SCL")
	)
	(via
		(at 57.222136 -32.840676)
		(size 0.508)
		(drill 0.254)
		(layers "F.Cu" "B.Cu")
		(net "SMB_BMC_MM8_SDA")
	)
	(via
		(at 57.41416 -25.70988)
		(size 0.508)
		(drill 0.254)
		(layers "F.Cu" "B.Cu")
		(net "SMB_BMC_MM8_SDA")
	)
	(via
		(at 46.99 -114.681)
		(size 0.508)
		(drill 0.254)
		(layers "F.Cu" "B.Cu")
		(net "SMB_BMC_MM8_SDA")
	)
	(segment
		(start 57.658 -34.14395)
		(end 57.531 -34.27095)
		(width 0.11684)
		(layer "B.Cu")
		(net "SMB_BMC_MM8_SDA")
	)
	(segment
		(start 47.45482 -115.06962)
		(end 47.0662 -114.681)
		(width 0.11684)
		(layer "B.Cu")
		(net "SMB_BMC_MM8_SDA")
	)
	(segment
		(start 47.0662 -114.681)
		(end 46.99 -114.681)
		(width 0.11684)
		(layer "B.Cu")
		(net "SMB_BMC_MM8_SDA")
	)
	(segment
		(start 57.658 -33.857692)
		(end 57.658 -34.14395)
		(width 0.11684)
		(layer "B.Cu")
		(net "SMB_BMC_MM8_SDA")
	)
	(segment
		(start 56.727852 -32.346392)
		(end 57.222136 -32.840676)
		(width 0.11684)
		(layer "B.Cu")
		(net "SMB_BMC_MM8_SDA")
	)
	(segment
		(start 47.265082 -118.460012)
		(end 47.265082 -116.336572)
		(width 0.11684)
		(layer "B.Cu")
		(net "SMB_BMC_MM8_SDA")
	)
	(segment
		(start 56.727852 -31.267654)
		(end 56.727852 -32.346392)
		(width 0.11684)
		(layer "B.Cu")
		(net "SMB_BMC_MM8_SDA")
	)
	(segment
		(start 47.265082 -116.336572)
		(end 47.45482 -116.146834)
		(width 0.11684)
		(layer "B.Cu")
		(net "SMB_BMC_MM8_SDA")
	)
	(segment
		(start 57.222136 -32.840676)
		(end 57.785 -33.40354)
		(width 0.11684)
		(layer "B.Cu")
		(net "SMB_BMC_MM8_SDA")
	)
	(segment
		(start 47.45482 -116.146834)
		(end 47.45482 -115.06962)
		(width 0.11684)
		(layer "B.Cu")
		(net "SMB_BMC_MM8_SDA")
	)
	(segment
		(start 57.785 -33.730692)
		(end 57.658 -33.857692)
		(width 0.11684)
		(layer "B.Cu")
		(net "SMB_BMC_MM8_SDA")
	)
	(segment
		(start 57.785 -33.40354)
		(end 57.785 -33.730692)
		(width 0.11684)
		(layer "B.Cu")
		(net "SMB_BMC_MM8_SDA")
	)
	(segment
		(start 55.0672 -28.702)
		(end 54.4322 -28.067)
		(width 0.10668)
		(layer "In4.Cu")
		(net "SMB_BMC_MM8_SDA")
	)
	(segment
		(start 56.87568 -26.24836)
		(end 57.41416 -25.70988)
		(width 0.10668)
		(layer "In4.Cu")
		(net "SMB_BMC_MM8_SDA")
	)
	(segment
		(start 57.6453 -30.7975)
		(end 56.4261 -30.7975)
		(width 0.10668)
		(layer "In4.Cu")
		(net "SMB_BMC_MM8_SDA")
	)
	(segment
		(start 54.4322 -26.8986)
		(end 55.08244 -26.24836)
		(width 0.10668)
		(layer "In4.Cu")
		(net "SMB_BMC_MM8_SDA")
	)
	(segment
		(start 55.0672 -29.4386)
		(end 55.0672 -28.702)
		(width 0.10668)
		(layer "In4.Cu")
		(net "SMB_BMC_MM8_SDA")
	)
	(segment
		(start 57.222136 -32.840676)
		(end 57.770268 -32.292544)
		(width 0.10668)
		(layer "In4.Cu")
		(net "SMB_BMC_MM8_SDA")
	)
	(segment
		(start 57.770268 -32.292544)
		(end 57.770268 -30.922468)
		(width 0.10668)
		(layer "In4.Cu")
		(net "SMB_BMC_MM8_SDA")
	)
	(segment
		(start 56.4261 -30.7975)
		(end 55.0672 -29.4386)
		(width 0.10668)
		(layer "In4.Cu")
		(net "SMB_BMC_MM8_SDA")
	)
	(segment
		(start 57.770268 -30.922468)
		(end 57.6453 -30.7975)
		(width 0.10668)
		(layer "In4.Cu")
		(net "SMB_BMC_MM8_SDA")
	)
	(segment
		(start 54.4322 -28.067)
		(end 54.4322 -26.8986)
		(width 0.10668)
		(layer "In4.Cu")
		(net "SMB_BMC_MM8_SDA")
	)
	(segment
		(start 55.08244 -26.24836)
		(end 56.87568 -26.24836)
		(width 0.10668)
		(layer "In4.Cu")
		(net "SMB_BMC_MM8_SDA")
	)
	(segment
		(start 41.934384 -111.50346)
		(end 40.79113 -110.360206)
		(width 0.10668)
		(layer "In7.Cu")
		(net "SMB_BMC_MM8_SDA")
	)
	(segment
		(start 26.94178 -31.63062)
		(end 28.4226 -30.1498)
		(width 0.10668)
		(layer "In7.Cu")
		(net "SMB_BMC_MM8_SDA")
	)
	(segment
		(start 19.6088 -50.292508)
		(end 19.6088 -48.58766)
		(width 0.10668)
		(layer "In7.Cu")
		(net "SMB_BMC_MM8_SDA")
	)
	(segment
		(start 36.554664 -20.59178)
		(end 38.985952 -20.59178)
		(width 0.10668)
		(layer "In7.Cu")
		(net "SMB_BMC_MM8_SDA")
	)
	(segment
		(start 40.79113 -110.360206)
		(end 40.79113 -106.80573)
		(width 0.10668)
		(layer "In7.Cu")
		(net "SMB_BMC_MM8_SDA")
	)
	(segment
		(start 21.29536 -60.478924)
		(end 21.29536 -59.056524)
		(width 0.10668)
		(layer "In7.Cu")
		(net "SMB_BMC_MM8_SDA")
	)
	(segment
		(start 19.6088 -48.58766)
		(end 20.1422 -47.299626)
		(width 0.10668)
		(layer "In7.Cu")
		(net "SMB_BMC_MM8_SDA")
	)
	(segment
		(start 20.2565 -47.022766)
		(end 20.2565 -45.458888)
		(width 0.10668)
		(layer "In7.Cu")
		(net "SMB_BMC_MM8_SDA")
	)
	(segment
		(start 28.42133 -27.53233)
		(end 27.7368 -26.8478)
		(width 0.10668)
		(layer "In7.Cu")
		(net "SMB_BMC_MM8_SDA")
	)
	(segment
		(start 27.145488 -77.88783)
		(end 26.848054 -77.76464)
		(width 0.10668)
		(layer "In7.Cu")
		(net "SMB_BMC_MM8_SDA")
	)
	(segment
		(start 26.848054 -77.76464)
		(end 26.431494 -77.76464)
		(width 0.10668)
		(layer "In7.Cu")
		(net "SMB_BMC_MM8_SDA")
	)
	(segment
		(start 28.42133 -24.892)
		(end 29.083 -24.23033)
		(width 0.10668)
		(layer "In7.Cu")
		(net "SMB_BMC_MM8_SDA")
	)
	(segment
		(start 24.765 -74.594466)
		(end 22.23262 -72.062086)
		(width 0.10668)
		(layer "In7.Cu")
		(net "SMB_BMC_MM8_SDA")
	)
	(segment
		(start 20.17776 -45.380148)
		(end 20.17776 -44.65447)
		(width 0.10668)
		(layer "In7.Cu")
		(net "SMB_BMC_MM8_SDA")
	)
	(segment
		(start 47.88408 -113.82248)
		(end 45.56506 -111.50346)
		(width 0.10668)
		(layer "In7.Cu")
		(net "SMB_BMC_MM8_SDA")
	)
	(segment
		(start 41.529 -19.4056)
		(end 42.3037 -20.1803)
		(width 0.10668)
		(layer "In7.Cu")
		(net "SMB_BMC_MM8_SDA")
	)
	(segment
		(start 36.453064 -20.49018)
		(end 36.554664 -20.59178)
		(width 0.10668)
		(layer "In7.Cu")
		(net "SMB_BMC_MM8_SDA")
	)
	(segment
		(start 33.689798 -19.812)
		(end 34.367978 -20.49018)
		(width 0.10668)
		(layer "In7.Cu")
		(net "SMB_BMC_MM8_SDA")
	)
	(segment
		(start 26.59888 -35.858958)
		(end 26.59888 -35.32632)
		(width 0.10668)
		(layer "In7.Cu")
		(net "SMB_BMC_MM8_SDA")
	)
	(segment
		(start 45.56506 -111.50346)
		(end 41.934384 -111.50346)
		(width 0.10668)
		(layer "In7.Cu")
		(net "SMB_BMC_MM8_SDA")
	)
	(segment
		(start 33.76168 -96.404176)
		(end 33.76168 -93.468444)
		(width 0.10668)
		(layer "In7.Cu")
		(net "SMB_BMC_MM8_SDA")
	)
	(segment
		(start 52.6288 -21.971)
		(end 55.3974 -24.7396)
		(width 0.10668)
		(layer "In7.Cu")
		(net "SMB_BMC_MM8_SDA")
	)
	(segment
		(start 28.4226 -30.1498)
		(end 28.4226 -28.2194)
		(width 0.10668)
		(layer "In7.Cu")
		(net "SMB_BMC_MM8_SDA")
	)
	(segment
		(start 31.759398 -19.471894)
		(end 32.099504 -19.812)
		(width 0.10668)
		(layer "In7.Cu")
		(net "SMB_BMC_MM8_SDA")
	)
	(segment
		(start 32.099504 -19.812)
		(end 33.689798 -19.812)
		(width 0.10668)
		(layer "In7.Cu")
		(net "SMB_BMC_MM8_SDA")
	)
	(segment
		(start 27.7368 -26.8478)
		(end 27.7368 -26.2636)
		(width 0.10668)
		(layer "In7.Cu")
		(net "SMB_BMC_MM8_SDA")
	)
	(segment
		(start 21.9329 -65.120774)
		(end 22.03196 -65.021714)
		(width 0.10668)
		(layer "In7.Cu")
		(net "SMB_BMC_MM8_SDA")
	)
	(segment
		(start 31.100268 -19.471894)
		(end 31.759398 -19.471894)
		(width 0.10668)
		(layer "In7.Cu")
		(net "SMB_BMC_MM8_SDA")
	)
	(segment
		(start 26.59888 -38.23335)
		(end 26.59888 -36.83381)
		(width 0.10668)
		(layer "In7.Cu")
		(net "SMB_BMC_MM8_SDA")
	)
	(segment
		(start 49.62144 -20.76704)
		(end 50.8254 -21.971)
		(width 0.10668)
		(layer "In7.Cu")
		(net "SMB_BMC_MM8_SDA")
	)
	(segment
		(start 26.778966 -36.653724)
		(end 27.544014 -36.653724)
		(width 0.10668)
		(layer "In7.Cu")
		(net "SMB_BMC_MM8_SDA")
	)
	(segment
		(start 27.49042 -80.867504)
		(end 27.49042 -78.232762)
		(width 0.10668)
		(layer "In7.Cu")
		(net "SMB_BMC_MM8_SDA")
	)
	(segment
		(start 29.083 -24.23033)
		(end 29.083 -22.352)
		(width 0.10668)
		(layer "In7.Cu")
		(net "SMB_BMC_MM8_SDA")
	)
	(segment
		(start 21.77542 -71.263256)
		(end 21.77542 -67.210686)
		(width 0.10668)
		(layer "In7.Cu")
		(net "SMB_BMC_MM8_SDA")
	)
	(segment
		(start 28.42133 -28.21813)
		(end 28.42133 -27.53233)
		(width 0.10668)
		(layer "In7.Cu")
		(net "SMB_BMC_MM8_SDA")
	)
	(segment
		(start 47.7266 -114.681)
		(end 47.88408 -114.52352)
		(width 0.10668)
		(layer "In7.Cu")
		(net "SMB_BMC_MM8_SDA")
	)
	(segment
		(start 27.02052 -33.047178)
		(end 26.94178 -32.968438)
		(width 0.10668)
		(layer "In7.Cu")
		(net "SMB_BMC_MM8_SDA")
	)
	(segment
		(start 38.985952 -20.59178)
		(end 40.172132 -19.4056)
		(width 0.10668)
		(layer "In7.Cu")
		(net "SMB_BMC_MM8_SDA")
	)
	(segment
		(start 27.7368 -26.2636)
		(end 28.42133 -25.57907)
		(width 0.10668)
		(layer "In7.Cu")
		(net "SMB_BMC_MM8_SDA")
	)
	(segment
		(start 40.06088 -104.382062)
		(end 37.6682 -101.989382)
		(width 0.10668)
		(layer "In7.Cu")
		(net "SMB_BMC_MM8_SDA")
	)
	(segment
		(start 28.64866 -82.025744)
		(end 27.49042 -80.867504)
		(width 0.10668)
		(layer "In7.Cu")
		(net "SMB_BMC_MM8_SDA")
	)
	(segment
		(start 21.9329 -67.053206)
		(end 21.9329 -65.120774)
		(width 0.10668)
		(layer "In7.Cu")
		(net "SMB_BMC_MM8_SDA")
	)
	(segment
		(start 30.549596 -20.885404)
		(end 30.549596 -20.022566)
		(width 0.10668)
		(layer "In7.Cu")
		(net "SMB_BMC_MM8_SDA")
	)
	(segment
		(start 22.03196 -65.021714)
		(end 22.03196 -61.215524)
		(width 0.10668)
		(layer "In7.Cu")
		(net "SMB_BMC_MM8_SDA")
	)
	(segment
		(start 40.79113 -106.80573)
		(end 40.06088 -106.07548)
		(width 0.10668)
		(layer "In7.Cu")
		(net "SMB_BMC_MM8_SDA")
	)
	(segment
		(start 47.43323 -20.1803)
		(end 48.01997 -20.76704)
		(width 0.10668)
		(layer "In7.Cu")
		(net "SMB_BMC_MM8_SDA")
	)
	(segment
		(start 28.42133 -25.57907)
		(end 28.42133 -24.892)
		(width 0.10668)
		(layer "In7.Cu")
		(net "SMB_BMC_MM8_SDA")
	)
	(segment
		(start 33.76168 -93.468444)
		(end 32.6517 -92.358464)
		(width 0.10668)
		(layer "In7.Cu")
		(net "SMB_BMC_MM8_SDA")
	)
	(segment
		(start 27.7241 -36.473638)
		(end 27.7241 -36.21913)
		(width 0.10668)
		(layer "In7.Cu")
		(net "SMB_BMC_MM8_SDA")
	)
	(segment
		(start 26.59888 -35.32632)
		(end 27.02052 -34.90468)
		(width 0.10668)
		(layer "In7.Cu")
		(net "SMB_BMC_MM8_SDA")
	)
	(segment
		(start 42.3037 -20.1803)
		(end 47.43323 -20.1803)
		(width 0.10668)
		(layer "In7.Cu")
		(net "SMB_BMC_MM8_SDA")
	)
	(segment
		(start 21.77542 -67.210686)
		(end 21.9329 -67.053206)
		(width 0.10668)
		(layer "In7.Cu")
		(net "SMB_BMC_MM8_SDA")
	)
	(segment
		(start 19.93392 -57.695084)
		(end 19.93392 -51.077622)
		(width 0.10668)
		(layer "In7.Cu")
		(net "SMB_BMC_MM8_SDA")
	)
	(segment
		(start 27.7241 -36.21913)
		(end 27.544014 -36.039044)
		(width 0.10668)
		(layer "In7.Cu")
		(net "SMB_BMC_MM8_SDA")
	)
	(segment
		(start 37.6682 -100.310696)
		(end 33.76168 -96.404176)
		(width 0.10668)
		(layer "In7.Cu")
		(net "SMB_BMC_MM8_SDA")
	)
	(segment
		(start 48.01997 -20.76704)
		(end 49.62144 -20.76704)
		(width 0.10668)
		(layer "In7.Cu")
		(net "SMB_BMC_MM8_SDA")
	)
	(segment
		(start 20.1422 -47.299118)
		(end 20.2565 -47.022766)
		(width 0.10668)
		(layer "In7.Cu")
		(net "SMB_BMC_MM8_SDA")
	)
	(segment
		(start 28.64866 -83.103466)
		(end 28.64866 -82.025744)
		(width 0.10668)
		(layer "In7.Cu")
		(net "SMB_BMC_MM8_SDA")
	)
	(segment
		(start 31.11246 -89.965784)
		(end 31.11246 -87.698072)
		(width 0.10668)
		(layer "In7.Cu")
		(net "SMB_BMC_MM8_SDA")
	)
	(segment
		(start 26.778966 -36.039044)
		(end 26.59888 -35.858958)
		(width 0.10668)
		(layer "In7.Cu")
		(net "SMB_BMC_MM8_SDA")
	)
	(segment
		(start 29.845 -86.430612)
		(end 29.845 -84.299806)
		(width 0.10668)
		(layer "In7.Cu")
		(net "SMB_BMC_MM8_SDA")
	)
	(segment
		(start 20.17776 -44.65447)
		(end 26.59888 -38.23335)
		(width 0.10668)
		(layer "In7.Cu")
		(net "SMB_BMC_MM8_SDA")
	)
	(segment
		(start 21.29536 -59.056524)
		(end 19.93392 -57.695084)
		(width 0.10668)
		(layer "In7.Cu")
		(net "SMB_BMC_MM8_SDA")
	)
	(segment
		(start 29.083 -22.352)
		(end 30.549596 -20.885404)
		(width 0.10668)
		(layer "In7.Cu")
		(net "SMB_BMC_MM8_SDA")
	)
	(segment
		(start 26.431494 -77.76464)
		(end 24.765 -76.098146)
		(width 0.10668)
		(layer "In7.Cu")
		(net "SMB_BMC_MM8_SDA")
	)
	(segment
		(start 56.44388 -24.7396)
		(end 57.41416 -25.70988)
		(width 0.10668)
		(layer "In7.Cu")
		(net "SMB_BMC_MM8_SDA")
	)
	(segment
		(start 55.3974 -24.7396)
		(end 56.44388 -24.7396)
		(width 0.10668)
		(layer "In7.Cu")
		(net "SMB_BMC_MM8_SDA")
	)
	(segment
		(start 30.549596 -20.022566)
		(end 31.100268 -19.471894)
		(width 0.10668)
		(layer "In7.Cu")
		(net "SMB_BMC_MM8_SDA")
	)
	(segment
		(start 50.8254 -21.971)
		(end 52.6288 -21.971)
		(width 0.10668)
		(layer "In7.Cu")
		(net "SMB_BMC_MM8_SDA")
	)
	(segment
		(start 27.02052 -34.90468)
		(end 27.02052 -33.047178)
		(width 0.10668)
		(layer "In7.Cu")
		(net "SMB_BMC_MM8_SDA")
	)
	(segment
		(start 40.06088 -106.07548)
		(end 40.06088 -104.382062)
		(width 0.10668)
		(layer "In7.Cu")
		(net "SMB_BMC_MM8_SDA")
	)
	(segment
		(start 20.2565 -45.458888)
		(end 20.17776 -45.380148)
		(width 0.10668)
		(layer "In7.Cu")
		(net "SMB_BMC_MM8_SDA")
	)
	(segment
		(start 46.99 -114.681)
		(end 47.7266 -114.681)
		(width 0.10668)
		(layer "In7.Cu")
		(net "SMB_BMC_MM8_SDA")
	)
	(segment
		(start 19.93392 -51.077622)
		(end 19.6088 -50.292508)
		(width 0.10668)
		(layer "In7.Cu")
		(net "SMB_BMC_MM8_SDA")
	)
	(segment
		(start 40.172132 -19.4056)
		(end 41.529 -19.4056)
		(width 0.10668)
		(layer "In7.Cu")
		(net "SMB_BMC_MM8_SDA")
	)
	(segment
		(start 32.6517 -92.358464)
		(end 32.6517 -91.505024)
		(width 0.10668)
		(layer "In7.Cu")
		(net "SMB_BMC_MM8_SDA")
	)
	(segment
		(start 29.845 -84.299806)
		(end 28.64866 -83.103466)
		(width 0.10668)
		(layer "In7.Cu")
		(net "SMB_BMC_MM8_SDA")
	)
	(segment
		(start 27.544014 -36.039044)
		(end 26.778966 -36.039044)
		(width 0.10668)
		(layer "In7.Cu")
		(net "SMB_BMC_MM8_SDA")
	)
	(segment
		(start 22.03196 -61.215524)
		(end 21.29536 -60.478924)
		(width 0.10668)
		(layer "In7.Cu")
		(net "SMB_BMC_MM8_SDA")
	)
	(segment
		(start 27.49042 -78.232762)
		(end 27.145488 -77.88783)
		(width 0.10668)
		(layer "In7.Cu")
		(net "SMB_BMC_MM8_SDA")
	)
	(segment
		(start 26.94178 -32.968438)
		(end 26.94178 -31.63062)
		(width 0.10668)
		(layer "In7.Cu")
		(net "SMB_BMC_MM8_SDA")
	)
	(segment
		(start 20.1422 -47.299626)
		(end 20.1422 -47.299118)
		(width 0.10668)
		(layer "In7.Cu")
		(net "SMB_BMC_MM8_SDA")
	)
	(segment
		(start 28.4226 -28.2194)
		(end 28.42133 -28.21813)
		(width 0.10668)
		(layer "In7.Cu")
		(net "SMB_BMC_MM8_SDA")
	)
	(segment
		(start 47.88408 -114.52352)
		(end 47.88408 -113.82248)
		(width 0.10668)
		(layer "In7.Cu")
		(net "SMB_BMC_MM8_SDA")
	)
	(segment
		(start 27.544014 -36.653724)
		(end 27.7241 -36.473638)
		(width 0.10668)
		(layer "In7.Cu")
		(net "SMB_BMC_MM8_SDA")
	)
	(segment
		(start 22.23262 -72.062086)
		(end 22.23262 -71.720456)
		(width 0.10668)
		(layer "In7.Cu")
		(net "SMB_BMC_MM8_SDA")
	)
	(segment
		(start 31.11246 -87.698072)
		(end 29.845 -86.430612)
		(width 0.10668)
		(layer "In7.Cu")
		(net "SMB_BMC_MM8_SDA")
	)
	(segment
		(start 37.6682 -101.989382)
		(end 37.6682 -100.310696)
		(width 0.10668)
		(layer "In7.Cu")
		(net "SMB_BMC_MM8_SDA")
	)
	(segment
		(start 32.6517 -91.505024)
		(end 31.11246 -89.965784)
		(width 0.10668)
		(layer "In7.Cu")
		(net "SMB_BMC_MM8_SDA")
	)
	(segment
		(start 22.23262 -71.720456)
		(end 21.77542 -71.263256)
		(width 0.10668)
		(layer "In7.Cu")
		(net "SMB_BMC_MM8_SDA")
	)
	(segment
		(start 26.59888 -36.83381)
		(end 26.778966 -36.653724)
		(width 0.10668)
		(layer "In7.Cu")
		(net "SMB_BMC_MM8_SDA")
	)
	(segment
		(start 24.765 -76.098146)
		(end 24.765 -74.594466)
		(width 0.10668)
		(layer "In7.Cu")
		(net "SMB_BMC_MM8_SDA")
	)
	(segment
		(start 34.367978 -20.49018)
		(end 36.453064 -20.49018)
		(width 0.10668)
		(layer "In7.Cu")
		(net "SMB_BMC_MM8_SDA")
	)
	(via
		(at 59.01055 -25.71242)
		(size 0.508)
		(drill 0.254)
		(layers "F.Cu" "B.Cu")
		(net "SMB_BMC_MM8_SCL")
	)
	(via
		(at 56.204612 -32.840676)
		(size 0.508)
		(drill 0.254)
		(layers "F.Cu" "B.Cu")
		(net "SMB_BMC_MM8_SCL")
	)
	(via
		(at 47.3202 -113.9698)
		(size 0.508)
		(drill 0.254)
		(layers "F.Cu" "B.Cu")
		(net "SMB_BMC_MM8_SCL")
	)
	(segment
		(start 55.705502 -32.341566)
		(end 56.204612 -32.840676)
		(width 0.11684)
		(layer "B.Cu")
		(net "SMB_BMC_MM8_SCL")
	)
	(segment
		(start 47.85106 -114.50066)
		(end 47.85106 -116.334794)
		(width 0.11684)
		(layer "B.Cu")
		(net "SMB_BMC_MM8_SCL")
	)
	(segment
		(start 56.204612 -32.840676)
		(end 56.6928 -33.328864)
		(width 0.11684)
		(layer "B.Cu")
		(net "SMB_BMC_MM8_SCL")
	)
	(segment
		(start 47.85106 -116.334794)
		(end 47.6758 -116.510054)
		(width 0.11684)
		(layer "B.Cu")
		(net "SMB_BMC_MM8_SCL")
	)
	(segment
		(start 55.705502 -31.267654)
		(end 55.705502 -32.341566)
		(width 0.11684)
		(layer "B.Cu")
		(net "SMB_BMC_MM8_SCL")
	)
	(segment
		(start 47.6758 -116.510054)
		(end 47.6758 -117.169946)
		(width 0.11684)
		(layer "B.Cu")
		(net "SMB_BMC_MM8_SCL")
	)
	(segment
		(start 56.553862 -34.27095)
		(end 56.515 -34.27095)
		(width 0.11684)
		(layer "B.Cu")
		(net "SMB_BMC_MM8_SCL")
	)
	(segment
		(start 56.6928 -33.328864)
		(end 56.6928 -34.132012)
		(width 0.11684)
		(layer "B.Cu")
		(net "SMB_BMC_MM8_SCL")
	)
	(segment
		(start 56.6928 -34.132012)
		(end 56.553862 -34.27095)
		(width 0.11684)
		(layer "B.Cu")
		(net "SMB_BMC_MM8_SCL")
	)
	(segment
		(start 47.3202 -113.9698)
		(end 47.85106 -114.50066)
		(width 0.11684)
		(layer "B.Cu")
		(net "SMB_BMC_MM8_SCL")
	)
	(segment
		(start 47.6758 -117.169946)
		(end 47.86503 -117.359176)
		(width 0.11684)
		(layer "B.Cu")
		(net "SMB_BMC_MM8_SCL")
	)
	(segment
		(start 47.86503 -117.359176)
		(end 47.86503 -118.25986)
		(width 0.11684)
		(layer "B.Cu")
		(net "SMB_BMC_MM8_SCL")
	)
	(segment
		(start 56.7436 -31.5214)
		(end 56.4388 -31.2166)
		(width 0.10668)
		(layer "In4.Cu")
		(net "SMB_BMC_MM8_SCL")
	)
	(segment
		(start 56.3118 -31.2166)
		(end 55.499 -30.4038)
		(width 0.10668)
		(layer "In4.Cu")
		(net "SMB_BMC_MM8_SCL")
	)
	(segment
		(start 55.499 -30.4038)
		(end 54.6608 -30.4038)
		(width 0.10668)
		(layer "In4.Cu")
		(net "SMB_BMC_MM8_SCL")
	)
	(segment
		(start 56.4388 -31.2166)
		(end 56.3118 -31.2166)
		(width 0.10668)
		(layer "In4.Cu")
		(net "SMB_BMC_MM8_SCL")
	)
	(segment
		(start 54.1782 -28.6004)
		(end 53.9496 -28.3718)
		(width 0.10668)
		(layer "In4.Cu")
		(net "SMB_BMC_MM8_SCL")
	)
	(segment
		(start 55.70728 -25.03932)
		(end 58.71972 -25.03932)
		(width 0.10668)
		(layer "In4.Cu")
		(net "SMB_BMC_MM8_SCL")
	)
	(segment
		(start 58.71972 -25.03932)
		(end 59.01055 -25.33015)
		(width 0.10668)
		(layer "In4.Cu")
		(net "SMB_BMC_MM8_SCL")
	)
	(segment
		(start 54.1782 -29.9212)
		(end 54.1782 -28.6004)
		(width 0.10668)
		(layer "In4.Cu")
		(net "SMB_BMC_MM8_SCL")
	)
	(segment
		(start 53.9496 -26.797)
		(end 55.70728 -25.03932)
		(width 0.10668)
		(layer "In4.Cu")
		(net "SMB_BMC_MM8_SCL")
	)
	(segment
		(start 56.414924 -32.840676)
		(end 56.7436 -32.512)
		(width 0.10668)
		(layer "In4.Cu")
		(net "SMB_BMC_MM8_SCL")
	)
	(segment
		(start 56.204612 -32.840676)
		(end 56.414924 -32.840676)
		(width 0.10668)
		(layer "In4.Cu")
		(net "SMB_BMC_MM8_SCL")
	)
	(segment
		(start 59.01055 -25.33015)
		(end 59.01055 -25.71242)
		(width 0.10668)
		(layer "In4.Cu")
		(net "SMB_BMC_MM8_SCL")
	)
	(segment
		(start 53.9496 -28.3718)
		(end 53.9496 -26.797)
		(width 0.10668)
		(layer "In4.Cu")
		(net "SMB_BMC_MM8_SCL")
	)
	(segment
		(start 56.7436 -32.512)
		(end 56.7436 -31.5214)
		(width 0.10668)
		(layer "In4.Cu")
		(net "SMB_BMC_MM8_SCL")
	)
	(segment
		(start 54.6608 -30.4038)
		(end 54.1782 -29.9212)
		(width 0.10668)
		(layer "In4.Cu")
		(net "SMB_BMC_MM8_SCL")
	)
	(segment
		(start 27.40152 -26.986738)
		(end 27.40152 -26.124662)
		(width 0.10668)
		(layer "In7.Cu")
		(net "SMB_BMC_MM8_SCL")
	)
	(segment
		(start 19.2532 -50.353214)
		(end 19.2532 -48.569372)
		(width 0.10668)
		(layer "In7.Cu")
		(net "SMB_BMC_MM8_SCL")
	)
	(segment
		(start 39.36746 -19.7358)
		(end 40.4114 -18.69186)
		(width 0.10668)
		(layer "In7.Cu")
		(net "SMB_BMC_MM8_SCL")
	)
	(segment
		(start 31.583884 -18.51406)
		(end 33.486852 -18.51406)
		(width 0.10668)
		(layer "In7.Cu")
		(net "SMB_BMC_MM8_SCL")
	)
	(segment
		(start 28.956254 -86.18474)
		(end 28.59786 -85.826346)
		(width 0.10668)
		(layer "In7.Cu")
		(net "SMB_BMC_MM8_SCL")
	)
	(segment
		(start 40.4114 -18.69186)
		(end 45.548296 -18.69186)
		(width 0.10668)
		(layer "In7.Cu")
		(net "SMB_BMC_MM8_SCL")
	)
	(segment
		(start 20.96008 -60.617862)
		(end 20.96008 -59.195462)
		(width 0.10668)
		(layer "In7.Cu")
		(net "SMB_BMC_MM8_SCL")
	)
	(segment
		(start 21.52523 -72.59574)
		(end 21.2217 -72.29221)
		(width 0.10668)
		(layer "In7.Cu")
		(net "SMB_BMC_MM8_SCL")
	)
	(segment
		(start 39.7256 -104.521)
		(end 37.33292 -102.12832)
		(width 0.10668)
		(layer "In7.Cu")
		(net "SMB_BMC_MM8_SCL")
	)
	(segment
		(start 19.7866 -47.281084)
		(end 19.92122 -46.955964)
		(width 0.10668)
		(layer "In7.Cu")
		(net "SMB_BMC_MM8_SCL")
	)
	(segment
		(start 19.92122 -46.955964)
		(end 19.92122 -45.597826)
		(width 0.10668)
		(layer "In7.Cu")
		(net "SMB_BMC_MM8_SCL")
	)
	(segment
		(start 28.31338 -83.242404)
		(end 28.31338 -82.164682)
		(width 0.10668)
		(layer "In7.Cu")
		(net "SMB_BMC_MM8_SCL")
	)
	(segment
		(start 26.2636 -35.187382)
		(end 26.68524 -34.765742)
		(width 0.10668)
		(layer "In7.Cu")
		(net "SMB_BMC_MM8_SCL")
	)
	(segment
		(start 21.744686 -72.59574)
		(end 21.52523 -72.59574)
		(width 0.10668)
		(layer "In7.Cu")
		(net "SMB_BMC_MM8_SCL")
	)
	(segment
		(start 23.427436 -73.73112)
		(end 22.880066 -73.73112)
		(width 0.10668)
		(layer "In7.Cu")
		(net "SMB_BMC_MM8_SCL")
	)
	(segment
		(start 40.45585 -107.02925)
		(end 39.7256 -106.299)
		(width 0.10668)
		(layer "In7.Cu")
		(net "SMB_BMC_MM8_SCL")
	)
	(segment
		(start 19.01444 -52.83454)
		(end 19.4437 -52.40528)
		(width 0.10668)
		(layer "In7.Cu")
		(net "SMB_BMC_MM8_SCL")
	)
	(segment
		(start 24.35352 -74.93508)
		(end 24.353774 -74.934826)
		(width 0.10668)
		(layer "In7.Cu")
		(net "SMB_BMC_MM8_SCL")
	)
	(segment
		(start 30.128972 -20.671028)
		(end 30.128972 -19.968972)
		(width 0.10668)
		(layer "In7.Cu")
		(net "SMB_BMC_MM8_SCL")
	)
	(segment
		(start 20.9169 -70.492112)
		(end 20.9169 -69.305424)
		(width 0.10668)
		(layer "In7.Cu")
		(net "SMB_BMC_MM8_SCL")
	)
	(segment
		(start 28.575 -24.14905)
		(end 28.575 -22.225)
		(width 0.10668)
		(layer "In7.Cu")
		(net "SMB_BMC_MM8_SCL")
	)
	(segment
		(start 26.6065 -33.107376)
		(end 26.6065 -31.491682)
		(width 0.10668)
		(layer "In7.Cu")
		(net "SMB_BMC_MM8_SCL")
	)
	(segment
		(start 48.158908 -20.43176)
		(end 51.563778 -20.43176)
		(width 0.10668)
		(layer "In7.Cu")
		(net "SMB_BMC_MM8_SCL")
	)
	(segment
		(start 21.2217 -71.228966)
		(end 20.9169 -70.492112)
		(width 0.10668)
		(layer "In7.Cu")
		(net "SMB_BMC_MM8_SCL")
	)
	(segment
		(start 19.4437 -50.813208)
		(end 19.2532 -50.353214)
		(width 0.10668)
		(layer "In7.Cu")
		(net "SMB_BMC_MM8_SCL")
	)
	(segment
		(start 40.45585 -110.50905)
		(end 40.45585 -107.02925)
		(width 0.10668)
		(layer "In7.Cu")
		(net "SMB_BMC_MM8_SCL")
	)
	(segment
		(start 32.31642 -91.643962)
		(end 30.77718 -90.104722)
		(width 0.10668)
		(layer "In7.Cu")
		(net "SMB_BMC_MM8_SCL")
	)
	(segment
		(start 19.01444 -53.218588)
		(end 19.01444 -52.83454)
		(width 0.10668)
		(layer "In7.Cu")
		(net "SMB_BMC_MM8_SCL")
	)
	(segment
		(start 37.27196 -19.431)
		(end 37.8714 -19.431)
		(width 0.10668)
		(layer "In7.Cu")
		(net "SMB_BMC_MM8_SCL")
	)
	(segment
		(start 46.670976 -19.81454)
		(end 47.541688 -19.81454)
		(width 0.10668)
		(layer "In7.Cu")
		(net "SMB_BMC_MM8_SCL")
	)
	(segment
		(start 19.84248 -45.519086)
		(end 19.84248 -44.509436)
		(width 0.10668)
		(layer "In7.Cu")
		(net "SMB_BMC_MM8_SCL")
	)
	(segment
		(start 26.6065 -31.491682)
		(end 27.27706 -30.821122)
		(width 0.10668)
		(layer "In7.Cu")
		(net "SMB_BMC_MM8_SCL")
	)
	(segment
		(start 38.1762 -19.7358)
		(end 39.36746 -19.7358)
		(width 0.10668)
		(layer "In7.Cu")
		(net "SMB_BMC_MM8_SCL")
	)
	(segment
		(start 19.92122 -45.597826)
		(end 19.84248 -45.519086)
		(width 0.10668)
		(layer "In7.Cu")
		(net "SMB_BMC_MM8_SCL")
	)
	(segment
		(start 22.880066 -73.73112)
		(end 21.744686 -72.59574)
		(width 0.10668)
		(layer "In7.Cu")
		(net "SMB_BMC_MM8_SCL")
	)
	(segment
		(start 19.59864 -53.802788)
		(end 19.01444 -53.218588)
		(width 0.10668)
		(layer "In7.Cu")
		(net "SMB_BMC_MM8_SCL")
	)
	(segment
		(start 24.353774 -74.934826)
		(end 24.353774 -74.657458)
		(width 0.10668)
		(layer "In7.Cu")
		(net "SMB_BMC_MM8_SCL")
	)
	(segment
		(start 27.15514 -78.3717)
		(end 26.95575 -78.17231)
		(width 0.10668)
		(layer "In7.Cu")
		(net "SMB_BMC_MM8_SCL")
	)
	(segment
		(start 20.785836 -66.458846)
		(end 20.785836 -65.116964)
		(width 0.10668)
		(layer "In7.Cu")
		(net "SMB_BMC_MM8_SCL")
	)
	(segment
		(start 28.59786 -83.526884)
		(end 28.31338 -83.242404)
		(width 0.10668)
		(layer "In7.Cu")
		(net "SMB_BMC_MM8_SCL")
	)
	(segment
		(start 28.31338 -82.164682)
		(end 27.15514 -81.006442)
		(width 0.10668)
		(layer "In7.Cu")
		(net "SMB_BMC_MM8_SCL")
	)
	(segment
		(start 19.2532 -48.569372)
		(end 19.7866 -47.281592)
		(width 0.10668)
		(layer "In7.Cu")
		(net "SMB_BMC_MM8_SCL")
	)
	(segment
		(start 27.7622 -27.347418)
		(end 27.40152 -26.986738)
		(width 0.10668)
		(layer "In7.Cu")
		(net "SMB_BMC_MM8_SCL")
	)
	(segment
		(start 41.88714 -111.94034)
		(end 40.45585 -110.50905)
		(width 0.10668)
		(layer "In7.Cu")
		(net "SMB_BMC_MM8_SCL")
	)
	(segment
		(start 33.486852 -18.51406)
		(end 35.127692 -20.1549)
		(width 0.10668)
		(layer "In7.Cu")
		(net "SMB_BMC_MM8_SCL")
	)
	(segment
		(start 20.785836 -65.116964)
		(end 21.69668 -64.20612)
		(width 0.10668)
		(layer "In7.Cu")
		(net "SMB_BMC_MM8_SCL")
	)
	(segment
		(start 20.58416 -68.972684)
		(end 20.58416 -67.424554)
		(width 0.10668)
		(layer "In7.Cu")
		(net "SMB_BMC_MM8_SCL")
	)
	(segment
		(start 29.041852 -86.18474)
		(end 28.956254 -86.18474)
		(width 0.10668)
		(layer "In7.Cu")
		(net "SMB_BMC_MM8_SCL")
	)
	(segment
		(start 19.84248 -44.509436)
		(end 26.2636 -38.088316)
		(width 0.10668)
		(layer "In7.Cu")
		(net "SMB_BMC_MM8_SCL")
	)
	(segment
		(start 45.548296 -18.69186)
		(end 46.670976 -19.81454)
		(width 0.10668)
		(layer "In7.Cu")
		(net "SMB_BMC_MM8_SCL")
	)
	(segment
		(start 33.4264 -96.543114)
		(end 33.4264 -93.607382)
		(width 0.10668)
		(layer "In7.Cu")
		(net "SMB_BMC_MM8_SCL")
	)
	(segment
		(start 37.33292 -102.12832)
		(end 37.33292 -100.449634)
		(width 0.10668)
		(layer "In7.Cu")
		(net "SMB_BMC_MM8_SCL")
	)
	(segment
		(start 21.69668 -64.20612)
		(end 21.69668 -61.354462)
		(width 0.10668)
		(layer "In7.Cu")
		(net "SMB_BMC_MM8_SCL")
	)
	(segment
		(start 35.127692 -20.1549)
		(end 36.54806 -20.1549)
		(width 0.10668)
		(layer "In7.Cu")
		(net "SMB_BMC_MM8_SCL")
	)
	(segment
		(start 26.95575 -78.17231)
		(end 26.780744 -78.09992)
		(width 0.10668)
		(layer "In7.Cu")
		(net "SMB_BMC_MM8_SCL")
	)
	(segment
		(start 27.27706 -29.06014)
		(end 27.7622 -28.575)
		(width 0.10668)
		(layer "In7.Cu")
		(net "SMB_BMC_MM8_SCL")
	)
	(segment
		(start 32.31642 -92.497402)
		(end 32.31642 -91.643962)
		(width 0.10668)
		(layer "In7.Cu")
		(net "SMB_BMC_MM8_SCL")
	)
	(segment
		(start 37.33292 -100.449634)
		(end 33.4264 -96.543114)
		(width 0.10668)
		(layer "In7.Cu")
		(net "SMB_BMC_MM8_SCL")
	)
	(segment
		(start 39.7256 -106.299)
		(end 39.7256 -104.521)
		(width 0.10668)
		(layer "In7.Cu")
		(net "SMB_BMC_MM8_SCL")
	)
	(segment
		(start 21.2217 -72.29221)
		(end 21.2217 -71.228966)
		(width 0.10668)
		(layer "In7.Cu")
		(net "SMB_BMC_MM8_SCL")
	)
	(segment
		(start 26.780744 -78.09992)
		(end 26.292556 -78.09992)
		(width 0.10668)
		(layer "In7.Cu")
		(net "SMB_BMC_MM8_SCL")
	)
	(segment
		(start 24.35352 -76.160884)
		(end 24.35352 -74.93508)
		(width 0.10668)
		(layer "In7.Cu")
		(net "SMB_BMC_MM8_SCL")
	)
	(segment
		(start 57.60593 -24.3078)
		(end 59.01055 -25.71242)
		(width 0.10668)
		(layer "In7.Cu")
		(net "SMB_BMC_MM8_SCL")
	)
	(segment
		(start 19.59864 -57.834022)
		(end 19.59864 -53.802788)
		(width 0.10668)
		(layer "In7.Cu")
		(net "SMB_BMC_MM8_SCL")
	)
	(segment
		(start 26.292556 -78.09992)
		(end 24.35352 -76.160884)
		(width 0.10668)
		(layer "In7.Cu")
		(net "SMB_BMC_MM8_SCL")
	)
	(segment
		(start 28.08605 -25.440132)
		(end 28.08605 -24.638)
		(width 0.10668)
		(layer "In7.Cu")
		(net "SMB_BMC_MM8_SCL")
	)
	(segment
		(start 26.2636 -38.088316)
		(end 26.2636 -35.187382)
		(width 0.10668)
		(layer "In7.Cu")
		(net "SMB_BMC_MM8_SCL")
	)
	(segment
		(start 36.54806 -20.1549)
		(end 37.27196 -19.431)
		(width 0.10668)
		(layer "In7.Cu")
		(net "SMB_BMC_MM8_SCL")
	)
	(segment
		(start 19.7866 -47.281592)
		(end 19.7866 -47.281084)
		(width 0.10668)
		(layer "In7.Cu")
		(net "SMB_BMC_MM8_SCL")
	)
	(segment
		(start 30.128972 -19.968972)
		(end 31.583884 -18.51406)
		(width 0.10668)
		(layer "In7.Cu")
		(net "SMB_BMC_MM8_SCL")
	)
	(segment
		(start 26.68524 -33.186116)
		(end 26.6065 -33.107376)
		(width 0.10668)
		(layer "In7.Cu")
		(net "SMB_BMC_MM8_SCL")
	)
	(segment
		(start 20.58416 -67.424554)
		(end 20.799298 -67.209416)
		(width 0.10668)
		(layer "In7.Cu")
		(net "SMB_BMC_MM8_SCL")
	)
	(segment
		(start 27.27706 -30.821122)
		(end 27.27706 -29.06014)
		(width 0.10668)
		(layer "In7.Cu")
		(net "SMB_BMC_MM8_SCL")
	)
	(segment
		(start 33.4264 -93.607382)
		(end 32.31642 -92.497402)
		(width 0.10668)
		(layer "In7.Cu")
		(net "SMB_BMC_MM8_SCL")
	)
	(segment
		(start 45.29074 -111.94034)
		(end 41.88714 -111.94034)
		(width 0.10668)
		(layer "In7.Cu")
		(net "SMB_BMC_MM8_SCL")
	)
	(segment
		(start 27.40152 -26.124662)
		(end 28.08605 -25.440132)
		(width 0.10668)
		(layer "In7.Cu")
		(net "SMB_BMC_MM8_SCL")
	)
	(segment
		(start 37.8714 -19.431)
		(end 38.1762 -19.7358)
		(width 0.10668)
		(layer "In7.Cu")
		(net "SMB_BMC_MM8_SCL")
	)
	(segment
		(start 27.15514 -81.006442)
		(end 27.15514 -78.3717)
		(width 0.10668)
		(layer "In7.Cu")
		(net "SMB_BMC_MM8_SCL")
	)
	(segment
		(start 24.353774 -74.657458)
		(end 23.427436 -73.73112)
		(width 0.10668)
		(layer "In7.Cu")
		(net "SMB_BMC_MM8_SCL")
	)
	(segment
		(start 28.59786 -85.826346)
		(end 28.59786 -83.526884)
		(width 0.10668)
		(layer "In7.Cu")
		(net "SMB_BMC_MM8_SCL")
	)
	(segment
		(start 20.799298 -67.209416)
		(end 20.799298 -66.491358)
		(width 0.10668)
		(layer "In7.Cu")
		(net "SMB_BMC_MM8_SCL")
	)
	(segment
		(start 30.77718 -90.104722)
		(end 30.77718 -87.920068)
		(width 0.10668)
		(layer "In7.Cu")
		(net "SMB_BMC_MM8_SCL")
	)
	(segment
		(start 20.799298 -66.491358)
		(end 20.785836 -66.458846)
		(width 0.10668)
		(layer "In7.Cu")
		(net "SMB_BMC_MM8_SCL")
	)
	(segment
		(start 19.4437 -52.40528)
		(end 19.4437 -50.813208)
		(width 0.10668)
		(layer "In7.Cu")
		(net "SMB_BMC_MM8_SCL")
	)
	(segment
		(start 28.575 -22.225)
		(end 30.128972 -20.671028)
		(width 0.10668)
		(layer "In7.Cu")
		(net "SMB_BMC_MM8_SCL")
	)
	(segment
		(start 26.68524 -34.765742)
		(end 26.68524 -33.186116)
		(width 0.10668)
		(layer "In7.Cu")
		(net "SMB_BMC_MM8_SCL")
	)
	(segment
		(start 47.3202 -113.9698)
		(end 45.29074 -111.94034)
		(width 0.10668)
		(layer "In7.Cu")
		(net "SMB_BMC_MM8_SCL")
	)
	(segment
		(start 28.08605 -24.638)
		(end 28.575 -24.14905)
		(width 0.10668)
		(layer "In7.Cu")
		(net "SMB_BMC_MM8_SCL")
	)
	(segment
		(start 20.9169 -69.305424)
		(end 20.58416 -68.972684)
		(width 0.10668)
		(layer "In7.Cu")
		(net "SMB_BMC_MM8_SCL")
	)
	(segment
		(start 27.7622 -28.575)
		(end 27.7622 -27.347418)
		(width 0.10668)
		(layer "In7.Cu")
		(net "SMB_BMC_MM8_SCL")
	)
	(segment
		(start 55.439818 -24.3078)
		(end 57.60593 -24.3078)
		(width 0.10668)
		(layer "In7.Cu")
		(net "SMB_BMC_MM8_SCL")
	)
	(segment
		(start 51.563778 -20.43176)
		(end 55.439818 -24.3078)
		(width 0.10668)
		(layer "In7.Cu")
		(net "SMB_BMC_MM8_SCL")
	)
	(segment
		(start 30.77718 -87.920068)
		(end 29.041852 -86.18474)
		(width 0.10668)
		(layer "In7.Cu")
		(net "SMB_BMC_MM8_SCL")
	)
	(segment
		(start 47.541688 -19.81454)
		(end 48.158908 -20.43176)
		(width 0.10668)
		(layer "In7.Cu")
		(net "SMB_BMC_MM8_SCL")
	)
	(segment
		(start 21.69668 -61.354462)
		(end 20.96008 -60.617862)
		(width 0.10668)
		(layer "In7.Cu")
		(net "SMB_BMC_MM8_SCL")
	)
	(segment
		(start 20.96008 -59.195462)
		(end 19.59864 -57.834022)
		(width 0.10668)
		(layer "In7.Cu")
		(net "SMB_BMC_MM8_SCL")
	)
	(segment
		(start 56.094884 -42.571162)
		(end 56.490108 -42.175938)
		(width 0.11684)
		(layer "F.Cu")
		(net "SMB_BMC_MM8_R_SDA")
	)
	(via
		(at 55.7784 -37.338)
		(size 0.508)
		(drill 0.254)
		(layers "F.Cu" "B.Cu")
		(net "SMB_BMC_MM8_R_SDA")
	)
	(via
		(at 56.490108 -42.175938)
		(size 0.4572)
		(drill 0.254)
		(layers "F.Cu" "B.Cu")
		(net "SMB_BMC_MM8_R_SDA")
	)
	(segment
		(start 57.1246 -36.101274)
		(end 56.116474 -37.1094)
		(width 0.11684)
		(layer "B.Cu")
		(net "SMB_BMC_MM8_R_SDA")
	)
	(segment
		(start 54.61508 -40.97782)
		(end 54.7624 -41.12514)
		(width 0.11684)
		(layer "B.Cu")
		(net "SMB_BMC_MM8_R_SDA")
	)
	(segment
		(start 54.61508 -39.182548)
		(end 54.61508 -40.97782)
		(width 0.11684)
		(layer "B.Cu")
		(net "SMB_BMC_MM8_R_SDA")
	)
	(segment
		(start 56.116474 -37.1094)
		(end 56.007 -37.1094)
		(width 0.11684)
		(layer "B.Cu")
		(net "SMB_BMC_MM8_R_SDA")
	)
	(segment
		(start 55.00624 -38.219634)
		(end 55.00624 -38.791388)
		(width 0.11684)
		(layer "B.Cu")
		(net "SMB_BMC_MM8_R_SDA")
	)
	(segment
		(start 54.7624 -41.851834)
		(end 55.481728 -42.571162)
		(width 0.11684)
		(layer "B.Cu")
		(net "SMB_BMC_MM8_R_SDA")
	)
	(segment
		(start 57.1246 -35.47745)
		(end 57.1246 -36.101274)
		(width 0.11684)
		(layer "B.Cu")
		(net "SMB_BMC_MM8_R_SDA")
	)
	(segment
		(start 57.531 -35.07105)
		(end 57.1246 -35.47745)
		(width 0.11684)
		(layer "B.Cu")
		(net "SMB_BMC_MM8_R_SDA")
	)
	(segment
		(start 56.094884 -42.571162)
		(end 56.490108 -42.175938)
		(width 0.11684)
		(layer "B.Cu")
		(net "SMB_BMC_MM8_R_SDA")
	)
	(segment
		(start 54.7624 -41.12514)
		(end 54.7624 -41.851834)
		(width 0.11684)
		(layer "B.Cu")
		(net "SMB_BMC_MM8_R_SDA")
	)
	(segment
		(start 55.7784 -37.338)
		(end 55.7784 -37.447474)
		(width 0.11684)
		(layer "B.Cu")
		(net "SMB_BMC_MM8_R_SDA")
	)
	(segment
		(start 55.00624 -38.791388)
		(end 54.61508 -39.182548)
		(width 0.11684)
		(layer "B.Cu")
		(net "SMB_BMC_MM8_R_SDA")
	)
	(segment
		(start 55.7784 -37.447474)
		(end 55.00624 -38.219634)
		(width 0.11684)
		(layer "B.Cu")
		(net "SMB_BMC_MM8_R_SDA")
	)
	(segment
		(start 56.007 -37.1094)
		(end 55.7784 -37.338)
		(width 0.11684)
		(layer "B.Cu")
		(net "SMB_BMC_MM8_R_SDA")
	)
	(segment
		(start 55.481728 -42.571162)
		(end 56.094884 -42.571162)
		(width 0.11684)
		(layer "B.Cu")
		(net "SMB_BMC_MM8_R_SDA")
	)
	(segment
		(start 55.295038 -43.371262)
		(end 55.690262 -42.976038)
		(width 0.11684)
		(layer "F.Cu")
		(net "SMB_BMC_MM8_R_SCL")
	)
	(via
		(at 56.2356 -36.2204)
		(size 0.6604)
		(drill 0.3302)
		(layers "F.Cu" "B.Cu")
		(net "SMB_BMC_MM8_R_SCL")
	)
	(via
		(at 55.690262 -42.976038)
		(size 0.4572)
		(drill 0.254)
		(layers "F.Cu" "B.Cu")
		(net "SMB_BMC_MM8_R_SCL")
	)
	(segment
		(start 55.9308 -36.2204)
		(end 56.2356 -36.2204)
		(width 0.11684)
		(layer "B.Cu")
		(net "SMB_BMC_MM8_R_SCL")
	)
	(segment
		(start 54.3052 -40.9956)
		(end 54.3052 -39.1414)
		(width 0.11684)
		(layer "B.Cu")
		(net "SMB_BMC_MM8_R_SCL")
	)
	(segment
		(start 56.515 -35.941)
		(end 56.515 -35.07105)
		(width 0.11684)
		(layer "B.Cu")
		(net "SMB_BMC_MM8_R_SCL")
	)
	(segment
		(start 55.690262 -42.976038)
		(end 55.275734 -42.804334)
		(width 0.11684)
		(layer "B.Cu")
		(net "SMB_BMC_MM8_R_SCL")
	)
	(segment
		(start 54.61 -38.055296)
		(end 55.18531 -37.479986)
		(width 0.11684)
		(layer "B.Cu")
		(net "SMB_BMC_MM8_R_SCL")
	)
	(segment
		(start 56.2356 -36.2204)
		(end 56.515 -35.941)
		(width 0.11684)
		(layer "B.Cu")
		(net "SMB_BMC_MM8_R_SCL")
	)
	(segment
		(start 54.5084 -41.1988)
		(end 54.3052 -40.9956)
		(width 0.11684)
		(layer "B.Cu")
		(net "SMB_BMC_MM8_R_SCL")
	)
	(segment
		(start 55.275734 -42.804334)
		(end 54.5084 -42.037)
		(width 0.11684)
		(layer "B.Cu")
		(net "SMB_BMC_MM8_R_SCL")
	)
	(segment
		(start 54.5084 -42.037)
		(end 54.5084 -41.1988)
		(width 0.11684)
		(layer "B.Cu")
		(net "SMB_BMC_MM8_R_SCL")
	)
	(segment
		(start 54.61 -38.8366)
		(end 54.61 -38.055296)
		(width 0.11684)
		(layer "B.Cu")
		(net "SMB_BMC_MM8_R_SCL")
	)
	(segment
		(start 55.4482 -36.845494)
		(end 55.4482 -36.703)
		(width 0.11684)
		(layer "B.Cu")
		(net "SMB_BMC_MM8_R_SCL")
	)
	(segment
		(start 54.3052 -39.1414)
		(end 54.61 -38.8366)
		(width 0.11684)
		(layer "B.Cu")
		(net "SMB_BMC_MM8_R_SCL")
	)
	(segment
		(start 55.4482 -36.703)
		(end 55.9308 -36.2204)
		(width 0.11684)
		(layer "B.Cu")
		(net "SMB_BMC_MM8_R_SCL")
	)
	(segment
		(start 55.18531 -37.479986)
		(end 55.4482 -36.845494)
		(width 0.11684)
		(layer "B.Cu")
		(net "SMB_BMC_MM8_R_SCL")
	)
	(via
		(at 46.44771 -28.881324)
		(size 0.508)
		(drill 0.254)
		(layers "F.Cu" "B.Cu")
		(net "SMB_BMC_MM7_SDA")
	)
	(via
		(at 46.85792 -109.05998)
		(size 0.508)
		(drill 0.254)
		(layers "F.Cu" "B.Cu")
		(net "SMB_BMC_MM7_SDA")
	)
	(via
		(at 64.2874 -30.4546)
		(size 0.508)
		(drill 0.254)
		(layers "F.Cu" "B.Cu")
		(net "SMB_BMC_MM7_SDA")
	)
	(segment
		(start 64.2874 -30.4546)
		(end 64.2874 -31.519876)
		(width 0.11684)
		(layer "B.Cu")
		(net "SMB_BMC_MM7_SDA")
	)
	(segment
		(start 48.2473 -114.236754)
		(end 48.2473 -116.2177)
		(width 0.11684)
		(layer "B.Cu")
		(net "SMB_BMC_MM7_SDA")
	)
	(segment
		(start 46.85792 -112.847374)
		(end 48.2473 -114.236754)
		(width 0.11684)
		(layer "B.Cu")
		(net "SMB_BMC_MM7_SDA")
	)
	(segment
		(start 64.1604 -31.646876)
		(end 64.1604 -32.06115)
		(width 0.11684)
		(layer "B.Cu")
		(net "SMB_BMC_MM7_SDA")
	)
	(segment
		(start 48.2473 -116.2177)
		(end 48.641 -116.6114)
		(width 0.11684)
		(layer "B.Cu")
		(net "SMB_BMC_MM7_SDA")
	)
	(segment
		(start 46.85792 -109.05998)
		(end 46.85792 -112.847374)
		(width 0.11684)
		(layer "B.Cu")
		(net "SMB_BMC_MM7_SDA")
	)
	(segment
		(start 64.2874 -31.519876)
		(end 64.1604 -31.646876)
		(width 0.11684)
		(layer "B.Cu")
		(net "SMB_BMC_MM7_SDA")
	)
	(segment
		(start 48.641 -117.094254)
		(end 48.464978 -117.270276)
		(width 0.11684)
		(layer "B.Cu")
		(net "SMB_BMC_MM7_SDA")
	)
	(segment
		(start 48.464978 -117.270276)
		(end 48.464978 -118.25986)
		(width 0.11684)
		(layer "B.Cu")
		(net "SMB_BMC_MM7_SDA")
	)
	(segment
		(start 48.641 -116.6114)
		(end 48.641 -117.094254)
		(width 0.11684)
		(layer "B.Cu")
		(net "SMB_BMC_MM7_SDA")
	)
	(segment
		(start 28.956 -66.778886)
		(end 28.66644 -67.478402)
		(width 0.10668)
		(layer "In7.Cu")
		(net "SMB_BMC_MM7_SDA")
	)
	(segment
		(start 41.220898 -88.98128)
		(end 43.19016 -90.950542)
		(width 0.10668)
		(layer "In7.Cu")
		(net "SMB_BMC_MM7_SDA")
	)
	(segment
		(start 27.203908 -70.31482)
		(end 27.697938 -70.31482)
		(width 0.10668)
		(layer "In7.Cu")
		(net "SMB_BMC_MM7_SDA")
	)
	(segment
		(start 28.66644 -68.359782)
		(end 28.301442 -68.72478)
		(width 0.10668)
		(layer "In7.Cu")
		(net "SMB_BMC_MM7_SDA")
	)
	(segment
		(start 43.19016 -98.900742)
		(end 45.1358 -100.846382)
		(width 0.10668)
		(layer "In7.Cu")
		(net "SMB_BMC_MM7_SDA")
	)
	(segment
		(start 27.81046 -65.0367)
		(end 28.956 -66.18224)
		(width 0.10668)
		(layer "In7.Cu")
		(net "SMB_BMC_MM7_SDA")
	)
	(segment
		(start 46.101 -28.3718)
		(end 41.630346 -28.3718)
		(width 0.10668)
		(layer "In7.Cu")
		(net "SMB_BMC_MM7_SDA")
	)
	(segment
		(start 41.630346 -28.3718)
		(end 40.375586 -27.11704)
		(width 0.10668)
		(layer "In7.Cu")
		(net "SMB_BMC_MM7_SDA")
	)
	(segment
		(start 34.66338 -30.390846)
		(end 34.66338 -31.223966)
		(width 0.10668)
		(layer "In7.Cu")
		(net "SMB_BMC_MM7_SDA")
	)
	(segment
		(start 28.19908 -71.316088)
		(end 30.17266 -73.289668)
		(width 0.10668)
		(layer "In7.Cu")
		(net "SMB_BMC_MM7_SDA")
	)
	(segment
		(start 28.956 -66.18224)
		(end 28.956 -66.778886)
		(width 0.10668)
		(layer "In7.Cu")
		(net "SMB_BMC_MM7_SDA")
	)
	(segment
		(start 26.90368 -70.014338)
		(end 26.90368 -70.014592)
		(width 0.10668)
		(layer "In7.Cu")
		(net "SMB_BMC_MM7_SDA")
	)
	(segment
		(start 30.200346 -53.500528)
		(end 30.200346 -54.723538)
		(width 0.10668)
		(layer "In7.Cu")
		(net "SMB_BMC_MM7_SDA")
	)
	(segment
		(start 30.17266 -73.289668)
		(end 30.17266 -74.92746)
		(width 0.10668)
		(layer "In7.Cu")
		(net "SMB_BMC_MM7_SDA")
	)
	(segment
		(start 31.72714 -76.17714)
		(end 31.72714 -77.458316)
		(width 0.10668)
		(layer "In7.Cu")
		(net "SMB_BMC_MM7_SDA")
	)
	(segment
		(start 36.8808 -83.99272)
		(end 38.442138 -83.99272)
		(width 0.10668)
		(layer "In7.Cu")
		(net "SMB_BMC_MM7_SDA")
	)
	(segment
		(start 47.079408 -108.525056)
		(end 46.85792 -109.05998)
		(width 0.10668)
		(layer "In7.Cu")
		(net "SMB_BMC_MM7_SDA")
	)
	(segment
		(start 45.1358 -106.461306)
		(end 46.941486 -108.266992)
		(width 0.10668)
		(layer "In7.Cu")
		(net "SMB_BMC_MM7_SDA")
	)
	(segment
		(start 29.7815 -50.91303)
		(end 30.353 -51.48453)
		(width 0.10668)
		(layer "In7.Cu")
		(net "SMB_BMC_MM7_SDA")
	)
	(segment
		(start 27.767534 -57.97423)
		(end 27.767534 -59.174888)
		(width 0.10668)
		(layer "In7.Cu")
		(net "SMB_BMC_MM7_SDA")
	)
	(segment
		(start 32.6898 -38.0746)
		(end 31.5214 -39.243)
		(width 0.10668)
		(layer "In7.Cu")
		(net "SMB_BMC_MM7_SDA")
	)
	(segment
		(start 39.60114 -85.151722)
		(end 39.60114 -88.50884)
		(width 0.10668)
		(layer "In7.Cu")
		(net "SMB_BMC_MM7_SDA")
	)
	(segment
		(start 27.767534 -59.174888)
		(end 27.70378 -59.238642)
		(width 0.10668)
		(layer "In7.Cu")
		(net "SMB_BMC_MM7_SDA")
	)
	(segment
		(start 27.38628 -60.382404)
		(end 27.38628 -62.971934)
		(width 0.10668)
		(layer "In7.Cu")
		(net "SMB_BMC_MM7_SDA")
	)
	(segment
		(start 30.353 -51.48453)
		(end 30.353 -53.347874)
		(width 0.10668)
		(layer "In7.Cu")
		(net "SMB_BMC_MM7_SDA")
	)
	(segment
		(start 31.72714 -77.458316)
		(end 33.277048 -79.008224)
		(width 0.10668)
		(layer "In7.Cu")
		(net "SMB_BMC_MM7_SDA")
	)
	(segment
		(start 45.1358 -100.846382)
		(end 45.1358 -106.461306)
		(width 0.10668)
		(layer "In7.Cu")
		(net "SMB_BMC_MM7_SDA")
	)
	(segment
		(start 27.70378 -60.064904)
		(end 27.38628 -60.382404)
		(width 0.10668)
		(layer "In7.Cu")
		(net "SMB_BMC_MM7_SDA")
	)
	(segment
		(start 27.38628 -62.971934)
		(end 27.81046 -63.396114)
		(width 0.10668)
		(layer "In7.Cu")
		(net "SMB_BMC_MM7_SDA")
	)
	(segment
		(start 46.228 -28.661614)
		(end 46.228 -28.4988)
		(width 0.10668)
		(layer "In7.Cu")
		(net "SMB_BMC_MM7_SDA")
	)
	(segment
		(start 29.7815 -50.53203)
		(end 29.7815 -50.91303)
		(width 0.10668)
		(layer "In7.Cu")
		(net "SMB_BMC_MM7_SDA")
	)
	(segment
		(start 34.66338 -31.223966)
		(end 32.6898 -33.197546)
		(width 0.10668)
		(layer "In7.Cu")
		(net "SMB_BMC_MM7_SDA")
	)
	(segment
		(start 31.5214 -39.243)
		(end 31.5214 -40.3606)
		(width 0.10668)
		(layer "In7.Cu")
		(net "SMB_BMC_MM7_SDA")
	)
	(segment
		(start 28.66644 -67.478402)
		(end 28.66644 -68.359782)
		(width 0.10668)
		(layer "In7.Cu")
		(net "SMB_BMC_MM7_SDA")
	)
	(segment
		(start 27.204162 -68.72478)
		(end 26.73858 -69.190362)
		(width 0.10668)
		(layer "In7.Cu")
		(net "SMB_BMC_MM7_SDA")
	)
	(segment
		(start 39.60114 -88.50884)
		(end 40.07358 -88.98128)
		(width 0.10668)
		(layer "In7.Cu")
		(net "SMB_BMC_MM7_SDA")
	)
	(segment
		(start 31.5214 -40.3606)
		(end 30.353 -41.529)
		(width 0.10668)
		(layer "In7.Cu")
		(net "SMB_BMC_MM7_SDA")
	)
	(segment
		(start 40.07358 -88.98128)
		(end 41.220898 -88.98128)
		(width 0.10668)
		(layer "In7.Cu")
		(net "SMB_BMC_MM7_SDA")
	)
	(segment
		(start 27.70378 -59.238642)
		(end 27.70378 -60.064904)
		(width 0.10668)
		(layer "In7.Cu")
		(net "SMB_BMC_MM7_SDA")
	)
	(segment
		(start 46.44771 -28.881324)
		(end 46.228 -28.661614)
		(width 0.10668)
		(layer "In7.Cu")
		(net "SMB_BMC_MM7_SDA")
	)
	(segment
		(start 38.442138 -83.99272)
		(end 39.60114 -85.151722)
		(width 0.10668)
		(layer "In7.Cu")
		(net "SMB_BMC_MM7_SDA")
	)
	(segment
		(start 40.375586 -27.11704)
		(end 37.937186 -27.11704)
		(width 0.10668)
		(layer "In7.Cu")
		(net "SMB_BMC_MM7_SDA")
	)
	(segment
		(start 30.200346 -54.723538)
		(end 29.621734 -56.12003)
		(width 0.10668)
		(layer "In7.Cu")
		(net "SMB_BMC_MM7_SDA")
	)
	(segment
		(start 30.17266 -74.92746)
		(end 30.882336 -75.637136)
		(width 0.10668)
		(layer "In7.Cu")
		(net "SMB_BMC_MM7_SDA")
	)
	(segment
		(start 30.882336 -75.637136)
		(end 31.187136 -75.637136)
		(width 0.10668)
		(layer "In7.Cu")
		(net "SMB_BMC_MM7_SDA")
	)
	(segment
		(start 28.19908 -70.815962)
		(end 28.19908 -71.316088)
		(width 0.10668)
		(layer "In7.Cu")
		(net "SMB_BMC_MM7_SDA")
	)
	(segment
		(start 30.353 -53.347874)
		(end 30.200346 -53.500528)
		(width 0.10668)
		(layer "In7.Cu")
		(net "SMB_BMC_MM7_SDA")
	)
	(segment
		(start 26.73858 -69.190362)
		(end 26.73858 -69.849238)
		(width 0.10668)
		(layer "In7.Cu")
		(net "SMB_BMC_MM7_SDA")
	)
	(segment
		(start 37.937186 -27.11704)
		(end 34.66338 -30.390846)
		(width 0.10668)
		(layer "In7.Cu")
		(net "SMB_BMC_MM7_SDA")
	)
	(segment
		(start 43.19016 -90.950542)
		(end 43.19016 -98.900742)
		(width 0.10668)
		(layer "In7.Cu")
		(net "SMB_BMC_MM7_SDA")
	)
	(segment
		(start 29.621734 -56.12003)
		(end 27.767534 -57.97423)
		(width 0.10668)
		(layer "In7.Cu")
		(net "SMB_BMC_MM7_SDA")
	)
	(segment
		(start 30.353 -41.529)
		(end 30.353 -49.96053)
		(width 0.10668)
		(layer "In7.Cu")
		(net "SMB_BMC_MM7_SDA")
	)
	(segment
		(start 26.73858 -69.849238)
		(end 26.90368 -70.014338)
		(width 0.10668)
		(layer "In7.Cu")
		(net "SMB_BMC_MM7_SDA")
	)
	(segment
		(start 31.187136 -75.637136)
		(end 31.72714 -76.17714)
		(width 0.10668)
		(layer "In7.Cu")
		(net "SMB_BMC_MM7_SDA")
	)
	(segment
		(start 27.697938 -70.31482)
		(end 28.19908 -70.815962)
		(width 0.10668)
		(layer "In7.Cu")
		(net "SMB_BMC_MM7_SDA")
	)
	(segment
		(start 46.941486 -108.266992)
		(end 47.079408 -108.525056)
		(width 0.10668)
		(layer "In7.Cu")
		(net "SMB_BMC_MM7_SDA")
	)
	(segment
		(start 30.353 -49.96053)
		(end 29.7815 -50.53203)
		(width 0.10668)
		(layer "In7.Cu")
		(net "SMB_BMC_MM7_SDA")
	)
	(segment
		(start 32.6898 -33.197546)
		(end 32.6898 -38.0746)
		(width 0.10668)
		(layer "In7.Cu")
		(net "SMB_BMC_MM7_SDA")
	)
	(segment
		(start 46.228 -28.4988)
		(end 46.101 -28.3718)
		(width 0.10668)
		(layer "In7.Cu")
		(net "SMB_BMC_MM7_SDA")
	)
	(segment
		(start 28.301442 -68.72478)
		(end 27.204162 -68.72478)
		(width 0.10668)
		(layer "In7.Cu")
		(net "SMB_BMC_MM7_SDA")
	)
	(segment
		(start 33.277048 -79.008224)
		(end 33.277048 -80.388968)
		(width 0.10668)
		(layer "In7.Cu")
		(net "SMB_BMC_MM7_SDA")
	)
	(segment
		(start 33.277048 -80.388968)
		(end 36.8808 -83.99272)
		(width 0.10668)
		(layer "In7.Cu")
		(net "SMB_BMC_MM7_SDA")
	)
	(segment
		(start 26.90368 -70.014592)
		(end 27.203908 -70.31482)
		(width 0.10668)
		(layer "In7.Cu")
		(net "SMB_BMC_MM7_SDA")
	)
	(segment
		(start 27.81046 -63.396114)
		(end 27.81046 -65.0367)
		(width 0.10668)
		(layer "In7.Cu")
		(net "SMB_BMC_MM7_SDA")
	)
	(segment
		(start 47.983394 -30.279594)
		(end 48.453802 -30.750002)
		(width 0.08382)
		(layer "In9.Cu")
		(net "SMB_BMC_MM7_SDA")
	)
	(segment
		(start 47.983394 -28.780994)
		(end 47.983394 -30.279594)
		(width 0.08382)
		(layer "In9.Cu")
		(net "SMB_BMC_MM7_SDA")
	)
	(segment
		(start 46.9646 -28.2702)
		(end 47.4726 -28.2702)
		(width 0.08382)
		(layer "In9.Cu")
		(net "SMB_BMC_MM7_SDA")
	)
	(segment
		(start 48.453802 -30.750002)
		(end 58.085736 -30.750002)
		(width 0.08382)
		(layer "In9.Cu")
		(net "SMB_BMC_MM7_SDA")
	)
	(segment
		(start 63.635636 -30.4546)
		(end 64.2874 -30.4546)
		(width 0.08382)
		(layer "In9.Cu")
		(net "SMB_BMC_MM7_SDA")
	)
	(segment
		(start 46.44771 -28.881324)
		(end 46.44771 -28.78709)
		(width 0.08382)
		(layer "In9.Cu")
		(net "SMB_BMC_MM7_SDA")
	)
	(segment
		(start 58.085736 -30.750002)
		(end 58.348118 -30.48762)
		(width 0.08382)
		(layer "In9.Cu")
		(net "SMB_BMC_MM7_SDA")
	)
	(segment
		(start 47.4726 -28.2702)
		(end 47.983394 -28.780994)
		(width 0.08382)
		(layer "In9.Cu")
		(net "SMB_BMC_MM7_SDA")
	)
	(segment
		(start 46.44771 -28.78709)
		(end 46.9646 -28.2702)
		(width 0.08382)
		(layer "In9.Cu")
		(net "SMB_BMC_MM7_SDA")
	)
	(segment
		(start 63.602616 -30.48762)
		(end 63.635636 -30.4546)
		(width 0.08382)
		(layer "In9.Cu")
		(net "SMB_BMC_MM7_SDA")
	)
	(segment
		(start 58.348118 -30.48762)
		(end 63.602616 -30.48762)
		(width 0.08382)
		(layer "In9.Cu")
		(net "SMB_BMC_MM7_SDA")
	)
	(via
		(at 62.36208 -33.1724)
		(size 0.508)
		(drill 0.254)
		(layers "F.Cu" "B.Cu")
		(net "SMB_BMC_MM7_SCL")
	)
	(via
		(at 47.42688 -109.85246)
		(size 0.762)
		(drill 0.254)
		(layers "F.Cu" "B.Cu")
		(net "SMB_BMC_MM7_SCL")
	)
	(via
		(at 43.5864 -28.956)
		(size 0.508)
		(drill 0.254)
		(layers "F.Cu" "B.Cu")
		(net "SMB_BMC_MM7_SCL")
	)
	(segment
		(start 49.276 -114.681254)
		(end 49.276 -116.205254)
		(width 0.11684)
		(layer "B.Cu")
		(net "SMB_BMC_MM7_SCL")
	)
	(segment
		(start 62.442344 -34.237676)
		(end 62.442344 -33.252664)
		(width 0.11684)
		(layer "B.Cu")
		(net "SMB_BMC_MM7_SCL")
	)
	(segment
		(start 47.42688 -112.832134)
		(end 49.276 -114.681254)
		(width 0.11684)
		(layer "B.Cu")
		(net "SMB_BMC_MM7_SCL")
	)
	(segment
		(start 49.064926 -116.416328)
		(end 49.064926 -118.460012)
		(width 0.11684)
		(layer "B.Cu")
		(net "SMB_BMC_MM7_SCL")
	)
	(segment
		(start 62.442344 -33.252664)
		(end 62.36208 -33.1724)
		(width 0.11684)
		(layer "B.Cu")
		(net "SMB_BMC_MM7_SCL")
	)
	(segment
		(start 47.42688 -109.85246)
		(end 47.42688 -112.832134)
		(width 0.11684)
		(layer "B.Cu")
		(net "SMB_BMC_MM7_SCL")
	)
	(segment
		(start 49.276 -116.205254)
		(end 49.064926 -116.416328)
		(width 0.11684)
		(layer "B.Cu")
		(net "SMB_BMC_MM7_SCL")
	)
	(segment
		(start 30.535626 -53.639466)
		(end 30.535626 -54.79034)
		(width 0.10668)
		(layer "In7.Cu")
		(net "SMB_BMC_MM7_SCL")
	)
	(segment
		(start 31.8008 -75.776582)
		(end 32.06242 -76.038202)
		(width 0.10668)
		(layer "In7.Cu")
		(net "SMB_BMC_MM7_SCL")
	)
	(segment
		(start 33.612328 -80.25003)
		(end 36.994338 -83.63204)
		(width 0.10668)
		(layer "In7.Cu")
		(net "SMB_BMC_MM7_SCL")
	)
	(segment
		(start 35.320986 -30.207458)
		(end 35.320986 -31.0896)
		(width 0.10668)
		(layer "In7.Cu")
		(net "SMB_BMC_MM7_SCL")
	)
	(segment
		(start 27.07386 -69.7103)
		(end 27.3431 -69.97954)
		(width 0.10668)
		(layer "In7.Cu")
		(net "SMB_BMC_MM7_SCL")
	)
	(segment
		(start 27.883358 -69.97954)
		(end 31.8008 -73.896982)
		(width 0.10668)
		(layer "In7.Cu")
		(net "SMB_BMC_MM7_SCL")
	)
	(segment
		(start 30.7086 -53.466492)
		(end 30.535626 -53.639466)
		(width 0.10668)
		(layer "In7.Cu")
		(net "SMB_BMC_MM7_SCL")
	)
	(segment
		(start 43.47972 -29.4894)
		(end 42.2656 -29.4894)
		(width 0.10668)
		(layer "In7.Cu")
		(net "SMB_BMC_MM7_SCL")
	)
	(segment
		(start 40.22852 -27.45232)
		(end 38.076124 -27.45232)
		(width 0.10668)
		(layer "In7.Cu")
		(net "SMB_BMC_MM7_SCL")
	)
	(segment
		(start 29.00172 -67.557142)
		(end 29.00172 -68.49872)
		(width 0.10668)
		(layer "In7.Cu")
		(net "SMB_BMC_MM7_SCL")
	)
	(segment
		(start 36.994338 -83.63204)
		(end 38.555676 -83.63204)
		(width 0.10668)
		(layer "In7.Cu")
		(net "SMB_BMC_MM7_SCL")
	)
	(segment
		(start 28.03906 -60.203842)
		(end 27.72156 -60.521342)
		(width 0.10668)
		(layer "In7.Cu")
		(net "SMB_BMC_MM7_SCL")
	)
	(segment
		(start 27.3431 -69.97954)
		(end 27.883358 -69.97954)
		(width 0.10668)
		(layer "In7.Cu")
		(net "SMB_BMC_MM7_SCL")
	)
	(segment
		(start 38.076124 -27.45232)
		(end 35.320986 -30.207458)
		(width 0.10668)
		(layer "In7.Cu")
		(net "SMB_BMC_MM7_SCL")
	)
	(segment
		(start 28.102814 -59.313826)
		(end 28.03906 -59.37758)
		(width 0.10668)
		(layer "In7.Cu")
		(net "SMB_BMC_MM7_SCL")
	)
	(segment
		(start 31.8008 -73.896982)
		(end 31.8008 -75.776582)
		(width 0.10668)
		(layer "In7.Cu")
		(net "SMB_BMC_MM7_SCL")
	)
	(segment
		(start 32.06242 -76.038202)
		(end 32.06242 -77.319378)
		(width 0.10668)
		(layer "In7.Cu")
		(net "SMB_BMC_MM7_SCL")
	)
	(segment
		(start 33.02508 -34.46272)
		(end 33.02508 -38.22192)
		(width 0.10668)
		(layer "In7.Cu")
		(net "SMB_BMC_MM7_SCL")
	)
	(segment
		(start 28.44038 -69.06006)
		(end 27.3431 -69.06006)
		(width 0.10668)
		(layer "In7.Cu")
		(net "SMB_BMC_MM7_SCL")
	)
	(segment
		(start 28.03906 -59.37758)
		(end 28.03906 -60.203842)
		(width 0.10668)
		(layer "In7.Cu")
		(net "SMB_BMC_MM7_SCL")
	)
	(segment
		(start 29.42336 -65.636394)
		(end 29.42336 -66.538348)
		(width 0.10668)
		(layer "In7.Cu")
		(net "SMB_BMC_MM7_SCL")
	)
	(segment
		(start 28.77947 -64.992504)
		(end 29.42336 -65.636394)
		(width 0.10668)
		(layer "In7.Cu")
		(net "SMB_BMC_MM7_SCL")
	)
	(segment
		(start 45.47108 -106.322114)
		(end 47.54372 -108.394754)
		(width 0.10668)
		(layer "In7.Cu")
		(net "SMB_BMC_MM7_SCL")
	)
	(segment
		(start 31.75 -40.6908)
		(end 30.7086 -41.7322)
		(width 0.10668)
		(layer "In7.Cu")
		(net "SMB_BMC_MM7_SCL")
	)
	(segment
		(start 34.798 -32.6898)
		(end 33.02508 -34.46272)
		(width 0.10668)
		(layer "In7.Cu")
		(net "SMB_BMC_MM7_SCL")
	)
	(segment
		(start 47.54372 -108.394754)
		(end 47.54372 -108.89488)
		(width 0.10668)
		(layer "In7.Cu")
		(net "SMB_BMC_MM7_SCL")
	)
	(segment
		(start 30.535626 -54.79034)
		(end 29.906468 -56.309514)
		(width 0.10668)
		(layer "In7.Cu")
		(net "SMB_BMC_MM7_SCL")
	)
	(segment
		(start 27.72156 -60.521342)
		(end 27.72156 -62.832996)
		(width 0.10668)
		(layer "In7.Cu")
		(net "SMB_BMC_MM7_SCL")
	)
	(segment
		(start 30.7086 -41.7322)
		(end 30.7086 -53.466492)
		(width 0.10668)
		(layer "In7.Cu")
		(net "SMB_BMC_MM7_SCL")
	)
	(segment
		(start 45.471334 -100.985066)
		(end 45.47108 -100.98532)
		(width 0.10668)
		(layer "In7.Cu")
		(net "SMB_BMC_MM7_SCL")
	)
	(segment
		(start 29.42336 -66.538348)
		(end 29.00172 -67.557142)
		(width 0.10668)
		(layer "In7.Cu")
		(net "SMB_BMC_MM7_SCL")
	)
	(segment
		(start 32.258 -40.6908)
		(end 31.75 -40.6908)
		(width 0.10668)
		(layer "In7.Cu")
		(net "SMB_BMC_MM7_SCL")
	)
	(segment
		(start 33.612328 -78.869286)
		(end 33.612328 -80.25003)
		(width 0.10668)
		(layer "In7.Cu")
		(net "SMB_BMC_MM7_SCL")
	)
	(segment
		(start 42.2656 -29.4894)
		(end 40.22852 -27.45232)
		(width 0.10668)
		(layer "In7.Cu")
		(net "SMB_BMC_MM7_SCL")
	)
	(segment
		(start 40.9194 -85.995764)
		(end 40.9194 -87.817452)
		(width 0.10668)
		(layer "In7.Cu")
		(net "SMB_BMC_MM7_SCL")
	)
	(segment
		(start 45.471334 -100.707698)
		(end 45.471334 -100.985066)
		(width 0.10668)
		(layer "In7.Cu")
		(net "SMB_BMC_MM7_SCL")
	)
	(segment
		(start 27.07386 -69.3293)
		(end 27.07386 -69.7103)
		(width 0.10668)
		(layer "In7.Cu")
		(net "SMB_BMC_MM7_SCL")
	)
	(segment
		(start 29.00172 -68.49872)
		(end 28.44038 -69.06006)
		(width 0.10668)
		(layer "In7.Cu")
		(net "SMB_BMC_MM7_SCL")
	)
	(segment
		(start 40.9194 -87.817452)
		(end 43.52544 -90.423492)
		(width 0.10668)
		(layer "In7.Cu")
		(net "SMB_BMC_MM7_SCL")
	)
	(segment
		(start 43.52544 -98.761804)
		(end 45.471334 -100.707698)
		(width 0.10668)
		(layer "In7.Cu")
		(net "SMB_BMC_MM7_SCL")
	)
	(segment
		(start 38.555676 -83.63204)
		(end 40.9194 -85.995764)
		(width 0.10668)
		(layer "In7.Cu")
		(net "SMB_BMC_MM7_SCL")
	)
	(segment
		(start 43.5864 -28.956)
		(end 43.5864 -29.38272)
		(width 0.10668)
		(layer "In7.Cu")
		(net "SMB_BMC_MM7_SCL")
	)
	(segment
		(start 27.3431 -69.06006)
		(end 27.07386 -69.3293)
		(width 0.10668)
		(layer "In7.Cu")
		(net "SMB_BMC_MM7_SCL")
	)
	(segment
		(start 28.77947 -63.890906)
		(end 28.77947 -64.992504)
		(width 0.10668)
		(layer "In7.Cu")
		(net "SMB_BMC_MM7_SCL")
	)
	(segment
		(start 43.52544 -90.423492)
		(end 43.52544 -98.761804)
		(width 0.10668)
		(layer "In7.Cu")
		(net "SMB_BMC_MM7_SCL")
	)
	(segment
		(start 27.72156 -62.832996)
		(end 28.77947 -63.890906)
		(width 0.10668)
		(layer "In7.Cu")
		(net "SMB_BMC_MM7_SCL")
	)
	(segment
		(start 47.54372 -108.89488)
		(end 47.42688 -109.177074)
		(width 0.10668)
		(layer "In7.Cu")
		(net "SMB_BMC_MM7_SCL")
	)
	(segment
		(start 29.906468 -56.309514)
		(end 28.102814 -58.113168)
		(width 0.10668)
		(layer "In7.Cu")
		(net "SMB_BMC_MM7_SCL")
	)
	(segment
		(start 28.102814 -58.113168)
		(end 28.102814 -59.313826)
		(width 0.10668)
		(layer "In7.Cu")
		(net "SMB_BMC_MM7_SCL")
	)
	(segment
		(start 45.47108 -100.98532)
		(end 45.47108 -106.322114)
		(width 0.10668)
		(layer "In7.Cu")
		(net "SMB_BMC_MM7_SCL")
	)
	(segment
		(start 32.639 -40.3098)
		(end 32.258 -40.6908)
		(width 0.10668)
		(layer "In7.Cu")
		(net "SMB_BMC_MM7_SCL")
	)
	(segment
		(start 47.42688 -109.177074)
		(end 47.42688 -109.85246)
		(width 0.10668)
		(layer "In7.Cu")
		(net "SMB_BMC_MM7_SCL")
	)
	(segment
		(start 34.798 -31.612586)
		(end 34.798 -32.6898)
		(width 0.10668)
		(layer "In7.Cu")
		(net "SMB_BMC_MM7_SCL")
	)
	(segment
		(start 43.5864 -29.38272)
		(end 43.47972 -29.4894)
		(width 0.10668)
		(layer "In7.Cu")
		(net "SMB_BMC_MM7_SCL")
	)
	(segment
		(start 35.320986 -31.0896)
		(end 34.798 -31.612586)
		(width 0.10668)
		(layer "In7.Cu")
		(net "SMB_BMC_MM7_SCL")
	)
	(segment
		(start 32.639 -38.608)
		(end 32.639 -40.3098)
		(width 0.10668)
		(layer "In7.Cu")
		(net "SMB_BMC_MM7_SCL")
	)
	(segment
		(start 32.06242 -77.319378)
		(end 33.612328 -78.869286)
		(width 0.10668)
		(layer "In7.Cu")
		(net "SMB_BMC_MM7_SCL")
	)
	(segment
		(start 33.02508 -38.22192)
		(end 32.639 -38.608)
		(width 0.10668)
		(layer "In7.Cu")
		(net "SMB_BMC_MM7_SCL")
	)
	(segment
		(start 43.5864 -28.956)
		(end 43.5864 -29.6164)
		(width 0.08382)
		(layer "In9.Cu")
		(net "SMB_BMC_MM7_SCL")
	)
	(segment
		(start 55.691532 -31.7246)
		(end 55.8292 -31.586932)
		(width 0.08382)
		(layer "In9.Cu")
		(net "SMB_BMC_MM7_SCL")
	)
	(segment
		(start 54.843172 -31.115762)
		(end 55.221632 -31.115762)
		(width 0.08382)
		(layer "In9.Cu")
		(net "SMB_BMC_MM7_SCL")
	)
	(segment
		(start 50.500026 -31.714694)
		(end 50.636932 -31.8516)
		(width 0.08382)
		(layer "In9.Cu")
		(net "SMB_BMC_MM7_SCL")
	)
	(segment
		(start 54.706266 -31.714694)
		(end 54.706266 -31.252668)
		(width 0.08382)
		(layer "In9.Cu")
		(net "SMB_BMC_MM7_SCL")
	)
	(segment
		(start 53.304186 -31.252668)
		(end 53.304186 -31.51378)
		(width 0.08382)
		(layer "In9.Cu")
		(net "SMB_BMC_MM7_SCL")
	)
	(segment
		(start 53.908452 -31.115762)
		(end 54.102 -31.115762)
		(width 0.08382)
		(layer "In9.Cu")
		(net "SMB_BMC_MM7_SCL")
	)
	(segment
		(start 55.221632 -31.115762)
		(end 55.3593 -31.25343)
		(width 0.08382)
		(layer "In9.Cu")
		(net "SMB_BMC_MM7_SCL")
	)
	(segment
		(start 51.518566 -31.4198)
		(end 51.818286 -31.4198)
		(width 0.08382)
		(layer "In9.Cu")
		(net "SMB_BMC_MM7_SCL")
	)
	(segment
		(start 50.636932 -31.8516)
		(end 50.83048 -31.8516)
		(width 0.08382)
		(layer "In9.Cu")
		(net "SMB_BMC_MM7_SCL")
	)
	(segment
		(start 53.16728 -31.115762)
		(end 53.304186 -31.252668)
		(width 0.08382)
		(layer "In9.Cu")
		(net "SMB_BMC_MM7_SCL")
	)
	(segment
		(start 54.102 -31.115762)
		(end 54.238906 -31.252668)
		(width 0.08382)
		(layer "In9.Cu")
		(net "SMB_BMC_MM7_SCL")
	)
	(segment
		(start 49.702212 -31.8516)
		(end 49.89576 -31.8516)
		(width 0.08382)
		(layer "In9.Cu")
		(net "SMB_BMC_MM7_SCL")
	)
	(segment
		(start 52.039012 -31.115762)
		(end 53.16728 -31.115762)
		(width 0.08382)
		(layer "In9.Cu")
		(net "SMB_BMC_MM7_SCL")
	)
	(segment
		(start 51.104292 -31.115762)
		(end 51.29784 -31.115762)
		(width 0.08382)
		(layer "In9.Cu")
		(net "SMB_BMC_MM7_SCL")
	)
	(segment
		(start 49.565306 -31.252668)
		(end 49.565306 -31.714694)
		(width 0.08382)
		(layer "In9.Cu")
		(net "SMB_BMC_MM7_SCL")
	)
	(segment
		(start 53.771546 -31.252668)
		(end 53.908452 -31.115762)
		(width 0.08382)
		(layer "In9.Cu")
		(net "SMB_BMC_MM7_SCL")
	)
	(segment
		(start 54.56936 -31.8516)
		(end 54.706266 -31.714694)
		(width 0.08382)
		(layer "In9.Cu")
		(net "SMB_BMC_MM7_SCL")
	)
	(segment
		(start 63.281306 -31.703264)
		(end 63.281306 -32.984948)
		(width 0.08382)
		(layer "In9.Cu")
		(net "SMB_BMC_MM7_SCL")
	)
	(segment
		(start 53.687726 -31.5976)
		(end 53.771546 -31.51378)
		(width 0.08382)
		(layer "In9.Cu")
		(net "SMB_BMC_MM7_SCL")
	)
	(segment
		(start 44.8183 -30.443678)
		(end 48.196754 -31.115762)
		(width 0.08382)
		(layer "In9.Cu")
		(net "SMB_BMC_MM7_SCL")
	)
	(segment
		(start 43.5864 -29.6164)
		(end 44.12742 -30.15742)
		(width 0.08382)
		(layer "In9.Cu")
		(net "SMB_BMC_MM7_SCL")
	)
	(segment
		(start 50.83048 -31.8516)
		(end 50.967386 -31.714694)
		(width 0.08382)
		(layer "In9.Cu")
		(net "SMB_BMC_MM7_SCL")
	)
	(segment
		(start 54.375812 -31.8516)
		(end 54.56936 -31.8516)
		(width 0.08382)
		(layer "In9.Cu")
		(net "SMB_BMC_MM7_SCL")
	)
	(segment
		(start 53.304186 -31.51378)
		(end 53.388006 -31.5976)
		(width 0.08382)
		(layer "In9.Cu")
		(net "SMB_BMC_MM7_SCL")
	)
	(segment
		(start 50.36312 -31.115762)
		(end 50.500026 -31.252668)
		(width 0.08382)
		(layer "In9.Cu")
		(net "SMB_BMC_MM7_SCL")
	)
	(segment
		(start 49.89576 -31.8516)
		(end 50.032666 -31.714694)
		(width 0.08382)
		(layer "In9.Cu")
		(net "SMB_BMC_MM7_SCL")
	)
	(segment
		(start 51.434746 -31.33598)
		(end 51.518566 -31.4198)
		(width 0.08382)
		(layer "In9.Cu")
		(net "SMB_BMC_MM7_SCL")
	)
	(segment
		(start 55.8292 -31.25343)
		(end 55.966868 -31.115762)
		(width 0.08382)
		(layer "In9.Cu")
		(net "SMB_BMC_MM7_SCL")
	)
	(segment
		(start 53.771546 -31.51378)
		(end 53.771546 -31.252668)
		(width 0.08382)
		(layer "In9.Cu")
		(net "SMB_BMC_MM7_SCL")
	)
	(segment
		(start 50.169572 -31.115762)
		(end 50.36312 -31.115762)
		(width 0.08382)
		(layer "In9.Cu")
		(net "SMB_BMC_MM7_SCL")
	)
	(segment
		(start 55.496968 -31.7246)
		(end 55.691532 -31.7246)
		(width 0.08382)
		(layer "In9.Cu")
		(net "SMB_BMC_MM7_SCL")
	)
	(segment
		(start 50.967386 -31.252668)
		(end 51.104292 -31.115762)
		(width 0.08382)
		(layer "In9.Cu")
		(net "SMB_BMC_MM7_SCL")
	)
	(segment
		(start 54.706266 -31.252668)
		(end 54.843172 -31.115762)
		(width 0.08382)
		(layer "In9.Cu")
		(net "SMB_BMC_MM7_SCL")
	)
	(segment
		(start 51.818286 -31.4198)
		(end 51.902106 -31.33598)
		(width 0.08382)
		(layer "In9.Cu")
		(net "SMB_BMC_MM7_SCL")
	)
	(segment
		(start 50.032666 -31.252668)
		(end 50.169572 -31.115762)
		(width 0.08382)
		(layer "In9.Cu")
		(net "SMB_BMC_MM7_SCL")
	)
	(segment
		(start 50.967386 -31.714694)
		(end 50.967386 -31.252668)
		(width 0.08382)
		(layer "In9.Cu")
		(net "SMB_BMC_MM7_SCL")
	)
	(segment
		(start 55.8292 -31.586932)
		(end 55.8292 -31.25343)
		(width 0.08382)
		(layer "In9.Cu")
		(net "SMB_BMC_MM7_SCL")
	)
	(segment
		(start 63.093854 -33.1724)
		(end 62.36208 -33.1724)
		(width 0.08382)
		(layer "In9.Cu")
		(net "SMB_BMC_MM7_SCL")
	)
	(segment
		(start 49.565306 -31.714694)
		(end 49.702212 -31.8516)
		(width 0.08382)
		(layer "In9.Cu")
		(net "SMB_BMC_MM7_SCL")
	)
	(segment
		(start 51.29784 -31.115762)
		(end 51.434746 -31.252668)
		(width 0.08382)
		(layer "In9.Cu")
		(net "SMB_BMC_MM7_SCL")
	)
	(segment
		(start 58.499756 -30.85338)
		(end 62.431422 -30.85338)
		(width 0.08382)
		(layer "In9.Cu")
		(net "SMB_BMC_MM7_SCL")
	)
	(segment
		(start 62.431422 -30.85338)
		(end 63.281306 -31.703264)
		(width 0.08382)
		(layer "In9.Cu")
		(net "SMB_BMC_MM7_SCL")
	)
	(segment
		(start 54.238906 -31.252668)
		(end 54.238906 -31.714694)
		(width 0.08382)
		(layer "In9.Cu")
		(net "SMB_BMC_MM7_SCL")
	)
	(segment
		(start 55.3593 -31.25343)
		(end 55.3593 -31.586932)
		(width 0.08382)
		(layer "In9.Cu")
		(net "SMB_BMC_MM7_SCL")
	)
	(segment
		(start 50.500026 -31.252668)
		(end 50.500026 -31.714694)
		(width 0.08382)
		(layer "In9.Cu")
		(net "SMB_BMC_MM7_SCL")
	)
	(segment
		(start 54.238906 -31.714694)
		(end 54.375812 -31.8516)
		(width 0.08382)
		(layer "In9.Cu")
		(net "SMB_BMC_MM7_SCL")
	)
	(segment
		(start 48.196754 -31.115762)
		(end 49.4284 -31.115762)
		(width 0.08382)
		(layer "In9.Cu")
		(net "SMB_BMC_MM7_SCL")
	)
	(segment
		(start 44.12742 -30.15742)
		(end 44.8183 -30.443678)
		(width 0.08382)
		(layer "In9.Cu")
		(net "SMB_BMC_MM7_SCL")
	)
	(segment
		(start 51.902106 -31.252668)
		(end 52.039012 -31.115762)
		(width 0.08382)
		(layer "In9.Cu")
		(net "SMB_BMC_MM7_SCL")
	)
	(segment
		(start 55.3593 -31.586932)
		(end 55.496968 -31.7246)
		(width 0.08382)
		(layer "In9.Cu")
		(net "SMB_BMC_MM7_SCL")
	)
	(segment
		(start 63.281306 -32.984948)
		(end 63.093854 -33.1724)
		(width 0.08382)
		(layer "In9.Cu")
		(net "SMB_BMC_MM7_SCL")
	)
	(segment
		(start 51.434746 -31.252668)
		(end 51.434746 -31.33598)
		(width 0.08382)
		(layer "In9.Cu")
		(net "SMB_BMC_MM7_SCL")
	)
	(segment
		(start 49.4284 -31.115762)
		(end 49.565306 -31.252668)
		(width 0.08382)
		(layer "In9.Cu")
		(net "SMB_BMC_MM7_SCL")
	)
	(segment
		(start 55.966868 -31.115762)
		(end 58.237374 -31.115762)
		(width 0.08382)
		(layer "In9.Cu")
		(net "SMB_BMC_MM7_SCL")
	)
	(segment
		(start 53.388006 -31.5976)
		(end 53.687726 -31.5976)
		(width 0.08382)
		(layer "In9.Cu")
		(net "SMB_BMC_MM7_SCL")
	)
	(segment
		(start 50.032666 -31.714694)
		(end 50.032666 -31.252668)
		(width 0.08382)
		(layer "In9.Cu")
		(net "SMB_BMC_MM7_SCL")
	)
	(segment
		(start 58.237374 -31.115762)
		(end 58.499756 -30.85338)
		(width 0.08382)
		(layer "In9.Cu")
		(net "SMB_BMC_MM7_SCL")
	)
	(segment
		(start 51.902106 -31.33598)
		(end 51.902106 -31.252668)
		(width 0.08382)
		(layer "In9.Cu")
		(net "SMB_BMC_MM7_SCL")
	)
	(segment
		(start 56.894984 -42.571162)
		(end 57.290208 -42.175938)
		(width 0.11684)
		(layer "F.Cu")
		(net "SMB_BMC_MM7_R_SDA")
	)
	(via
		(at 57.290208 -42.175938)
		(size 0.4572)
		(drill 0.254)
		(layers "F.Cu" "B.Cu")
		(net "SMB_BMC_MM7_R_SDA")
	)
	(segment
		(start 64.036194 -28.756356)
		(end 64.036194 -29.18206)
		(width 0.11684)
		(layer "B.Cu")
		(net "SMB_BMC_MM7_R_SDA")
	)
	(segment
		(start 63.950342 -32.521652)
		(end 64.1604 -32.73171)
		(width 0.11684)
		(layer "B.Cu")
		(net "SMB_BMC_MM7_R_SDA")
	)
	(segment
		(start 59.639962 -38.4556)
		(end 59.942222 -38.330378)
		(width 0.11684)
		(layer "B.Cu")
		(net "SMB_BMC_MM7_R_SDA")
	)
	(segment
		(start 57.769506 -40.326056)
		(end 59.639962 -38.4556)
		(width 0.11684)
		(layer "B.Cu")
		(net "SMB_BMC_MM7_R_SDA")
	)
	(segment
		(start 63.709296 -33.293558)
		(end 64.045846 -32.957008)
		(width 0.11684)
		(layer "B.Cu")
		(net "SMB_BMC_MM7_R_SDA")
	)
	(segment
		(start 63.71844 -31.477204)
		(end 63.71844 -32.40659)
		(width 0.11684)
		(layer "B.Cu")
		(net "SMB_BMC_MM7_R_SDA")
	)
	(segment
		(start 60.351162 -37.921438)
		(end 60.995306 -37.654484)
		(width 0.11684)
		(layer "B.Cu")
		(net "SMB_BMC_MM7_R_SDA")
	)
	(segment
		(start 64.1604 -32.73171)
		(end 64.1604 -32.86125)
		(width 0.11684)
		(layer "B.Cu")
		(net "SMB_BMC_MM7_R_SDA")
	)
	(segment
		(start 57.513982 -41.78427)
		(end 57.678828 -41.537128)
		(width 0.11684)
		(layer "B.Cu")
		(net "SMB_BMC_MM7_R_SDA")
	)
	(segment
		(start 63.82766 -31.367984)
		(end 63.71844 -31.477204)
		(width 0.11684)
		(layer "B.Cu")
		(net "SMB_BMC_MM7_R_SDA")
	)
	(segment
		(start 63.71844 -32.40659)
		(end 63.833502 -32.521652)
		(width 0.11684)
		(layer "B.Cu")
		(net "SMB_BMC_MM7_R_SDA")
	)
	(segment
		(start 64.07785 -32.9438)
		(end 64.1604 -32.86125)
		(width 0.11684)
		(layer "B.Cu")
		(net "SMB_BMC_MM7_R_SDA")
	)
	(segment
		(start 63.754 -29.464254)
		(end 63.754 -30.496256)
		(width 0.11684)
		(layer "B.Cu")
		(net "SMB_BMC_MM7_R_SDA")
	)
	(segment
		(start 60.995306 -37.654484)
		(end 62.186058 -36.463732)
		(width 0.11684)
		(layer "B.Cu")
		(net "SMB_BMC_MM7_R_SDA")
	)
	(segment
		(start 63.833502 -32.521652)
		(end 63.950342 -32.521652)
		(width 0.11684)
		(layer "B.Cu")
		(net "SMB_BMC_MM7_R_SDA")
	)
	(segment
		(start 63.610744 -33.531302)
		(end 63.709296 -33.293558)
		(width 0.11684)
		(layer "B.Cu")
		(net "SMB_BMC_MM7_R_SDA")
	)
	(segment
		(start 64.045846 -32.957008)
		(end 64.07785 -32.9438)
		(width 0.11684)
		(layer "B.Cu")
		(net "SMB_BMC_MM7_R_SDA")
	)
	(segment
		(start 62.186058 -36.463732)
		(end 62.488826 -35.73272)
		(width 0.11684)
		(layer "B.Cu")
		(net "SMB_BMC_MM7_R_SDA")
	)
	(segment
		(start 57.678828 -41.537128)
		(end 57.678828 -40.545004)
		(width 0.11684)
		(layer "B.Cu")
		(net "SMB_BMC_MM7_R_SDA")
	)
	(segment
		(start 57.290208 -42.175938)
		(end 57.39511 -42.071036)
		(width 0.11684)
		(layer "B.Cu")
		(net "SMB_BMC_MM7_R_SDA")
	)
	(segment
		(start 57.678828 -40.545004)
		(end 57.769506 -40.326056)
		(width 0.11684)
		(layer "B.Cu")
		(net "SMB_BMC_MM7_R_SDA")
	)
	(segment
		(start 62.488826 -35.73272)
		(end 62.890654 -35.330892)
		(width 0.11684)
		(layer "B.Cu")
		(net "SMB_BMC_MM7_R_SDA")
	)
	(segment
		(start 63.754 -30.496256)
		(end 63.82766 -30.569916)
		(width 0.11684)
		(layer "B.Cu")
		(net "SMB_BMC_MM7_R_SDA")
	)
	(segment
		(start 62.890654 -35.330892)
		(end 63.211964 -34.85007)
		(width 0.11684)
		(layer "B.Cu")
		(net "SMB_BMC_MM7_R_SDA")
	)
	(segment
		(start 64.036194 -29.18206)
		(end 63.754 -29.464254)
		(width 0.11684)
		(layer "B.Cu")
		(net "SMB_BMC_MM7_R_SDA")
	)
	(segment
		(start 63.211964 -34.85007)
		(end 63.4746 -34.215832)
		(width 0.11684)
		(layer "B.Cu")
		(net "SMB_BMC_MM7_R_SDA")
	)
	(segment
		(start 59.942222 -38.330378)
		(end 60.351162 -37.921438)
		(width 0.11684)
		(layer "B.Cu")
		(net "SMB_BMC_MM7_R_SDA")
	)
	(segment
		(start 63.82766 -30.569916)
		(end 63.82766 -31.367984)
		(width 0.11684)
		(layer "B.Cu")
		(net "SMB_BMC_MM7_R_SDA")
	)
	(segment
		(start 63.4746 -34.215832)
		(end 63.610744 -33.531302)
		(width 0.11684)
		(layer "B.Cu")
		(net "SMB_BMC_MM7_R_SDA")
	)
	(segment
		(start 57.39511 -42.071036)
		(end 57.513982 -41.78427)
		(width 0.11684)
		(layer "B.Cu")
		(net "SMB_BMC_MM7_R_SDA")
	)
	(segment
		(start 56.894984 -41.771316)
		(end 57.290208 -41.376092)
		(width 0.11684)
		(layer "F.Cu")
		(net "SMB_BMC_MM7_R_SCL")
	)
	(via
		(at 60.735972 -36.87318)
		(size 0.6604)
		(drill 0.3302)
		(layers "F.Cu" "B.Cu")
		(net "SMB_BMC_MM7_R_SCL")
	)
	(via
		(at 57.290208 -41.376092)
		(size 0.4572)
		(drill 0.254)
		(layers "F.Cu" "B.Cu")
		(net "SMB_BMC_MM7_R_SCL")
	)
	(segment
		(start 62.061852 -35.72764)
		(end 61.850016 -36.239196)
		(width 0.11684)
		(layer "B.Cu")
		(net "SMB_BMC_MM7_R_SCL")
	)
	(segment
		(start 63.3222 -33.191958)
		(end 63.3222 -31.312866)
		(width 0.11684)
		(layer "B.Cu")
		(net "SMB_BMC_MM7_R_SCL")
	)
	(segment
		(start 63.43142 -30.734254)
		(end 63.35776 -30.660594)
		(width 0.11684)
		(layer "B.Cu")
		(net "SMB_BMC_MM7_R_SCL")
	)
	(segment
		(start 63.13805 -33.87598)
		(end 63.13805 -33.636712)
		(width 0.11684)
		(layer "B.Cu")
		(net "SMB_BMC_MM7_R_SCL")
	)
	(segment
		(start 62.442344 -35.037776)
		(end 62.442344 -35.012376)
		(width 0.11684)
		(layer "B.Cu")
		(net "SMB_BMC_MM7_R_SCL")
	)
	(segment
		(start 59.96051 -37.648642)
		(end 59.96051 -37.715444)
		(width 0.11684)
		(layer "B.Cu")
		(net "SMB_BMC_MM7_R_SCL")
	)
	(segment
		(start 60.735972 -36.87318)
		(end 59.96051 -37.648642)
		(width 0.11684)
		(layer "B.Cu")
		(net "SMB_BMC_MM7_R_SCL")
	)
	(segment
		(start 56.884062 -40.969946)
		(end 57.290208 -41.376092)
		(width 0.11684)
		(layer "B.Cu")
		(net "SMB_BMC_MM7_R_SCL")
	)
	(segment
		(start 61.850016 -36.239196)
		(end 61.547502 -36.54171)
		(width 0.11684)
		(layer "B.Cu")
		(net "SMB_BMC_MM7_R_SCL")
	)
	(segment
		(start 62.061852 -35.396932)
		(end 62.061852 -35.72764)
		(width 0.11684)
		(layer "B.Cu")
		(net "SMB_BMC_MM7_R_SCL")
	)
	(segment
		(start 59.96051 -37.715444)
		(end 57.500266 -40.175688)
		(width 0.11684)
		(layer "B.Cu")
		(net "SMB_BMC_MM7_R_SCL")
	)
	(segment
		(start 56.884062 -40.390318)
		(end 56.884062 -40.969946)
		(width 0.11684)
		(layer "B.Cu")
		(net "SMB_BMC_MM7_R_SCL")
	)
	(segment
		(start 63.35776 -29.423106)
		(end 63.014098 -29.079444)
		(width 0.11684)
		(layer "B.Cu")
		(net "SMB_BMC_MM7_R_SCL")
	)
	(segment
		(start 61.547502 -36.54171)
		(end 61.067442 -36.54171)
		(width 0.11684)
		(layer "B.Cu")
		(net "SMB_BMC_MM7_R_SCL")
	)
	(segment
		(start 63.43142 -31.203646)
		(end 63.43142 -30.734254)
		(width 0.11684)
		(layer "B.Cu")
		(net "SMB_BMC_MM7_R_SCL")
	)
	(segment
		(start 63.3222 -31.312866)
		(end 63.43142 -31.203646)
		(width 0.11684)
		(layer "B.Cu")
		(net "SMB_BMC_MM7_R_SCL")
	)
	(segment
		(start 57.098692 -40.175688)
		(end 56.884062 -40.390318)
		(width 0.11684)
		(layer "B.Cu")
		(net "SMB_BMC_MM7_R_SCL")
	)
	(segment
		(start 62.826646 -34.628074)
		(end 63.13805 -33.87598)
		(width 0.11684)
		(layer "B.Cu")
		(net "SMB_BMC_MM7_R_SCL")
	)
	(segment
		(start 57.500266 -40.175688)
		(end 57.098692 -40.175688)
		(width 0.11684)
		(layer "B.Cu")
		(net "SMB_BMC_MM7_R_SCL")
	)
	(segment
		(start 62.421008 -35.037776)
		(end 62.061852 -35.396932)
		(width 0.11684)
		(layer "B.Cu")
		(net "SMB_BMC_MM7_R_SCL")
	)
	(segment
		(start 63.35776 -30.660594)
		(end 63.35776 -29.423106)
		(width 0.11684)
		(layer "B.Cu")
		(net "SMB_BMC_MM7_R_SCL")
	)
	(segment
		(start 61.067442 -36.54171)
		(end 60.735972 -36.87318)
		(width 0.11684)
		(layer "B.Cu")
		(net "SMB_BMC_MM7_R_SCL")
	)
	(segment
		(start 62.442344 -35.037776)
		(end 62.421008 -35.037776)
		(width 0.11684)
		(layer "B.Cu")
		(net "SMB_BMC_MM7_R_SCL")
	)
	(segment
		(start 63.014098 -29.079444)
		(end 63.014098 -28.756356)
		(width 0.11684)
		(layer "B.Cu")
		(net "SMB_BMC_MM7_R_SCL")
	)
	(segment
		(start 62.442344 -35.012376)
		(end 62.826646 -34.628074)
		(width 0.11684)
		(layer "B.Cu")
		(net "SMB_BMC_MM7_R_SCL")
	)
	(segment
		(start 63.13805 -33.636712)
		(end 63.3222 -33.191958)
		(width 0.11684)
		(layer "B.Cu")
		(net "SMB_BMC_MM7_R_SCL")
	)
	(via
		(at 58.252868 -32.82696)
		(size 0.508)
		(drill 0.254)
		(layers "F.Cu" "B.Cu")
		(net "SMB_BMC_MM6_SDA")
	)
	(via
		(at 48.218852 -110.46714)
		(size 0.508)
		(drill 0.254)
		(layers "F.Cu" "B.Cu")
		(net "SMB_BMC_MM6_SDA")
	)
	(segment
		(start 49.665128 -116.581682)
		(end 49.7078 -116.53901)
		(width 0.11684)
		(layer "B.Cu")
		(net "SMB_BMC_MM6_SDA")
	)
	(segment
		(start 49.7078 -116.53901)
		(end 49.7078 -114.5286)
		(width 0.11684)
		(layer "B.Cu")
		(net "SMB_BMC_MM6_SDA")
	)
	(segment
		(start 49.665128 -118.25986)
		(end 49.665128 -116.581682)
		(width 0.11684)
		(layer "B.Cu")
		(net "SMB_BMC_MM6_SDA")
	)
	(segment
		(start 58.252868 -32.82696)
		(end 58.7502 -33.324292)
		(width 0.11684)
		(layer "B.Cu")
		(net "SMB_BMC_MM6_SDA")
	)
	(segment
		(start 58.547 -34.2646)
		(end 58.547 -34.27095)
		(width 0.11684)
		(layer "B.Cu")
		(net "SMB_BMC_MM6_SDA")
	)
	(segment
		(start 49.7078 -114.5286)
		(end 48.218852 -113.039652)
		(width 0.11684)
		(layer "B.Cu")
		(net "SMB_BMC_MM6_SDA")
	)
	(segment
		(start 58.7502 -33.324292)
		(end 58.7502 -34.0614)
		(width 0.11684)
		(layer "B.Cu")
		(net "SMB_BMC_MM6_SDA")
	)
	(segment
		(start 48.218852 -113.039652)
		(end 48.218852 -110.46714)
		(width 0.11684)
		(layer "B.Cu")
		(net "SMB_BMC_MM6_SDA")
	)
	(segment
		(start 58.7502 -34.0614)
		(end 58.547 -34.2646)
		(width 0.11684)
		(layer "B.Cu")
		(net "SMB_BMC_MM6_SDA")
	)
	(segment
		(start 57.75198 -31.267654)
		(end 57.75198 -32.326072)
		(width 0.11684)
		(layer "B.Cu")
		(net "SMB_BMC_MM6_SDA")
	)
	(segment
		(start 57.75198 -32.326072)
		(end 58.252868 -32.82696)
		(width 0.11684)
		(layer "B.Cu")
		(net "SMB_BMC_MM6_SDA")
	)
	(segment
		(start 46.2915 -110.71606)
		(end 47.969932 -110.71606)
		(width 0.10668)
		(layer "In7.Cu")
		(net "SMB_BMC_MM6_SDA")
	)
	(segment
		(start 54.446678 -31.31566)
		(end 51.862736 -28.731718)
		(width 0.10668)
		(layer "In7.Cu")
		(net "SMB_BMC_MM6_SDA")
	)
	(segment
		(start 22.123654 -43.677586)
		(end 21.23694 -45.818298)
		(width 0.10668)
		(layer "In7.Cu")
		(net "SMB_BMC_MM6_SDA")
	)
	(segment
		(start 31.110428 -30.306518)
		(end 31.050992 -30.306518)
		(width 0.10668)
		(layer "In7.Cu")
		(net "SMB_BMC_MM6_SDA")
	)
	(segment
		(start 31.549086 -29.86786)
		(end 31.110428 -30.306518)
		(width 0.10668)
		(layer "In7.Cu")
		(net "SMB_BMC_MM6_SDA")
	)
	(segment
		(start 40.93972 -102.069392)
		(end 40.93972 -103.15448)
		(width 0.10668)
		(layer "In7.Cu")
		(net "SMB_BMC_MM6_SDA")
	)
	(segment
		(start 22.60346 -65.39865)
		(end 22.60346 -67.331082)
		(width 0.10668)
		(layer "In7.Cu")
		(net "SMB_BMC_MM6_SDA")
	)
	(segment
		(start 22.73046 -64.4271)
		(end 22.7584 -64.45504)
		(width 0.10668)
		(layer "In7.Cu")
		(net "SMB_BMC_MM6_SDA")
	)
	(segment
		(start 26.03754 -75.9079)
		(end 26.037286 -75.908154)
		(width 0.10668)
		(layer "In7.Cu")
		(net "SMB_BMC_MM6_SDA")
	)
	(segment
		(start 57.50306 -31.31566)
		(end 54.446678 -31.31566)
		(width 0.10668)
		(layer "In7.Cu")
		(net "SMB_BMC_MM6_SDA")
	)
	(segment
		(start 22.60346 -67.331082)
		(end 22.44598 -67.488562)
		(width 0.10668)
		(layer "In7.Cu")
		(net "SMB_BMC_MM6_SDA")
	)
	(segment
		(start 28.16098 -80.589628)
		(end 29.319474 -81.748122)
		(width 0.10668)
		(layer "In7.Cu")
		(net "SMB_BMC_MM6_SDA")
	)
	(segment
		(start 26.037286 -75.908154)
		(end 26.037286 -76.185522)
		(width 0.10668)
		(layer "In7.Cu")
		(net "SMB_BMC_MM6_SDA")
	)
	(segment
		(start 22.7584 -63.034418)
		(end 22.7584 -64.01816)
		(width 0.10668)
		(layer "In7.Cu")
		(net "SMB_BMC_MM6_SDA")
	)
	(segment
		(start 21.23694 -48.59528)
		(end 20.3454 -49.48682)
		(width 0.10668)
		(layer "In7.Cu")
		(net "SMB_BMC_MM6_SDA")
	)
	(segment
		(start 30.179264 -32.114998)
		(end 29.668724 -32.625538)
		(width 0.10668)
		(layer "In7.Cu")
		(net "SMB_BMC_MM6_SDA")
	)
	(segment
		(start 25.23363 -74.11466)
		(end 25.7683 -74.11466)
		(width 0.10668)
		(layer "In7.Cu")
		(net "SMB_BMC_MM6_SDA")
	)
	(segment
		(start 57.7342 -31.5468)
		(end 57.50306 -31.31566)
		(width 0.10668)
		(layer "In7.Cu")
		(net "SMB_BMC_MM6_SDA")
	)
	(segment
		(start 49.5046 -27.059382)
		(end 49.5046 -25.5016)
		(width 0.10668)
		(layer "In7.Cu")
		(net "SMB_BMC_MM6_SDA")
	)
	(segment
		(start 39.11219 -100.241862)
		(end 40.93972 -102.069392)
		(width 0.10668)
		(layer "In7.Cu")
		(net "SMB_BMC_MM6_SDA")
	)
	(segment
		(start 22.70252 -62.978538)
		(end 22.7584 -63.034418)
		(width 0.10668)
		(layer "In7.Cu")
		(net "SMB_BMC_MM6_SDA")
	)
	(segment
		(start 34.43224 -93.190568)
		(end 34.43224 -96.1263)
		(width 0.10668)
		(layer "In7.Cu")
		(net "SMB_BMC_MM6_SDA")
	)
	(segment
		(start 45.212 -24.1554)
		(end 43.7642 -22.7076)
		(width 0.10668)
		(layer "In7.Cu")
		(net "SMB_BMC_MM6_SDA")
	)
	(segment
		(start 28.93568 -36.283138)
		(end 27.26944 -37.949378)
		(width 0.10668)
		(layer "In7.Cu")
		(net "SMB_BMC_MM6_SDA")
	)
	(segment
		(start 26.03754 -76.185776)
		(end 26.03754 -76.42225)
		(width 0.10668)
		(layer "In7.Cu")
		(net "SMB_BMC_MM6_SDA")
	)
	(segment
		(start 42.926 -105.14076)
		(end 42.926 -107.2134)
		(width 0.10668)
		(layer "In7.Cu")
		(net "SMB_BMC_MM6_SDA")
	)
	(segment
		(start 28.16098 -77.954886)
		(end 28.16098 -80.589628)
		(width 0.10668)
		(layer "In7.Cu")
		(net "SMB_BMC_MM6_SDA")
	)
	(segment
		(start 40.1574 -22.7076)
		(end 38.8112 -24.0538)
		(width 0.10668)
		(layer "In7.Cu")
		(net "SMB_BMC_MM6_SDA")
	)
	(segment
		(start 30.51556 -84.02193)
		(end 30.51556 -86.13013)
		(width 0.10668)
		(layer "In7.Cu")
		(net "SMB_BMC_MM6_SDA")
	)
	(segment
		(start 34.43224 -96.1263)
		(end 38.547802 -100.241862)
		(width 0.10668)
		(layer "In7.Cu")
		(net "SMB_BMC_MM6_SDA")
	)
	(segment
		(start 29.31922 -82.025744)
		(end 29.31922 -82.82559)
		(width 0.10668)
		(layer "In7.Cu")
		(net "SMB_BMC_MM6_SDA")
	)
	(segment
		(start 40.93972 -103.15448)
		(end 42.926 -105.14076)
		(width 0.10668)
		(layer "In7.Cu")
		(net "SMB_BMC_MM6_SDA")
	)
	(segment
		(start 45.67682 -109.36732)
		(end 45.931328 -109.36732)
		(width 0.10668)
		(layer "In7.Cu")
		(net "SMB_BMC_MM6_SDA")
	)
	(segment
		(start 51.176936 -28.731718)
		(end 49.5046 -27.059382)
		(width 0.10668)
		(layer "In7.Cu")
		(net "SMB_BMC_MM6_SDA")
	)
	(segment
		(start 51.862736 -28.731718)
		(end 51.176936 -28.731718)
		(width 0.10668)
		(layer "In7.Cu")
		(net "SMB_BMC_MM6_SDA")
	)
	(segment
		(start 29.668724 -32.625538)
		(end 28.93568 -34.395156)
		(width 0.10668)
		(layer "In7.Cu")
		(net "SMB_BMC_MM6_SDA")
	)
	(segment
		(start 45.496734 -110.535974)
		(end 45.496734 -109.547406)
		(width 0.10668)
		(layer "In7.Cu")
		(net "SMB_BMC_MM6_SDA")
	)
	(segment
		(start 41.46169 -108.67771)
		(end 41.46169 -110.08233)
		(width 0.10668)
		(layer "In7.Cu")
		(net "SMB_BMC_MM6_SDA")
	)
	(segment
		(start 31.29661 -86.91118)
		(end 32.079692 -86.91118)
		(width 0.10668)
		(layer "In7.Cu")
		(net "SMB_BMC_MM6_SDA")
	)
	(segment
		(start 45.931328 -109.36732)
		(end 46.111414 -109.547406)
		(width 0.10668)
		(layer "In7.Cu")
		(net "SMB_BMC_MM6_SDA")
	)
	(segment
		(start 43.7642 -22.7076)
		(end 40.1574 -22.7076)
		(width 0.10668)
		(layer "In7.Cu")
		(net "SMB_BMC_MM6_SDA")
	)
	(segment
		(start 25.7683 -74.11466)
		(end 26.03754 -74.3839)
		(width 0.10668)
		(layer "In7.Cu")
		(net "SMB_BMC_MM6_SDA")
	)
	(segment
		(start 21.23694 -45.818298)
		(end 21.23694 -48.59528)
		(width 0.10668)
		(layer "In7.Cu")
		(net "SMB_BMC_MM6_SDA")
	)
	(segment
		(start 30.912562 -25.666192)
		(end 30.08503 -26.493724)
		(width 0.10668)
		(layer "In7.Cu")
		(net "SMB_BMC_MM6_SDA")
	)
	(segment
		(start 22.7584 -64.01816)
		(end 22.73046 -64.0461)
		(width 0.10668)
		(layer "In7.Cu")
		(net "SMB_BMC_MM6_SDA")
	)
	(segment
		(start 42.926 -107.2134)
		(end 41.46169 -108.67771)
		(width 0.10668)
		(layer "In7.Cu")
		(net "SMB_BMC_MM6_SDA")
	)
	(segment
		(start 38.547802 -100.241862)
		(end 39.11219 -100.241862)
		(width 0.10668)
		(layer "In7.Cu")
		(net "SMB_BMC_MM6_SDA")
	)
	(segment
		(start 35.41014 -24.0538)
		(end 33.797748 -25.666192)
		(width 0.10668)
		(layer "In7.Cu")
		(net "SMB_BMC_MM6_SDA")
	)
	(segment
		(start 29.31922 -82.82559)
		(end 30.51556 -84.02193)
		(width 0.10668)
		(layer "In7.Cu")
		(net "SMB_BMC_MM6_SDA")
	)
	(segment
		(start 33.32226 -92.080588)
		(end 34.43224 -93.190568)
		(width 0.10668)
		(layer "In7.Cu")
		(net "SMB_BMC_MM6_SDA")
	)
	(segment
		(start 31.549086 -29.427678)
		(end 31.549086 -29.86786)
		(width 0.10668)
		(layer "In7.Cu")
		(net "SMB_BMC_MM6_SDA")
	)
	(segment
		(start 58.252868 -32.675068)
		(end 57.7342 -32.1564)
		(width 0.10668)
		(layer "In7.Cu")
		(net "SMB_BMC_MM6_SDA")
	)
	(segment
		(start 26.037286 -76.185522)
		(end 26.03754 -76.185776)
		(width 0.10668)
		(layer "In7.Cu")
		(net "SMB_BMC_MM6_SDA")
	)
	(segment
		(start 22.7584 -65.24371)
		(end 22.60346 -65.39865)
		(width 0.10668)
		(layer "In7.Cu")
		(net "SMB_BMC_MM6_SDA")
	)
	(segment
		(start 26.70937 -77.09408)
		(end 26.981658 -77.09408)
		(width 0.10668)
		(layer "In7.Cu")
		(net "SMB_BMC_MM6_SDA")
	)
	(segment
		(start 41.46169 -110.08233)
		(end 42.09542 -110.71606)
		(width 0.10668)
		(layer "In7.Cu")
		(net "SMB_BMC_MM6_SDA")
	)
	(segment
		(start 46.111414 -109.547406)
		(end 46.111414 -110.535974)
		(width 0.10668)
		(layer "In7.Cu")
		(net "SMB_BMC_MM6_SDA")
	)
	(segment
		(start 38.8112 -24.0538)
		(end 35.41014 -24.0538)
		(width 0.10668)
		(layer "In7.Cu")
		(net "SMB_BMC_MM6_SDA")
	)
	(segment
		(start 20.3454 -49.48682)
		(end 20.3454 -50.199036)
		(width 0.10668)
		(layer "In7.Cu")
		(net "SMB_BMC_MM6_SDA")
	)
	(segment
		(start 26.981658 -77.09408)
		(end 27.525472 -77.319378)
		(width 0.10668)
		(layer "In7.Cu")
		(net "SMB_BMC_MM6_SDA")
	)
	(segment
		(start 30.51556 -86.13013)
		(end 31.29661 -86.91118)
		(width 0.10668)
		(layer "In7.Cu")
		(net "SMB_BMC_MM6_SDA")
	)
	(segment
		(start 27.26944 -38.5318)
		(end 22.123654 -43.677586)
		(width 0.10668)
		(layer "In7.Cu")
		(net "SMB_BMC_MM6_SDA")
	)
	(segment
		(start 30.179264 -31.178246)
		(end 30.179264 -32.114998)
		(width 0.10668)
		(layer "In7.Cu")
		(net "SMB_BMC_MM6_SDA")
	)
	(segment
		(start 32.39262 -87.224108)
		(end 32.39262 -90.297508)
		(width 0.10668)
		(layer "In7.Cu")
		(net "SMB_BMC_MM6_SDA")
	)
	(segment
		(start 26.03754 -74.3839)
		(end 26.03754 -75.9079)
		(width 0.10668)
		(layer "In7.Cu")
		(net "SMB_BMC_MM6_SDA")
	)
	(segment
		(start 33.797748 -25.666192)
		(end 30.912562 -25.666192)
		(width 0.10668)
		(layer "In7.Cu")
		(net "SMB_BMC_MM6_SDA")
	)
	(segment
		(start 20.3454 -50.199036)
		(end 20.60448 -50.824638)
		(width 0.10668)
		(layer "In7.Cu")
		(net "SMB_BMC_MM6_SDA")
	)
	(segment
		(start 22.70252 -59.346084)
		(end 22.70252 -62.978538)
		(width 0.10668)
		(layer "In7.Cu")
		(net "SMB_BMC_MM6_SDA")
	)
	(segment
		(start 30.08503 -26.493724)
		(end 30.08503 -27.963622)
		(width 0.10668)
		(layer "In7.Cu")
		(net "SMB_BMC_MM6_SDA")
	)
	(segment
		(start 48.1584 -24.1554)
		(end 45.212 -24.1554)
		(width 0.10668)
		(layer "In7.Cu")
		(net "SMB_BMC_MM6_SDA")
	)
	(segment
		(start 26.03754 -76.42225)
		(end 26.70937 -77.09408)
		(width 0.10668)
		(layer "In7.Cu")
		(net "SMB_BMC_MM6_SDA")
	)
	(segment
		(start 22.44598 -67.488562)
		(end 22.44598 -70.98538)
		(width 0.10668)
		(layer "In7.Cu")
		(net "SMB_BMC_MM6_SDA")
	)
	(segment
		(start 42.09542 -110.71606)
		(end 45.316648 -110.71606)
		(width 0.10668)
		(layer "In7.Cu")
		(net "SMB_BMC_MM6_SDA")
	)
	(segment
		(start 49.5046 -25.5016)
		(end 48.1584 -24.1554)
		(width 0.10668)
		(layer "In7.Cu")
		(net "SMB_BMC_MM6_SDA")
	)
	(segment
		(start 57.7342 -32.1564)
		(end 57.7342 -31.5468)
		(width 0.10668)
		(layer "In7.Cu")
		(net "SMB_BMC_MM6_SDA")
	)
	(segment
		(start 20.60448 -57.248044)
		(end 22.70252 -59.346084)
		(width 0.10668)
		(layer "In7.Cu")
		(net "SMB_BMC_MM6_SDA")
	)
	(segment
		(start 22.7584 -64.45504)
		(end 22.7584 -65.24371)
		(width 0.10668)
		(layer "In7.Cu")
		(net "SMB_BMC_MM6_SDA")
	)
	(segment
		(start 45.316648 -110.71606)
		(end 45.496734 -110.535974)
		(width 0.10668)
		(layer "In7.Cu")
		(net "SMB_BMC_MM6_SDA")
	)
	(segment
		(start 31.050992 -30.306518)
		(end 30.179264 -31.178246)
		(width 0.10668)
		(layer "In7.Cu")
		(net "SMB_BMC_MM6_SDA")
	)
	(segment
		(start 27.26944 -37.949378)
		(end 27.26944 -38.5318)
		(width 0.10668)
		(layer "In7.Cu")
		(net "SMB_BMC_MM6_SDA")
	)
	(segment
		(start 46.111414 -110.535974)
		(end 46.2915 -110.71606)
		(width 0.10668)
		(layer "In7.Cu")
		(net "SMB_BMC_MM6_SDA")
	)
	(segment
		(start 32.39262 -90.297508)
		(end 33.32226 -91.227148)
		(width 0.10668)
		(layer "In7.Cu")
		(net "SMB_BMC_MM6_SDA")
	)
	(segment
		(start 47.969932 -110.71606)
		(end 48.218852 -110.46714)
		(width 0.10668)
		(layer "In7.Cu")
		(net "SMB_BMC_MM6_SDA")
	)
	(segment
		(start 33.32226 -91.227148)
		(end 33.32226 -92.080588)
		(width 0.10668)
		(layer "In7.Cu")
		(net "SMB_BMC_MM6_SDA")
	)
	(segment
		(start 27.525472 -77.319378)
		(end 28.16098 -77.954886)
		(width 0.10668)
		(layer "In7.Cu")
		(net "SMB_BMC_MM6_SDA")
	)
	(segment
		(start 22.90318 -71.78421)
		(end 25.23363 -74.11466)
		(width 0.10668)
		(layer "In7.Cu")
		(net "SMB_BMC_MM6_SDA")
	)
	(segment
		(start 29.319474 -81.748122)
		(end 29.319474 -82.02549)
		(width 0.10668)
		(layer "In7.Cu")
		(net "SMB_BMC_MM6_SDA")
	)
	(segment
		(start 58.252868 -32.82696)
		(end 58.252868 -32.675068)
		(width 0.10668)
		(layer "In7.Cu")
		(net "SMB_BMC_MM6_SDA")
	)
	(segment
		(start 22.73046 -64.0461)
		(end 22.73046 -64.4271)
		(width 0.10668)
		(layer "In7.Cu")
		(net "SMB_BMC_MM6_SDA")
	)
	(segment
		(start 20.60448 -50.824638)
		(end 20.60448 -57.248044)
		(width 0.10668)
		(layer "In7.Cu")
		(net "SMB_BMC_MM6_SDA")
	)
	(segment
		(start 22.44598 -70.98538)
		(end 22.90318 -71.44258)
		(width 0.10668)
		(layer "In7.Cu")
		(net "SMB_BMC_MM6_SDA")
	)
	(segment
		(start 29.319474 -82.02549)
		(end 29.31922 -82.025744)
		(width 0.10668)
		(layer "In7.Cu")
		(net "SMB_BMC_MM6_SDA")
	)
	(segment
		(start 45.496734 -109.547406)
		(end 45.67682 -109.36732)
		(width 0.10668)
		(layer "In7.Cu")
		(net "SMB_BMC_MM6_SDA")
	)
	(segment
		(start 30.08503 -27.963622)
		(end 31.549086 -29.427678)
		(width 0.10668)
		(layer "In7.Cu")
		(net "SMB_BMC_MM6_SDA")
	)
	(segment
		(start 28.93568 -34.395156)
		(end 28.93568 -36.283138)
		(width 0.10668)
		(layer "In7.Cu")
		(net "SMB_BMC_MM6_SDA")
	)
	(segment
		(start 22.90318 -71.44258)
		(end 22.90318 -71.78421)
		(width 0.10668)
		(layer "In7.Cu")
		(net "SMB_BMC_MM6_SDA")
	)
	(segment
		(start 32.079692 -86.91118)
		(end 32.39262 -87.224108)
		(width 0.10668)
		(layer "In7.Cu")
		(net "SMB_BMC_MM6_SDA")
	)
	(via
		(at 59.311794 -32.916876)
		(size 0.762)
		(drill 0.254)
		(layers "F.Cu" "B.Cu")
		(net "SMB_BMC_MM6_SCL")
	)
	(via
		(at 48.200564 -109.7407)
		(size 0.508)
		(drill 0.254)
		(layers "F.Cu" "B.Cu")
		(net "SMB_BMC_MM6_SCL")
	)
	(segment
		(start 59.311794 -32.916876)
		(end 59.362594 -32.916876)
		(width 0.11684)
		(layer "B.Cu")
		(net "SMB_BMC_MM6_SCL")
	)
	(segment
		(start 59.182 -31.670244)
		(end 59.182 -32.736282)
		(width 0.11684)
		(layer "B.Cu")
		(net "SMB_BMC_MM6_SCL")
	)
	(segment
		(start 50.265076 -117.168676)
		(end 50.265076 -118.25986)
		(width 0.11684)
		(layer "B.Cu")
		(net "SMB_BMC_MM6_SCL")
	)
	(segment
		(start 59.311794 -32.866076)
		(end 59.311794 -32.916876)
		(width 0.11684)
		(layer "B.Cu")
		(net "SMB_BMC_MM6_SCL")
	)
	(segment
		(start 48.7426 -112.954054)
		(end 50.1396 -114.351054)
		(width 0.11684)
		(layer "B.Cu")
		(net "SMB_BMC_MM6_SCL")
	)
	(segment
		(start 59.182 -32.736282)
		(end 59.311794 -32.866076)
		(width 0.11684)
		(layer "B.Cu")
		(net "SMB_BMC_MM6_SCL")
	)
	(segment
		(start 58.77941 -31.267654)
		(end 59.182 -31.670244)
		(width 0.11684)
		(layer "B.Cu")
		(net "SMB_BMC_MM6_SCL")
	)
	(segment
		(start 59.362594 -32.916876)
		(end 59.798204 -33.352486)
		(width 0.11684)
		(layer "B.Cu")
		(net "SMB_BMC_MM6_SCL")
	)
	(segment
		(start 59.563 -34.27095)
		(end 59.563 -34.32175)
		(width 0.11684)
		(layer "B.Cu")
		(net "SMB_BMC_MM6_SCL")
	)
	(segment
		(start 48.200564 -109.7407)
		(end 48.7426 -110.282736)
		(width 0.11684)
		(layer "B.Cu")
		(net "SMB_BMC_MM6_SCL")
	)
	(segment
		(start 50.1396 -114.351054)
		(end 50.1396 -117.0432)
		(width 0.11684)
		(layer "B.Cu")
		(net "SMB_BMC_MM6_SCL")
	)
	(segment
		(start 50.1396 -117.0432)
		(end 50.265076 -117.168676)
		(width 0.11684)
		(layer "B.Cu")
		(net "SMB_BMC_MM6_SCL")
	)
	(segment
		(start 59.798204 -34.035746)
		(end 59.563 -34.27095)
		(width 0.11684)
		(layer "B.Cu")
		(net "SMB_BMC_MM6_SCL")
	)
	(segment
		(start 59.798204 -33.352486)
		(end 59.798204 -34.035746)
		(width 0.11684)
		(layer "B.Cu")
		(net "SMB_BMC_MM6_SCL")
	)
	(segment
		(start 48.7426 -110.282736)
		(end 48.7426 -112.954054)
		(width 0.11684)
		(layer "B.Cu")
		(net "SMB_BMC_MM6_SCL")
	)
	(segment
		(start 29.69768 -26.370788)
		(end 30.771846 -25.296622)
		(width 0.10668)
		(layer "In7.Cu")
		(net "SMB_BMC_MM6_SCL")
	)
	(segment
		(start 28.98394 -81.886806)
		(end 27.8257 -80.728566)
		(width 0.10668)
		(layer "In7.Cu")
		(net "SMB_BMC_MM6_SCL")
	)
	(segment
		(start 48.6918 -110.231936)
		(end 48.6918 -110.6932)
		(width 0.10668)
		(layer "In7.Cu")
		(net "SMB_BMC_MM6_SCL")
	)
	(segment
		(start 26.914856 -77.42936)
		(end 26.570432 -77.42936)
		(width 0.10668)
		(layer "In7.Cu")
		(net "SMB_BMC_MM6_SCL")
	)
	(segment
		(start 32.98698 -91.366086)
		(end 32.05734 -90.436446)
		(width 0.10668)
		(layer "In7.Cu")
		(net "SMB_BMC_MM6_SCL")
	)
	(segment
		(start 58.06948 -31.407862)
		(end 58.06948 -31.993332)
		(width 0.10668)
		(layer "In7.Cu")
		(net "SMB_BMC_MM6_SCL")
	)
	(segment
		(start 54.67858 -30.98038)
		(end 57.641998 -30.98038)
		(width 0.10668)
		(layer "In7.Cu")
		(net "SMB_BMC_MM6_SCL")
	)
	(segment
		(start 25.11806 -74.473308)
		(end 22.5679 -71.923148)
		(width 0.10668)
		(layer "In7.Cu")
		(net "SMB_BMC_MM6_SCL")
	)
	(segment
		(start 22.5679 -71.923148)
		(end 22.5679 -71.581518)
		(width 0.10668)
		(layer "In7.Cu")
		(net "SMB_BMC_MM6_SCL")
	)
	(segment
		(start 27.8257 -78.093824)
		(end 27.33548 -77.603604)
		(width 0.10668)
		(layer "In7.Cu")
		(net "SMB_BMC_MM6_SCL")
	)
	(segment
		(start 48.5394 -23.7744)
		(end 49.8856 -25.1206)
		(width 0.10668)
		(layer "In7.Cu")
		(net "SMB_BMC_MM6_SCL")
	)
	(segment
		(start 19.9898 -50.287682)
		(end 19.9898 -48.543972)
		(width 0.10668)
		(layer "In7.Cu")
		(net "SMB_BMC_MM6_SCL")
	)
	(segment
		(start 38.408864 -100.577142)
		(end 34.09696 -96.265238)
		(width 0.10668)
		(layer "In7.Cu")
		(net "SMB_BMC_MM6_SCL")
	)
	(segment
		(start 34.09696 -93.329506)
		(end 32.98698 -92.219526)
		(width 0.10668)
		(layer "In7.Cu")
		(net "SMB_BMC_MM6_SCL")
	)
	(segment
		(start 33.481518 -25.296622)
		(end 35.10534 -23.6728)
		(width 0.10668)
		(layer "In7.Cu")
		(net "SMB_BMC_MM6_SCL")
	)
	(segment
		(start 22.1107 -67.349624)
		(end 22.26818 -67.192144)
		(width 0.10668)
		(layer "In7.Cu")
		(net "SMB_BMC_MM6_SCL")
	)
	(segment
		(start 29.69768 -28.40355)
		(end 29.69768 -26.370788)
		(width 0.10668)
		(layer "In7.Cu")
		(net "SMB_BMC_MM6_SCL")
	)
	(segment
		(start 42.022522 -111.11738)
		(end 41.12641 -110.221268)
		(width 0.10668)
		(layer "In7.Cu")
		(net "SMB_BMC_MM6_SCL")
	)
	(segment
		(start 58.942224 -32.866076)
		(end 59.260994 -32.866076)
		(width 0.10668)
		(layer "In7.Cu")
		(net "SMB_BMC_MM6_SCL")
	)
	(segment
		(start 48.26762 -111.11738)
		(end 42.022522 -111.11738)
		(width 0.10668)
		(layer "In7.Cu")
		(net "SMB_BMC_MM6_SCL")
	)
	(segment
		(start 22.26818 -65.259712)
		(end 22.42312 -65.104772)
		(width 0.10668)
		(layer "In7.Cu")
		(net "SMB_BMC_MM6_SCL")
	)
	(segment
		(start 22.36724 -63.117476)
		(end 22.36724 -61.076586)
		(width 0.10668)
		(layer "In7.Cu")
		(net "SMB_BMC_MM6_SCL")
	)
	(segment
		(start 34.09696 -96.265238)
		(end 34.09696 -93.329506)
		(width 0.10668)
		(layer "In7.Cu")
		(net "SMB_BMC_MM6_SCL")
	)
	(segment
		(start 26.93416 -38.38321)
		(end 26.93416 -37.81044)
		(width 0.10668)
		(layer "In7.Cu")
		(net "SMB_BMC_MM6_SCL")
	)
	(segment
		(start 21.846032 -43.471338)
		(end 26.93416 -38.38321)
		(width 0.10668)
		(layer "In7.Cu")
		(net "SMB_BMC_MM6_SCL")
	)
	(segment
		(start 29.9974 -30.885892)
		(end 29.9974 -28.70327)
		(width 0.10668)
		(layer "In7.Cu")
		(net "SMB_BMC_MM6_SCL")
	)
	(segment
		(start 27.33548 -77.603604)
		(end 26.914856 -77.42936)
		(width 0.10668)
		(layer "In7.Cu")
		(net "SMB_BMC_MM6_SCL")
	)
	(segment
		(start 29.843984 -31.97606)
		(end 29.843984 -31.039308)
		(width 0.10668)
		(layer "In7.Cu")
		(net "SMB_BMC_MM6_SCL")
	)
	(segment
		(start 22.42312 -64.593978)
		(end 22.39518 -64.566038)
		(width 0.10668)
		(layer "In7.Cu")
		(net "SMB_BMC_MM6_SCL")
	)
	(segment
		(start 22.42312 -63.173356)
		(end 22.36724 -63.117476)
		(width 0.10668)
		(layer "In7.Cu")
		(net "SMB_BMC_MM6_SCL")
	)
	(segment
		(start 51.121818 -28.202382)
		(end 51.807618 -28.202382)
		(width 0.10668)
		(layer "In7.Cu")
		(net "SMB_BMC_MM6_SCL")
	)
	(segment
		(start 28.6004 -36.1442)
		(end 28.6004 -34.301684)
		(width 0.10668)
		(layer "In7.Cu")
		(net "SMB_BMC_MM6_SCL")
	)
	(segment
		(start 58.06948 -31.993332)
		(end 58.942224 -32.866076)
		(width 0.10668)
		(layer "In7.Cu")
		(net "SMB_BMC_MM6_SCL")
	)
	(segment
		(start 48.200564 -109.7407)
		(end 48.6918 -110.231936)
		(width 0.10668)
		(layer "In7.Cu")
		(net "SMB_BMC_MM6_SCL")
	)
	(segment
		(start 35.10534 -23.6728)
		(end 38.6334 -23.6728)
		(width 0.10668)
		(layer "In7.Cu")
		(net "SMB_BMC_MM6_SCL")
	)
	(segment
		(start 30.771846 -25.296622)
		(end 33.481518 -25.296622)
		(width 0.10668)
		(layer "In7.Cu")
		(net "SMB_BMC_MM6_SCL")
	)
	(segment
		(start 49.8856 -26.966164)
		(end 51.121818 -28.202382)
		(width 0.10668)
		(layer "In7.Cu")
		(net "SMB_BMC_MM6_SCL")
	)
	(segment
		(start 20.90166 -45.750988)
		(end 21.846032 -43.471338)
		(width 0.10668)
		(layer "In7.Cu")
		(net "SMB_BMC_MM6_SCL")
	)
	(segment
		(start 43.9928 -22.3012)
		(end 45.466 -23.7744)
		(width 0.10668)
		(layer "In7.Cu")
		(net "SMB_BMC_MM6_SCL")
	)
	(segment
		(start 22.1107 -71.124318)
		(end 22.1107 -67.349624)
		(width 0.10668)
		(layer "In7.Cu")
		(net "SMB_BMC_MM6_SCL")
	)
	(segment
		(start 30.18028 -86.291674)
		(end 30.18028 -84.160868)
		(width 0.10668)
		(layer "In7.Cu")
		(net "SMB_BMC_MM6_SCL")
	)
	(segment
		(start 40.60444 -103.293418)
		(end 40.60444 -102.20833)
		(width 0.10668)
		(layer "In7.Cu")
		(net "SMB_BMC_MM6_SCL")
	)
	(segment
		(start 30.18028 -84.160868)
		(end 28.98394 -82.964528)
		(width 0.10668)
		(layer "In7.Cu")
		(net "SMB_BMC_MM6_SCL")
	)
	(segment
		(start 26.93416 -37.81044)
		(end 28.6004 -36.1442)
		(width 0.10668)
		(layer "In7.Cu")
		(net "SMB_BMC_MM6_SCL")
	)
	(segment
		(start 57.641998 -30.98038)
		(end 58.06948 -31.407862)
		(width 0.10668)
		(layer "In7.Cu")
		(net "SMB_BMC_MM6_SCL")
	)
	(segment
		(start 40.005 -22.3012)
		(end 43.9928 -22.3012)
		(width 0.10668)
		(layer "In7.Cu")
		(net "SMB_BMC_MM6_SCL")
	)
	(segment
		(start 20.2692 -57.556146)
		(end 20.2692 -50.96256)
		(width 0.10668)
		(layer "In7.Cu")
		(net "SMB_BMC_MM6_SCL")
	)
	(segment
		(start 49.8856 -25.1206)
		(end 49.8856 -26.966164)
		(width 0.10668)
		(layer "In7.Cu")
		(net "SMB_BMC_MM6_SCL")
	)
	(segment
		(start 54.2036 -30.5054)
		(end 54.67858 -30.98038)
		(width 0.10668)
		(layer "In7.Cu")
		(net "SMB_BMC_MM6_SCL")
	)
	(segment
		(start 22.39518 -64.566038)
		(end 22.39518 -63.907162)
		(width 0.10668)
		(layer "In7.Cu")
		(net "SMB_BMC_MM6_SCL")
	)
	(segment
		(start 59.260994 -32.866076)
		(end 59.311794 -32.916876)
		(width 0.10668)
		(layer "In7.Cu")
		(net "SMB_BMC_MM6_SCL")
	)
	(segment
		(start 38.6334 -23.6728)
		(end 40.005 -22.3012)
		(width 0.10668)
		(layer "In7.Cu")
		(net "SMB_BMC_MM6_SCL")
	)
	(segment
		(start 31.135066 -87.24646)
		(end 30.18028 -86.291674)
		(width 0.10668)
		(layer "In7.Cu")
		(net "SMB_BMC_MM6_SCL")
	)
	(segment
		(start 27.8257 -80.728566)
		(end 27.8257 -78.093824)
		(width 0.10668)
		(layer "In7.Cu")
		(net "SMB_BMC_MM6_SCL")
	)
	(segment
		(start 52.764436 -29.1592)
		(end 53.8226 -29.1592)
		(width 0.10668)
		(layer "In7.Cu")
		(net "SMB_BMC_MM6_SCL")
	)
	(segment
		(start 31.7881 -87.24646)
		(end 31.135066 -87.24646)
		(width 0.10668)
		(layer "In7.Cu")
		(net "SMB_BMC_MM6_SCL")
	)
	(segment
		(start 19.9898 -48.543972)
		(end 20.90166 -46.3423)
		(width 0.10668)
		(layer "In7.Cu")
		(net "SMB_BMC_MM6_SCL")
	)
	(segment
		(start 32.98698 -92.219526)
		(end 32.98698 -91.366086)
		(width 0.10668)
		(layer "In7.Cu")
		(net "SMB_BMC_MM6_SCL")
	)
	(segment
		(start 20.90166 -46.3423)
		(end 20.90166 -45.750988)
		(width 0.10668)
		(layer "In7.Cu")
		(net "SMB_BMC_MM6_SCL")
	)
	(segment
		(start 54.2036 -29.5402)
		(end 54.2036 -30.5054)
		(width 0.10668)
		(layer "In7.Cu")
		(net "SMB_BMC_MM6_SCL")
	)
	(segment
		(start 41.12641 -110.221268)
		(end 41.12641 -108.538772)
		(width 0.10668)
		(layer "In7.Cu")
		(net "SMB_BMC_MM6_SCL")
	)
	(segment
		(start 20.2692 -50.96256)
		(end 19.9898 -50.287682)
		(width 0.10668)
		(layer "In7.Cu")
		(net "SMB_BMC_MM6_SCL")
	)
	(segment
		(start 42.59072 -107.074462)
		(end 42.59072 -105.279698)
		(width 0.10668)
		(layer "In7.Cu")
		(net "SMB_BMC_MM6_SCL")
	)
	(segment
		(start 40.60444 -102.20833)
		(end 38.973252 -100.577142)
		(width 0.10668)
		(layer "In7.Cu")
		(net "SMB_BMC_MM6_SCL")
	)
	(segment
		(start 53.8226 -29.1592)
		(end 54.2036 -29.5402)
		(width 0.10668)
		(layer "In7.Cu")
		(net "SMB_BMC_MM6_SCL")
	)
	(segment
		(start 29.365448 -32.454596)
		(end 29.843984 -31.97606)
		(width 0.10668)
		(layer "In7.Cu")
		(net "SMB_BMC_MM6_SCL")
	)
	(segment
		(start 41.12641 -108.538772)
		(end 42.59072 -107.074462)
		(width 0.10668)
		(layer "In7.Cu")
		(net "SMB_BMC_MM6_SCL")
	)
	(segment
		(start 29.843984 -31.039308)
		(end 29.9974 -30.885892)
		(width 0.10668)
		(layer "In7.Cu")
		(net "SMB_BMC_MM6_SCL")
	)
	(segment
		(start 45.466 -23.7744)
		(end 48.5394 -23.7744)
		(width 0.10668)
		(layer "In7.Cu")
		(net "SMB_BMC_MM6_SCL")
	)
	(segment
		(start 32.05734 -87.5157)
		(end 31.7881 -87.24646)
		(width 0.10668)
		(layer "In7.Cu")
		(net "SMB_BMC_MM6_SCL")
	)
	(segment
		(start 22.42312 -63.879222)
		(end 22.42312 -63.173356)
		(width 0.10668)
		(layer "In7.Cu")
		(net "SMB_BMC_MM6_SCL")
	)
	(segment
		(start 29.9974 -28.70327)
		(end 29.69768 -28.40355)
		(width 0.10668)
		(layer "In7.Cu")
		(net "SMB_BMC_MM6_SCL")
	)
	(segment
		(start 48.6918 -110.6932)
		(end 48.26762 -111.11738)
		(width 0.10668)
		(layer "In7.Cu")
		(net "SMB_BMC_MM6_SCL")
	)
	(segment
		(start 51.807618 -28.202382)
		(end 52.764436 -29.1592)
		(width 0.10668)
		(layer "In7.Cu")
		(net "SMB_BMC_MM6_SCL")
	)
	(segment
		(start 42.59072 -105.279698)
		(end 40.60444 -103.293418)
		(width 0.10668)
		(layer "In7.Cu")
		(net "SMB_BMC_MM6_SCL")
	)
	(segment
		(start 38.973252 -100.577142)
		(end 38.408864 -100.577142)
		(width 0.10668)
		(layer "In7.Cu")
		(net "SMB_BMC_MM6_SCL")
	)
	(segment
		(start 32.05734 -90.436446)
		(end 32.05734 -87.5157)
		(width 0.10668)
		(layer "In7.Cu")
		(net "SMB_BMC_MM6_SCL")
	)
	(segment
		(start 28.6004 -34.301684)
		(end 29.365448 -32.454596)
		(width 0.10668)
		(layer "In7.Cu")
		(net "SMB_BMC_MM6_SCL")
	)
	(segment
		(start 21.63064 -58.917586)
		(end 20.2692 -57.556146)
		(width 0.10668)
		(layer "In7.Cu")
		(net "SMB_BMC_MM6_SCL")
	)
	(segment
		(start 22.36724 -61.076586)
		(end 21.63064 -60.339986)
		(width 0.10668)
		(layer "In7.Cu")
		(net "SMB_BMC_MM6_SCL")
	)
	(segment
		(start 22.42312 -65.104772)
		(end 22.42312 -64.593978)
		(width 0.10668)
		(layer "In7.Cu")
		(net "SMB_BMC_MM6_SCL")
	)
	(segment
		(start 22.26818 -67.192144)
		(end 22.26818 -65.259712)
		(width 0.10668)
		(layer "In7.Cu")
		(net "SMB_BMC_MM6_SCL")
	)
	(segment
		(start 28.98394 -82.964528)
		(end 28.98394 -81.886806)
		(width 0.10668)
		(layer "In7.Cu")
		(net "SMB_BMC_MM6_SCL")
	)
	(segment
		(start 22.5679 -71.581518)
		(end 22.1107 -71.124318)
		(width 0.10668)
		(layer "In7.Cu")
		(net "SMB_BMC_MM6_SCL")
	)
	(segment
		(start 21.63064 -60.339986)
		(end 21.63064 -58.917586)
		(width 0.10668)
		(layer "In7.Cu")
		(net "SMB_BMC_MM6_SCL")
	)
	(segment
		(start 26.570432 -77.42936)
		(end 25.11806 -75.976988)
		(width 0.10668)
		(layer "In7.Cu")
		(net "SMB_BMC_MM6_SCL")
	)
	(segment
		(start 22.39518 -63.907162)
		(end 22.42312 -63.879222)
		(width 0.10668)
		(layer "In7.Cu")
		(net "SMB_BMC_MM6_SCL")
	)
	(segment
		(start 25.11806 -75.976988)
		(end 25.11806 -74.473308)
		(width 0.10668)
		(layer "In7.Cu")
		(net "SMB_BMC_MM6_SCL")
	)
	(segment
		(start 55.295038 -42.571162)
		(end 55.690262 -42.175938)
		(width 0.11684)
		(layer "F.Cu")
		(net "SMB_BMC_MM6_R_SDA")
	)
	(via
		(at 55.532274 -38.387274)
		(size 0.6604)
		(drill 0.3302)
		(layers "F.Cu" "B.Cu")
		(net "SMB_BMC_MM6_R_SDA")
	)
	(via
		(at 55.690262 -42.175938)
		(size 0.4572)
		(drill 0.254)
		(layers "F.Cu" "B.Cu")
		(net "SMB_BMC_MM6_R_SDA")
	)
	(segment
		(start 55.365142 -38.744144)
		(end 55.512716 -38.387274)
		(width 0.11684)
		(layer "B.Cu")
		(net "SMB_BMC_MM6_R_SDA")
	)
	(segment
		(start 55.716424 -38.070028)
		(end 57.52084 -36.265612)
		(width 0.11684)
		(layer "B.Cu")
		(net "SMB_BMC_MM6_R_SDA")
	)
	(segment
		(start 55.0418 -41.783254)
		(end 55.0418 -41.095422)
		(width 0.11684)
		(layer "B.Cu")
		(net "SMB_BMC_MM6_R_SDA")
	)
	(segment
		(start 55.690262 -42.175938)
		(end 55.434484 -42.175938)
		(width 0.11684)
		(layer "B.Cu")
		(net "SMB_BMC_MM6_R_SDA")
	)
	(segment
		(start 57.52846 -35.841686)
		(end 57.810146 -35.56)
		(width 0.11684)
		(layer "B.Cu")
		(net "SMB_BMC_MM6_R_SDA")
	)
	(segment
		(start 57.52846 -36.17214)
		(end 57.52846 -35.841686)
		(width 0.11684)
		(layer "B.Cu")
		(net "SMB_BMC_MM6_R_SDA")
	)
	(segment
		(start 55.595774 -38.360858)
		(end 55.716424 -38.070028)
		(width 0.11684)
		(layer "B.Cu")
		(net "SMB_BMC_MM6_R_SDA")
	)
	(segment
		(start 55.434484 -42.175938)
		(end 55.0418 -41.783254)
		(width 0.11684)
		(layer "B.Cu")
		(net "SMB_BMC_MM6_R_SDA")
	)
	(segment
		(start 58.05805 -35.56)
		(end 58.547 -35.07105)
		(width 0.11684)
		(layer "B.Cu")
		(net "SMB_BMC_MM6_R_SDA")
	)
	(segment
		(start 54.83352 -39.273226)
		(end 55.361078 -38.745668)
		(width 0.11684)
		(layer "B.Cu")
		(net "SMB_BMC_MM6_R_SDA")
	)
	(segment
		(start 57.52084 -36.17976)
		(end 57.52846 -36.17214)
		(width 0.11684)
		(layer "B.Cu")
		(net "SMB_BMC_MM6_R_SDA")
	)
	(segment
		(start 57.810146 -35.56)
		(end 58.05805 -35.56)
		(width 0.11684)
		(layer "B.Cu")
		(net "SMB_BMC_MM6_R_SDA")
	)
	(segment
		(start 55.532274 -38.387274)
		(end 55.595774 -38.360858)
		(width 0.11684)
		(layer "B.Cu")
		(net "SMB_BMC_MM6_R_SDA")
	)
	(segment
		(start 55.512716 -38.387274)
		(end 55.532274 -38.387274)
		(width 0.11684)
		(layer "B.Cu")
		(net "SMB_BMC_MM6_R_SDA")
	)
	(segment
		(start 55.361078 -38.745668)
		(end 55.365142 -38.744144)
		(width 0.11684)
		(layer "B.Cu")
		(net "SMB_BMC_MM6_R_SDA")
	)
	(segment
		(start 54.83352 -40.887142)
		(end 54.83352 -39.273226)
		(width 0.11684)
		(layer "B.Cu")
		(net "SMB_BMC_MM6_R_SDA")
	)
	(segment
		(start 55.0418 -41.095422)
		(end 54.83352 -40.887142)
		(width 0.11684)
		(layer "B.Cu")
		(net "SMB_BMC_MM6_R_SDA")
	)
	(segment
		(start 57.52084 -36.265612)
		(end 57.52084 -36.17976)
		(width 0.11684)
		(layer "B.Cu")
		(net "SMB_BMC_MM6_R_SDA")
	)
	(segment
		(start 56.094884 -41.771316)
		(end 56.490108 -41.376092)
		(width 0.11684)
		(layer "F.Cu")
		(net "SMB_BMC_MM6_R_SCL")
	)
	(via
		(at 58.106564 -36.20643)
		(size 0.6604)
		(drill 0.3302)
		(layers "F.Cu" "B.Cu")
		(net "SMB_BMC_MM6_R_SCL")
	)
	(via
		(at 56.490108 -41.376092)
		(size 0.4572)
		(drill 0.254)
		(layers "F.Cu" "B.Cu")
		(net "SMB_BMC_MM6_R_SCL")
	)
	(segment
		(start 58.106564 -36.20643)
		(end 58.059828 -36.225734)
		(width 0.11684)
		(layer "B.Cu")
		(net "SMB_BMC_MM6_R_SCL")
	)
	(segment
		(start 55.5752 -39.116)
		(end 55.3212 -39.116)
		(width 0.11684)
		(layer "B.Cu")
		(net "SMB_BMC_MM6_R_SCL")
	)
	(segment
		(start 55.2958 -41.040304)
		(end 55.2958 -41.5544)
		(width 0.11684)
		(layer "B.Cu")
		(net "SMB_BMC_MM6_R_SCL")
	)
	(segment
		(start 58.874914 -35.7886)
		(end 58.524394 -35.7886)
		(width 0.11684)
		(layer "B.Cu")
		(net "SMB_BMC_MM6_R_SCL")
	)
	(segment
		(start 59.563 -35.12185)
		(end 59.541664 -35.12185)
		(width 0.11684)
		(layer "B.Cu")
		(net "SMB_BMC_MM6_R_SCL")
	)
	(segment
		(start 57.926732 -36.54679)
		(end 56.307482 -38.16604)
		(width 0.11684)
		(layer "B.Cu")
		(net "SMB_BMC_MM6_R_SCL")
	)
	(segment
		(start 55.05196 -39.38524)
		(end 55.05196 -40.796464)
		(width 0.11684)
		(layer "B.Cu")
		(net "SMB_BMC_MM6_R_SCL")
	)
	(segment
		(start 55.2958 -41.5544)
		(end 55.5244 -41.783)
		(width 0.11684)
		(layer "B.Cu")
		(net "SMB_BMC_MM6_R_SCL")
	)
	(segment
		(start 55.5244 -41.783)
		(end 56.0832 -41.783)
		(width 0.11684)
		(layer "B.Cu")
		(net "SMB_BMC_MM6_R_SCL")
	)
	(segment
		(start 55.3212 -39.116)
		(end 55.05196 -39.38524)
		(width 0.11684)
		(layer "B.Cu")
		(net "SMB_BMC_MM6_R_SCL")
	)
	(segment
		(start 56.307482 -38.383718)
		(end 55.5752 -39.116)
		(width 0.11684)
		(layer "B.Cu")
		(net "SMB_BMC_MM6_R_SCL")
	)
	(segment
		(start 56.307482 -38.16604)
		(end 56.307482 -38.383718)
		(width 0.11684)
		(layer "B.Cu")
		(net "SMB_BMC_MM6_R_SCL")
	)
	(segment
		(start 58.524394 -35.7886)
		(end 58.106564 -36.20643)
		(width 0.11684)
		(layer "B.Cu")
		(net "SMB_BMC_MM6_R_SCL")
	)
	(segment
		(start 55.05196 -40.796464)
		(end 55.2958 -41.040304)
		(width 0.11684)
		(layer "B.Cu")
		(net "SMB_BMC_MM6_R_SCL")
	)
	(segment
		(start 58.059828 -36.225734)
		(end 57.926732 -36.54679)
		(width 0.11684)
		(layer "B.Cu")
		(net "SMB_BMC_MM6_R_SCL")
	)
	(segment
		(start 56.0832 -41.783)
		(end 56.490108 -41.376092)
		(width 0.11684)
		(layer "B.Cu")
		(net "SMB_BMC_MM6_R_SCL")
	)
	(segment
		(start 59.541664 -35.12185)
		(end 58.874914 -35.7886)
		(width 0.11684)
		(layer "B.Cu")
		(net "SMB_BMC_MM6_R_SCL")
	)
	(via
		(at 34.3789 -109.986064)
		(size 0.508)
		(drill 0.254)
		(layers "F.Cu" "B.Cu")
		(net "SMB_BMC_MM5_SDA")
	)
	(via
		(at 59.563 -29.845)
		(size 0.508)
		(drill 0.254)
		(layers "F.Cu" "B.Cu")
		(net "SMB_BMC_MM5_SDA")
	)
	(via
		(at 57.15 -110.0074)
		(size 0.508)
		(drill 0.254)
		(layers "F.Cu" "B.Cu")
		(net "SMB_BMC_MM5_SDA")
	)
	(segment
		(start 59.563 -29.845)
		(end 59.81954 -30.10154)
		(width 0.11684)
		(layer "B.Cu")
		(net "SMB_BMC_MM5_SDA")
	)
	(segment
		(start 56.94172 -116.997734)
		(end 56.94172 -115.64112)
		(width 0.11684)
		(layer "B.Cu")
		(net "SMB_BMC_MM5_SDA")
	)
	(segment
		(start 56.94172 -115.64112)
		(end 57.404 -114.525044)
		(width 0.11684)
		(layer "B.Cu")
		(net "SMB_BMC_MM5_SDA")
	)
	(segment
		(start 56.865012 -117.074442)
		(end 56.94172 -116.997734)
		(width 0.11684)
		(layer "B.Cu")
		(net "SMB_BMC_MM5_SDA")
	)
	(segment
		(start 57.404 -112.29721)
		(end 57.15 -111.6838)
		(width 0.11684)
		(layer "B.Cu")
		(net "SMB_BMC_MM5_SDA")
	)
	(segment
		(start 56.865012 -118.25986)
		(end 56.865012 -117.074442)
		(width 0.11684)
		(layer "B.Cu")
		(net "SMB_BMC_MM5_SDA")
	)
	(segment
		(start 59.81954 -30.10154)
		(end 59.81954 -30.467554)
		(width 0.11684)
		(layer "B.Cu")
		(net "SMB_BMC_MM5_SDA")
	)
	(segment
		(start 57.404 -114.525044)
		(end 57.404 -112.29721)
		(width 0.11684)
		(layer "B.Cu")
		(net "SMB_BMC_MM5_SDA")
	)
	(segment
		(start 57.15 -111.6838)
		(end 57.15 -110.0074)
		(width 0.11684)
		(layer "B.Cu")
		(net "SMB_BMC_MM5_SDA")
	)
	(segment
		(start 56.6166 -110.0074)
		(end 57.15 -110.0074)
		(width 0.08382)
		(layer "In2.Cu")
		(net "SMB_BMC_MM5_SDA")
	)
	(segment
		(start 37.527992 -110.53191)
		(end 37.90569 -110.53191)
		(width 0.08382)
		(layer "In2.Cu")
		(net "SMB_BMC_MM5_SDA")
	)
	(segment
		(start 52.139088 -111.030766)
		(end 53.288184 -109.88167)
		(width 0.08382)
		(layer "In2.Cu")
		(net "SMB_BMC_MM5_SDA")
	)
	(segment
		(start 34.3789 -109.986064)
		(end 36.21024 -109.986064)
		(width 0.08382)
		(layer "In2.Cu")
		(net "SMB_BMC_MM5_SDA")
	)
	(segment
		(start 36.21024 -109.986064)
		(end 37.527992 -110.53191)
		(width 0.08382)
		(layer "In2.Cu")
		(net "SMB_BMC_MM5_SDA")
	)
	(segment
		(start 51.482752 -111.3028)
		(end 52.139088 -111.030766)
		(width 0.08382)
		(layer "In2.Cu")
		(net "SMB_BMC_MM5_SDA")
	)
	(segment
		(start 48.294036 -111.176816)
		(end 48.598328 -111.3028)
		(width 0.08382)
		(layer "In2.Cu")
		(net "SMB_BMC_MM5_SDA")
	)
	(segment
		(start 38.2778 -110.1598)
		(end 41.232582 -110.1598)
		(width 0.08382)
		(layer "In2.Cu")
		(net "SMB_BMC_MM5_SDA")
	)
	(segment
		(start 41.947084 -110.45571)
		(end 42.126408 -110.45571)
		(width 0.08382)
		(layer "In2.Cu")
		(net "SMB_BMC_MM5_SDA")
	)
	(segment
		(start 53.288184 -109.88167)
		(end 56.49087 -109.88167)
		(width 0.08382)
		(layer "In2.Cu")
		(net "SMB_BMC_MM5_SDA")
	)
	(segment
		(start 47.54118 -110.42396)
		(end 48.294036 -111.176816)
		(width 0.08382)
		(layer "In2.Cu")
		(net "SMB_BMC_MM5_SDA")
	)
	(segment
		(start 42.203116 -110.42396)
		(end 47.54118 -110.42396)
		(width 0.08382)
		(layer "In2.Cu")
		(net "SMB_BMC_MM5_SDA")
	)
	(segment
		(start 41.232582 -110.1598)
		(end 41.947084 -110.45571)
		(width 0.08382)
		(layer "In2.Cu")
		(net "SMB_BMC_MM5_SDA")
	)
	(segment
		(start 37.90569 -110.53191)
		(end 38.2778 -110.1598)
		(width 0.08382)
		(layer "In2.Cu")
		(net "SMB_BMC_MM5_SDA")
	)
	(segment
		(start 48.598328 -111.3028)
		(end 51.482752 -111.3028)
		(width 0.08382)
		(layer "In2.Cu")
		(net "SMB_BMC_MM5_SDA")
	)
	(segment
		(start 56.49087 -109.88167)
		(end 56.6166 -110.0074)
		(width 0.08382)
		(layer "In2.Cu")
		(net "SMB_BMC_MM5_SDA")
	)
	(segment
		(start 42.126408 -110.45571)
		(end 42.203116 -110.42396)
		(width 0.08382)
		(layer "In2.Cu")
		(net "SMB_BMC_MM5_SDA")
	)
	(segment
		(start 58.770774 -34.87928)
		(end 60.1853 -33.464754)
		(width 0.10668)
		(layer "In4.Cu")
		(net "SMB_BMC_MM5_SDA")
	)
	(segment
		(start 43.10888 -40.423592)
		(end 43.10888 -39.073074)
		(width 0.10668)
		(layer "In4.Cu")
		(net "SMB_BMC_MM5_SDA")
	)
	(segment
		(start 32.924496 -107.953556)
		(end 32.924496 -106.305096)
		(width 0.10668)
		(layer "In4.Cu")
		(net "SMB_BMC_MM5_SDA")
	)
	(segment
		(start 35.081972 -72.538082)
		(end 36.188396 -71.431912)
		(width 0.10668)
		(layer "In4.Cu")
		(net "SMB_BMC_MM5_SDA")
	)
	(segment
		(start 55.31612 -34.87928)
		(end 58.770774 -34.87928)
		(width 0.10668)
		(layer "In4.Cu")
		(net "SMB_BMC_MM5_SDA")
	)
	(segment
		(start 44.271184 -37.91077)
		(end 44.369228 -37.763958)
		(width 0.10668)
		(layer "In4.Cu")
		(net "SMB_BMC_MM5_SDA")
	)
	(segment
		(start 34.45764 -56.6674)
		(end 34.74974 -56.3753)
		(width 0.10668)
		(layer "In4.Cu")
		(net "SMB_BMC_MM5_SDA")
	)
	(segment
		(start 54.3814 -37.32657)
		(end 54.6608 -37.04717)
		(width 0.10668)
		(layer "In4.Cu")
		(net "SMB_BMC_MM5_SDA")
	)
	(segment
		(start 32.23514 -105.61574)
		(end 32.23514 -103.20655)
		(width 0.10668)
		(layer "In4.Cu")
		(net "SMB_BMC_MM5_SDA")
	)
	(segment
		(start 30.28188 -95.10776)
		(end 30.134306 -94.960186)
		(width 0.10668)
		(layer "In4.Cu")
		(net "SMB_BMC_MM5_SDA")
	)
	(segment
		(start 54.6608 -37.04717)
		(end 54.6608 -35.5346)
		(width 0.10668)
		(layer "In4.Cu")
		(net "SMB_BMC_MM5_SDA")
	)
	(segment
		(start 54.6608 -35.5346)
		(end 55.31612 -34.87928)
		(width 0.10668)
		(layer "In4.Cu")
		(net "SMB_BMC_MM5_SDA")
	)
	(segment
		(start 43.10888 -39.073074)
		(end 44.271184 -37.91077)
		(width 0.10668)
		(layer "In4.Cu")
		(net "SMB_BMC_MM5_SDA")
	)
	(segment
		(start 30.134306 -94.960186)
		(end 30.134306 -94.294706)
		(width 0.10668)
		(layer "In4.Cu")
		(net "SMB_BMC_MM5_SDA")
	)
	(segment
		(start 30.76448 -89.35212)
		(end 30.76448 -84.266532)
		(width 0.10668)
		(layer "In4.Cu")
		(net "SMB_BMC_MM5_SDA")
	)
	(segment
		(start 29.30652 -100.27793)
		(end 29.30652 -98.02876)
		(width 0.10668)
		(layer "In4.Cu")
		(net "SMB_BMC_MM5_SDA")
	)
	(segment
		(start 34.758122 -51.862482)
		(end 34.758122 -49.007268)
		(width 0.10668)
		(layer "In4.Cu")
		(net "SMB_BMC_MM5_SDA")
	)
	(segment
		(start 37.444426 -44.20108)
		(end 37.981636 -44.20108)
		(width 0.10668)
		(layer "In4.Cu")
		(net "SMB_BMC_MM5_SDA")
	)
	(segment
		(start 34.3789 -109.40796)
		(end 32.924496 -107.953556)
		(width 0.10668)
		(layer "In4.Cu")
		(net "SMB_BMC_MM5_SDA")
	)
	(segment
		(start 34.92246 -67.721734)
		(end 34.92246 -64.116712)
		(width 0.10668)
		(layer "In4.Cu")
		(net "SMB_BMC_MM5_SDA")
	)
	(segment
		(start 34.0106 -56.6674)
		(end 34.45764 -56.6674)
		(width 0.10668)
		(layer "In4.Cu")
		(net "SMB_BMC_MM5_SDA")
	)
	(segment
		(start 30.94736 -82.53984)
		(end 32.73298 -80.75422)
		(width 0.10668)
		(layer "In4.Cu")
		(net "SMB_BMC_MM5_SDA")
	)
	(segment
		(start 32.73298 -80.75422)
		(end 32.73298 -73.845674)
		(width 0.10668)
		(layer "In4.Cu")
		(net "SMB_BMC_MM5_SDA")
	)
	(segment
		(start 32.004 -92.89796)
		(end 32.004 -90.59164)
		(width 0.10668)
		(layer "In4.Cu")
		(net "SMB_BMC_MM5_SDA")
	)
	(segment
		(start 34.86658 -52.63642)
		(end 34.86658 -51.97094)
		(width 0.10668)
		(layer "In4.Cu")
		(net "SMB_BMC_MM5_SDA")
	)
	(segment
		(start 36.313364 -69.414644)
		(end 36.09975 -68.899024)
		(width 0.10668)
		(layer "In4.Cu")
		(net "SMB_BMC_MM5_SDA")
	)
	(segment
		(start 60.1853 -33.464754)
		(end 60.1853 -31.87446)
		(width 0.10668)
		(layer "In4.Cu")
		(net "SMB_BMC_MM5_SDA")
	)
	(segment
		(start 38.342316 -44.56176)
		(end 38.970712 -44.56176)
		(width 0.10668)
		(layer "In4.Cu")
		(net "SMB_BMC_MM5_SDA")
	)
	(segment
		(start 33.802574 -57.462674)
		(end 33.802574 -56.875426)
		(width 0.10668)
		(layer "In4.Cu")
		(net "SMB_BMC_MM5_SDA")
	)
	(segment
		(start 45.187108 -37.32657)
		(end 54.3814 -37.32657)
		(width 0.10668)
		(layer "In4.Cu")
		(net "SMB_BMC_MM5_SDA")
	)
	(segment
		(start 34.040572 -72.538082)
		(end 35.081972 -72.538082)
		(width 0.10668)
		(layer "In4.Cu")
		(net "SMB_BMC_MM5_SDA")
	)
	(segment
		(start 32.924496 -106.305096)
		(end 32.23514 -105.61574)
		(width 0.10668)
		(layer "In4.Cu")
		(net "SMB_BMC_MM5_SDA")
	)
	(segment
		(start 32.004 -90.59164)
		(end 30.76448 -89.35212)
		(width 0.10668)
		(layer "In4.Cu")
		(net "SMB_BMC_MM5_SDA")
	)
	(segment
		(start 30.28188 -97.0534)
		(end 30.28188 -95.10776)
		(width 0.10668)
		(layer "In4.Cu")
		(net "SMB_BMC_MM5_SDA")
	)
	(segment
		(start 34.11728 -55.361586)
		(end 34.11728 -53.38572)
		(width 0.10668)
		(layer "In4.Cu")
		(net "SMB_BMC_MM5_SDA")
	)
	(segment
		(start 34.5567 -59.0931)
		(end 34.586672 -59.063128)
		(width 0.10668)
		(layer "In4.Cu")
		(net "SMB_BMC_MM5_SDA")
	)
	(segment
		(start 34.758122 -49.007268)
		(end 35.546284 -47.104808)
		(width 0.10668)
		(layer "In4.Cu")
		(net "SMB_BMC_MM5_SDA")
	)
	(segment
		(start 30.76448 -84.266532)
		(end 30.94736 -84.083652)
		(width 0.10668)
		(layer "In4.Cu")
		(net "SMB_BMC_MM5_SDA")
	)
	(segment
		(start 36.313364 -71.165974)
		(end 36.313364 -69.414644)
		(width 0.10668)
		(layer "In4.Cu")
		(net "SMB_BMC_MM5_SDA")
	)
	(segment
		(start 36.09975 -68.899024)
		(end 34.92246 -67.721734)
		(width 0.10668)
		(layer "In4.Cu")
		(net "SMB_BMC_MM5_SDA")
	)
	(segment
		(start 31.24454 -93.65742)
		(end 32.004 -92.89796)
		(width 0.10668)
		(layer "In4.Cu")
		(net "SMB_BMC_MM5_SDA")
	)
	(segment
		(start 34.5567 -63.750952)
		(end 34.5567 -59.0931)
		(width 0.10668)
		(layer "In4.Cu")
		(net "SMB_BMC_MM5_SDA")
	)
	(segment
		(start 36.188396 -71.431912)
		(end 36.313364 -71.165974)
		(width 0.10668)
		(layer "In4.Cu")
		(net "SMB_BMC_MM5_SDA")
	)
	(segment
		(start 29.30652 -98.02876)
		(end 30.28188 -97.0534)
		(width 0.10668)
		(layer "In4.Cu")
		(net "SMB_BMC_MM5_SDA")
	)
	(segment
		(start 30.134306 -94.294706)
		(end 30.771592 -93.65742)
		(width 0.10668)
		(layer "In4.Cu")
		(net "SMB_BMC_MM5_SDA")
	)
	(segment
		(start 34.92246 -64.116712)
		(end 34.5567 -63.750952)
		(width 0.10668)
		(layer "In4.Cu")
		(net "SMB_BMC_MM5_SDA")
	)
	(segment
		(start 44.369228 -37.763958)
		(end 45.187108 -37.32657)
		(width 0.10668)
		(layer "In4.Cu")
		(net "SMB_BMC_MM5_SDA")
	)
	(segment
		(start 34.86658 -51.97094)
		(end 34.758122 -51.862482)
		(width 0.10668)
		(layer "In4.Cu")
		(net "SMB_BMC_MM5_SDA")
	)
	(segment
		(start 34.3789 -109.986064)
		(end 34.3789 -109.40796)
		(width 0.10668)
		(layer "In4.Cu")
		(net "SMB_BMC_MM5_SDA")
	)
	(segment
		(start 30.771592 -93.65742)
		(end 31.24454 -93.65742)
		(width 0.10668)
		(layer "In4.Cu")
		(net "SMB_BMC_MM5_SDA")
	)
	(segment
		(start 33.802574 -56.875426)
		(end 34.0106 -56.6674)
		(width 0.10668)
		(layer "In4.Cu")
		(net "SMB_BMC_MM5_SDA")
	)
	(segment
		(start 35.546284 -46.54677)
		(end 36.1696 -45.923454)
		(width 0.10668)
		(layer "In4.Cu")
		(net "SMB_BMC_MM5_SDA")
	)
	(segment
		(start 34.11728 -53.38572)
		(end 34.86658 -52.63642)
		(width 0.10668)
		(layer "In4.Cu")
		(net "SMB_BMC_MM5_SDA")
	)
	(segment
		(start 32.73298 -73.845674)
		(end 34.040572 -72.538082)
		(width 0.10668)
		(layer "In4.Cu")
		(net "SMB_BMC_MM5_SDA")
	)
	(segment
		(start 59.563 -31.25216)
		(end 59.563 -29.845)
		(width 0.10668)
		(layer "In4.Cu")
		(net "SMB_BMC_MM5_SDA")
	)
	(segment
		(start 36.1696 -45.617384)
		(end 36.169854 -45.475652)
		(width 0.10668)
		(layer "In4.Cu")
		(net "SMB_BMC_MM5_SDA")
	)
	(segment
		(start 34.74974 -56.3753)
		(end 34.74974 -55.994046)
		(width 0.10668)
		(layer "In4.Cu")
		(net "SMB_BMC_MM5_SDA")
	)
	(segment
		(start 36.169854 -45.475652)
		(end 37.444426 -44.20108)
		(width 0.10668)
		(layer "In4.Cu")
		(net "SMB_BMC_MM5_SDA")
	)
	(segment
		(start 30.94736 -84.083652)
		(end 30.94736 -82.53984)
		(width 0.10668)
		(layer "In4.Cu")
		(net "SMB_BMC_MM5_SDA")
	)
	(segment
		(start 34.586672 -59.063128)
		(end 34.586672 -58.246772)
		(width 0.10668)
		(layer "In4.Cu")
		(net "SMB_BMC_MM5_SDA")
	)
	(segment
		(start 60.1853 -31.87446)
		(end 59.563 -31.25216)
		(width 0.10668)
		(layer "In4.Cu")
		(net "SMB_BMC_MM5_SDA")
	)
	(segment
		(start 34.586672 -58.246772)
		(end 33.802574 -57.462674)
		(width 0.10668)
		(layer "In4.Cu")
		(net "SMB_BMC_MM5_SDA")
	)
	(segment
		(start 38.970712 -44.56176)
		(end 43.10888 -40.423592)
		(width 0.10668)
		(layer "In4.Cu")
		(net "SMB_BMC_MM5_SDA")
	)
	(segment
		(start 35.546284 -47.104808)
		(end 35.546284 -46.54677)
		(width 0.10668)
		(layer "In4.Cu")
		(net "SMB_BMC_MM5_SDA")
	)
	(segment
		(start 36.1696 -45.923454)
		(end 36.1696 -45.617384)
		(width 0.10668)
		(layer "In4.Cu")
		(net "SMB_BMC_MM5_SDA")
	)
	(segment
		(start 37.981636 -44.20108)
		(end 38.342316 -44.56176)
		(width 0.10668)
		(layer "In4.Cu")
		(net "SMB_BMC_MM5_SDA")
	)
	(segment
		(start 34.74974 -55.994046)
		(end 34.11728 -55.361586)
		(width 0.10668)
		(layer "In4.Cu")
		(net "SMB_BMC_MM5_SDA")
	)
	(segment
		(start 32.23514 -103.20655)
		(end 29.30652 -100.27793)
		(width 0.10668)
		(layer "In4.Cu")
		(net "SMB_BMC_MM5_SDA")
	)
	(segment
		(start 58.266584 -34.237676)
		(end 58.266584 -33.602676)
		(width 0.11684)
		(layer "F.Cu")
		(net "SMB_BMC_MM5_SCL")
	)
	(via
		(at 58.266584 -33.602676)
		(size 0.508)
		(drill 0.254)
		(layers "F.Cu" "B.Cu")
		(net "SMB_BMC_MM5_SCL")
	)
	(via
		(at 57.61482 -110.53318)
		(size 0.508)
		(drill 0.254)
		(layers "F.Cu" "B.Cu")
		(net "SMB_BMC_MM5_SCL")
	)
	(via
		(at 32.731964 -109.998764)
		(size 0.508)
		(drill 0.254)
		(layers "F.Cu" "B.Cu")
		(net "SMB_BMC_MM5_SCL")
	)
	(segment
		(start 57.61482 -111.588042)
		(end 57.61482 -110.53318)
		(width 0.11684)
		(layer "B.Cu")
		(net "SMB_BMC_MM5_SCL")
	)
	(segment
		(start 57.80024 -115.148106)
		(end 57.80024 -111.773462)
		(width 0.11684)
		(layer "B.Cu")
		(net "SMB_BMC_MM5_SCL")
	)
	(segment
		(start 57.80024 -111.773462)
		(end 57.61482 -111.588042)
		(width 0.11684)
		(layer "B.Cu")
		(net "SMB_BMC_MM5_SCL")
	)
	(segment
		(start 57.46496 -118.25986)
		(end 57.46496 -115.483386)
		(width 0.11684)
		(layer "B.Cu")
		(net "SMB_BMC_MM5_SCL")
	)
	(segment
		(start 57.46496 -115.483386)
		(end 57.80024 -115.148106)
		(width 0.11684)
		(layer "B.Cu")
		(net "SMB_BMC_MM5_SCL")
	)
	(segment
		(start 43.274488 -111.096552)
		(end 43.58132 -110.78972)
		(width 0.08382)
		(layer "In2.Cu")
		(net "SMB_BMC_MM5_SCL")
	)
	(segment
		(start 38.881812 -110.49)
		(end 39.140892 -110.49)
		(width 0.08382)
		(layer "In2.Cu")
		(net "SMB_BMC_MM5_SCL")
	)
	(segment
		(start 55.345838 -110.19409)
		(end 55.9308 -110.779052)
		(width 0.08382)
		(layer "In2.Cu")
		(net "SMB_BMC_MM5_SCL")
	)
	(segment
		(start 41.512236 -111.096552)
		(end 41.779444 -111.096552)
		(width 0.08382)
		(layer "In2.Cu")
		(net "SMB_BMC_MM5_SCL")
	)
	(segment
		(start 42.373804 -110.7694)
		(end 42.700956 -111.096552)
		(width 0.08382)
		(layer "In2.Cu")
		(net "SMB_BMC_MM5_SCL")
	)
	(segment
		(start 39.140892 -110.49)
		(end 39.308532 -110.65764)
		(width 0.08382)
		(layer "In2.Cu")
		(net "SMB_BMC_MM5_SCL")
	)
	(segment
		(start 47.464726 -110.78972)
		(end 48.308006 -111.633)
		(width 0.08382)
		(layer "In2.Cu")
		(net "SMB_BMC_MM5_SCL")
	)
	(segment
		(start 48.308006 -111.633)
		(end 51.46294 -111.633)
		(width 0.08382)
		(layer "In2.Cu")
		(net "SMB_BMC_MM5_SCL")
	)
	(segment
		(start 32.731964 -109.998764)
		(end 32.731964 -110.3376)
		(width 0.08382)
		(layer "In2.Cu")
		(net "SMB_BMC_MM5_SCL")
	)
	(segment
		(start 52.316126 -111.295688)
		(end 53.417724 -110.19409)
		(width 0.08382)
		(layer "In2.Cu")
		(net "SMB_BMC_MM5_SCL")
	)
	(segment
		(start 40.590724 -111.096552)
		(end 40.917876 -110.7694)
		(width 0.08382)
		(layer "In2.Cu")
		(net "SMB_BMC_MM5_SCL")
	)
	(segment
		(start 53.417724 -110.19409)
		(end 55.345838 -110.19409)
		(width 0.08382)
		(layer "In2.Cu")
		(net "SMB_BMC_MM5_SCL")
	)
	(segment
		(start 38.714172 -110.65764)
		(end 38.881812 -110.49)
		(width 0.08382)
		(layer "In2.Cu")
		(net "SMB_BMC_MM5_SCL")
	)
	(segment
		(start 51.46294 -111.633)
		(end 51.482752 -111.641128)
		(width 0.08382)
		(layer "In2.Cu")
		(net "SMB_BMC_MM5_SCL")
	)
	(segment
		(start 36.373562 -110.4646)
		(end 37.89934 -111.096552)
		(width 0.08382)
		(layer "In2.Cu")
		(net "SMB_BMC_MM5_SCL")
	)
	(segment
		(start 38.546532 -111.096552)
		(end 38.714172 -110.928912)
		(width 0.08382)
		(layer "In2.Cu")
		(net "SMB_BMC_MM5_SCL")
	)
	(segment
		(start 42.106596 -110.7694)
		(end 42.373804 -110.7694)
		(width 0.08382)
		(layer "In2.Cu")
		(net "SMB_BMC_MM5_SCL")
	)
	(segment
		(start 55.9308 -110.779052)
		(end 57.368948 -110.779052)
		(width 0.08382)
		(layer "In2.Cu")
		(net "SMB_BMC_MM5_SCL")
	)
	(segment
		(start 40.917876 -110.7694)
		(end 41.185084 -110.7694)
		(width 0.08382)
		(layer "In2.Cu")
		(net "SMB_BMC_MM5_SCL")
	)
	(segment
		(start 39.308532 -110.928912)
		(end 39.476172 -111.096552)
		(width 0.08382)
		(layer "In2.Cu")
		(net "SMB_BMC_MM5_SCL")
	)
	(segment
		(start 38.714172 -110.928912)
		(end 38.714172 -110.65764)
		(width 0.08382)
		(layer "In2.Cu")
		(net "SMB_BMC_MM5_SCL")
	)
	(segment
		(start 43.58132 -110.78972)
		(end 47.464726 -110.78972)
		(width 0.08382)
		(layer "In2.Cu")
		(net "SMB_BMC_MM5_SCL")
	)
	(segment
		(start 32.731964 -110.3376)
		(end 32.858964 -110.4646)
		(width 0.08382)
		(layer "In2.Cu")
		(net "SMB_BMC_MM5_SCL")
	)
	(segment
		(start 32.858964 -110.4646)
		(end 36.373562 -110.4646)
		(width 0.08382)
		(layer "In2.Cu")
		(net "SMB_BMC_MM5_SCL")
	)
	(segment
		(start 37.89934 -111.096552)
		(end 38.546532 -111.096552)
		(width 0.08382)
		(layer "In2.Cu")
		(net "SMB_BMC_MM5_SCL")
	)
	(segment
		(start 51.482752 -111.641128)
		(end 52.316126 -111.295688)
		(width 0.08382)
		(layer "In2.Cu")
		(net "SMB_BMC_MM5_SCL")
	)
	(segment
		(start 39.308532 -110.65764)
		(end 39.308532 -110.928912)
		(width 0.08382)
		(layer "In2.Cu")
		(net "SMB_BMC_MM5_SCL")
	)
	(segment
		(start 41.779444 -111.096552)
		(end 42.106596 -110.7694)
		(width 0.08382)
		(layer "In2.Cu")
		(net "SMB_BMC_MM5_SCL")
	)
	(segment
		(start 39.476172 -111.096552)
		(end 40.590724 -111.096552)
		(width 0.08382)
		(layer "In2.Cu")
		(net "SMB_BMC_MM5_SCL")
	)
	(segment
		(start 42.700956 -111.096552)
		(end 43.274488 -111.096552)
		(width 0.08382)
		(layer "In2.Cu")
		(net "SMB_BMC_MM5_SCL")
	)
	(segment
		(start 57.368948 -110.779052)
		(end 57.61482 -110.53318)
		(width 0.08382)
		(layer "In2.Cu")
		(net "SMB_BMC_MM5_SCL")
	)
	(segment
		(start 41.185084 -110.7694)
		(end 41.512236 -111.096552)
		(width 0.08382)
		(layer "In2.Cu")
		(net "SMB_BMC_MM5_SCL")
	)
	(segment
		(start 31.343854 -81.64576)
		(end 31.52394 -81.465674)
		(width 0.10668)
		(layer "In4.Cu")
		(net "SMB_BMC_MM5_SCL")
	)
	(segment
		(start 37.895276 -43.53052)
		(end 38.743636 -42.68216)
		(width 0.10668)
		(layer "In4.Cu")
		(net "SMB_BMC_MM5_SCL")
	)
	(segment
		(start 30.4292 -84.127594)
		(end 30.61208 -83.944714)
		(width 0.10668)
		(layer "In4.Cu")
		(net "SMB_BMC_MM5_SCL")
	)
	(segment
		(start 38.743636 -42.68216)
		(end 39.823898 -42.68216)
		(width 0.10668)
		(layer "In4.Cu")
		(net "SMB_BMC_MM5_SCL")
	)
	(segment
		(start 32.731964 -109.754416)
		(end 33.415986 -109.070394)
		(width 0.10668)
		(layer "In4.Cu")
		(net "SMB_BMC_MM5_SCL")
	)
	(segment
		(start 31.098998 -103.371142)
		(end 31.098998 -102.865936)
		(width 0.10668)
		(layer "In4.Cu")
		(net "SMB_BMC_MM5_SCL")
	)
	(segment
		(start 31.098998 -102.865936)
		(end 28.97124 -100.738178)
		(width 0.10668)
		(layer "In4.Cu")
		(net "SMB_BMC_MM5_SCL")
	)
	(segment
		(start 53.13172 -35.1155)
		(end 53.69814 -34.54908)
		(width 0.10668)
		(layer "In4.Cu")
		(net "SMB_BMC_MM5_SCL")
	)
	(segment
		(start 34.804096 -71.867522)
		(end 35.63112 -71.040498)
		(width 0.10668)
		(layer "In4.Cu")
		(net "SMB_BMC_MM5_SCL")
	)
	(segment
		(start 39.823898 -42.68216)
		(end 42.42308 -40.082978)
		(width 0.10668)
		(layer "In4.Cu")
		(net "SMB_BMC_MM5_SCL")
	)
	(segment
		(start 32.731964 -109.998764)
		(end 32.731964 -109.754416)
		(width 0.10668)
		(layer "In4.Cu")
		(net "SMB_BMC_MM5_SCL")
	)
	(segment
		(start 33.95726 -46.1391)
		(end 33.95726 -45.41774)
		(width 0.10668)
		(layer "In4.Cu")
		(net "SMB_BMC_MM5_SCL")
	)
	(segment
		(start 30.614366 -93.32214)
		(end 31.061914 -93.32214)
		(width 0.10668)
		(layer "In4.Cu")
		(net "SMB_BMC_MM5_SCL")
	)
	(segment
		(start 55.0164 -34.0868)
		(end 57.78246 -34.0868)
		(width 0.10668)
		(layer "In4.Cu")
		(net "SMB_BMC_MM5_SCL")
	)
	(segment
		(start 31.89986 -104.172004)
		(end 31.098998 -103.371142)
		(width 0.10668)
		(layer "In4.Cu")
		(net "SMB_BMC_MM5_SCL")
	)
	(segment
		(start 30.4292 -89.491058)
		(end 30.4292 -84.127594)
		(width 0.10668)
		(layer "In4.Cu")
		(net "SMB_BMC_MM5_SCL")
	)
	(segment
		(start 33.10636 -54.385464)
		(end 33.10636 -50.365152)
		(width 0.10668)
		(layer "In4.Cu")
		(net "SMB_BMC_MM5_SCL")
	)
	(segment
		(start 30.792166 -81.64576)
		(end 31.343854 -81.64576)
		(width 0.10668)
		(layer "In4.Cu")
		(net "SMB_BMC_MM5_SCL")
	)
	(segment
		(start 31.66872 -92.715334)
		(end 31.66872 -90.730578)
		(width 0.10668)
		(layer "In4.Cu")
		(net "SMB_BMC_MM5_SCL")
	)
	(segment
		(start 31.52394 -81.465674)
		(end 31.52394 -81.211166)
		(width 0.10668)
		(layer "In4.Cu")
		(net "SMB_BMC_MM5_SCL")
	)
	(segment
		(start 30.89148 -80.137508)
		(end 30.89148 -78.28026)
		(width 0.10668)
		(layer "In4.Cu")
		(net "SMB_BMC_MM5_SCL")
	)
	(segment
		(start 28.97124 -97.85096)
		(end 29.34208 -97.48012)
		(width 0.10668)
		(layer "In4.Cu")
		(net "SMB_BMC_MM5_SCL")
	)
	(segment
		(start 43.181524 -38.032182)
		(end 43.181524 -37.041582)
		(width 0.10668)
		(layer "In4.Cu")
		(net "SMB_BMC_MM5_SCL")
	)
	(segment
		(start 31.52394 -81.211166)
		(end 31.343854 -81.03108)
		(width 0.10668)
		(layer "In4.Cu")
		(net "SMB_BMC_MM5_SCL")
	)
	(segment
		(start 29.799026 -94.13748)
		(end 30.614366 -93.32214)
		(width 0.10668)
		(layer "In4.Cu")
		(net "SMB_BMC_MM5_SCL")
	)
	(segment
		(start 32.06242 -73.567798)
		(end 33.762696 -71.867522)
		(width 0.10668)
		(layer "In4.Cu")
		(net "SMB_BMC_MM5_SCL")
	)
	(segment
		(start 32.350964 -61.052964)
		(end 32.350964 -56.2102)
		(width 0.10668)
		(layer "In4.Cu")
		(net "SMB_BMC_MM5_SCL")
	)
	(segment
		(start 34.3916 -44.9834)
		(end 35.713416 -44.9834)
		(width 0.10668)
		(layer "In4.Cu")
		(net "SMB_BMC_MM5_SCL")
	)
	(segment
		(start 34.2519 -68.000372)
		(end 34.2519 -64.394588)
		(width 0.10668)
		(layer "In4.Cu")
		(net "SMB_BMC_MM5_SCL")
	)
	(segment
		(start 33.10636 -50.365152)
		(end 34.40811 -47.221394)
		(width 0.10668)
		(layer "In4.Cu")
		(net "SMB_BMC_MM5_SCL")
	)
	(segment
		(start 43.567096 -36.65601)
		(end 52.47259 -36.65601)
		(width 0.10668)
		(layer "In4.Cu")
		(net "SMB_BMC_MM5_SCL")
	)
	(segment
		(start 53.69814 -34.54908)
		(end 54.55412 -34.54908)
		(width 0.10668)
		(layer "In4.Cu")
		(net "SMB_BMC_MM5_SCL")
	)
	(segment
		(start 32.06242 -77.10932)
		(end 32.06242 -73.567798)
		(width 0.10668)
		(layer "In4.Cu")
		(net "SMB_BMC_MM5_SCL")
	)
	(segment
		(start 30.61208 -80.850994)
		(end 30.61208 -80.416908)
		(width 0.10668)
		(layer "In4.Cu")
		(net "SMB_BMC_MM5_SCL")
	)
	(segment
		(start 43.181524 -37.041582)
		(end 43.567096 -36.65601)
		(width 0.10668)
		(layer "In4.Cu")
		(net "SMB_BMC_MM5_SCL")
	)
	(segment
		(start 30.61208 -81.825846)
		(end 30.792166 -81.64576)
		(width 0.10668)
		(layer "In4.Cu")
		(net "SMB_BMC_MM5_SCL")
	)
	(segment
		(start 32.6644 -61.3664)
		(end 32.350964 -61.052964)
		(width 0.10668)
		(layer "In4.Cu")
		(net "SMB_BMC_MM5_SCL")
	)
	(segment
		(start 30.792166 -81.03108)
		(end 30.61208 -80.850994)
		(width 0.10668)
		(layer "In4.Cu")
		(net "SMB_BMC_MM5_SCL")
	)
	(segment
		(start 34.40811 -47.221394)
		(end 34.40811 -46.58995)
		(width 0.10668)
		(layer "In4.Cu")
		(net "SMB_BMC_MM5_SCL")
	)
	(segment
		(start 32.589216 -106.444034)
		(end 31.89986 -105.754678)
		(width 0.10668)
		(layer "In4.Cu")
		(net "SMB_BMC_MM5_SCL")
	)
	(segment
		(start 35.63112 -71.040498)
		(end 35.642804 -71.015606)
		(width 0.10668)
		(layer "In4.Cu")
		(net "SMB_BMC_MM5_SCL")
	)
	(segment
		(start 32.589216 -108.092748)
		(end 32.589216 -106.444034)
		(width 0.10668)
		(layer "In4.Cu")
		(net "SMB_BMC_MM5_SCL")
	)
	(segment
		(start 29.34208 -97.48012)
		(end 29.34208 -95.478346)
		(width 0.10668)
		(layer "In4.Cu")
		(net "SMB_BMC_MM5_SCL")
	)
	(segment
		(start 30.89148 -78.28026)
		(end 32.06242 -77.10932)
		(width 0.10668)
		(layer "In4.Cu")
		(net "SMB_BMC_MM5_SCL")
	)
	(segment
		(start 52.47259 -36.65601)
		(end 53.13172 -35.99688)
		(width 0.10668)
		(layer "In4.Cu")
		(net "SMB_BMC_MM5_SCL")
	)
	(segment
		(start 34.40811 -46.58995)
		(end 33.95726 -46.1391)
		(width 0.10668)
		(layer "In4.Cu")
		(net "SMB_BMC_MM5_SCL")
	)
	(segment
		(start 31.343854 -81.03108)
		(end 30.792166 -81.03108)
		(width 0.10668)
		(layer "In4.Cu")
		(net "SMB_BMC_MM5_SCL")
	)
	(segment
		(start 32.350964 -56.2102)
		(end 33.10636 -54.385464)
		(width 0.10668)
		(layer "In4.Cu")
		(net "SMB_BMC_MM5_SCL")
	)
	(segment
		(start 31.89986 -105.754678)
		(end 31.89986 -104.172004)
		(width 0.10668)
		(layer "In4.Cu")
		(net "SMB_BMC_MM5_SCL")
	)
	(segment
		(start 33.415986 -108.919518)
		(end 32.589216 -108.092748)
		(width 0.10668)
		(layer "In4.Cu")
		(net "SMB_BMC_MM5_SCL")
	)
	(segment
		(start 28.97124 -100.738178)
		(end 28.97124 -97.85096)
		(width 0.10668)
		(layer "In4.Cu")
		(net "SMB_BMC_MM5_SCL")
	)
	(segment
		(start 54.55412 -34.54908)
		(end 55.0164 -34.0868)
		(width 0.10668)
		(layer "In4.Cu")
		(net "SMB_BMC_MM5_SCL")
	)
	(segment
		(start 35.53079 -69.279262)
		(end 34.2519 -68.000372)
		(width 0.10668)
		(layer "In4.Cu")
		(net "SMB_BMC_MM5_SCL")
	)
	(segment
		(start 35.642804 -69.549518)
		(end 35.53079 -69.279262)
		(width 0.10668)
		(layer "In4.Cu")
		(net "SMB_BMC_MM5_SCL")
	)
	(segment
		(start 34.2519 -64.394588)
		(end 32.6644 -62.807088)
		(width 0.10668)
		(layer "In4.Cu")
		(net "SMB_BMC_MM5_SCL")
	)
	(segment
		(start 30.61208 -83.944714)
		(end 30.61208 -81.825846)
		(width 0.10668)
		(layer "In4.Cu")
		(net "SMB_BMC_MM5_SCL")
	)
	(segment
		(start 30.61208 -80.416908)
		(end 30.89148 -80.137508)
		(width 0.10668)
		(layer "In4.Cu")
		(net "SMB_BMC_MM5_SCL")
	)
	(segment
		(start 33.762696 -71.867522)
		(end 34.804096 -71.867522)
		(width 0.10668)
		(layer "In4.Cu")
		(net "SMB_BMC_MM5_SCL")
	)
	(segment
		(start 35.642804 -71.015606)
		(end 35.642804 -69.549518)
		(width 0.10668)
		(layer "In4.Cu")
		(net "SMB_BMC_MM5_SCL")
	)
	(segment
		(start 32.6644 -62.807088)
		(end 32.6644 -61.3664)
		(width 0.10668)
		(layer "In4.Cu")
		(net "SMB_BMC_MM5_SCL")
	)
	(segment
		(start 57.78246 -34.0868)
		(end 58.266584 -33.602676)
		(width 0.10668)
		(layer "In4.Cu")
		(net "SMB_BMC_MM5_SCL")
	)
	(segment
		(start 33.415986 -109.070394)
		(end 33.415986 -108.919518)
		(width 0.10668)
		(layer "In4.Cu")
		(net "SMB_BMC_MM5_SCL")
	)
	(segment
		(start 33.95726 -45.41774)
		(end 34.3916 -44.9834)
		(width 0.10668)
		(layer "In4.Cu")
		(net "SMB_BMC_MM5_SCL")
	)
	(segment
		(start 53.13172 -35.99688)
		(end 53.13172 -35.1155)
		(width 0.10668)
		(layer "In4.Cu")
		(net "SMB_BMC_MM5_SCL")
	)
	(segment
		(start 42.42308 -38.790626)
		(end 43.181524 -38.032182)
		(width 0.10668)
		(layer "In4.Cu")
		(net "SMB_BMC_MM5_SCL")
	)
	(segment
		(start 31.66872 -90.730578)
		(end 30.4292 -89.491058)
		(width 0.10668)
		(layer "In4.Cu")
		(net "SMB_BMC_MM5_SCL")
	)
	(segment
		(start 42.42308 -40.082978)
		(end 42.42308 -38.790626)
		(width 0.10668)
		(layer "In4.Cu")
		(net "SMB_BMC_MM5_SCL")
	)
	(segment
		(start 37.166296 -43.53052)
		(end 37.895276 -43.53052)
		(width 0.10668)
		(layer "In4.Cu")
		(net "SMB_BMC_MM5_SCL")
	)
	(segment
		(start 31.061914 -93.32214)
		(end 31.66872 -92.715334)
		(width 0.10668)
		(layer "In4.Cu")
		(net "SMB_BMC_MM5_SCL")
	)
	(segment
		(start 29.34208 -95.478346)
		(end 29.799026 -95.0214)
		(width 0.10668)
		(layer "In4.Cu")
		(net "SMB_BMC_MM5_SCL")
	)
	(segment
		(start 29.799026 -95.0214)
		(end 29.799026 -94.13748)
		(width 0.10668)
		(layer "In4.Cu")
		(net "SMB_BMC_MM5_SCL")
	)
	(segment
		(start 35.713416 -44.9834)
		(end 37.166296 -43.53052)
		(width 0.10668)
		(layer "In4.Cu")
		(net "SMB_BMC_MM5_SCL")
	)
	(segment
		(start 56.894984 -40.971216)
		(end 57.290208 -40.575992)
		(width 0.11684)
		(layer "F.Cu")
		(net "SMB_BMC_MM5_R_SDA")
	)
	(via
		(at 59.6646 -32.0294)
		(size 0.508)
		(drill 0.254)
		(layers "F.Cu" "B.Cu")
		(net "SMB_BMC_MM5_R_SDA")
	)
	(via
		(at 59.91352 -29.21)
		(size 0.6604)
		(drill 0.3302)
		(layers "F.Cu" "B.Cu")
		(net "SMB_BMC_MM5_R_SDA")
	)
	(via
		(at 57.290208 -40.575992)
		(size 0.4572)
		(drill 0.254)
		(layers "F.Cu" "B.Cu")
		(net "SMB_BMC_MM5_R_SDA")
	)
	(segment
		(start 59.842908 -31.244286)
		(end 59.81954 -31.267654)
		(width 0.11684)
		(layer "B.Cu")
		(net "SMB_BMC_MM5_R_SDA")
	)
	(segment
		(start 60.409582 -31.137352)
		(end 60.302648 -31.244286)
		(width 0.11684)
		(layer "B.Cu")
		(net "SMB_BMC_MM5_R_SDA")
	)
	(segment
		(start 59.6646 -31.549594)
		(end 59.81954 -31.394654)
		(width 0.11684)
		(layer "B.Cu")
		(net "SMB_BMC_MM5_R_SDA")
	)
	(segment
		(start 60.409582 -30.030928)
		(end 60.409582 -31.137352)
		(width 0.11684)
		(layer "B.Cu")
		(net "SMB_BMC_MM5_R_SDA")
	)
	(segment
		(start 60.05195 -27.87904)
		(end 60.05195 -29.07157)
		(width 0.11684)
		(layer "B.Cu")
		(net "SMB_BMC_MM5_R_SDA")
	)
	(segment
		(start 60.302648 -31.244286)
		(end 59.842908 -31.244286)
		(width 0.11684)
		(layer "B.Cu")
		(net "SMB_BMC_MM5_R_SDA")
	)
	(segment
		(start 59.6646 -32.0294)
		(end 59.6646 -31.549594)
		(width 0.11684)
		(layer "B.Cu")
		(net "SMB_BMC_MM5_R_SDA")
	)
	(segment
		(start 59.91352 -29.534866)
		(end 60.409582 -30.030928)
		(width 0.11684)
		(layer "B.Cu")
		(net "SMB_BMC_MM5_R_SDA")
	)
	(segment
		(start 59.81954 -31.394654)
		(end 59.81954 -31.267654)
		(width 0.11684)
		(layer "B.Cu")
		(net "SMB_BMC_MM5_R_SDA")
	)
	(segment
		(start 59.91352 -29.21)
		(end 59.91352 -29.534866)
		(width 0.11684)
		(layer "B.Cu")
		(net "SMB_BMC_MM5_R_SDA")
	)
	(segment
		(start 60.05195 -29.07157)
		(end 59.91352 -29.21)
		(width 0.11684)
		(layer "B.Cu")
		(net "SMB_BMC_MM5_R_SDA")
	)
	(segment
		(start 57.290208 -40.329104)
		(end 56.876442 -39.915338)
		(width 0.08382)
		(layer "In9.Cu")
		(net "SMB_BMC_MM5_R_SDA")
	)
	(segment
		(start 59.944 -35.39109)
		(end 59.944 -32.3088)
		(width 0.08382)
		(layer "In9.Cu")
		(net "SMB_BMC_MM5_R_SDA")
	)
	(segment
		(start 59.944 -32.3088)
		(end 59.6646 -32.0294)
		(width 0.08382)
		(layer "In9.Cu")
		(net "SMB_BMC_MM5_R_SDA")
	)
	(segment
		(start 57.290208 -40.575992)
		(end 57.290208 -40.329104)
		(width 0.08382)
		(layer "In9.Cu")
		(net "SMB_BMC_MM5_R_SDA")
	)
	(segment
		(start 56.876442 -38.458648)
		(end 59.944 -35.39109)
		(width 0.08382)
		(layer "In9.Cu")
		(net "SMB_BMC_MM5_R_SDA")
	)
	(segment
		(start 56.876442 -39.915338)
		(end 56.876442 -38.458648)
		(width 0.08382)
		(layer "In9.Cu")
		(net "SMB_BMC_MM5_R_SDA")
	)
	(segment
		(start 56.894984 -39.37127)
		(end 56.894984 -38.558216)
		(width 0.11684)
		(layer "F.Cu")
		(net "SMB_BMC_MM5_R_SCL")
	)
	(segment
		(start 59.2836 -31.2674)
		(end 60.548774 -31.2674)
		(width 0.11684)
		(layer "F.Cu")
		(net "SMB_BMC_MM5_R_SCL")
	)
	(segment
		(start 58.719974 -33.315402)
		(end 58.719974 -32.59328)
		(width 0.11684)
		(layer "F.Cu")
		(net "SMB_BMC_MM5_R_SCL")
	)
	(segment
		(start 59.182 -31.369)
		(end 59.2836 -31.2674)
		(width 0.11684)
		(layer "F.Cu")
		(net "SMB_BMC_MM5_R_SCL")
	)
	(segment
		(start 58.801 -34.798)
		(end 58.801 -33.396428)
		(width 0.11684)
		(layer "F.Cu")
		(net "SMB_BMC_MM5_R_SCL")
	)
	(segment
		(start 56.894984 -38.558216)
		(end 58.266584 -37.186616)
		(width 0.11684)
		(layer "F.Cu")
		(net "SMB_BMC_MM5_R_SCL")
	)
	(segment
		(start 58.561224 -35.037776)
		(end 58.801 -34.798)
		(width 0.11684)
		(layer "F.Cu")
		(net "SMB_BMC_MM5_R_SCL")
	)
	(segment
		(start 58.801 -33.396428)
		(end 58.719974 -33.315402)
		(width 0.11684)
		(layer "F.Cu")
		(net "SMB_BMC_MM5_R_SCL")
	)
	(segment
		(start 59.182 -32.131254)
		(end 59.182 -31.369)
		(width 0.11684)
		(layer "F.Cu")
		(net "SMB_BMC_MM5_R_SCL")
	)
	(segment
		(start 58.266584 -37.186616)
		(end 58.266584 -35.037776)
		(width 0.11684)
		(layer "F.Cu")
		(net "SMB_BMC_MM5_R_SCL")
	)
	(segment
		(start 58.719974 -32.59328)
		(end 59.182 -32.131254)
		(width 0.11684)
		(layer "F.Cu")
		(net "SMB_BMC_MM5_R_SCL")
	)
	(segment
		(start 60.548774 -31.2674)
		(end 60.549028 -31.267654)
		(width 0.11684)
		(layer "F.Cu")
		(net "SMB_BMC_MM5_R_SCL")
	)
	(segment
		(start 58.266584 -35.037776)
		(end 58.561224 -35.037776)
		(width 0.11684)
		(layer "F.Cu")
		(net "SMB_BMC_MM5_R_SCL")
	)
	(via
		(at 59.2836 -31.2674)
		(size 0.762)
		(drill 0.381)
		(layers "F.Cu" "B.Cu")
		(net "SMB_BMC_MM5_R_SCL")
	)
	(via
		(at 44.336462 -32.696912)
		(size 0.508)
		(drill 0.254)
		(layers "F.Cu" "B.Cu")
		(net "SMB_BMC_MM4_SDA")
	)
	(via
		(at 59.7408 -114.0714)
		(size 0.508)
		(drill 0.254)
		(layers "F.Cu" "B.Cu")
		(net "SMB_BMC_MM4_SDA")
	)
	(segment
		(start 44.38396 -34.237676)
		(end 44.704762 -34.237676)
		(width 0.11684)
		(layer "B.Cu")
		(net "SMB_BMC_MM4_SDA")
	)
	(segment
		(start 58.2422 -115.28298)
		(end 58.4454 -115.48618)
		(width 0.11684)
		(layer "B.Cu")
		(net "SMB_BMC_MM4_SDA")
	)
	(segment
		(start 44.363132 -31.216854)
		(end 43.89374 -31.686246)
		(width 0.11684)
		(layer "B.Cu")
		(net "SMB_BMC_MM4_SDA")
	)
	(segment
		(start 44.819316 -34.123122)
		(end 44.819316 -33.179766)
		(width 0.11684)
		(layer "B.Cu")
		(net "SMB_BMC_MM4_SDA")
	)
	(segment
		(start 59.7408 -113.6396)
		(end 59.17438 -113.07318)
		(width 0.11684)
		(layer "B.Cu")
		(net "SMB_BMC_MM4_SDA")
	)
	(segment
		(start 58.4454 -115.48618)
		(end 58.4454 -116.9162)
		(width 0.11684)
		(layer "B.Cu")
		(net "SMB_BMC_MM4_SDA")
	)
	(segment
		(start 58.4454 -116.9162)
		(end 58.064908 -117.296692)
		(width 0.11684)
		(layer "B.Cu")
		(net "SMB_BMC_MM4_SDA")
	)
	(segment
		(start 59.17438 -113.07318)
		(end 58.544714 -113.07318)
		(width 0.11684)
		(layer "B.Cu")
		(net "SMB_BMC_MM4_SDA")
	)
	(segment
		(start 44.819316 -33.179766)
		(end 44.336462 -32.696912)
		(width 0.11684)
		(layer "B.Cu")
		(net "SMB_BMC_MM4_SDA")
	)
	(segment
		(start 58.544714 -113.07318)
		(end 58.2422 -113.375694)
		(width 0.11684)
		(layer "B.Cu")
		(net "SMB_BMC_MM4_SDA")
	)
	(segment
		(start 58.064908 -117.296692)
		(end 58.064908 -118.25986)
		(width 0.11684)
		(layer "B.Cu")
		(net "SMB_BMC_MM4_SDA")
	)
	(segment
		(start 43.89374 -32.25419)
		(end 44.336462 -32.696912)
		(width 0.11684)
		(layer "B.Cu")
		(net "SMB_BMC_MM4_SDA")
	)
	(segment
		(start 44.704762 -34.237676)
		(end 44.819316 -34.123122)
		(width 0.11684)
		(layer "B.Cu")
		(net "SMB_BMC_MM4_SDA")
	)
	(segment
		(start 44.384214 -31.216854)
		(end 44.363132 -31.216854)
		(width 0.11684)
		(layer "B.Cu")
		(net "SMB_BMC_MM4_SDA")
	)
	(segment
		(start 59.7408 -114.0714)
		(end 59.7408 -113.6396)
		(width 0.11684)
		(layer "B.Cu")
		(net "SMB_BMC_MM4_SDA")
	)
	(segment
		(start 58.2422 -113.375694)
		(end 58.2422 -115.28298)
		(width 0.11684)
		(layer "B.Cu")
		(net "SMB_BMC_MM4_SDA")
	)
	(segment
		(start 43.89374 -31.686246)
		(end 43.89374 -32.25419)
		(width 0.11684)
		(layer "B.Cu")
		(net "SMB_BMC_MM4_SDA")
	)
	(segment
		(start 32.51454 -69.060314)
		(end 32.89554 -69.060314)
		(width 0.10668)
		(layer "In7.Cu")
		(net "SMB_BMC_MM4_SDA")
	)
	(segment
		(start 33.81248 -74.942954)
		(end 33.81248 -73.063354)
		(width 0.10668)
		(layer "In7.Cu")
		(net "SMB_BMC_MM4_SDA")
	)
	(segment
		(start 37.61994 -41.08704)
		(end 37.61994 -40.762682)
		(width 0.10668)
		(layer "In7.Cu")
		(net "SMB_BMC_MM4_SDA")
	)
	(segment
		(start 37.61994 -40.762682)
		(end 38.5191 -39.863522)
		(width 0.10668)
		(layer "In7.Cu")
		(net "SMB_BMC_MM4_SDA")
	)
	(segment
		(start 33.81248 -73.063354)
		(end 33.655 -72.905874)
		(width 0.10668)
		(layer "In7.Cu")
		(net "SMB_BMC_MM4_SDA")
	)
	(segment
		(start 59.7408 -113.584736)
		(end 58.449464 -112.2934)
		(width 0.10668)
		(layer "In7.Cu")
		(net "SMB_BMC_MM4_SDA")
	)
	(segment
		(start 41.25976 -34.094166)
		(end 41.884854 -33.469072)
		(width 0.10668)
		(layer "In7.Cu")
		(net "SMB_BMC_MM4_SDA")
	)
	(segment
		(start 47.89424 -89.228168)
		(end 47.2694 -88.603328)
		(width 0.10668)
		(layer "In7.Cu")
		(net "SMB_BMC_MM4_SDA")
	)
	(segment
		(start 50.66792 -92.945712)
		(end 50.56124 -92.839032)
		(width 0.10668)
		(layer "In7.Cu")
		(net "SMB_BMC_MM4_SDA")
	)
	(segment
		(start 34.19856 -51.51247)
		(end 34.19856 -48.038004)
		(width 0.10668)
		(layer "In7.Cu")
		(net "SMB_BMC_MM4_SDA")
	)
	(segment
		(start 33.83026 -52.402486)
		(end 34.19856 -51.51247)
		(width 0.10668)
		(layer "In7.Cu")
		(net "SMB_BMC_MM4_SDA")
	)
	(segment
		(start 55.600346 -110.11789)
		(end 52.114704 -106.632248)
		(width 0.10668)
		(layer "In7.Cu")
		(net "SMB_BMC_MM4_SDA")
	)
	(segment
		(start 37.338 -43.196764)
		(end 37.338 -41.36898)
		(width 0.10668)
		(layer "In7.Cu")
		(net "SMB_BMC_MM4_SDA")
	)
	(segment
		(start 34.19856 -48.038004)
		(end 36.17722 -46.059344)
		(width 0.10668)
		(layer "In7.Cu")
		(net "SMB_BMC_MM4_SDA")
	)
	(segment
		(start 32.379158 -63.429388)
		(end 32.379158 -60.955682)
		(width 0.10668)
		(layer "In7.Cu")
		(net "SMB_BMC_MM4_SDA")
	)
	(segment
		(start 33.655 -72.905874)
		(end 33.655 -72.90562)
		(width 0.10668)
		(layer "In7.Cu")
		(net "SMB_BMC_MM4_SDA")
	)
	(segment
		(start 43.804078 -83.52028)
		(end 42.461434 -83.52028)
		(width 0.10668)
		(layer "In7.Cu")
		(net "SMB_BMC_MM4_SDA")
	)
	(segment
		(start 32.650176 -66.4464)
		(end 32.1818 -66.4464)
		(width 0.10668)
		(layer "In7.Cu")
		(net "SMB_BMC_MM4_SDA")
	)
	(segment
		(start 36.382706 -78.08976)
		(end 35.703764 -78.08976)
		(width 0.10668)
		(layer "In7.Cu")
		(net "SMB_BMC_MM4_SDA")
	)
	(segment
		(start 31.75508 -64.053466)
		(end 32.379158 -63.429388)
		(width 0.10668)
		(layer "In7.Cu")
		(net "SMB_BMC_MM4_SDA")
	)
	(segment
		(start 51.637184 -106.632248)
		(end 51.05273 -106.047794)
		(width 0.10668)
		(layer "In7.Cu")
		(net "SMB_BMC_MM4_SDA")
	)
	(segment
		(start 51.05273 -105.029)
		(end 51.33086 -104.75087)
		(width 0.10668)
		(layer "In7.Cu")
		(net "SMB_BMC_MM4_SDA")
	)
	(segment
		(start 57.759346 -112.2934)
		(end 55.600346 -110.1344)
		(width 0.10668)
		(layer "In7.Cu")
		(net "SMB_BMC_MM4_SDA")
	)
	(segment
		(start 32.85998 -56.032654)
		(end 33.83026 -55.062374)
		(width 0.10668)
		(layer "In7.Cu")
		(net "SMB_BMC_MM4_SDA")
	)
	(segment
		(start 50.56124 -92.839032)
		(end 48.97628 -92.839032)
		(width 0.10668)
		(layer "In7.Cu")
		(net "SMB_BMC_MM4_SDA")
	)
	(segment
		(start 32.89554 -69.060314)
		(end 33.34512 -68.610734)
		(width 0.10668)
		(layer "In7.Cu")
		(net "SMB_BMC_MM4_SDA")
	)
	(segment
		(start 38.616636 -79.675482)
		(end 37.968428 -79.675482)
		(width 0.10668)
		(layer "In7.Cu")
		(net "SMB_BMC_MM4_SDA")
	)
	(segment
		(start 52.04968 -100.91674)
		(end 52.04968 -96.935798)
		(width 0.10668)
		(layer "In7.Cu")
		(net "SMB_BMC_MM4_SDA")
	)
	(segment
		(start 33.58642 -59.74842)
		(end 33.58642 -59.49569)
		(width 0.10668)
		(layer "In7.Cu")
		(net "SMB_BMC_MM4_SDA")
	)
	(segment
		(start 34.0741 -76.460096)
		(end 34.0741 -75.204574)
		(width 0.10668)
		(layer "In7.Cu")
		(net "SMB_BMC_MM4_SDA")
	)
	(segment
		(start 37.338 -41.36898)
		(end 37.61994 -41.08704)
		(width 0.10668)
		(layer "In7.Cu")
		(net "SMB_BMC_MM4_SDA")
	)
	(segment
		(start 47.2694 -86.985602)
		(end 43.804078 -83.52028)
		(width 0.10668)
		(layer "In7.Cu")
		(net "SMB_BMC_MM4_SDA")
	)
	(segment
		(start 36.17722 -46.059344)
		(end 36.17722 -44.357544)
		(width 0.10668)
		(layer "In7.Cu")
		(net "SMB_BMC_MM4_SDA")
	)
	(segment
		(start 33.34512 -67.141344)
		(end 32.650176 -66.4464)
		(width 0.10668)
		(layer "In7.Cu")
		(net "SMB_BMC_MM4_SDA")
	)
	(segment
		(start 32.85998 -58.76925)
		(end 32.85998 -56.032654)
		(width 0.10668)
		(layer "In7.Cu")
		(net "SMB_BMC_MM4_SDA")
	)
	(segment
		(start 35.703764 -78.08976)
		(end 34.0741 -76.460096)
		(width 0.10668)
		(layer "In7.Cu")
		(net "SMB_BMC_MM4_SDA")
	)
	(segment
		(start 32.1818 -66.4464)
		(end 31.75508 -66.01968)
		(width 0.10668)
		(layer "In7.Cu")
		(net "SMB_BMC_MM4_SDA")
	)
	(segment
		(start 51.33086 -101.63556)
		(end 52.04968 -100.91674)
		(width 0.10668)
		(layer "In7.Cu")
		(net "SMB_BMC_MM4_SDA")
	)
	(segment
		(start 32.379158 -60.955682)
		(end 33.58642 -59.74842)
		(width 0.10668)
		(layer "In7.Cu")
		(net "SMB_BMC_MM4_SDA")
	)
	(segment
		(start 59.7408 -114.0714)
		(end 59.7408 -113.584736)
		(width 0.10668)
		(layer "In7.Cu")
		(net "SMB_BMC_MM4_SDA")
	)
	(segment
		(start 37.968428 -79.675482)
		(end 36.382706 -78.08976)
		(width 0.10668)
		(layer "In7.Cu")
		(net "SMB_BMC_MM4_SDA")
	)
	(segment
		(start 58.449464 -112.2934)
		(end 57.759346 -112.2934)
		(width 0.10668)
		(layer "In7.Cu")
		(net "SMB_BMC_MM4_SDA")
	)
	(segment
		(start 31.75508 -66.01968)
		(end 31.75508 -64.053466)
		(width 0.10668)
		(layer "In7.Cu")
		(net "SMB_BMC_MM4_SDA")
	)
	(segment
		(start 52.114704 -106.632248)
		(end 51.637184 -106.632248)
		(width 0.10668)
		(layer "In7.Cu")
		(net "SMB_BMC_MM4_SDA")
	)
	(segment
		(start 47.89424 -91.756992)
		(end 47.89424 -89.228168)
		(width 0.10668)
		(layer "In7.Cu")
		(net "SMB_BMC_MM4_SDA")
	)
	(segment
		(start 41.25976 -36.33216)
		(end 41.25976 -34.094166)
		(width 0.10668)
		(layer "In7.Cu")
		(net "SMB_BMC_MM4_SDA")
	)
	(segment
		(start 33.83026 -55.062374)
		(end 33.83026 -52.402486)
		(width 0.10668)
		(layer "In7.Cu")
		(net "SMB_BMC_MM4_SDA")
	)
	(segment
		(start 36.17722 -44.357544)
		(end 37.338 -43.196764)
		(width 0.10668)
		(layer "In7.Cu")
		(net "SMB_BMC_MM4_SDA")
	)
	(segment
		(start 55.600346 -110.1344)
		(end 55.600346 -110.11789)
		(width 0.10668)
		(layer "In7.Cu")
		(net "SMB_BMC_MM4_SDA")
	)
	(segment
		(start 33.34512 -68.610734)
		(end 33.34512 -67.141344)
		(width 0.10668)
		(layer "In7.Cu")
		(net "SMB_BMC_MM4_SDA")
	)
	(segment
		(start 51.05273 -106.047794)
		(end 51.05273 -105.029)
		(width 0.10668)
		(layer "In7.Cu")
		(net "SMB_BMC_MM4_SDA")
	)
	(segment
		(start 41.884854 -31.851346)
		(end 42.1386 -31.5976)
		(width 0.10668)
		(layer "In7.Cu")
		(net "SMB_BMC_MM4_SDA")
	)
	(segment
		(start 51.33086 -104.75087)
		(end 51.33086 -101.63556)
		(width 0.10668)
		(layer "In7.Cu")
		(net "SMB_BMC_MM4_SDA")
	)
	(segment
		(start 32.2453 -69.329554)
		(end 32.51454 -69.060314)
		(width 0.10668)
		(layer "In7.Cu")
		(net "SMB_BMC_MM4_SDA")
	)
	(segment
		(start 33.655 -72.90562)
		(end 32.2453 -71.49592)
		(width 0.10668)
		(layer "In7.Cu")
		(net "SMB_BMC_MM4_SDA")
	)
	(segment
		(start 42.461434 -83.52028)
		(end 38.616636 -79.675482)
		(width 0.10668)
		(layer "In7.Cu")
		(net "SMB_BMC_MM4_SDA")
	)
	(segment
		(start 52.04968 -96.935798)
		(end 50.66792 -95.554038)
		(width 0.10668)
		(layer "In7.Cu")
		(net "SMB_BMC_MM4_SDA")
	)
	(segment
		(start 38.5191 -39.07282)
		(end 41.25976 -36.33216)
		(width 0.10668)
		(layer "In7.Cu")
		(net "SMB_BMC_MM4_SDA")
	)
	(segment
		(start 43.23715 -31.5976)
		(end 44.336462 -32.696912)
		(width 0.10668)
		(layer "In7.Cu")
		(net "SMB_BMC_MM4_SDA")
	)
	(segment
		(start 38.5191 -39.863522)
		(end 38.5191 -39.07282)
		(width 0.10668)
		(layer "In7.Cu")
		(net "SMB_BMC_MM4_SDA")
	)
	(segment
		(start 33.58642 -59.49569)
		(end 32.85998 -58.76925)
		(width 0.10668)
		(layer "In7.Cu")
		(net "SMB_BMC_MM4_SDA")
	)
	(segment
		(start 41.884854 -33.469072)
		(end 41.884854 -31.851346)
		(width 0.10668)
		(layer "In7.Cu")
		(net "SMB_BMC_MM4_SDA")
	)
	(segment
		(start 47.2694 -88.603328)
		(end 47.2694 -86.985602)
		(width 0.10668)
		(layer "In7.Cu")
		(net "SMB_BMC_MM4_SDA")
	)
	(segment
		(start 32.2453 -71.49592)
		(end 32.2453 -69.329554)
		(width 0.10668)
		(layer "In7.Cu")
		(net "SMB_BMC_MM4_SDA")
	)
	(segment
		(start 50.66792 -95.554038)
		(end 50.66792 -92.945712)
		(width 0.10668)
		(layer "In7.Cu")
		(net "SMB_BMC_MM4_SDA")
	)
	(segment
		(start 42.1386 -31.5976)
		(end 43.23715 -31.5976)
		(width 0.10668)
		(layer "In7.Cu")
		(net "SMB_BMC_MM4_SDA")
	)
	(segment
		(start 48.97628 -92.839032)
		(end 47.89424 -91.756992)
		(width 0.10668)
		(layer "In7.Cu")
		(net "SMB_BMC_MM4_SDA")
	)
	(segment
		(start 34.0741 -75.204574)
		(end 33.81248 -74.942954)
		(width 0.10668)
		(layer "In7.Cu")
		(net "SMB_BMC_MM4_SDA")
	)
	(via
		(at 52.126642 -107.35691)
		(size 0.508)
		(drill 0.254)
		(layers "F.Cu" "B.Cu")
		(net "SMB_BMC_MM4_SCL")
	)
	(via
		(at 58.7375 -113.538)
		(size 0.508)
		(drill 0.254)
		(layers "F.Cu" "B.Cu")
		(net "SMB_BMC_MM4_SCL")
	)
	(via
		(at 45.28566 -32.721296)
		(size 0.508)
		(drill 0.254)
		(layers "F.Cu" "B.Cu")
		(net "SMB_BMC_MM4_SCL")
	)
	(segment
		(start 45.419264 -34.237676)
		(end 45.748956 -33.907984)
		(width 0.11684)
		(layer "B.Cu")
		(net "SMB_BMC_MM4_SCL")
	)
	(segment
		(start 58.798206 -113.538)
		(end 58.7375 -113.538)
		(width 0.11684)
		(layer "B.Cu")
		(net "SMB_BMC_MM4_SCL")
	)
	(segment
		(start 58.8518 -115.6208)
		(end 59.076844 -115.395756)
		(width 0.11684)
		(layer "B.Cu")
		(net "SMB_BMC_MM4_SCL")
	)
	(segment
		(start 58.66511 -117.305836)
		(end 58.8518 -117.119146)
		(width 0.11684)
		(layer "B.Cu")
		(net "SMB_BMC_MM4_SCL")
	)
	(segment
		(start 58.8518 -117.119146)
		(end 58.8518 -115.6208)
		(width 0.11684)
		(layer "B.Cu")
		(net "SMB_BMC_MM4_SCL")
	)
	(segment
		(start 59.24042 -115.00104)
		(end 59.24042 -113.980214)
		(width 0.11684)
		(layer "B.Cu")
		(net "SMB_BMC_MM4_SCL")
	)
	(segment
		(start 45.28566 -32.252666)
		(end 45.28566 -32.721296)
		(width 0.11684)
		(layer "B.Cu")
		(net "SMB_BMC_MM4_SCL")
	)
	(segment
		(start 59.076844 -115.395756)
		(end 59.24042 -115.00104)
		(width 0.11684)
		(layer "B.Cu")
		(net "SMB_BMC_MM4_SCL")
	)
	(segment
		(start 59.24042 -113.980214)
		(end 58.798206 -113.538)
		(width 0.11684)
		(layer "B.Cu")
		(net "SMB_BMC_MM4_SCL")
	)
	(segment
		(start 45.748956 -33.907984)
		(end 45.748956 -33.18383)
		(width 0.11684)
		(layer "B.Cu")
		(net "SMB_BMC_MM4_SCL")
	)
	(segment
		(start 45.58538 -31.952946)
		(end 45.28566 -32.252666)
		(width 0.11684)
		(layer "B.Cu")
		(net "SMB_BMC_MM4_SCL")
	)
	(segment
		(start 45.405294 -31.216854)
		(end 45.58538 -31.39694)
		(width 0.11684)
		(layer "B.Cu")
		(net "SMB_BMC_MM4_SCL")
	)
	(segment
		(start 45.748956 -33.18383)
		(end 45.286422 -32.721296)
		(width 0.11684)
		(layer "B.Cu")
		(net "SMB_BMC_MM4_SCL")
	)
	(segment
		(start 45.58538 -31.39694)
		(end 45.58538 -31.952946)
		(width 0.11684)
		(layer "B.Cu")
		(net "SMB_BMC_MM4_SCL")
	)
	(segment
		(start 45.286422 -32.721296)
		(end 45.28566 -32.721296)
		(width 0.11684)
		(layer "B.Cu")
		(net "SMB_BMC_MM4_SCL")
	)
	(segment
		(start 58.66511 -118.25986)
		(end 58.66511 -117.305836)
		(width 0.11684)
		(layer "B.Cu")
		(net "SMB_BMC_MM4_SCL")
	)
	(segment
		(start 33.86328 -51.378358)
		(end 33.86328 -47.899066)
		(width 0.10668)
		(layer "In7.Cu")
		(net "SMB_BMC_MM4_SCL")
	)
	(segment
		(start 33.49498 -52.267358)
		(end 33.86328 -51.378358)
		(width 0.10668)
		(layer "In7.Cu")
		(net "SMB_BMC_MM4_SCL")
	)
	(segment
		(start 32.5247 -55.893462)
		(end 33.49498 -54.923182)
		(width 0.10668)
		(layer "In7.Cu")
		(net "SMB_BMC_MM4_SCL")
	)
	(segment
		(start 32.2326 -68.3768)
		(end 32.2326 -66.971418)
		(width 0.10668)
		(layer "In7.Cu")
		(net "SMB_BMC_MM4_SCL")
	)
	(segment
		(start 35.84194 -44.218606)
		(end 36.24326 -43.817286)
		(width 0.10668)
		(layer "In7.Cu")
		(net "SMB_BMC_MM4_SCL")
	)
	(segment
		(start 37.531294 -80.60944)
		(end 36.7538 -79.831946)
		(width 0.10668)
		(layer "In7.Cu")
		(net "SMB_BMC_MM4_SCL")
	)
	(segment
		(start 48.7426 -99.299776)
		(end 48.7426 -93.07957)
		(width 0.10668)
		(layer "In7.Cu")
		(net "SMB_BMC_MM4_SCL")
	)
	(segment
		(start 49.731676 -106.16184)
		(end 49.2506 -105.680764)
		(width 0.10668)
		(layer "In7.Cu")
		(net "SMB_BMC_MM4_SCL")
	)
	(segment
		(start 56.779668 -111.78794)
		(end 57.620408 -112.62868)
		(width 0.10668)
		(layer "In7.Cu")
		(net "SMB_BMC_MM4_SCL")
	)
	(segment
		(start 52.4764 -110.864904)
		(end 53.399436 -111.78794)
		(width 0.10668)
		(layer "In7.Cu")
		(net "SMB_BMC_MM4_SCL")
	)
	(segment
		(start 45.57776 -86.183724)
		(end 43.249596 -83.85556)
		(width 0.10668)
		(layer "In7.Cu")
		(net "SMB_BMC_MM4_SCL")
	)
	(segment
		(start 50.63744 -106.16184)
		(end 49.731676 -106.16184)
		(width 0.10668)
		(layer "In7.Cu")
		(net "SMB_BMC_MM4_SCL")
	)
	(segment
		(start 31.4198 -66.158618)
		(end 31.4198 -63.914528)
		(width 0.10668)
		(layer "In7.Cu")
		(net "SMB_BMC_MM4_SCL")
	)
	(segment
		(start 35.84194 -45.920406)
		(end 35.84194 -44.218606)
		(width 0.10668)
		(layer "In7.Cu")
		(net "SMB_BMC_MM4_SCL")
	)
	(segment
		(start 57.82818 -112.62868)
		(end 58.7375 -113.538)
		(width 0.10668)
		(layer "In7.Cu")
		(net "SMB_BMC_MM4_SCL")
	)
	(segment
		(start 57.620408 -112.62868)
		(end 57.82818 -112.62868)
		(width 0.10668)
		(layer "In7.Cu")
		(net "SMB_BMC_MM4_SCL")
	)
	(segment
		(start 41.335198 -31.879794)
		(end 41.952672 -31.26232)
		(width 0.10668)
		(layer "In7.Cu")
		(net "SMB_BMC_MM4_SCL")
	)
	(segment
		(start 33.73882 -76.614274)
		(end 33.73882 -75.343512)
		(width 0.10668)
		(layer "In7.Cu")
		(net "SMB_BMC_MM4_SCL")
	)
	(segment
		(start 31.31566 -69.29374)
		(end 32.2326 -68.3768)
		(width 0.10668)
		(layer "In7.Cu")
		(net "SMB_BMC_MM4_SCL")
	)
	(segment
		(start 45.013372 -32.449008)
		(end 45.28566 -32.721296)
		(width 0.10668)
		(layer "In7.Cu")
		(net "SMB_BMC_MM4_SCL")
	)
	(segment
		(start 49.2506 -103.931212)
		(end 47.45736 -102.137972)
		(width 0.10668)
		(layer "In7.Cu")
		(net "SMB_BMC_MM4_SCL")
	)
	(segment
		(start 48.84674 -99.403916)
		(end 48.7426 -99.299776)
		(width 0.10668)
		(layer "In7.Cu")
		(net "SMB_BMC_MM4_SCL")
	)
	(segment
		(start 52.126642 -107.35691)
		(end 51.83251 -107.35691)
		(width 0.10668)
		(layer "In7.Cu")
		(net "SMB_BMC_MM4_SCL")
	)
	(segment
		(start 52.4764 -110.167928)
		(end 52.4764 -110.864904)
		(width 0.10668)
		(layer "In7.Cu")
		(net "SMB_BMC_MM4_SCL")
	)
	(segment
		(start 48.84674 -99.869244)
		(end 48.84674 -99.403916)
		(width 0.10668)
		(layer "In7.Cu")
		(net "SMB_BMC_MM4_SCL")
	)
	(segment
		(start 38.15334 -38.964362)
		(end 40.84574 -36.271962)
		(width 0.10668)
		(layer "In7.Cu")
		(net "SMB_BMC_MM4_SCL")
	)
	(segment
		(start 45.57776 -87.385906)
		(end 45.57776 -86.183724)
		(width 0.10668)
		(layer "In7.Cu")
		(net "SMB_BMC_MM4_SCL")
	)
	(segment
		(start 37.38245 -40.02405)
		(end 37.8841 -40.02405)
		(width 0.10668)
		(layer "In7.Cu")
		(net "SMB_BMC_MM4_SCL")
	)
	(segment
		(start 40.84574 -33.76422)
		(end 40.7416 -33.66008)
		(width 0.10668)
		(layer "In7.Cu")
		(net "SMB_BMC_MM4_SCL")
	)
	(segment
		(start 43.376088 -31.26232)
		(end 44.244006 -32.130238)
		(width 0.10668)
		(layer "In7.Cu")
		(net "SMB_BMC_MM4_SCL")
	)
	(segment
		(start 38.15334 -39.75481)
		(end 38.15334 -38.964362)
		(width 0.10668)
		(layer "In7.Cu")
		(net "SMB_BMC_MM4_SCL")
	)
	(segment
		(start 40.7416 -32.767524)
		(end 41.335198 -31.879794)
		(width 0.10668)
		(layer "In7.Cu")
		(net "SMB_BMC_MM4_SCL")
	)
	(segment
		(start 47.55896 -91.89593)
		(end 47.55896 -89.367106)
		(width 0.10668)
		(layer "In7.Cu")
		(net "SMB_BMC_MM4_SCL")
	)
	(segment
		(start 36.24326 -43.817286)
		(end 36.24326 -42.21734)
		(width 0.10668)
		(layer "In7.Cu")
		(net "SMB_BMC_MM4_SCL")
	)
	(segment
		(start 32.5247 -56.58866)
		(end 32.5247 -55.893462)
		(width 0.10668)
		(layer "In7.Cu")
		(net "SMB_BMC_MM4_SCL")
	)
	(segment
		(start 32.043878 -59.990228)
		(end 32.51708 -59.517026)
		(width 0.10668)
		(layer "In7.Cu")
		(net "SMB_BMC_MM4_SCL")
	)
	(segment
		(start 40.84574 -36.271962)
		(end 40.84574 -33.76422)
		(width 0.10668)
		(layer "In7.Cu")
		(net "SMB_BMC_MM4_SCL")
	)
	(segment
		(start 36.70046 -40.70604)
		(end 37.38245 -40.02405)
		(width 0.10668)
		(layer "In7.Cu")
		(net "SMB_BMC_MM4_SCL")
	)
	(segment
		(start 48.284384 -100.4316)
		(end 48.84674 -99.869244)
		(width 0.10668)
		(layer "In7.Cu")
		(net "SMB_BMC_MM4_SCL")
	)
	(segment
		(start 33.25368 -72.978772)
		(end 33.25368 -72.978518)
		(width 0.10668)
		(layer "In7.Cu")
		(net "SMB_BMC_MM4_SCL")
	)
	(segment
		(start 36.7538 -78.948026)
		(end 36.230814 -78.42504)
		(width 0.10668)
		(layer "In7.Cu")
		(net "SMB_BMC_MM4_SCL")
	)
	(segment
		(start 33.49498 -54.923182)
		(end 33.49498 -52.267358)
		(width 0.10668)
		(layer "In7.Cu")
		(net "SMB_BMC_MM4_SCL")
	)
	(segment
		(start 37.8841 -40.02405)
		(end 38.15334 -39.75481)
		(width 0.10668)
		(layer "In7.Cu")
		(net "SMB_BMC_MM4_SCL")
	)
	(segment
		(start 47.45736 -100.734876)
		(end 47.760636 -100.4316)
		(width 0.10668)
		(layer "In7.Cu")
		(net "SMB_BMC_MM4_SCL")
	)
	(segment
		(start 33.4772 -75.081892)
		(end 33.4772 -73.202292)
		(width 0.10668)
		(layer "In7.Cu")
		(net "SMB_BMC_MM4_SCL")
	)
	(segment
		(start 47.55896 -89.367106)
		(end 45.57776 -87.385906)
		(width 0.10668)
		(layer "In7.Cu")
		(net "SMB_BMC_MM4_SCL")
	)
	(segment
		(start 31.31566 -71.040498)
		(end 31.31566 -69.29374)
		(width 0.10668)
		(layer "In7.Cu")
		(net "SMB_BMC_MM4_SCL")
	)
	(segment
		(start 36.24326 -42.21734)
		(end 36.70046 -41.76014)
		(width 0.10668)
		(layer "In7.Cu")
		(net "SMB_BMC_MM4_SCL")
	)
	(segment
		(start 31.4198 -63.914528)
		(end 32.043878 -63.29045)
		(width 0.10668)
		(layer "In7.Cu")
		(net "SMB_BMC_MM4_SCL")
	)
	(segment
		(start 52.126642 -107.35691)
		(end 52.57292 -107.803188)
		(width 0.10668)
		(layer "In7.Cu")
		(net "SMB_BMC_MM4_SCL")
	)
	(segment
		(start 33.73882 -75.343512)
		(end 33.4772 -75.081892)
		(width 0.10668)
		(layer "In7.Cu")
		(net "SMB_BMC_MM4_SCL")
	)
	(segment
		(start 32.043878 -63.29045)
		(end 32.043878 -59.990228)
		(width 0.10668)
		(layer "In7.Cu")
		(net "SMB_BMC_MM4_SCL")
	)
	(segment
		(start 33.86328 -47.899066)
		(end 35.84194 -45.920406)
		(width 0.10668)
		(layer "In7.Cu")
		(net "SMB_BMC_MM4_SCL")
	)
	(segment
		(start 42.322496 -83.85556)
		(end 39.076376 -80.60944)
		(width 0.10668)
		(layer "In7.Cu")
		(net "SMB_BMC_MM4_SCL")
	)
	(segment
		(start 39.076376 -80.60944)
		(end 37.531294 -80.60944)
		(width 0.10668)
		(layer "In7.Cu")
		(net "SMB_BMC_MM4_SCL")
	)
	(segment
		(start 49.2506 -105.680764)
		(end 49.2506 -103.931212)
		(width 0.10668)
		(layer "In7.Cu")
		(net "SMB_BMC_MM4_SCL")
	)
	(segment
		(start 52.57292 -107.803188)
		(end 52.57292 -110.071408)
		(width 0.10668)
		(layer "In7.Cu")
		(net "SMB_BMC_MM4_SCL")
	)
	(segment
		(start 47.760636 -100.4316)
		(end 48.284384 -100.4316)
		(width 0.10668)
		(layer "In7.Cu")
		(net "SMB_BMC_MM4_SCL")
	)
	(segment
		(start 51.83251 -107.35691)
		(end 50.63744 -106.16184)
		(width 0.10668)
		(layer "In7.Cu")
		(net "SMB_BMC_MM4_SCL")
	)
	(segment
		(start 40.7416 -33.66008)
		(end 40.7416 -32.767524)
		(width 0.10668)
		(layer "In7.Cu")
		(net "SMB_BMC_MM4_SCL")
	)
	(segment
		(start 32.51708 -56.59628)
		(end 32.5247 -56.58866)
		(width 0.10668)
		(layer "In7.Cu")
		(net "SMB_BMC_MM4_SCL")
	)
	(segment
		(start 32.2326 -66.971418)
		(end 31.4198 -66.158618)
		(width 0.10668)
		(layer "In7.Cu")
		(net "SMB_BMC_MM4_SCL")
	)
	(segment
		(start 47.45736 -102.137972)
		(end 47.45736 -100.734876)
		(width 0.10668)
		(layer "In7.Cu")
		(net "SMB_BMC_MM4_SCL")
	)
	(segment
		(start 41.952672 -31.26232)
		(end 43.376088 -31.26232)
		(width 0.10668)
		(layer "In7.Cu")
		(net "SMB_BMC_MM4_SCL")
	)
	(segment
		(start 36.70046 -41.76014)
		(end 36.70046 -40.70604)
		(width 0.10668)
		(layer "In7.Cu")
		(net "SMB_BMC_MM4_SCL")
	)
	(segment
		(start 33.4772 -73.202292)
		(end 33.25368 -72.978772)
		(width 0.10668)
		(layer "In7.Cu")
		(net "SMB_BMC_MM4_SCL")
	)
	(segment
		(start 36.7538 -79.831946)
		(end 36.7538 -78.948026)
		(width 0.10668)
		(layer "In7.Cu")
		(net "SMB_BMC_MM4_SCL")
	)
	(segment
		(start 33.25368 -72.978518)
		(end 31.31566 -71.040498)
		(width 0.10668)
		(layer "In7.Cu")
		(net "SMB_BMC_MM4_SCL")
	)
	(segment
		(start 36.230814 -78.42504)
		(end 35.549586 -78.42504)
		(width 0.10668)
		(layer "In7.Cu")
		(net "SMB_BMC_MM4_SCL")
	)
	(segment
		(start 52.57292 -110.071408)
		(end 52.4764 -110.167928)
		(width 0.10668)
		(layer "In7.Cu")
		(net "SMB_BMC_MM4_SCL")
	)
	(segment
		(start 53.399436 -111.78794)
		(end 56.779668 -111.78794)
		(width 0.10668)
		(layer "In7.Cu")
		(net "SMB_BMC_MM4_SCL")
	)
	(segment
		(start 35.549586 -78.42504)
		(end 33.73882 -76.614274)
		(width 0.10668)
		(layer "In7.Cu")
		(net "SMB_BMC_MM4_SCL")
	)
	(segment
		(start 48.7426 -93.07957)
		(end 47.55896 -91.89593)
		(width 0.10668)
		(layer "In7.Cu")
		(net "SMB_BMC_MM4_SCL")
	)
	(segment
		(start 44.244006 -32.130238)
		(end 45.013372 -32.449008)
		(width 0.10668)
		(layer "In7.Cu")
		(net "SMB_BMC_MM4_SCL")
	)
	(segment
		(start 43.249596 -83.85556)
		(end 42.322496 -83.85556)
		(width 0.10668)
		(layer "In7.Cu")
		(net "SMB_BMC_MM4_SCL")
	)
	(segment
		(start 32.51708 -59.517026)
		(end 32.51708 -56.59628)
		(width 0.10668)
		(layer "In7.Cu")
		(net "SMB_BMC_MM4_SCL")
	)
	(segment
		(start 50.494946 -41.771316)
		(end 50.099722 -41.376092)
		(width 0.11684)
		(layer "F.Cu")
		(net "SMB_BMC_MM4_R_SDA")
	)
	(via
		(at 46.165008 -37.351208)
		(size 0.6604)
		(drill 0.3302)
		(layers "F.Cu" "B.Cu")
		(net "SMB_BMC_MM4_R_SDA")
	)
	(via
		(at 50.099722 -41.376092)
		(size 0.4572)
		(drill 0.254)
		(layers "F.Cu" "B.Cu")
		(net "SMB_BMC_MM4_R_SDA")
	)
	(segment
		(start 48.088296 -38.530784)
		(end 47.647352 -38.08984)
		(width 0.11684)
		(layer "B.Cu")
		(net "SMB_BMC_MM4_R_SDA")
	)
	(segment
		(start 45.16882 -36.35502)
		(end 46.165008 -37.351208)
		(width 0.11684)
		(layer "B.Cu")
		(net "SMB_BMC_MM4_R_SDA")
	)
	(segment
		(start 49.631854 -40.9702)
		(end 49.096422 -40.9702)
		(width 0.11684)
		(layer "B.Cu")
		(net "SMB_BMC_MM4_R_SDA")
	)
	(segment
		(start 45.1358 -35.461194)
		(end 45.16882 -35.494214)
		(width 0.11684)
		(layer "B.Cu")
		(net "SMB_BMC_MM4_R_SDA")
	)
	(segment
		(start 50.099722 -41.376092)
		(end 50.037746 -41.376092)
		(width 0.11684)
		(layer "B.Cu")
		(net "SMB_BMC_MM4_R_SDA")
	)
	(segment
		(start 48.088296 -38.88994)
		(end 48.088296 -38.530784)
		(width 0.11684)
		(layer "B.Cu")
		(net "SMB_BMC_MM4_R_SDA")
	)
	(segment
		(start 50.037746 -41.376092)
		(end 49.631854 -40.9702)
		(width 0.11684)
		(layer "B.Cu")
		(net "SMB_BMC_MM4_R_SDA")
	)
	(segment
		(start 46.90364 -38.08984)
		(end 46.165008 -37.351208)
		(width 0.11684)
		(layer "B.Cu")
		(net "SMB_BMC_MM4_R_SDA")
	)
	(segment
		(start 49.096422 -40.9702)
		(end 48.911256 -40.785034)
		(width 0.11684)
		(layer "B.Cu")
		(net "SMB_BMC_MM4_R_SDA")
	)
	(segment
		(start 45.1358 -35.4584)
		(end 45.1358 -35.461194)
		(width 0.11684)
		(layer "B.Cu")
		(net "SMB_BMC_MM4_R_SDA")
	)
	(segment
		(start 44.38396 -35.037776)
		(end 44.715176 -35.037776)
		(width 0.11684)
		(layer "B.Cu")
		(net "SMB_BMC_MM4_R_SDA")
	)
	(segment
		(start 48.911256 -40.785034)
		(end 48.911256 -39.7129)
		(width 0.11684)
		(layer "B.Cu")
		(net "SMB_BMC_MM4_R_SDA")
	)
	(segment
		(start 48.911256 -39.7129)
		(end 48.088296 -38.88994)
		(width 0.11684)
		(layer "B.Cu")
		(net "SMB_BMC_MM4_R_SDA")
	)
	(segment
		(start 44.715176 -35.037776)
		(end 45.1358 -35.4584)
		(width 0.11684)
		(layer "B.Cu")
		(net "SMB_BMC_MM4_R_SDA")
	)
	(segment
		(start 45.16882 -35.494214)
		(end 45.16882 -36.35502)
		(width 0.11684)
		(layer "B.Cu")
		(net "SMB_BMC_MM4_R_SDA")
	)
	(segment
		(start 47.647352 -38.08984)
		(end 46.90364 -38.08984)
		(width 0.11684)
		(layer "B.Cu")
		(net "SMB_BMC_MM4_R_SDA")
	)
	(segment
		(start 49.6951 -40.971216)
		(end 49.299876 -40.575992)
		(width 0.11684)
		(layer "F.Cu")
		(net "SMB_BMC_MM4_R_SCL")
	)
	(via
		(at 48.0822 -37.6936)
		(size 0.508)
		(drill 0.254)
		(layers "F.Cu" "B.Cu")
		(net "SMB_BMC_MM4_R_SCL")
	)
	(via
		(at 49.299876 -40.575992)
		(size 0.4572)
		(drill 0.254)
		(layers "F.Cu" "B.Cu")
		(net "SMB_BMC_MM4_R_SCL")
	)
	(segment
		(start 45.53204 -35.296856)
		(end 45.56506 -35.329876)
		(width 0.11684)
		(layer "B.Cu")
		(net "SMB_BMC_MM4_R_SCL")
	)
	(segment
		(start 49.2506 -40.526716)
		(end 49.299876 -40.575992)
		(width 0.11684)
		(layer "B.Cu")
		(net "SMB_BMC_MM4_R_SCL")
	)
	(segment
		(start 45.56506 -35.887914)
		(end 47.370746 -37.6936)
		(width 0.11684)
		(layer "B.Cu")
		(net "SMB_BMC_MM4_R_SCL")
	)
	(segment
		(start 48.48098 -38.39337)
		(end 48.48098 -38.973252)
		(width 0.11684)
		(layer "B.Cu")
		(net "SMB_BMC_MM4_R_SCL")
	)
	(segment
		(start 48.243998 -38.156388)
		(end 48.48098 -38.39337)
		(width 0.11684)
		(layer "B.Cu")
		(net "SMB_BMC_MM4_R_SCL")
	)
	(segment
		(start 49.2506 -39.742872)
		(end 49.2506 -40.526716)
		(width 0.11684)
		(layer "B.Cu")
		(net "SMB_BMC_MM4_R_SCL")
	)
	(segment
		(start 48.0822 -37.6936)
		(end 48.243998 -37.855398)
		(width 0.11684)
		(layer "B.Cu")
		(net "SMB_BMC_MM4_R_SCL")
	)
	(segment
		(start 45.419264 -35.181286)
		(end 45.53204 -35.294062)
		(width 0.11684)
		(layer "B.Cu")
		(net "SMB_BMC_MM4_R_SCL")
	)
	(segment
		(start 48.48098 -38.973252)
		(end 49.2506 -39.742872)
		(width 0.11684)
		(layer "B.Cu")
		(net "SMB_BMC_MM4_R_SCL")
	)
	(segment
		(start 45.53204 -35.294062)
		(end 45.53204 -35.296856)
		(width 0.11684)
		(layer "B.Cu")
		(net "SMB_BMC_MM4_R_SCL")
	)
	(segment
		(start 45.419264 -35.037776)
		(end 45.419264 -35.181286)
		(width 0.11684)
		(layer "B.Cu")
		(net "SMB_BMC_MM4_R_SCL")
	)
	(segment
		(start 47.370746 -37.6936)
		(end 48.0822 -37.6936)
		(width 0.11684)
		(layer "B.Cu")
		(net "SMB_BMC_MM4_R_SCL")
	)
	(segment
		(start 48.243998 -37.855398)
		(end 48.243998 -38.156388)
		(width 0.11684)
		(layer "B.Cu")
		(net "SMB_BMC_MM4_R_SCL")
	)
	(segment
		(start 45.56506 -35.329876)
		(end 45.56506 -35.887914)
		(width 0.11684)
		(layer "B.Cu")
		(net "SMB_BMC_MM4_R_SCL")
	)
	(segment
		(start 49.779682 -33.602676)
		(end 49.779682 -34.237676)
		(width 0.11684)
		(layer "F.Cu")
		(net "SMB_BMC_MM3_SDA")
	)
	(segment
		(start 49.251362 -31.816802)
		(end 49.251362 -33.074356)
		(width 0.11684)
		(layer "F.Cu")
		(net "SMB_BMC_MM3_SDA")
	)
	(segment
		(start 49.80051 -31.267654)
		(end 49.251362 -31.816802)
		(width 0.11684)
		(layer "F.Cu")
		(net "SMB_BMC_MM3_SDA")
	)
	(segment
		(start 49.251362 -33.074356)
		(end 49.779682 -33.602676)
		(width 0.11684)
		(layer "F.Cu")
		(net "SMB_BMC_MM3_SDA")
	)
	(via
		(at 59.7916 -114.7064)
		(size 0.508)
		(drill 0.254)
		(layers "F.Cu" "B.Cu")
		(net "SMB_BMC_MM3_SDA")
	)
	(via
		(at 50.78476 -107.6198)
		(size 0.508)
		(drill 0.254)
		(layers "F.Cu" "B.Cu")
		(net "SMB_BMC_MM3_SDA")
	)
	(via
		(at 49.779682 -33.602676)
		(size 0.508)
		(drill 0.254)
		(layers "F.Cu" "B.Cu")
		(net "SMB_BMC_MM3_SDA")
	)
	(segment
		(start 59.265058 -118.25986)
		(end 59.265058 -116.321078)
		(width 0.11684)
		(layer "B.Cu")
		(net "SMB_BMC_MM3_SDA")
	)
	(segment
		(start 59.265058 -116.321078)
		(end 59.396376 -115.660424)
		(width 0.11684)
		(layer "B.Cu")
		(net "SMB_BMC_MM3_SDA")
	)
	(segment
		(start 59.396376 -115.660424)
		(end 59.7916 -114.7064)
		(width 0.11684)
		(layer "B.Cu")
		(net "SMB_BMC_MM3_SDA")
	)
	(segment
		(start 32.80664 -75.359768)
		(end 33.06826 -75.621388)
		(width 0.10668)
		(layer "In7.Cu")
		(net "SMB_BMC_MM3_SDA")
	)
	(segment
		(start 50.78476 -107.6198)
		(end 50.9778 -107.81284)
		(width 0.10668)
		(layer "In7.Cu")
		(net "SMB_BMC_MM3_SDA")
	)
	(segment
		(start 49.99736 -106.8324)
		(end 50.78476 -107.6198)
		(width 0.10668)
		(layer "In7.Cu")
		(net "SMB_BMC_MM3_SDA")
	)
	(segment
		(start 30.605222 -59.191398)
		(end 30.32506 -59.47156)
		(width 0.10668)
		(layer "In7.Cu")
		(net "SMB_BMC_MM3_SDA")
	)
	(segment
		(start 47.68469 -105.06329)
		(end 49.4538 -106.8324)
		(width 0.10668)
		(layer "In7.Cu")
		(net "SMB_BMC_MM3_SDA")
	)
	(segment
		(start 47.68469 -104.88549)
		(end 47.68469 -105.06329)
		(width 0.10668)
		(layer "In7.Cu")
		(net "SMB_BMC_MM3_SDA")
	)
	(segment
		(start 50.9778 -112.037114)
		(end 51.34737 -112.929416)
		(width 0.10668)
		(layer "In7.Cu")
		(net "SMB_BMC_MM3_SDA")
	)
	(segment
		(start 47.36592 -98.58248)
		(end 47.36592 -99.87788)
		(width 0.10668)
		(layer "In7.Cu")
		(net "SMB_BMC_MM3_SDA")
	)
	(segment
		(start 32.44088 -47.271178)
		(end 32.44088 -49.365408)
		(width 0.10668)
		(layer "In7.Cu")
		(net "SMB_BMC_MM3_SDA")
	)
	(segment
		(start 44.9072 -87.8078)
		(end 46.8884 -89.789)
		(width 0.10668)
		(layer "In7.Cu")
		(net "SMB_BMC_MM3_SDA")
	)
	(segment
		(start 32.80664 -73.480168)
		(end 32.80664 -75.359768)
		(width 0.10668)
		(layer "In7.Cu")
		(net "SMB_BMC_MM3_SDA")
	)
	(segment
		(start 35.24504 -79.06893)
		(end 35.24504 -79.61884)
		(width 0.10668)
		(layer "In7.Cu")
		(net "SMB_BMC_MM3_SDA")
	)
	(segment
		(start 52.591462 -114.1476)
		(end 54.790848 -115.058444)
		(width 0.10668)
		(layer "In7.Cu")
		(net "SMB_BMC_MM3_SDA")
	)
	(segment
		(start 33.173162 -51.288696)
		(end 32.831278 -52.11445)
		(width 0.10668)
		(layer "In7.Cu")
		(net "SMB_BMC_MM3_SDA")
	)
	(segment
		(start 32.831278 -52.11445)
		(end 32.82442 -52.148994)
		(width 0.10668)
		(layer "In7.Cu")
		(net "SMB_BMC_MM3_SDA")
	)
	(segment
		(start 50.3301 -32.54502)
		(end 48.7172 -30.93212)
		(width 0.10668)
		(layer "In7.Cu")
		(net "SMB_BMC_MM3_SDA")
	)
	(segment
		(start 29.78531 -64.57569)
		(end 30.74924 -65.53962)
		(width 0.10668)
		(layer "In7.Cu")
		(net "SMB_BMC_MM3_SDA")
	)
	(segment
		(start 40.001952 -32.290766)
		(end 39.687754 -32.290766)
		(width 0.10668)
		(layer "In7.Cu")
		(net "SMB_BMC_MM3_SDA")
	)
	(segment
		(start 50.9778 -107.81284)
		(end 50.9778 -112.037114)
		(width 0.10668)
		(layer "In7.Cu")
		(net "SMB_BMC_MM3_SDA")
	)
	(segment
		(start 42.04462 -84.52612)
		(end 42.97172 -84.52612)
		(width 0.10668)
		(layer "In7.Cu")
		(net "SMB_BMC_MM3_SDA")
	)
	(segment
		(start 31.56204 -67.249294)
		(end 31.56204 -67.8053)
		(width 0.10668)
		(layer "In7.Cu")
		(net "SMB_BMC_MM3_SDA")
	)
	(segment
		(start 30.605222 -57.507632)
		(end 30.605222 -59.191398)
		(width 0.10668)
		(layer "In7.Cu")
		(net "SMB_BMC_MM3_SDA")
	)
	(segment
		(start 36.0299 -40.428164)
		(end 36.0299 -41.059354)
		(width 0.10668)
		(layer "In7.Cu")
		(net "SMB_BMC_MM3_SDA")
	)
	(segment
		(start 41.673272 -30.59176)
		(end 41.11117 -30.824424)
		(width 0.10668)
		(layer "In7.Cu")
		(net "SMB_BMC_MM3_SDA")
	)
	(segment
		(start 54.790848 -115.058444)
		(end 57.246774 -115.058444)
		(width 0.10668)
		(layer "In7.Cu")
		(net "SMB_BMC_MM3_SDA")
	)
	(segment
		(start 47.36592 -99.87788)
		(end 46.7868 -100.457)
		(width 0.10668)
		(layer "In7.Cu")
		(net "SMB_BMC_MM3_SDA")
	)
	(segment
		(start 60.1472 -114.7064)
		(end 59.7916 -114.7064)
		(width 0.10668)
		(layer "In7.Cu")
		(net "SMB_BMC_MM3_SDA")
	)
	(segment
		(start 32.82442 -54.645306)
		(end 31.49981 -55.969916)
		(width 0.10668)
		(layer "In7.Cu")
		(net "SMB_BMC_MM3_SDA")
	)
	(segment
		(start 32.92602 -46.786038)
		(end 32.44088 -47.271178)
		(width 0.10668)
		(layer "In7.Cu")
		(net "SMB_BMC_MM3_SDA")
	)
	(segment
		(start 48.7172 -30.93212)
		(end 44.512484 -30.93212)
		(width 0.10668)
		(layer "In7.Cu")
		(net "SMB_BMC_MM3_SDA")
	)
	(segment
		(start 32.44088 -49.365408)
		(end 33.173162 -50.09769)
		(width 0.10668)
		(layer "In7.Cu")
		(net "SMB_BMC_MM3_SDA")
	)
	(segment
		(start 44.512484 -30.93212)
		(end 44.172124 -30.59176)
		(width 0.10668)
		(layer "In7.Cu")
		(net "SMB_BMC_MM3_SDA")
	)
	(segment
		(start 37.719762 -35.921188)
		(end 36.90112 -36.73983)
		(width 0.10668)
		(layer "In7.Cu")
		(net "SMB_BMC_MM3_SDA")
	)
	(segment
		(start 49.4538 -106.8324)
		(end 49.99736 -106.8324)
		(width 0.10668)
		(layer "In7.Cu")
		(net "SMB_BMC_MM3_SDA")
	)
	(segment
		(start 30.50794 -60.5155)
		(end 30.4292 -60.59424)
		(width 0.10668)
		(layer "In7.Cu")
		(net "SMB_BMC_MM3_SDA")
	)
	(segment
		(start 29.78531 -63.098426)
		(end 29.78531 -64.57569)
		(width 0.10668)
		(layer "In7.Cu")
		(net "SMB_BMC_MM3_SDA")
	)
	(segment
		(start 39.697152 -35.921188)
		(end 37.719762 -35.921188)
		(width 0.10668)
		(layer "In7.Cu")
		(net "SMB_BMC_MM3_SDA")
	)
	(segment
		(start 40.391334 -31.901384)
		(end 40.001952 -32.290766)
		(width 0.10668)
		(layer "In7.Cu")
		(net "SMB_BMC_MM3_SDA")
	)
	(segment
		(start 36.0299 -41.059354)
		(end 33.19272 -43.896534)
		(width 0.10668)
		(layer "In7.Cu")
		(net "SMB_BMC_MM3_SDA")
	)
	(segment
		(start 36.89858 -39.559484)
		(end 36.0299 -40.428164)
		(width 0.10668)
		(layer "In7.Cu")
		(net "SMB_BMC_MM3_SDA")
	)
	(segment
		(start 38.2524 -82.6262)
		(end 40.1447 -82.6262)
		(width 0.10668)
		(layer "In7.Cu")
		(net "SMB_BMC_MM3_SDA")
	)
	(segment
		(start 44.9072 -86.4616)
		(end 44.9072 -87.8078)
		(width 0.10668)
		(layer "In7.Cu")
		(net "SMB_BMC_MM3_SDA")
	)
	(segment
		(start 32.92602 -44.44238)
		(end 32.92602 -46.786038)
		(width 0.10668)
		(layer "In7.Cu")
		(net "SMB_BMC_MM3_SDA")
	)
	(segment
		(start 49.779682 -33.602676)
		(end 50.3301 -33.052258)
		(width 0.10668)
		(layer "In7.Cu")
		(net "SMB_BMC_MM3_SDA")
	)
	(segment
		(start 46.7868 -100.457)
		(end 46.7868 -103.9876)
		(width 0.10668)
		(layer "In7.Cu")
		(net "SMB_BMC_MM3_SDA")
	)
	(segment
		(start 40.07358 -35.54476)
		(end 39.697152 -35.921188)
		(width 0.10668)
		(layer "In7.Cu")
		(net "SMB_BMC_MM3_SDA")
	)
	(segment
		(start 50.3301 -33.052258)
		(end 50.3301 -32.54502)
		(width 0.10668)
		(layer "In7.Cu")
		(net "SMB_BMC_MM3_SDA")
	)
	(segment
		(start 35.24504 -79.61884)
		(end 38.2524 -82.6262)
		(width 0.10668)
		(layer "In7.Cu")
		(net "SMB_BMC_MM3_SDA")
	)
	(segment
		(start 39.334948 -32.577278)
		(end 39.144956 -32.76727)
		(width 0.10668)
		(layer "In7.Cu")
		(net "SMB_BMC_MM3_SDA")
	)
	(segment
		(start 58.92292 -115.75288)
		(end 59.517026 -115.75288)
		(width 0.10668)
		(layer "In7.Cu")
		(net "SMB_BMC_MM3_SDA")
	)
	(segment
		(start 39.144956 -32.76727)
		(end 39.144956 -33.677606)
		(width 0.10668)
		(layer "In7.Cu")
		(net "SMB_BMC_MM3_SDA")
	)
	(segment
		(start 30.4292 -62.454536)
		(end 29.78531 -63.098426)
		(width 0.10668)
		(layer "In7.Cu")
		(net "SMB_BMC_MM3_SDA")
	)
	(segment
		(start 30.50794 -60.03544)
		(end 30.50794 -60.5155)
		(width 0.10668)
		(layer "In7.Cu")
		(net "SMB_BMC_MM3_SDA")
	)
	(segment
		(start 46.8884 -92.2274)
		(end 48.07204 -93.41104)
		(width 0.10668)
		(layer "In7.Cu")
		(net "SMB_BMC_MM3_SDA")
	)
	(segment
		(start 30.74924 -66.436494)
		(end 31.56204 -67.249294)
		(width 0.10668)
		(layer "In7.Cu")
		(net "SMB_BMC_MM3_SDA")
	)
	(segment
		(start 51.34737 -113.34877)
		(end 52.1462 -114.1476)
		(width 0.10668)
		(layer "In7.Cu")
		(net "SMB_BMC_MM3_SDA")
	)
	(segment
		(start 60.459874 -115.6081)
		(end 60.459874 -115.019074)
		(width 0.10668)
		(layer "In7.Cu")
		(net "SMB_BMC_MM3_SDA")
	)
	(segment
		(start 31.044388 -57.068466)
		(end 30.605222 -57.507632)
		(width 0.10668)
		(layer "In7.Cu")
		(net "SMB_BMC_MM3_SDA")
	)
	(segment
		(start 30.03804 -69.3293)
		(end 30.03804 -70.711568)
		(width 0.10668)
		(layer "In7.Cu")
		(net "SMB_BMC_MM3_SDA")
	)
	(segment
		(start 39.682928 -34.822638)
		(end 40.07358 -35.21329)
		(width 0.10668)
		(layer "In7.Cu")
		(net "SMB_BMC_MM3_SDA")
	)
	(segment
		(start 48.07204 -97.87636)
		(end 47.36592 -98.58248)
		(width 0.10668)
		(layer "In7.Cu")
		(net "SMB_BMC_MM3_SDA")
	)
	(segment
		(start 40.07358 -35.21329)
		(end 40.07358 -35.54476)
		(width 0.10668)
		(layer "In7.Cu")
		(net "SMB_BMC_MM3_SDA")
	)
	(segment
		(start 46.7868 -103.9876)
		(end 47.68469 -104.88549)
		(width 0.10668)
		(layer "In7.Cu")
		(net "SMB_BMC_MM3_SDA")
	)
	(segment
		(start 30.32506 -59.47156)
		(end 30.32506 -59.85256)
		(width 0.10668)
		(layer "In7.Cu")
		(net "SMB_BMC_MM3_SDA")
	)
	(segment
		(start 52.1462 -114.1476)
		(end 52.591462 -114.1476)
		(width 0.10668)
		(layer "In7.Cu")
		(net "SMB_BMC_MM3_SDA")
	)
	(segment
		(start 31.49981 -55.969916)
		(end 31.044388 -57.068466)
		(width 0.10668)
		(layer "In7.Cu")
		(net "SMB_BMC_MM3_SDA")
	)
	(segment
		(start 42.97172 -84.52612)
		(end 44.9072 -86.4616)
		(width 0.10668)
		(layer "In7.Cu")
		(net "SMB_BMC_MM3_SDA")
	)
	(segment
		(start 36.90112 -36.73983)
		(end 36.90112 -37.388546)
		(width 0.10668)
		(layer "In7.Cu")
		(net "SMB_BMC_MM3_SDA")
	)
	(segment
		(start 33.06826 -76.89215)
		(end 35.24504 -79.06893)
		(width 0.10668)
		(layer "In7.Cu")
		(net "SMB_BMC_MM3_SDA")
	)
	(segment
		(start 60.075318 -115.992656)
		(end 60.459874 -115.6081)
		(width 0.10668)
		(layer "In7.Cu")
		(net "SMB_BMC_MM3_SDA")
	)
	(segment
		(start 36.89858 -37.391086)
		(end 36.89858 -39.559484)
		(width 0.10668)
		(layer "In7.Cu")
		(net "SMB_BMC_MM3_SDA")
	)
	(segment
		(start 40.1447 -82.6262)
		(end 42.04462 -84.52612)
		(width 0.10668)
		(layer "In7.Cu")
		(net "SMB_BMC_MM3_SDA")
	)
	(segment
		(start 60.459874 -115.019074)
		(end 60.1472 -114.7064)
		(width 0.10668)
		(layer "In7.Cu")
		(net "SMB_BMC_MM3_SDA")
	)
	(segment
		(start 41.11117 -30.824424)
		(end 40.391334 -31.901384)
		(width 0.10668)
		(layer "In7.Cu")
		(net "SMB_BMC_MM3_SDA")
	)
	(segment
		(start 48.07204 -93.41104)
		(end 48.07204 -97.87636)
		(width 0.10668)
		(layer "In7.Cu")
		(net "SMB_BMC_MM3_SDA")
	)
	(segment
		(start 30.32506 -59.85256)
		(end 30.50794 -60.03544)
		(width 0.10668)
		(layer "In7.Cu")
		(net "SMB_BMC_MM3_SDA")
	)
	(segment
		(start 59.756802 -115.992656)
		(end 60.075318 -115.992656)
		(width 0.10668)
		(layer "In7.Cu")
		(net "SMB_BMC_MM3_SDA")
	)
	(segment
		(start 33.19272 -43.896534)
		(end 33.19272 -44.17568)
		(width 0.10668)
		(layer "In7.Cu")
		(net "SMB_BMC_MM3_SDA")
	)
	(segment
		(start 44.172124 -30.59176)
		(end 41.673272 -30.59176)
		(width 0.10668)
		(layer "In7.Cu")
		(net "SMB_BMC_MM3_SDA")
	)
	(segment
		(start 36.90112 -37.388546)
		(end 36.89858 -37.391086)
		(width 0.10668)
		(layer "In7.Cu")
		(net "SMB_BMC_MM3_SDA")
	)
	(segment
		(start 33.19272 -44.17568)
		(end 32.92602 -44.44238)
		(width 0.10668)
		(layer "In7.Cu")
		(net "SMB_BMC_MM3_SDA")
	)
	(segment
		(start 59.517026 -115.75288)
		(end 59.756802 -115.992656)
		(width 0.10668)
		(layer "In7.Cu")
		(net "SMB_BMC_MM3_SDA")
	)
	(segment
		(start 31.56204 -67.8053)
		(end 30.03804 -69.3293)
		(width 0.10668)
		(layer "In7.Cu")
		(net "SMB_BMC_MM3_SDA")
	)
	(segment
		(start 39.144956 -33.677606)
		(end 39.52621 -34.05886)
		(width 0.10668)
		(layer "In7.Cu")
		(net "SMB_BMC_MM3_SDA")
	)
	(segment
		(start 39.687754 -32.290766)
		(end 39.363904 -32.507174)
		(width 0.10668)
		(layer "In7.Cu")
		(net "SMB_BMC_MM3_SDA")
	)
	(segment
		(start 33.06826 -75.621388)
		(end 33.06826 -76.89215)
		(width 0.10668)
		(layer "In7.Cu")
		(net "SMB_BMC_MM3_SDA")
	)
	(segment
		(start 33.173162 -50.09769)
		(end 33.173162 -51.288696)
		(width 0.10668)
		(layer "In7.Cu")
		(net "SMB_BMC_MM3_SDA")
	)
	(segment
		(start 51.34737 -112.929416)
		(end 51.34737 -113.34877)
		(width 0.10668)
		(layer "In7.Cu")
		(net "SMB_BMC_MM3_SDA")
	)
	(segment
		(start 30.4292 -60.59424)
		(end 30.4292 -62.454536)
		(width 0.10668)
		(layer "In7.Cu")
		(net "SMB_BMC_MM3_SDA")
	)
	(segment
		(start 30.74924 -65.53962)
		(end 30.74924 -66.436494)
		(width 0.10668)
		(layer "In7.Cu")
		(net "SMB_BMC_MM3_SDA")
	)
	(segment
		(start 30.03804 -70.711568)
		(end 32.80664 -73.480168)
		(width 0.10668)
		(layer "In7.Cu")
		(net "SMB_BMC_MM3_SDA")
	)
	(segment
		(start 57.246774 -115.058444)
		(end 58.92292 -115.75288)
		(width 0.10668)
		(layer "In7.Cu")
		(net "SMB_BMC_MM3_SDA")
	)
	(segment
		(start 39.363904 -32.507174)
		(end 39.334948 -32.577278)
		(width 0.10668)
		(layer "In7.Cu")
		(net "SMB_BMC_MM3_SDA")
	)
	(segment
		(start 46.8884 -89.789)
		(end 46.8884 -92.2274)
		(width 0.10668)
		(layer "In7.Cu")
		(net "SMB_BMC_MM3_SDA")
	)
	(segment
		(start 39.52621 -34.444432)
		(end 39.682928 -34.822638)
		(width 0.10668)
		(layer "In7.Cu")
		(net "SMB_BMC_MM3_SDA")
	)
	(segment
		(start 39.52621 -34.05886)
		(end 39.52621 -34.444432)
		(width 0.10668)
		(layer "In7.Cu")
		(net "SMB_BMC_MM3_SDA")
	)
	(segment
		(start 32.82442 -52.148994)
		(end 32.82442 -54.645306)
		(width 0.10668)
		(layer "In7.Cu")
		(net "SMB_BMC_MM3_SDA")
	)
	(via
		(at 47.60849 -32.924242)
		(size 0.508)
		(drill 0.254)
		(layers "F.Cu" "B.Cu")
		(net "SMB_BMC_MM3_SCL")
	)
	(via
		(at 60.000134 -115.4176)
		(size 0.508)
		(drill 0.254)
		(layers "F.Cu" "B.Cu")
		(net "SMB_BMC_MM3_SCL")
	)
	(segment
		(start 60.000134 -115.81892)
		(end 60.000134 -115.4176)
		(width 0.11684)
		(layer "B.Cu")
		(net "SMB_BMC_MM3_SCL")
	)
	(segment
		(start 48.086772 -33.055052)
		(end 48.086772 -34.072322)
		(width 0.11684)
		(layer "B.Cu")
		(net "SMB_BMC_MM3_SCL")
	)
	(segment
		(start 48.086772 -34.072322)
		(end 47.888144 -34.27095)
		(width 0.11684)
		(layer "B.Cu")
		(net "SMB_BMC_MM3_SCL")
	)
	(segment
		(start 47.888144 -34.27095)
		(end 47.498 -34.27095)
		(width 0.11684)
		(layer "B.Cu")
		(net "SMB_BMC_MM3_SCL")
	)
	(segment
		(start 48.12538 -32.284416)
		(end 47.60849 -32.801306)
		(width 0.11684)
		(layer "B.Cu")
		(net "SMB_BMC_MM3_SCL")
	)
	(segment
		(start 47.60849 -32.801306)
		(end 47.60849 -32.924242)
		(width 0.11684)
		(layer "B.Cu")
		(net "SMB_BMC_MM3_SCL")
	)
	(segment
		(start 48.12538 -31.775654)
		(end 48.12538 -32.284416)
		(width 0.11684)
		(layer "B.Cu")
		(net "SMB_BMC_MM3_SCL")
	)
	(segment
		(start 47.60849 -32.924242)
		(end 47.612808 -32.919924)
		(width 0.11684)
		(layer "B.Cu")
		(net "SMB_BMC_MM3_SCL")
	)
	(segment
		(start 59.865006 -118.25986)
		(end 59.865006 -115.954048)
		(width 0.11684)
		(layer "B.Cu")
		(net "SMB_BMC_MM3_SCL")
	)
	(segment
		(start 47.951644 -32.919924)
		(end 48.086772 -33.055052)
		(width 0.11684)
		(layer "B.Cu")
		(net "SMB_BMC_MM3_SCL")
	)
	(segment
		(start 47.612808 -32.919924)
		(end 47.951644 -32.919924)
		(width 0.11684)
		(layer "B.Cu")
		(net "SMB_BMC_MM3_SCL")
	)
	(segment
		(start 59.865006 -115.954048)
		(end 60.000134 -115.81892)
		(width 0.11684)
		(layer "B.Cu")
		(net "SMB_BMC_MM3_SCL")
	)
	(segment
		(start 47.607474 -31.257748)
		(end 48.12538 -31.775654)
		(width 0.11684)
		(layer "B.Cu")
		(net "SMB_BMC_MM3_SCL")
	)
	(segment
		(start 42.183558 -84.19084)
		(end 40.283638 -82.29092)
		(width 0.10668)
		(layer "In7.Cu")
		(net "SMB_BMC_MM3_SCL")
	)
	(segment
		(start 52.14112 -110.306866)
		(end 51.31308 -109.478826)
		(width 0.10668)
		(layer "In7.Cu")
		(net "SMB_BMC_MM3_SCL")
	)
	(segment
		(start 32.1818 -59.378088)
		(end 32.1818 -56.63692)
		(width 0.10668)
		(layer "In7.Cu")
		(net "SMB_BMC_MM3_SCL")
	)
	(segment
		(start 31.708598 -59.85129)
		(end 32.1818 -59.378088)
		(width 0.10668)
		(layer "In7.Cu")
		(net "SMB_BMC_MM3_SCL")
	)
	(segment
		(start 41.418256 -31.06039)
		(end 41.740328 -30.92704)
		(width 0.10668)
		(layer "In7.Cu")
		(net "SMB_BMC_MM3_SCL")
	)
	(segment
		(start 36.36518 -41.198292)
		(end 36.36518 -40.567102)
		(width 0.10668)
		(layer "In7.Cu")
		(net "SMB_BMC_MM3_SCL")
	)
	(segment
		(start 39.91229 -33.79089)
		(end 40.40632 -33.29686)
		(width 0.10668)
		(layer "In7.Cu")
		(net "SMB_BMC_MM3_SCL")
	)
	(segment
		(start 52.14112 -111.003842)
		(end 52.14112 -110.306866)
		(width 0.10668)
		(layer "In7.Cu")
		(net "SMB_BMC_MM3_SCL")
	)
	(segment
		(start 57.986168 -114.723164)
		(end 56.20385 -114.723164)
		(width 0.10668)
		(layer "In7.Cu")
		(net "SMB_BMC_MM3_SCL")
	)
	(segment
		(start 33.14192 -73.34123)
		(end 32.9184 -73.11771)
		(width 0.10668)
		(layer "In7.Cu")
		(net "SMB_BMC_MM3_SCL")
	)
	(segment
		(start 53.06822 -113.69802)
		(end 53.06822 -112.12322)
		(width 0.10668)
		(layer "In7.Cu")
		(net "SMB_BMC_MM3_SCL")
	)
	(segment
		(start 37.2364 -37.527484)
		(end 37.2364 -36.878768)
		(width 0.10668)
		(layer "In7.Cu")
		(net "SMB_BMC_MM3_SCL")
	)
	(segment
		(start 35.58032 -78.929992)
		(end 33.40354 -76.753212)
		(width 0.10668)
		(layer "In7.Cu")
		(net "SMB_BMC_MM3_SCL")
	)
	(segment
		(start 39.857172 -36.307268)
		(end 40.45966 -35.70478)
		(width 0.10668)
		(layer "In7.Cu")
		(net "SMB_BMC_MM3_SCL")
	)
	(segment
		(start 33.528 -44.035472)
		(end 36.36518 -41.198292)
		(width 0.10668)
		(layer "In7.Cu")
		(net "SMB_BMC_MM3_SCL")
	)
	(segment
		(start 45.24248 -86.322662)
		(end 43.110658 -84.19084)
		(width 0.10668)
		(layer "In7.Cu")
		(net "SMB_BMC_MM3_SCL")
	)
	(segment
		(start 55.842154 -113.7158)
		(end 55.58663 -113.7158)
		(width 0.10668)
		(layer "In7.Cu")
		(net "SMB_BMC_MM3_SCL")
	)
	(segment
		(start 33.1597 -52.19954)
		(end 33.528 -51.31054)
		(width 0.10668)
		(layer "In7.Cu")
		(net "SMB_BMC_MM3_SCL")
	)
	(segment
		(start 40.45966 -35.70478)
		(end 40.45966 -35.05327)
		(width 0.10668)
		(layer "In7.Cu")
		(net "SMB_BMC_MM3_SCL")
	)
	(segment
		(start 40.40632 -33.29686)
		(end 40.40632 -32.57423)
		(width 0.10668)
		(layer "In7.Cu")
		(net "SMB_BMC_MM3_SCL")
	)
	(segment
		(start 48.40732 -93.218508)
		(end 47.22368 -92.034868)
		(width 0.10668)
		(layer "In7.Cu")
		(net "SMB_BMC_MM3_SCL")
	)
	(segment
		(start 55.58663 -113.7158)
		(end 55.405782 -113.896648)
		(width 0.10668)
		(layer "In7.Cu")
		(net "SMB_BMC_MM3_SCL")
	)
	(segment
		(start 36.36518 -40.567102)
		(end 37.23386 -39.698422)
		(width 0.10668)
		(layer "In7.Cu")
		(net "SMB_BMC_MM3_SCL")
	)
	(segment
		(start 32.0548 -56.330342)
		(end 32.0548 -55.889144)
		(width 0.10668)
		(layer "In7.Cu")
		(net "SMB_BMC_MM3_SCL")
	)
	(segment
		(start 41.740328 -30.92704)
		(end 44.033186 -30.92704)
		(width 0.10668)
		(layer "In7.Cu")
		(net "SMB_BMC_MM3_SCL")
	)
	(segment
		(start 33.528 -51.31054)
		(end 33.528 -44.035472)
		(width 0.10668)
		(layer "In7.Cu")
		(net "SMB_BMC_MM3_SCL")
	)
	(segment
		(start 58.990992 -115.4176)
		(end 58.461148 -115.198144)
		(width 0.10668)
		(layer "In7.Cu")
		(net "SMB_BMC_MM3_SCL")
	)
	(segment
		(start 37.23386 -37.530024)
		(end 37.2364 -37.527484)
		(width 0.10668)
		(layer "In7.Cu")
		(net "SMB_BMC_MM3_SCL")
	)
	(segment
		(start 39.41064 -82.29092)
		(end 38.19398 -81.07426)
		(width 0.10668)
		(layer "In7.Cu")
		(net "SMB_BMC_MM3_SCL")
	)
	(segment
		(start 31.89732 -67.110356)
		(end 31.08452 -66.297556)
		(width 0.10668)
		(layer "In7.Cu")
		(net "SMB_BMC_MM3_SCL")
	)
	(segment
		(start 30.98038 -69.154802)
		(end 31.89732 -68.237862)
		(width 0.10668)
		(layer "In7.Cu")
		(net "SMB_BMC_MM3_SCL")
	)
	(segment
		(start 40.283638 -82.29092)
		(end 39.41064 -82.29092)
		(width 0.10668)
		(layer "In7.Cu")
		(net "SMB_BMC_MM3_SCL")
	)
	(segment
		(start 47.22368 -89.64168)
		(end 45.24248 -87.66048)
		(width 0.10668)
		(layer "In7.Cu")
		(net "SMB_BMC_MM3_SCL")
	)
	(segment
		(start 49.592738 -106.49712)
		(end 48.01997 -104.924352)
		(width 0.10668)
		(layer "In7.Cu")
		(net "SMB_BMC_MM3_SCL")
	)
	(segment
		(start 56.023002 -113.896648)
		(end 55.842154 -113.7158)
		(width 0.10668)
		(layer "In7.Cu")
		(net "SMB_BMC_MM3_SCL")
	)
	(segment
		(start 47.035212 -32.686752)
		(end 47.60849 -32.924242)
		(width 0.10668)
		(layer "In7.Cu")
		(net "SMB_BMC_MM3_SCL")
	)
	(segment
		(start 53.06822 -112.12322)
		(end 52.1462 -111.2012)
		(width 0.10668)
		(layer "In7.Cu")
		(net "SMB_BMC_MM3_SCL")
	)
	(segment
		(start 60.000134 -115.4176)
		(end 58.990992 -115.4176)
		(width 0.10668)
		(layer "In7.Cu")
		(net "SMB_BMC_MM3_SCL")
	)
	(segment
		(start 30.98038 -71.179436)
		(end 30.98038 -69.154802)
		(width 0.10668)
		(layer "In7.Cu")
		(net "SMB_BMC_MM3_SCL")
	)
	(segment
		(start 40.45966 -35.05327)
		(end 40.023796 -34.617406)
		(width 0.10668)
		(layer "In7.Cu")
		(net "SMB_BMC_MM3_SCL")
	)
	(segment
		(start 45.61586 -31.2674)
		(end 47.035212 -32.686752)
		(width 0.10668)
		(layer "In7.Cu")
		(net "SMB_BMC_MM3_SCL")
	)
	(segment
		(start 33.40354 -76.753212)
		(end 33.40354 -75.48245)
		(width 0.10668)
		(layer "In7.Cu")
		(net "SMB_BMC_MM3_SCL")
	)
	(segment
		(start 31.08452 -66.297556)
		(end 31.08452 -63.77559)
		(width 0.10668)
		(layer "In7.Cu")
		(net "SMB_BMC_MM3_SCL")
	)
	(segment
		(start 47.7012 -98.730054)
		(end 48.40732 -98.023934)
		(width 0.10668)
		(layer "In7.Cu")
		(net "SMB_BMC_MM3_SCL")
	)
	(segment
		(start 33.14192 -75.22083)
		(end 33.14192 -73.34123)
		(width 0.10668)
		(layer "In7.Cu")
		(net "SMB_BMC_MM3_SCL")
	)
	(segment
		(start 55.026306 -114.723164)
		(end 53.433726 -114.063526)
		(width 0.10668)
		(layer "In7.Cu")
		(net "SMB_BMC_MM3_SCL")
	)
	(segment
		(start 48.01997 -104.746552)
		(end 47.12208 -103.848662)
		(width 0.10668)
		(layer "In7.Cu")
		(net "SMB_BMC_MM3_SCL")
	)
	(segment
		(start 31.708598 -63.151512)
		(end 31.708598 -59.85129)
		(width 0.10668)
		(layer "In7.Cu")
		(net "SMB_BMC_MM3_SCL")
	)
	(segment
		(start 56.023002 -114.542316)
		(end 56.023002 -113.896648)
		(width 0.10668)
		(layer "In7.Cu")
		(net "SMB_BMC_MM3_SCL")
	)
	(segment
		(start 31.08452 -63.77559)
		(end 31.708598 -63.151512)
		(width 0.10668)
		(layer "In7.Cu")
		(net "SMB_BMC_MM3_SCL")
	)
	(segment
		(start 47.7012 -100.016818)
		(end 47.7012 -98.730054)
		(width 0.10668)
		(layer "In7.Cu")
		(net "SMB_BMC_MM3_SCL")
	)
	(segment
		(start 51.31308 -109.478826)
		(end 51.31308 -107.345226)
		(width 0.10668)
		(layer "In7.Cu")
		(net "SMB_BMC_MM3_SCL")
	)
	(segment
		(start 56.20385 -114.723164)
		(end 56.023002 -114.542316)
		(width 0.10668)
		(layer "In7.Cu")
		(net "SMB_BMC_MM3_SCL")
	)
	(segment
		(start 43.110658 -84.19084)
		(end 42.183558 -84.19084)
		(width 0.10668)
		(layer "In7.Cu")
		(net "SMB_BMC_MM3_SCL")
	)
	(segment
		(start 37.8079 -36.307268)
		(end 39.857172 -36.307268)
		(width 0.10668)
		(layer "In7.Cu")
		(net "SMB_BMC_MM3_SCL")
	)
	(segment
		(start 55.405782 -114.542316)
		(end 55.224934 -114.723164)
		(width 0.10668)
		(layer "In7.Cu")
		(net "SMB_BMC_MM3_SCL")
	)
	(segment
		(start 37.23386 -39.698422)
		(end 37.23386 -37.530024)
		(width 0.10668)
		(layer "In7.Cu")
		(net "SMB_BMC_MM3_SCL")
	)
	(segment
		(start 32.9184 -73.11771)
		(end 32.9184 -73.117456)
		(width 0.10668)
		(layer "In7.Cu")
		(net "SMB_BMC_MM3_SCL")
	)
	(segment
		(start 31.89732 -68.237862)
		(end 31.89732 -67.110356)
		(width 0.10668)
		(layer "In7.Cu")
		(net "SMB_BMC_MM3_SCL")
	)
	(segment
		(start 40.40632 -32.57423)
		(end 41.418256 -31.06039)
		(width 0.10668)
		(layer "In7.Cu")
		(net "SMB_BMC_MM3_SCL")
	)
	(segment
		(start 55.224934 -114.723164)
		(end 55.026306 -114.723164)
		(width 0.10668)
		(layer "In7.Cu")
		(net "SMB_BMC_MM3_SCL")
	)
	(segment
		(start 32.1818 -56.63692)
		(end 32.0548 -56.330342)
		(width 0.10668)
		(layer "In7.Cu")
		(net "SMB_BMC_MM3_SCL")
	)
	(segment
		(start 48.01997 -104.924352)
		(end 48.01997 -104.746552)
		(width 0.10668)
		(layer "In7.Cu")
		(net "SMB_BMC_MM3_SCL")
	)
	(segment
		(start 45.24248 -87.66048)
		(end 45.24248 -86.322662)
		(width 0.10668)
		(layer "In7.Cu")
		(net "SMB_BMC_MM3_SCL")
	)
	(segment
		(start 55.405782 -113.896648)
		(end 55.405782 -114.542316)
		(width 0.10668)
		(layer "In7.Cu")
		(net "SMB_BMC_MM3_SCL")
	)
	(segment
		(start 40.023796 -34.617406)
		(end 39.91229 -34.348166)
		(width 0.10668)
		(layer "In7.Cu")
		(net "SMB_BMC_MM3_SCL")
	)
	(segment
		(start 51.31308 -107.345226)
		(end 50.464974 -106.49712)
		(width 0.10668)
		(layer "In7.Cu")
		(net "SMB_BMC_MM3_SCL")
	)
	(segment
		(start 39.91229 -34.348166)
		(end 39.91229 -33.79089)
		(width 0.10668)
		(layer "In7.Cu")
		(net "SMB_BMC_MM3_SCL")
	)
	(segment
		(start 33.1597 -54.784244)
		(end 33.1597 -52.19954)
		(width 0.10668)
		(layer "In7.Cu")
		(net "SMB_BMC_MM3_SCL")
	)
	(segment
		(start 52.1462 -111.008922)
		(end 52.14112 -111.003842)
		(width 0.10668)
		(layer "In7.Cu")
		(net "SMB_BMC_MM3_SCL")
	)
	(segment
		(start 47.12208 -100.595938)
		(end 47.7012 -100.016818)
		(width 0.10668)
		(layer "In7.Cu")
		(net "SMB_BMC_MM3_SCL")
	)
	(segment
		(start 52.1462 -111.2012)
		(end 52.1462 -111.008922)
		(width 0.10668)
		(layer "In7.Cu")
		(net "SMB_BMC_MM3_SCL")
	)
	(segment
		(start 53.433726 -114.063526)
		(end 53.06822 -113.69802)
		(width 0.10668)
		(layer "In7.Cu")
		(net "SMB_BMC_MM3_SCL")
	)
	(segment
		(start 47.12208 -103.848662)
		(end 47.12208 -100.595938)
		(width 0.10668)
		(layer "In7.Cu")
		(net "SMB_BMC_MM3_SCL")
	)
	(segment
		(start 38.19398 -81.07426)
		(end 37.174678 -81.07426)
		(width 0.10668)
		(layer "In7.Cu")
		(net "SMB_BMC_MM3_SCL")
	)
	(segment
		(start 47.22368 -92.034868)
		(end 47.22368 -89.64168)
		(width 0.10668)
		(layer "In7.Cu")
		(net "SMB_BMC_MM3_SCL")
	)
	(segment
		(start 32.0548 -55.889144)
		(end 33.1597 -54.784244)
		(width 0.10668)
		(layer "In7.Cu")
		(net "SMB_BMC_MM3_SCL")
	)
	(segment
		(start 48.40732 -98.023934)
		(end 48.40732 -93.218508)
		(width 0.10668)
		(layer "In7.Cu")
		(net "SMB_BMC_MM3_SCL")
	)
	(segment
		(start 44.033186 -30.92704)
		(end 44.373546 -31.2674)
		(width 0.10668)
		(layer "In7.Cu")
		(net "SMB_BMC_MM3_SCL")
	)
	(segment
		(start 35.58032 -79.479902)
		(end 35.58032 -78.929992)
		(width 0.10668)
		(layer "In7.Cu")
		(net "SMB_BMC_MM3_SCL")
	)
	(segment
		(start 33.40354 -75.48245)
		(end 33.14192 -75.22083)
		(width 0.10668)
		(layer "In7.Cu")
		(net "SMB_BMC_MM3_SCL")
	)
	(segment
		(start 44.373546 -31.2674)
		(end 45.61586 -31.2674)
		(width 0.10668)
		(layer "In7.Cu")
		(net "SMB_BMC_MM3_SCL")
	)
	(segment
		(start 32.9184 -73.117456)
		(end 30.98038 -71.179436)
		(width 0.10668)
		(layer "In7.Cu")
		(net "SMB_BMC_MM3_SCL")
	)
	(segment
		(start 37.174678 -81.07426)
		(end 35.58032 -79.479902)
		(width 0.10668)
		(layer "In7.Cu")
		(net "SMB_BMC_MM3_SCL")
	)
	(segment
		(start 58.461148 -115.198144)
		(end 57.986168 -114.723164)
		(width 0.10668)
		(layer "In7.Cu")
		(net "SMB_BMC_MM3_SCL")
	)
	(segment
		(start 50.464974 -106.49712)
		(end 49.592738 -106.49712)
		(width 0.10668)
		(layer "In7.Cu")
		(net "SMB_BMC_MM3_SCL")
	)
	(segment
		(start 37.2364 -36.878768)
		(end 37.8079 -36.307268)
		(width 0.10668)
		(layer "In7.Cu")
		(net "SMB_BMC_MM3_SCL")
	)
	(segment
		(start 49.426114 -37.373052)
		(end 50.210466 -38.157404)
		(width 0.11684)
		(layer "F.Cu")
		(net "SMB_BMC_MM3_R_SDA")
	)
	(segment
		(start 49.779682 -35.037776)
		(end 49.426114 -35.391344)
		(width 0.11684)
		(layer "F.Cu")
		(net "SMB_BMC_MM3_R_SDA")
	)
	(segment
		(start 50.210466 -38.157404)
		(end 50.210466 -39.08679)
		(width 0.11684)
		(layer "F.Cu")
		(net "SMB_BMC_MM3_R_SDA")
	)
	(segment
		(start 49.426114 -35.391344)
		(end 49.426114 -37.373052)
		(width 0.11684)
		(layer "F.Cu")
		(net "SMB_BMC_MM3_R_SDA")
	)
	(segment
		(start 50.210466 -39.08679)
		(end 50.494946 -39.37127)
		(width 0.11684)
		(layer "F.Cu")
		(net "SMB_BMC_MM3_R_SDA")
	)
	(segment
		(start 50.494946 -40.971216)
		(end 50.099722 -40.575992)
		(width 0.11684)
		(layer "F.Cu")
		(net "SMB_BMC_MM3_R_SCL")
	)
	(via
		(at 50.099722 -40.575992)
		(size 0.4572)
		(drill 0.254)
		(layers "F.Cu" "B.Cu")
		(net "SMB_BMC_MM3_R_SCL")
	)
	(segment
		(start 49.711102 -38.501574)
		(end 49.036478 -37.82695)
		(width 0.11684)
		(layer "B.Cu")
		(net "SMB_BMC_MM3_R_SCL")
	)
	(segment
		(start 49.036478 -37.82695)
		(end 49.036478 -37.199824)
		(width 0.11684)
		(layer "B.Cu")
		(net "SMB_BMC_MM3_R_SCL")
	)
	(segment
		(start 50.099722 -40.325802)
		(end 49.711102 -39.937182)
		(width 0.11684)
		(layer "B.Cu")
		(net "SMB_BMC_MM3_R_SCL")
	)
	(segment
		(start 47.498 -35.661346)
		(end 47.498 -35.07105)
		(width 0.11684)
		(layer "B.Cu")
		(net "SMB_BMC_MM3_R_SCL")
	)
	(segment
		(start 49.711102 -39.937182)
		(end 49.711102 -38.501574)
		(width 0.11684)
		(layer "B.Cu")
		(net "SMB_BMC_MM3_R_SCL")
	)
	(segment
		(start 50.099722 -40.575992)
		(end 50.099722 -40.325802)
		(width 0.11684)
		(layer "B.Cu")
		(net "SMB_BMC_MM3_R_SCL")
	)
	(segment
		(start 49.036478 -37.199824)
		(end 47.498 -35.661346)
		(width 0.11684)
		(layer "B.Cu")
		(net "SMB_BMC_MM3_R_SCL")
	)
	(segment
		(start 45.8724 -21.7678)
		(end 45.1866 -22.4536)
		(width 0.11684)
		(layer "F.Cu")
		(net "SMB_BMC_MM2_SDA")
	)
	(segment
		(start 45.6946 -24.4348)
		(end 45.6946 -25.3746)
		(width 0.11684)
		(layer "F.Cu")
		(net "SMB_BMC_MM2_SDA")
	)
	(segment
		(start 42.425366 -29.939234)
		(end 42.2656 -30.099)
		(width 0.11684)
		(layer "F.Cu")
		(net "SMB_BMC_MM2_SDA")
	)
	(segment
		(start 42.392854 -31.573216)
		(end 42.501566 -31.681928)
		(width 0.11684)
		(layer "F.Cu")
		(net "SMB_BMC_MM2_SDA")
	)
	(segment
		(start 17.892522 -9.478518)
		(end 20.58924 -6.7818)
		(width 0.11684)
		(layer "F.Cu")
		(net "SMB_BMC_MM2_SDA")
	)
	(segment
		(start 20.58924 -6.7818)
		(end 20.58924 -5.80136)
		(width 0.11684)
		(layer "F.Cu")
		(net "SMB_BMC_MM2_SDA")
	)
	(segment
		(start 43.398694 -32.56407)
		(end 43.400218 -32.565594)
		(width 0.11684)
		(layer "F.Cu")
		(net "SMB_BMC_MM2_SDA")
	)
	(segment
		(start 17.892522 -13.796772)
		(end 17.892522 -9.478518)
		(width 0.11684)
		(layer "F.Cu")
		(net "SMB_BMC_MM2_SDA")
	)
	(segment
		(start 52.7558 -12.5984)
		(end 48.8188 -16.5354)
		(width 0.11684)
		(layer "F.Cu")
		(net "SMB_BMC_MM2_SDA")
	)
	(segment
		(start 16.023844 -16.703548)
		(end 16.023844 -15.66545)
		(width 0.11684)
		(layer "F.Cu")
		(net "SMB_BMC_MM2_SDA")
	)
	(segment
		(start 52.7558 -9.5758)
		(end 52.7558 -12.5984)
		(width 0.11684)
		(layer "F.Cu")
		(net "SMB_BMC_MM2_SDA")
	)
	(segment
		(start 43.398694 -32.239966)
		(end 43.398694 -32.56407)
		(width 0.11684)
		(layer "F.Cu")
		(net "SMB_BMC_MM2_SDA")
	)
	(segment
		(start 45.1866 -22.4536)
		(end 45.1866 -23.9268)
		(width 0.11684)
		(layer "F.Cu")
		(net "SMB_BMC_MM2_SDA")
	)
	(segment
		(start 20.58924 -5.80136)
		(end 21.7678 -4.6228)
		(width 0.11684)
		(layer "F.Cu")
		(net "SMB_BMC_MM2_SDA")
	)
	(segment
		(start 46.6344 -17.3228)
		(end 46.6344 -20.3708)
		(width 0.11684)
		(layer "F.Cu")
		(net "SMB_BMC_MM2_SDA")
	)
	(segment
		(start 42.392854 -31.572454)
		(end 42.392854 -31.573216)
		(width 0.11684)
		(layer "F.Cu")
		(net "SMB_BMC_MM2_SDA")
	)
	(segment
		(start 45.8724 -21.1328)
		(end 45.8724 -21.7678)
		(width 0.11684)
		(layer "F.Cu")
		(net "SMB_BMC_MM2_SDA")
	)
	(segment
		(start 43.279822 -31.953454)
		(end 43.398694 -32.239966)
		(width 0.11684)
		(layer "F.Cu")
		(net "SMB_BMC_MM2_SDA")
	)
	(segment
		(start 21.7678 -4.6228)
		(end 47.8028 -4.6228)
		(width 0.11684)
		(layer "F.Cu")
		(net "SMB_BMC_MM2_SDA")
	)
	(segment
		(start 46.482 -27.375612)
		(end 45.258736 -28.598876)
		(width 0.11684)
		(layer "F.Cu")
		(net "SMB_BMC_MM2_SDA")
	)
	(segment
		(start 42.2656 -30.099)
		(end 42.2656 -31.4452)
		(width 0.11684)
		(layer "F.Cu")
		(net "SMB_BMC_MM2_SDA")
	)
	(segment
		(start 47.4218 -16.5354)
		(end 46.6344 -17.3228)
		(width 0.11684)
		(layer "F.Cu")
		(net "SMB_BMC_MM2_SDA")
	)
	(segment
		(start 48.8188 -16.5354)
		(end 47.4218 -16.5354)
		(width 0.11684)
		(layer "F.Cu")
		(net "SMB_BMC_MM2_SDA")
	)
	(segment
		(start 44.635166 -29.939234)
		(end 42.425366 -29.939234)
		(width 0.11684)
		(layer "F.Cu")
		(net "SMB_BMC_MM2_SDA")
	)
	(segment
		(start 46.482 -26.162)
		(end 46.482 -27.375612)
		(width 0.11684)
		(layer "F.Cu")
		(net "SMB_BMC_MM2_SDA")
	)
	(segment
		(start 46.6344 -20.3708)
		(end 45.8724 -21.1328)
		(width 0.11684)
		(layer "F.Cu")
		(net "SMB_BMC_MM2_SDA")
	)
	(segment
		(start 45.258736 -28.598876)
		(end 45.258736 -29.315664)
		(width 0.11684)
		(layer "F.Cu")
		(net "SMB_BMC_MM2_SDA")
	)
	(segment
		(start 43.008296 -31.681928)
		(end 43.279822 -31.953454)
		(width 0.11684)
		(layer "F.Cu")
		(net "SMB_BMC_MM2_SDA")
	)
	(segment
		(start 47.8028 -4.6228)
		(end 52.7558 -9.5758)
		(width 0.11684)
		(layer "F.Cu")
		(net "SMB_BMC_MM2_SDA")
	)
	(segment
		(start 42.501566 -31.681928)
		(end 43.008296 -31.681928)
		(width 0.11684)
		(layer "F.Cu")
		(net "SMB_BMC_MM2_SDA")
	)
	(segment
		(start 16.023844 -15.66545)
		(end 17.892522 -13.796772)
		(width 0.11684)
		(layer "F.Cu")
		(net "SMB_BMC_MM2_SDA")
	)
	(segment
		(start 45.1866 -23.9268)
		(end 45.6946 -24.4348)
		(width 0.11684)
		(layer "F.Cu")
		(net "SMB_BMC_MM2_SDA")
	)
	(segment
		(start 42.2656 -31.4452)
		(end 42.392854 -31.572454)
		(width 0.11684)
		(layer "F.Cu")
		(net "SMB_BMC_MM2_SDA")
	)
	(segment
		(start 45.6946 -25.3746)
		(end 46.482 -26.162)
		(width 0.11684)
		(layer "F.Cu")
		(net "SMB_BMC_MM2_SDA")
	)
	(segment
		(start 45.258736 -29.315664)
		(end 44.635166 -29.939234)
		(width 0.11684)
		(layer "F.Cu")
		(net "SMB_BMC_MM2_SDA")
	)
	(via
		(at 16.023844 -16.703548)
		(size 0.508)
		(drill 0.254)
		(layers "F.Cu" "B.Cu")
		(net "SMB_BMC_MM2_SDA")
	)
	(via
		(at 43.400218 -32.565594)
		(size 0.508)
		(drill 0.254)
		(layers "F.Cu" "B.Cu")
		(net "SMB_BMC_MM2_SDA")
	)
	(via
		(at 60.833 -113.7285)
		(size 0.508)
		(drill 0.254)
		(layers "F.Cu" "B.Cu")
		(net "SMB_BMC_MM2_SDA")
	)
	(segment
		(start 43.400218 -32.201866)
		(end 43.367452 -32.1691)
		(width 0.11684)
		(layer "B.Cu")
		(net "SMB_BMC_MM2_SDA")
	)
	(segment
		(start 43.83913 -34.123376)
		(end 43.83913 -33.069784)
		(width 0.11684)
		(layer "B.Cu")
		(net "SMB_BMC_MM2_SDA")
	)
	(segment
		(start 43.83913 -33.069784)
		(end 43.400218 -32.630872)
		(width 0.11684)
		(layer "B.Cu")
		(net "SMB_BMC_MM2_SDA")
	)
	(segment
		(start 15.947644 -16.9799)
		(end 16.023844 -16.9037)
		(width 0.11684)
		(layer "B.Cu")
		(net "SMB_BMC_MM2_SDA")
	)
	(segment
		(start 60.466478 -118.458488)
		(end 60.464954 -118.460012)
		(width 0.11684)
		(layer "B.Cu")
		(net "SMB_BMC_MM2_SDA")
	)
	(segment
		(start 16.023844 -16.9037)
		(end 16.023844 -16.703548)
		(width 0.11684)
		(layer "B.Cu")
		(net "SMB_BMC_MM2_SDA")
	)
	(segment
		(start 43.367198 -34.237676)
		(end 43.72483 -34.237676)
		(width 0.11684)
		(layer "B.Cu")
		(net "SMB_BMC_MM2_SDA")
	)
	(segment
		(start 43.400218 -32.630872)
		(end 43.400218 -32.565594)
		(width 0.11684)
		(layer "B.Cu")
		(net "SMB_BMC_MM2_SDA")
	)
	(segment
		(start 43.400218 -32.565594)
		(end 43.400218 -32.201866)
		(width 0.11684)
		(layer "B.Cu")
		(net "SMB_BMC_MM2_SDA")
	)
	(segment
		(start 43.72483 -34.237676)
		(end 43.83913 -34.123376)
		(width 0.11684)
		(layer "B.Cu")
		(net "SMB_BMC_MM2_SDA")
	)
	(segment
		(start 60.466478 -114.095022)
		(end 60.466478 -118.458488)
		(width 0.11684)
		(layer "B.Cu")
		(net "SMB_BMC_MM2_SDA")
	)
	(segment
		(start 43.367452 -32.1691)
		(end 43.367452 -31.216854)
		(width 0.11684)
		(layer "B.Cu")
		(net "SMB_BMC_MM2_SDA")
	)
	(segment
		(start 60.833 -113.7285)
		(end 60.466478 -114.095022)
		(width 0.11684)
		(layer "B.Cu")
		(net "SMB_BMC_MM2_SDA")
	)
	(segment
		(start 16.383 -18.30705)
		(end 15.947644 -17.871694)
		(width 0.11684)
		(layer "B.Cu")
		(net "SMB_BMC_MM2_SDA")
	)
	(segment
		(start 15.947644 -17.871694)
		(end 15.947644 -16.9799)
		(width 0.11684)
		(layer "B.Cu")
		(net "SMB_BMC_MM2_SDA")
	)
	(segment
		(start 54.261766 -106.948478)
		(end 54.118764 -107.09148)
		(width 0.10668)
		(layer "In7.Cu")
		(net "SMB_BMC_MM2_SDA")
	)
	(segment
		(start 52.82184 -98.761042)
		(end 53.48224 -98.100642)
		(width 0.10668)
		(layer "In7.Cu")
		(net "SMB_BMC_MM2_SDA")
	)
	(segment
		(start 52.29352 -104.301036)
		(end 52.16652 -104.174036)
		(width 0.10668)
		(layer "In7.Cu")
		(net "SMB_BMC_MM2_SDA")
	)
	(segment
		(start 58.6867 -111.5822)
		(end 58.013346 -111.5822)
		(width 0.10668)
		(layer "In7.Cu")
		(net "SMB_BMC_MM2_SDA")
	)
	(segment
		(start 34.39668 -66.32448)
		(end 33.20034 -65.12814)
		(width 0.10668)
		(layer "In7.Cu")
		(net "SMB_BMC_MM2_SDA")
	)
	(segment
		(start 36.84778 -46.33722)
		(end 36.84778 -44.76242)
		(width 0.10668)
		(layer "In7.Cu")
		(net "SMB_BMC_MM2_SDA")
	)
	(segment
		(start 53.48224 -97.276158)
		(end 51.4604 -95.254318)
		(width 0.10668)
		(layer "In7.Cu")
		(net "SMB_BMC_MM2_SDA")
	)
	(segment
		(start 34.61766 -53.349398)
		(end 35.20186 -52.765198)
		(width 0.10668)
		(layer "In7.Cu")
		(net "SMB_BMC_MM2_SDA")
	)
	(segment
		(start 42.2656 -79.756)
		(end 41.79062 -79.28102)
		(width 0.10668)
		(layer "In7.Cu")
		(net "SMB_BMC_MM2_SDA")
	)
	(segment
		(start 53.773832 -105.070402)
		(end 53.004466 -104.301036)
		(width 0.10668)
		(layer "In7.Cu")
		(net "SMB_BMC_MM2_SDA")
	)
	(segment
		(start 43.400218 -32.671766)
		(end 43.400218 -32.565594)
		(width 0.10668)
		(layer "In7.Cu")
		(net "SMB_BMC_MM2_SDA")
	)
	(segment
		(start 35.35172 -72.33412)
		(end 35.35172 -69.691504)
		(width 0.10668)
		(layer "In7.Cu")
		(net "SMB_BMC_MM2_SDA")
	)
	(segment
		(start 46.99 -83.90382)
		(end 46.42358 -83.3374)
		(width 0.10668)
		(layer "In7.Cu")
		(net "SMB_BMC_MM2_SDA")
	)
	(segment
		(start 41.79062 -79.28102)
		(end 41.79062 -77.731874)
		(width 0.10668)
		(layer "In7.Cu")
		(net "SMB_BMC_MM2_SDA")
	)
	(segment
		(start 52.16652 -104.174036)
		(end 52.16652 -101.8921)
		(width 0.10668)
		(layer "In7.Cu")
		(net "SMB_BMC_MM2_SDA")
	)
	(segment
		(start 41.998392 -35.74034)
		(end 43.829732 -33.909)
		(width 0.10668)
		(layer "In7.Cu")
		(net "SMB_BMC_MM2_SDA")
	)
	(segment
		(start 36.66998 -73.838308)
		(end 36.66998 -73.65238)
		(width 0.10668)
		(layer "In7.Cu")
		(net "SMB_BMC_MM2_SDA")
	)
	(segment
		(start 43.86072 -81.98612)
		(end 42.2656 -80.391)
		(width 0.10668)
		(layer "In7.Cu")
		(net "SMB_BMC_MM2_SDA")
	)
	(segment
		(start 34.25698 -60.026296)
		(end 34.25698 -59.217814)
		(width 0.10668)
		(layer "In7.Cu")
		(net "SMB_BMC_MM2_SDA")
	)
	(segment
		(start 35.20186 -52.279042)
		(end 34.86912 -51.946302)
		(width 0.10668)
		(layer "In7.Cu")
		(net "SMB_BMC_MM2_SDA")
	)
	(segment
		(start 53.773832 -106.948478)
		(end 53.773832 -105.070402)
		(width 0.10668)
		(layer "In7.Cu")
		(net "SMB_BMC_MM2_SDA")
	)
	(segment
		(start 34.071814 -56.733694)
		(end 34.452052 -56.733694)
		(width 0.10668)
		(layer "In7.Cu")
		(net "SMB_BMC_MM2_SDA")
	)
	(segment
		(start 38.2905 -41.040558)
		(end 39.18966 -40.141398)
		(width 0.10668)
		(layer "In7.Cu")
		(net "SMB_BMC_MM2_SDA")
	)
	(segment
		(start 44.563792 -81.98612)
		(end 43.86072 -81.98612)
		(width 0.10668)
		(layer "In7.Cu")
		(net "SMB_BMC_MM2_SDA")
	)
	(segment
		(start 42.2656 -80.391)
		(end 42.2656 -79.756)
		(width 0.10668)
		(layer "In7.Cu")
		(net "SMB_BMC_MM2_SDA")
	)
	(segment
		(start 52.16652 -101.8921)
		(end 52.82184 -101.23678)
		(width 0.10668)
		(layer "In7.Cu")
		(net "SMB_BMC_MM2_SDA")
	)
	(segment
		(start 53.004466 -104.301036)
		(end 52.29352 -104.301036)
		(width 0.10668)
		(layer "In7.Cu")
		(net "SMB_BMC_MM2_SDA")
	)
	(segment
		(start 34.61766 -55.62346)
		(end 34.61766 -53.349398)
		(width 0.10668)
		(layer "In7.Cu")
		(net "SMB_BMC_MM2_SDA")
	)
	(segment
		(start 33.53054 -58.491374)
		(end 33.53054 -57.274968)
		(width 0.10668)
		(layer "In7.Cu")
		(net "SMB_BMC_MM2_SDA")
	)
	(segment
		(start 54.118764 -107.09148)
		(end 53.916834 -107.09148)
		(width 0.10668)
		(layer "In7.Cu")
		(net "SMB_BMC_MM2_SDA")
	)
	(segment
		(start 53.916834 -107.09148)
		(end 53.773832 -106.948478)
		(width 0.10668)
		(layer "In7.Cu")
		(net "SMB_BMC_MM2_SDA")
	)
	(segment
		(start 34.86912 -48.31588)
		(end 36.84778 -46.33722)
		(width 0.10668)
		(layer "In7.Cu")
		(net "SMB_BMC_MM2_SDA")
	)
	(segment
		(start 36.66998 -73.65238)
		(end 35.35172 -72.33412)
		(width 0.10668)
		(layer "In7.Cu")
		(net "SMB_BMC_MM2_SDA")
	)
	(segment
		(start 33.20034 -61.082936)
		(end 34.25698 -60.026296)
		(width 0.10668)
		(layer "In7.Cu")
		(net "SMB_BMC_MM2_SDA")
	)
	(segment
		(start 52.82184 -101.23678)
		(end 52.82184 -98.761042)
		(width 0.10668)
		(layer "In7.Cu")
		(net "SMB_BMC_MM2_SDA")
	)
	(segment
		(start 50.704242 -86.371684)
		(end 49.105058 -84.7725)
		(width 0.10668)
		(layer "In7.Cu")
		(net "SMB_BMC_MM2_SDA")
	)
	(segment
		(start 56.5785 -106.2101)
		(end 55.2958 -104.9274)
		(width 0.10668)
		(layer "In7.Cu")
		(net "SMB_BMC_MM2_SDA")
	)
	(segment
		(start 34.452052 -56.733694)
		(end 34.74974 -56.436006)
		(width 0.10668)
		(layer "In7.Cu")
		(net "SMB_BMC_MM2_SDA")
	)
	(segment
		(start 38.00856 -43.60164)
		(end 38.00856 -41.646856)
		(width 0.10668)
		(layer "In7.Cu")
		(net "SMB_BMC_MM2_SDA")
	)
	(segment
		(start 37.32149 -74.30389)
		(end 37.135562 -74.30389)
		(width 0.10668)
		(layer "In7.Cu")
		(net "SMB_BMC_MM2_SDA")
	)
	(segment
		(start 43.829732 -33.382712)
		(end 43.630596 -32.902144)
		(width 0.10668)
		(layer "In7.Cu")
		(net "SMB_BMC_MM2_SDA")
	)
	(segment
		(start 43.829732 -33.909)
		(end 43.829732 -33.382712)
		(width 0.10668)
		(layer "In7.Cu")
		(net "SMB_BMC_MM2_SDA")
	)
	(segment
		(start 38.2905 -41.364916)
		(end 38.2905 -41.040558)
		(width 0.10668)
		(layer "In7.Cu")
		(net "SMB_BMC_MM2_SDA")
	)
	(segment
		(start 38.00856 -41.646856)
		(end 38.2905 -41.364916)
		(width 0.10668)
		(layer "In7.Cu")
		(net "SMB_BMC_MM2_SDA")
	)
	(segment
		(start 39.18966 -39.422578)
		(end 41.998392 -36.613846)
		(width 0.10668)
		(layer "In7.Cu")
		(net "SMB_BMC_MM2_SDA")
	)
	(segment
		(start 35.29457 -69.553582)
		(end 35.22091 -69.443346)
		(width 0.10668)
		(layer "In7.Cu")
		(net "SMB_BMC_MM2_SDA")
	)
	(segment
		(start 56.5785 -110.147354)
		(end 56.5785 -106.2101)
		(width 0.10668)
		(layer "In7.Cu")
		(net "SMB_BMC_MM2_SDA")
	)
	(segment
		(start 54.261766 -105.070402)
		(end 54.261766 -106.948478)
		(width 0.10668)
		(layer "In7.Cu")
		(net "SMB_BMC_MM2_SDA")
	)
	(segment
		(start 39.18966 -40.141398)
		(end 39.18966 -39.422578)
		(width 0.10668)
		(layer "In7.Cu")
		(net "SMB_BMC_MM2_SDA")
	)
	(segment
		(start 36.84778 -44.76242)
		(end 38.00856 -43.60164)
		(width 0.10668)
		(layer "In7.Cu")
		(net "SMB_BMC_MM2_SDA")
	)
	(segment
		(start 33.53054 -57.274968)
		(end 34.071814 -56.733694)
		(width 0.10668)
		(layer "In7.Cu")
		(net "SMB_BMC_MM2_SDA")
	)
	(segment
		(start 41.79062 -77.731874)
		(end 41.256204 -77.197458)
		(width 0.10668)
		(layer "In7.Cu")
		(net "SMB_BMC_MM2_SDA")
	)
	(segment
		(start 41.998392 -36.613846)
		(end 41.998392 -35.74034)
		(width 0.10668)
		(layer "In7.Cu")
		(net "SMB_BMC_MM2_SDA")
	)
	(segment
		(start 60.833 -113.7285)
		(end 58.6867 -111.5822)
		(width 0.10668)
		(layer "In7.Cu")
		(net "SMB_BMC_MM2_SDA")
	)
	(segment
		(start 33.20034 -65.12814)
		(end 33.20034 -61.082936)
		(width 0.10668)
		(layer "In7.Cu")
		(net "SMB_BMC_MM2_SDA")
	)
	(segment
		(start 51.4604 -95.254318)
		(end 51.4604 -88.196674)
		(width 0.10668)
		(layer "In7.Cu")
		(net "SMB_BMC_MM2_SDA")
	)
	(segment
		(start 45.915072 -83.3374)
		(end 44.563792 -81.98612)
		(width 0.10668)
		(layer "In7.Cu")
		(net "SMB_BMC_MM2_SDA")
	)
	(segment
		(start 40.215058 -77.197458)
		(end 37.32149 -74.30389)
		(width 0.10668)
		(layer "In7.Cu")
		(net "SMB_BMC_MM2_SDA")
	)
	(segment
		(start 34.74974 -56.436006)
		(end 34.74974 -55.75554)
		(width 0.10668)
		(layer "In7.Cu")
		(net "SMB_BMC_MM2_SDA")
	)
	(segment
		(start 34.86912 -51.946302)
		(end 34.86912 -48.31588)
		(width 0.10668)
		(layer "In7.Cu")
		(net "SMB_BMC_MM2_SDA")
	)
	(segment
		(start 51.4604 -88.196674)
		(end 50.704242 -86.371684)
		(width 0.10668)
		(layer "In7.Cu")
		(net "SMB_BMC_MM2_SDA")
	)
	(segment
		(start 35.20186 -52.765198)
		(end 35.20186 -52.279042)
		(width 0.10668)
		(layer "In7.Cu")
		(net "SMB_BMC_MM2_SDA")
	)
	(segment
		(start 34.74974 -55.75554)
		(end 34.61766 -55.62346)
		(width 0.10668)
		(layer "In7.Cu")
		(net "SMB_BMC_MM2_SDA")
	)
	(segment
		(start 53.48224 -98.100642)
		(end 53.48224 -97.276158)
		(width 0.10668)
		(layer "In7.Cu")
		(net "SMB_BMC_MM2_SDA")
	)
	(segment
		(start 55.2958 -104.9274)
		(end 54.404768 -104.9274)
		(width 0.10668)
		(layer "In7.Cu")
		(net "SMB_BMC_MM2_SDA")
	)
	(segment
		(start 43.630596 -32.902144)
		(end 43.400218 -32.671766)
		(width 0.10668)
		(layer "In7.Cu")
		(net "SMB_BMC_MM2_SDA")
	)
	(segment
		(start 34.25698 -59.217814)
		(end 33.53054 -58.491374)
		(width 0.10668)
		(layer "In7.Cu")
		(net "SMB_BMC_MM2_SDA")
	)
	(segment
		(start 47.360586 -83.90382)
		(end 46.99 -83.90382)
		(width 0.10668)
		(layer "In7.Cu")
		(net "SMB_BMC_MM2_SDA")
	)
	(segment
		(start 49.105058 -84.7725)
		(end 48.229266 -84.7725)
		(width 0.10668)
		(layer "In7.Cu")
		(net "SMB_BMC_MM2_SDA")
	)
	(segment
		(start 48.229266 -84.7725)
		(end 47.360586 -83.90382)
		(width 0.10668)
		(layer "In7.Cu")
		(net "SMB_BMC_MM2_SDA")
	)
	(segment
		(start 34.39668 -68.619116)
		(end 34.39668 -66.32448)
		(width 0.10668)
		(layer "In7.Cu")
		(net "SMB_BMC_MM2_SDA")
	)
	(segment
		(start 35.35172 -69.691504)
		(end 35.29457 -69.553582)
		(width 0.10668)
		(layer "In7.Cu")
		(net "SMB_BMC_MM2_SDA")
	)
	(segment
		(start 35.22091 -69.443346)
		(end 34.39668 -68.619116)
		(width 0.10668)
		(layer "In7.Cu")
		(net "SMB_BMC_MM2_SDA")
	)
	(segment
		(start 54.404768 -104.9274)
		(end 54.261766 -105.070402)
		(width 0.10668)
		(layer "In7.Cu")
		(net "SMB_BMC_MM2_SDA")
	)
	(segment
		(start 37.135562 -74.30389)
		(end 36.66998 -73.838308)
		(width 0.10668)
		(layer "In7.Cu")
		(net "SMB_BMC_MM2_SDA")
	)
	(segment
		(start 46.42358 -83.3374)
		(end 45.915072 -83.3374)
		(width 0.10668)
		(layer "In7.Cu")
		(net "SMB_BMC_MM2_SDA")
	)
	(segment
		(start 41.256204 -77.197458)
		(end 40.215058 -77.197458)
		(width 0.10668)
		(layer "In7.Cu")
		(net "SMB_BMC_MM2_SDA")
	)
	(segment
		(start 58.013346 -111.5822)
		(end 56.5785 -110.147354)
		(width 0.10668)
		(layer "In7.Cu")
		(net "SMB_BMC_MM2_SDA")
	)
	(segment
		(start 52.35956 -9.740138)
		(end 52.35956 -12.434062)
		(width 0.11684)
		(layer "F.Cu")
		(net "SMB_BMC_MM2_SCL")
	)
	(segment
		(start 45.2882 -24.588978)
		(end 45.2882 -25.6032)
		(width 0.11684)
		(layer "F.Cu")
		(net "SMB_BMC_MM2_SCL")
	)
	(segment
		(start 20.398232 -10.556748)
		(end 21.22424 -9.73074)
		(width 0.11684)
		(layer "F.Cu")
		(net "SMB_BMC_MM2_SCL")
	)
	(segment
		(start 21.22424 -5.90296)
		(end 22.10816 -5.01904)
		(width 0.11684)
		(layer "F.Cu")
		(net "SMB_BMC_MM2_SCL")
	)
	(segment
		(start 42.171366 -29.542994)
		(end 41.86936 -29.845)
		(width 0.11684)
		(layer "F.Cu")
		(net "SMB_BMC_MM2_SCL")
	)
	(segment
		(start 46.228 -20.0406)
		(end 45.47616 -20.79244)
		(width 0.11684)
		(layer "F.Cu")
		(net "SMB_BMC_MM2_SCL")
	)
	(segment
		(start 47.257462 -16.13916)
		(end 46.228 -17.168622)
		(width 0.11684)
		(layer "F.Cu")
		(net "SMB_BMC_MM2_SCL")
	)
	(segment
		(start 47.638462 -5.01904)
		(end 52.35956 -9.740138)
		(width 0.11684)
		(layer "F.Cu")
		(net "SMB_BMC_MM2_SCL")
	)
	(segment
		(start 18.415 -16.891)
		(end 18.415 -15.889224)
		(width 0.11684)
		(layer "F.Cu")
		(net "SMB_BMC_MM2_SCL")
	)
	(segment
		(start 41.86936 -30.34919)
		(end 41.7576 -30.46095)
		(width 0.11684)
		(layer "F.Cu")
		(net "SMB_BMC_MM2_SCL")
	)
	(segment
		(start 44.79036 -22.289262)
		(end 44.79036 -24.091138)
		(width 0.11684)
		(layer "F.Cu")
		(net "SMB_BMC_MM2_SCL")
	)
	(segment
		(start 48.654462 -16.13916)
		(end 47.257462 -16.13916)
		(width 0.11684)
		(layer "F.Cu")
		(net "SMB_BMC_MM2_SCL")
	)
	(segment
		(start 22.10816 -5.01904)
		(end 47.638462 -5.01904)
		(width 0.11684)
		(layer "F.Cu")
		(net "SMB_BMC_MM2_SCL")
	)
	(segment
		(start 52.35956 -12.434062)
		(end 48.654462 -16.13916)
		(width 0.11684)
		(layer "F.Cu")
		(net "SMB_BMC_MM2_SCL")
	)
	(segment
		(start 18.415 -15.889224)
		(end 20.398232 -13.905992)
		(width 0.11684)
		(layer "F.Cu")
		(net "SMB_BMC_MM2_SCL")
	)
	(segment
		(start 41.446704 -30.46095)
		(end 41.302432 -30.605222)
		(width 0.11684)
		(layer "F.Cu")
		(net "SMB_BMC_MM2_SCL")
	)
	(segment
		(start 41.302432 -31.722314)
		(end 42.269918 -32.6898)
		(width 0.11684)
		(layer "F.Cu")
		(net "SMB_BMC_MM2_SCL")
	)
	(segment
		(start 45.47616 -20.79244)
		(end 45.47616 -21.603462)
		(width 0.11684)
		(layer "F.Cu")
		(net "SMB_BMC_MM2_SCL")
	)
	(segment
		(start 41.86936 -29.845)
		(end 41.86936 -30.34919)
		(width 0.11684)
		(layer "F.Cu")
		(net "SMB_BMC_MM2_SCL")
	)
	(segment
		(start 41.7576 -30.46095)
		(end 41.446704 -30.46095)
		(width 0.11684)
		(layer "F.Cu")
		(net "SMB_BMC_MM2_SCL")
	)
	(segment
		(start 41.302432 -30.605222)
		(end 41.302432 -31.722314)
		(width 0.11684)
		(layer "F.Cu")
		(net "SMB_BMC_MM2_SCL")
	)
	(segment
		(start 45.47616 -21.603462)
		(end 44.79036 -22.289262)
		(width 0.11684)
		(layer "F.Cu")
		(net "SMB_BMC_MM2_SCL")
	)
	(segment
		(start 42.269918 -32.6898)
		(end 42.350182 -32.6898)
		(width 0.11684)
		(layer "F.Cu")
		(net "SMB_BMC_MM2_SCL")
	)
	(segment
		(start 46.228 -17.168622)
		(end 46.228 -20.0406)
		(width 0.11684)
		(layer "F.Cu")
		(net "SMB_BMC_MM2_SCL")
	)
	(segment
		(start 45.974 -27.25928)
		(end 44.827952 -28.405328)
		(width 0.11684)
		(layer "F.Cu")
		(net "SMB_BMC_MM2_SCL")
	)
	(segment
		(start 44.79036 -24.091138)
		(end 45.2882 -24.588978)
		(width 0.11684)
		(layer "F.Cu")
		(net "SMB_BMC_MM2_SCL")
	)
	(segment
		(start 20.398232 -13.905992)
		(end 20.398232 -10.556748)
		(width 0.11684)
		(layer "F.Cu")
		(net "SMB_BMC_MM2_SCL")
	)
	(segment
		(start 45.2882 -25.6032)
		(end 45.974 -26.289)
		(width 0.11684)
		(layer "F.Cu")
		(net "SMB_BMC_MM2_SCL")
	)
	(segment
		(start 44.827952 -29.136848)
		(end 44.421806 -29.542994)
		(width 0.11684)
		(layer "F.Cu")
		(net "SMB_BMC_MM2_SCL")
	)
	(segment
		(start 21.22424 -9.73074)
		(end 21.22424 -5.90296)
		(width 0.11684)
		(layer "F.Cu")
		(net "SMB_BMC_MM2_SCL")
	)
	(segment
		(start 44.827952 -28.405328)
		(end 44.827952 -29.136848)
		(width 0.11684)
		(layer "F.Cu")
		(net "SMB_BMC_MM2_SCL")
	)
	(segment
		(start 45.974 -26.289)
		(end 45.974 -27.25928)
		(width 0.11684)
		(layer "F.Cu")
		(net "SMB_BMC_MM2_SCL")
	)
	(segment
		(start 44.421806 -29.542994)
		(end 42.171366 -29.542994)
		(width 0.11684)
		(layer "F.Cu")
		(net "SMB_BMC_MM2_SCL")
	)
	(via
		(at 18.415 -16.891)
		(size 0.508)
		(drill 0.254)
		(layers "F.Cu" "B.Cu")
		(net "SMB_BMC_MM2_SCL")
	)
	(via
		(at 42.350182 -32.6898)
		(size 0.508)
		(drill 0.254)
		(layers "F.Cu" "B.Cu")
		(net "SMB_BMC_MM2_SCL")
	)
	(segment
		(start 42.350182 -32.6898)
		(end 42.350182 -31.216854)
		(width 0.11684)
		(layer "B.Cu")
		(net "SMB_BMC_MM2_SCL")
	)
	(segment
		(start 42.726102 -34.237676)
		(end 42.346118 -34.237676)
		(width 0.11684)
		(layer "B.Cu")
		(net "SMB_BMC_MM2_SCL")
	)
	(segment
		(start 42.350182 -32.6898)
		(end 42.840656 -33.180274)
		(width 0.11684)
		(layer "B.Cu")
		(net "SMB_BMC_MM2_SCL")
	)
	(segment
		(start 42.840656 -33.180274)
		(end 42.840656 -34.123122)
		(width 0.11684)
		(layer "B.Cu")
		(net "SMB_BMC_MM2_SCL")
	)
	(segment
		(start 42.840656 -34.123122)
		(end 42.726102 -34.237676)
		(width 0.11684)
		(layer "B.Cu")
		(net "SMB_BMC_MM2_SCL")
	)
	(segment
		(start 18.415 -17.50695)
		(end 18.415 -16.891)
		(width 0.11684)
		(layer "B.Cu")
		(net "SMB_BMC_MM2_SCL")
	)
	(segment
		(start 49.6951 -41.771316)
		(end 49.299876 -41.376092)
		(width 0.11684)
		(layer "F.Cu")
		(net "SMB_BMC_MM2_R_SDA")
	)
	(via
		(at 44.5643 -36.500816)
		(size 0.6604)
		(drill 0.3302)
		(layers "F.Cu" "B.Cu")
		(net "SMB_BMC_MM2_R_SDA")
	)
	(via
		(at 49.299876 -41.376092)
		(size 0.4572)
		(drill 0.254)
		(layers "F.Cu" "B.Cu")
		(net "SMB_BMC_MM2_R_SDA")
	)
	(segment
		(start 46.738794 -39.364666)
		(end 46.51121 -39.137082)
		(width 0.11684)
		(layer "B.Cu")
		(net "SMB_BMC_MM2_R_SDA")
	)
	(segment
		(start 44.5643 -36.500816)
		(end 44.262802 -36.199318)
		(width 0.11684)
		(layer "B.Cu")
		(net "SMB_BMC_MM2_R_SDA")
	)
	(segment
		(start 49.299876 -41.376092)
		(end 49.049432 -41.376092)
		(width 0.11684)
		(layer "B.Cu")
		(net "SMB_BMC_MM2_R_SDA")
	)
	(segment
		(start 48.105568 -40.256968)
		(end 48.013366 -40.164766)
		(width 0.11684)
		(layer "B.Cu")
		(net "SMB_BMC_MM2_R_SDA")
	)
	(segment
		(start 47.311056 -39.614856)
		(end 47.060866 -39.364666)
		(width 0.11684)
		(layer "B.Cu")
		(net "SMB_BMC_MM2_R_SDA")
	)
	(segment
		(start 48.651922 -40.978582)
		(end 48.265334 -40.978582)
		(width 0.11684)
		(layer "B.Cu")
		(net "SMB_BMC_MM2_R_SDA")
	)
	(segment
		(start 44.074588 -35.745166)
		(end 43.367198 -35.037776)
		(width 0.11684)
		(layer "B.Cu")
		(net "SMB_BMC_MM2_R_SDA")
	)
	(segment
		(start 47.060866 -39.364666)
		(end 46.738794 -39.364666)
		(width 0.11684)
		(layer "B.Cu")
		(net "SMB_BMC_MM2_R_SDA")
	)
	(segment
		(start 48.013366 -40.164766)
		(end 47.53864 -40.164766)
		(width 0.11684)
		(layer "B.Cu")
		(net "SMB_BMC_MM2_R_SDA")
	)
	(segment
		(start 46.51121 -38.73881)
		(end 45.8978 -38.1254)
		(width 0.11684)
		(layer "B.Cu")
		(net "SMB_BMC_MM2_R_SDA")
	)
	(segment
		(start 48.265334 -40.978582)
		(end 48.105568 -40.818816)
		(width 0.11684)
		(layer "B.Cu")
		(net "SMB_BMC_MM2_R_SDA")
	)
	(segment
		(start 48.105568 -40.818816)
		(end 48.105568 -40.256968)
		(width 0.11684)
		(layer "B.Cu")
		(net "SMB_BMC_MM2_R_SDA")
	)
	(segment
		(start 45.668946 -38.1254)
		(end 44.9326 -37.389054)
		(width 0.11684)
		(layer "B.Cu")
		(net "SMB_BMC_MM2_R_SDA")
	)
	(segment
		(start 44.9326 -36.869116)
		(end 44.5643 -36.500816)
		(width 0.11684)
		(layer "B.Cu")
		(net "SMB_BMC_MM2_R_SDA")
	)
	(segment
		(start 46.51121 -39.137082)
		(end 46.51121 -38.73881)
		(width 0.11684)
		(layer "B.Cu")
		(net "SMB_BMC_MM2_R_SDA")
	)
	(segment
		(start 44.9326 -37.389054)
		(end 44.9326 -36.869116)
		(width 0.11684)
		(layer "B.Cu")
		(net "SMB_BMC_MM2_R_SDA")
	)
	(segment
		(start 47.311056 -39.937182)
		(end 47.311056 -39.614856)
		(width 0.11684)
		(layer "B.Cu")
		(net "SMB_BMC_MM2_R_SDA")
	)
	(segment
		(start 44.262802 -36.199318)
		(end 44.074588 -35.745166)
		(width 0.11684)
		(layer "B.Cu")
		(net "SMB_BMC_MM2_R_SDA")
	)
	(segment
		(start 47.53864 -40.164766)
		(end 47.311056 -39.937182)
		(width 0.11684)
		(layer "B.Cu")
		(net "SMB_BMC_MM2_R_SDA")
	)
	(segment
		(start 49.049432 -41.376092)
		(end 48.651922 -40.978582)
		(width 0.11684)
		(layer "B.Cu")
		(net "SMB_BMC_MM2_R_SDA")
	)
	(segment
		(start 45.8978 -38.1254)
		(end 45.668946 -38.1254)
		(width 0.11684)
		(layer "B.Cu")
		(net "SMB_BMC_MM2_R_SDA")
	)
	(segment
		(start 50.494946 -42.571162)
		(end 50.099722 -42.175938)
		(width 0.11684)
		(layer "F.Cu")
		(net "SMB_BMC_MM2_R_SCL")
	)
	(via
		(at 50.099722 -42.175938)
		(size 0.4572)
		(drill 0.254)
		(layers "F.Cu" "B.Cu")
		(net "SMB_BMC_MM2_R_SCL")
	)
	(via
		(at 44.5516 -37.846)
		(size 0.6604)
		(drill 0.3302)
		(layers "F.Cu" "B.Cu")
		(net "SMB_BMC_MM2_R_SCL")
	)
	(segment
		(start 48.098202 -41.140126)
		(end 48.098202 -41.530778)
		(width 0.11684)
		(layer "B.Cu")
		(net "SMB_BMC_MM2_R_SCL")
	)
	(segment
		(start 47.922688 -40.964612)
		(end 48.098202 -41.140126)
		(width 0.11684)
		(layer "B.Cu")
		(net "SMB_BMC_MM2_R_SCL")
	)
	(segment
		(start 49.405286 -41.769792)
		(end 49.897538 -41.973754)
		(width 0.11684)
		(layer "B.Cu")
		(net "SMB_BMC_MM2_R_SCL")
	)
	(segment
		(start 47.53864 -40.964612)
		(end 47.922688 -40.964612)
		(width 0.11684)
		(layer "B.Cu")
		(net "SMB_BMC_MM2_R_SCL")
	)
	(segment
		(start 46.51121 -39.937182)
		(end 46.738794 -40.164766)
		(width 0.11684)
		(layer "B.Cu")
		(net "SMB_BMC_MM2_R_SCL")
	)
	(segment
		(start 48.337216 -41.769792)
		(end 49.405286 -41.769792)
		(width 0.11684)
		(layer "B.Cu")
		(net "SMB_BMC_MM2_R_SCL")
	)
	(segment
		(start 48.098202 -41.530778)
		(end 48.337216 -41.769792)
		(width 0.11684)
		(layer "B.Cu")
		(net "SMB_BMC_MM2_R_SCL")
	)
	(segment
		(start 46.296072 -39.387526)
		(end 46.51121 -39.602664)
		(width 0.11684)
		(layer "B.Cu")
		(net "SMB_BMC_MM2_R_SCL")
	)
	(segment
		(start 45.71111 -39.137082)
		(end 45.961554 -39.387526)
		(width 0.11684)
		(layer "B.Cu")
		(net "SMB_BMC_MM2_R_SCL")
	)
	(segment
		(start 45.961554 -39.387526)
		(end 46.296072 -39.387526)
		(width 0.11684)
		(layer "B.Cu")
		(net "SMB_BMC_MM2_R_SCL")
	)
	(segment
		(start 46.738794 -40.164766)
		(end 47.073312 -40.164766)
		(width 0.11684)
		(layer "B.Cu")
		(net "SMB_BMC_MM2_R_SCL")
	)
	(segment
		(start 47.311056 -40.40251)
		(end 47.311056 -40.737028)
		(width 0.11684)
		(layer "B.Cu")
		(net "SMB_BMC_MM2_R_SCL")
	)
	(segment
		(start 45.71111 -39.00551)
		(end 45.71111 -39.137082)
		(width 0.11684)
		(layer "B.Cu")
		(net "SMB_BMC_MM2_R_SCL")
	)
	(segment
		(start 43.674284 -36.07943)
		(end 42.993818 -35.398964)
		(width 0.11684)
		(layer "B.Cu")
		(net "SMB_BMC_MM2_R_SCL")
	)
	(segment
		(start 43.920664 -36.674044)
		(end 43.674284 -36.07943)
		(width 0.11684)
		(layer "B.Cu")
		(net "SMB_BMC_MM2_R_SCL")
	)
	(segment
		(start 44.2976 -37.592)
		(end 44.2976 -37.05098)
		(width 0.11684)
		(layer "B.Cu")
		(net "SMB_BMC_MM2_R_SCL")
	)
	(segment
		(start 44.5516 -37.846)
		(end 44.2976 -37.592)
		(width 0.11684)
		(layer "B.Cu")
		(net "SMB_BMC_MM2_R_SCL")
	)
	(segment
		(start 47.311056 -40.737028)
		(end 47.53864 -40.964612)
		(width 0.11684)
		(layer "B.Cu")
		(net "SMB_BMC_MM2_R_SCL")
	)
	(segment
		(start 46.51121 -39.602664)
		(end 46.51121 -39.937182)
		(width 0.11684)
		(layer "B.Cu")
		(net "SMB_BMC_MM2_R_SCL")
	)
	(segment
		(start 42.993818 -35.398964)
		(end 42.504868 -35.196272)
		(width 0.11684)
		(layer "B.Cu")
		(net "SMB_BMC_MM2_R_SCL")
	)
	(segment
		(start 49.897538 -41.973754)
		(end 50.099722 -42.175938)
		(width 0.11684)
		(layer "B.Cu")
		(net "SMB_BMC_MM2_R_SCL")
	)
	(segment
		(start 44.5516 -37.846)
		(end 45.71111 -39.00551)
		(width 0.11684)
		(layer "B.Cu")
		(net "SMB_BMC_MM2_R_SCL")
	)
	(segment
		(start 42.504868 -35.196272)
		(end 42.346118 -35.037776)
		(width 0.11684)
		(layer "B.Cu")
		(net "SMB_BMC_MM2_R_SCL")
	)
	(segment
		(start 47.073312 -40.164766)
		(end 47.311056 -40.40251)
		(width 0.11684)
		(layer "B.Cu")
		(net "SMB_BMC_MM2_R_SCL")
	)
	(segment
		(start 44.2976 -37.05098)
		(end 43.920664 -36.674044)
		(width 0.11684)
		(layer "B.Cu")
		(net "SMB_BMC_MM2_R_SCL")
	)
	(segment
		(start 48.1584 -33.63595)
		(end 48.1584 -32.359854)
		(width 0.11684)
		(layer "F.Cu")
		(net "SMB_BMC_MM1_SDA")
	)
	(segment
		(start 48.1584 -32.359854)
		(end 48.6156 -31.902654)
		(width 0.11684)
		(layer "F.Cu")
		(net "SMB_BMC_MM1_SDA")
	)
	(segment
		(start 47.703994 -29.6672)
		(end 48.133 -30.096206)
		(width 0.11684)
		(layer "F.Cu")
		(net "SMB_BMC_MM1_SDA")
	)
	(segment
		(start 48.354234 -31.267654)
		(end 48.6156 -31.267654)
		(width 0.11684)
		(layer "F.Cu")
		(net "SMB_BMC_MM1_SDA")
	)
	(segment
		(start 48.133 -31.04642)
		(end 48.354234 -31.267654)
		(width 0.11684)
		(layer "F.Cu")
		(net "SMB_BMC_MM1_SDA")
	)
	(segment
		(start 48.133 -30.096206)
		(end 48.133 -31.04642)
		(width 0.11684)
		(layer "F.Cu")
		(net "SMB_BMC_MM1_SDA")
	)
	(segment
		(start 48.6156 -31.902654)
		(end 48.6156 -31.267654)
		(width 0.11684)
		(layer "F.Cu")
		(net "SMB_BMC_MM1_SDA")
	)
	(segment
		(start 47.515526 -29.6672)
		(end 47.703994 -29.6672)
		(width 0.11684)
		(layer "F.Cu")
		(net "SMB_BMC_MM1_SDA")
	)
	(segment
		(start 48.768 -34.24555)
		(end 48.1584 -33.63595)
		(width 0.11684)
		(layer "F.Cu")
		(net "SMB_BMC_MM1_SDA")
	)
	(via
		(at 49.53 -107.32516)
		(size 0.762)
		(drill 0.254)
		(layers "F.Cu" "B.Cu")
		(net "SMB_BMC_MM1_SDA")
	)
	(via
		(at 47.515526 -29.6672)
		(size 0.508)
		(drill 0.254)
		(layers "F.Cu" "B.Cu")
		(net "SMB_BMC_MM1_SDA")
	)
	(via
		(at 62.6618 -114.681)
		(size 0.508)
		(drill 0.254)
		(layers "F.Cu" "B.Cu")
		(net "SMB_BMC_MM1_SDA")
	)
	(segment
		(start 62.0268 -114.681)
		(end 62.6618 -114.681)
		(width 0.11684)
		(layer "B.Cu")
		(net "SMB_BMC_MM1_SDA")
	)
	(segment
		(start 61.665104 -116.846096)
		(end 61.8744 -116.6368)
		(width 0.11684)
		(layer "B.Cu")
		(net "SMB_BMC_MM1_SDA")
	)
	(segment
		(start 61.665104 -118.460012)
		(end 61.665104 -116.846096)
		(width 0.11684)
		(layer "B.Cu")
		(net "SMB_BMC_MM1_SDA")
	)
	(segment
		(start 61.8744 -114.8334)
		(end 62.0268 -114.681)
		(width 0.11684)
		(layer "B.Cu")
		(net "SMB_BMC_MM1_SDA")
	)
	(segment
		(start 61.8744 -116.6368)
		(end 61.8744 -114.8334)
		(width 0.11684)
		(layer "B.Cu")
		(net "SMB_BMC_MM1_SDA")
	)
	(segment
		(start 49.20996 -107.32516)
		(end 49.53 -107.32516)
		(width 0.10668)
		(layer "In7.Cu")
		(net "SMB_BMC_MM1_SDA")
	)
	(segment
		(start 33.19526 -43.33494)
		(end 32.59074 -43.93946)
		(width 0.10668)
		(layer "In7.Cu")
		(net "SMB_BMC_MM1_SDA")
	)
	(segment
		(start 39.214552 -82.96148)
		(end 41.655492 -85.40242)
		(width 0.10668)
		(layer "In7.Cu")
		(net "SMB_BMC_MM1_SDA")
	)
	(segment
		(start 59.617864 -116.327936)
		(end 59.378088 -116.08816)
		(width 0.10668)
		(layer "In7.Cu")
		(net "SMB_BMC_MM1_SDA")
	)
	(segment
		(start 41.655492 -85.40242)
		(end 43.315128 -85.40242)
		(width 0.10668)
		(layer "In7.Cu")
		(net "SMB_BMC_MM1_SDA")
	)
	(segment
		(start 29.70276 -69.190362)
		(end 29.70276 -70.850506)
		(width 0.10668)
		(layer "In7.Cu")
		(net "SMB_BMC_MM1_SDA")
	)
	(segment
		(start 32.1056 -49.504346)
		(end 32.837882 -50.236628)
		(width 0.10668)
		(layer "In7.Cu")
		(net "SMB_BMC_MM1_SDA")
	)
	(segment
		(start 50.06594 -109.620558)
		(end 49.53 -109.084618)
		(width 0.10668)
		(layer "In7.Cu")
		(net "SMB_BMC_MM1_SDA")
	)
	(segment
		(start 38.3032 -35.5854)
		(end 37.581332 -35.5854)
		(width 0.10668)
		(layer "In7.Cu")
		(net "SMB_BMC_MM1_SDA")
	)
	(segment
		(start 48.7426 -111.8362)
		(end 49.36236 -111.21644)
		(width 0.10668)
		(layer "In7.Cu")
		(net "SMB_BMC_MM1_SDA")
	)
	(segment
		(start 50.56632 -114.72672)
		(end 48.7426 -112.903)
		(width 0.10668)
		(layer "In7.Cu")
		(net "SMB_BMC_MM1_SDA")
	)
	(segment
		(start 43.315128 -85.40242)
		(end 44.519088 -86.60638)
		(width 0.10668)
		(layer "In7.Cu")
		(net "SMB_BMC_MM1_SDA")
	)
	(segment
		(start 44.651422 -30.59684)
		(end 44.311062 -30.25648)
		(width 0.10668)
		(layer "In7.Cu")
		(net "SMB_BMC_MM1_SDA")
	)
	(segment
		(start 62.1538 -115.189)
		(end 62.1538 -115.81892)
		(width 0.10668)
		(layer "In7.Cu")
		(net "SMB_BMC_MM1_SDA")
	)
	(segment
		(start 46.14164 -106.043984)
		(end 46.777656 -106.68)
		(width 0.10668)
		(layer "In7.Cu")
		(net "SMB_BMC_MM1_SDA")
	)
	(segment
		(start 33.949386 -42.03446)
		(end 33.4645 -42.03446)
		(width 0.10668)
		(layer "In7.Cu")
		(net "SMB_BMC_MM1_SDA")
	)
	(segment
		(start 32.837882 -51.221894)
		(end 32.508698 -52.016406)
		(width 0.10668)
		(layer "In7.Cu")
		(net "SMB_BMC_MM1_SDA")
	)
	(segment
		(start 29.70276 -70.850506)
		(end 32.47136 -73.619106)
		(width 0.10668)
		(layer "In7.Cu")
		(net "SMB_BMC_MM1_SDA")
	)
	(segment
		(start 37.581332 -35.5854)
		(end 36.56584 -36.600892)
		(width 0.10668)
		(layer "In7.Cu")
		(net "SMB_BMC_MM1_SDA")
	)
	(segment
		(start 32.1056 -47.13224)
		(end 32.1056 -49.504346)
		(width 0.10668)
		(layer "In7.Cu")
		(net "SMB_BMC_MM1_SDA")
	)
	(segment
		(start 46.8884 -30.08376)
		(end 46.37532 -30.59684)
		(width 0.10668)
		(layer "In7.Cu")
		(net "SMB_BMC_MM1_SDA")
	)
	(segment
		(start 59.378088 -116.08816)
		(end 58.85561 -116.08816)
		(width 0.10668)
		(layer "In7.Cu")
		(net "SMB_BMC_MM1_SDA")
	)
	(segment
		(start 44.311062 -30.25648)
		(end 41.605962 -30.25648)
		(width 0.10668)
		(layer "In7.Cu")
		(net "SMB_BMC_MM1_SDA")
	)
	(segment
		(start 50.06594 -110.001558)
		(end 50.06594 -109.620558)
		(width 0.10668)
		(layer "In7.Cu")
		(net "SMB_BMC_MM1_SDA")
	)
	(segment
		(start 40.193722 -30.841188)
		(end 39.819326 -30.841188)
		(width 0.10668)
		(layer "In7.Cu")
		(net "SMB_BMC_MM1_SDA")
	)
	(segment
		(start 39.819326 -30.841188)
		(end 39.160196 -31.500318)
		(width 0.10668)
		(layer "In7.Cu")
		(net "SMB_BMC_MM1_SDA")
	)
	(segment
		(start 36.2204 -38.696138)
		(end 36.2204 -39.763446)
		(width 0.10668)
		(layer "In7.Cu")
		(net "SMB_BMC_MM1_SDA")
	)
	(segment
		(start 29.45003 -64.714628)
		(end 30.4038 -65.668398)
		(width 0.10668)
		(layer "In7.Cu")
		(net "SMB_BMC_MM1_SDA")
	)
	(segment
		(start 29.45003 -63.61303)
		(end 29.45003 -64.714628)
		(width 0.10668)
		(layer "In7.Cu")
		(net "SMB_BMC_MM1_SDA")
	)
	(segment
		(start 34.90976 -79.757778)
		(end 38.113462 -82.96148)
		(width 0.10668)
		(layer "In7.Cu")
		(net "SMB_BMC_MM1_SDA")
	)
	(segment
		(start 36.2204 -37.73551)
		(end 35.930586 -38.025324)
		(width 0.10668)
		(layer "In7.Cu")
		(net "SMB_BMC_MM1_SDA")
	)
	(segment
		(start 58.85561 -116.08816)
		(end 57.179718 -115.393724)
		(width 0.10668)
		(layer "In7.Cu")
		(net "SMB_BMC_MM1_SDA")
	)
	(segment
		(start 46.141894 -101.262942)
		(end 46.14164 -101.263196)
		(width 0.10668)
		(layer "In7.Cu")
		(net "SMB_BMC_MM1_SDA")
	)
	(segment
		(start 34.90976 -79.207868)
		(end 34.90976 -79.757778)
		(width 0.10668)
		(layer "In7.Cu")
		(net "SMB_BMC_MM1_SDA")
	)
	(segment
		(start 46.37532 -30.59684)
		(end 44.651422 -30.59684)
		(width 0.10668)
		(layer "In7.Cu")
		(net "SMB_BMC_MM1_SDA")
	)
	(segment
		(start 32.47136 -73.619106)
		(end 32.47136 -75.498706)
		(width 0.10668)
		(layer "In7.Cu")
		(net "SMB_BMC_MM1_SDA")
	)
	(segment
		(start 36.2204 -37.595048)
		(end 36.2204 -37.73551)
		(width 0.10668)
		(layer "In7.Cu")
		(net "SMB_BMC_MM1_SDA")
	)
	(segment
		(start 30.759654 -56.878982)
		(end 30.225238 -57.413398)
		(width 0.10668)
		(layer "In7.Cu")
		(net "SMB_BMC_MM1_SDA")
	)
	(segment
		(start 48.5648 -106.68)
		(end 49.20996 -107.32516)
		(width 0.10668)
		(layer "In7.Cu")
		(net "SMB_BMC_MM1_SDA")
	)
	(segment
		(start 44.519088 -86.60638)
		(end 44.519088 -98.807016)
		(width 0.10668)
		(layer "In7.Cu")
		(net "SMB_BMC_MM1_SDA")
	)
	(segment
		(start 33.4645 -42.03446)
		(end 33.19526 -42.3037)
		(width 0.10668)
		(layer "In7.Cu")
		(net "SMB_BMC_MM1_SDA")
	)
	(segment
		(start 30.4038 -65.668398)
		(end 30.4038 -68.489322)
		(width 0.10668)
		(layer "In7.Cu")
		(net "SMB_BMC_MM1_SDA")
	)
	(segment
		(start 32.73298 -77.031088)
		(end 34.90976 -79.207868)
		(width 0.10668)
		(layer "In7.Cu")
		(net "SMB_BMC_MM1_SDA")
	)
	(segment
		(start 44.519088 -98.807016)
		(end 46.141894 -100.429822)
		(width 0.10668)
		(layer "In7.Cu")
		(net "SMB_BMC_MM1_SDA")
	)
	(segment
		(start 29.13634 -60.9473)
		(end 28.39212 -61.69152)
		(width 0.10668)
		(layer "In7.Cu")
		(net "SMB_BMC_MM1_SDA")
	)
	(segment
		(start 48.7426 -112.903)
		(end 48.7426 -111.8362)
		(width 0.10668)
		(layer "In7.Cu")
		(net "SMB_BMC_MM1_SDA")
	)
	(segment
		(start 49.36236 -111.21644)
		(end 49.36236 -110.705392)
		(width 0.10668)
		(layer "In7.Cu")
		(net "SMB_BMC_MM1_SDA")
	)
	(segment
		(start 32.73298 -75.760326)
		(end 32.73298 -77.031088)
		(width 0.10668)
		(layer "In7.Cu")
		(net "SMB_BMC_MM1_SDA")
	)
	(segment
		(start 62.6618 -114.681)
		(end 62.1538 -115.189)
		(width 0.10668)
		(layer "In7.Cu")
		(net "SMB_BMC_MM1_SDA")
	)
	(segment
		(start 47.515526 -29.6672)
		(end 47.098966 -30.08376)
		(width 0.10668)
		(layer "In7.Cu")
		(net "SMB_BMC_MM1_SDA")
	)
	(segment
		(start 32.59074 -46.6471)
		(end 32.1056 -47.13224)
		(width 0.10668)
		(layer "In7.Cu")
		(net "SMB_BMC_MM1_SDA")
	)
	(segment
		(start 30.225238 -59.037982)
		(end 29.13634 -60.12688)
		(width 0.10668)
		(layer "In7.Cu")
		(net "SMB_BMC_MM1_SDA")
	)
	(segment
		(start 28.39212 -61.69152)
		(end 28.39212 -62.55512)
		(width 0.10668)
		(layer "In7.Cu")
		(net "SMB_BMC_MM1_SDA")
	)
	(segment
		(start 35.930586 -38.406324)
		(end 36.2204 -38.696138)
		(width 0.10668)
		(layer "In7.Cu")
		(net "SMB_BMC_MM1_SDA")
	)
	(segment
		(start 32.47136 -75.498706)
		(end 32.73298 -75.760326)
		(width 0.10668)
		(layer "In7.Cu")
		(net "SMB_BMC_MM1_SDA")
	)
	(segment
		(start 39.160196 -31.500318)
		(end 39.134796 -31.517336)
		(width 0.10668)
		(layer "In7.Cu")
		(net "SMB_BMC_MM1_SDA")
	)
	(segment
		(start 57.179718 -115.393724)
		(end 53.722524 -115.393724)
		(width 0.10668)
		(layer "In7.Cu")
		(net "SMB_BMC_MM1_SDA")
	)
	(segment
		(start 41.605962 -30.25648)
		(end 40.193722 -30.841188)
		(width 0.10668)
		(layer "In7.Cu")
		(net "SMB_BMC_MM1_SDA")
	)
	(segment
		(start 49.58334 -110.484158)
		(end 50.06594 -110.001558)
		(width 0.10668)
		(layer "In7.Cu")
		(net "SMB_BMC_MM1_SDA")
	)
	(segment
		(start 46.141894 -100.429822)
		(end 46.141894 -101.262942)
		(width 0.10668)
		(layer "In7.Cu")
		(net "SMB_BMC_MM1_SDA")
	)
	(segment
		(start 38.113462 -82.96148)
		(end 39.214552 -82.96148)
		(width 0.10668)
		(layer "In7.Cu")
		(net "SMB_BMC_MM1_SDA")
	)
	(segment
		(start 33.19526 -42.3037)
		(end 33.19526 -43.33494)
		(width 0.10668)
		(layer "In7.Cu")
		(net "SMB_BMC_MM1_SDA")
	)
	(segment
		(start 36.2204 -39.763446)
		(end 33.949386 -42.03446)
		(width 0.10668)
		(layer "In7.Cu")
		(net "SMB_BMC_MM1_SDA")
	)
	(segment
		(start 31.214822 -55.780686)
		(end 30.759654 -56.878982)
		(width 0.10668)
		(layer "In7.Cu")
		(net "SMB_BMC_MM1_SDA")
	)
	(segment
		(start 49.53 -109.084618)
		(end 49.53 -107.32516)
		(width 0.10668)
		(layer "In7.Cu")
		(net "SMB_BMC_MM1_SDA")
	)
	(segment
		(start 32.488632 -54.506876)
		(end 31.214822 -55.780686)
		(width 0.10668)
		(layer "In7.Cu")
		(net "SMB_BMC_MM1_SDA")
	)
	(segment
		(start 30.225238 -57.413398)
		(end 30.225238 -59.037982)
		(width 0.10668)
		(layer "In7.Cu")
		(net "SMB_BMC_MM1_SDA")
	)
	(segment
		(start 62.1538 -115.81892)
		(end 61.644784 -116.327936)
		(width 0.10668)
		(layer "In7.Cu")
		(net "SMB_BMC_MM1_SDA")
	)
	(segment
		(start 46.14164 -101.263196)
		(end 46.14164 -106.043984)
		(width 0.10668)
		(layer "In7.Cu")
		(net "SMB_BMC_MM1_SDA")
	)
	(segment
		(start 46.777656 -106.68)
		(end 48.5648 -106.68)
		(width 0.10668)
		(layer "In7.Cu")
		(net "SMB_BMC_MM1_SDA")
	)
	(segment
		(start 30.4038 -68.489322)
		(end 29.70276 -69.190362)
		(width 0.10668)
		(layer "In7.Cu")
		(net "SMB_BMC_MM1_SDA")
	)
	(segment
		(start 28.39212 -62.55512)
		(end 29.45003 -63.61303)
		(width 0.10668)
		(layer "In7.Cu")
		(net "SMB_BMC_MM1_SDA")
	)
	(segment
		(start 29.13634 -60.12688)
		(end 29.13634 -60.9473)
		(width 0.10668)
		(layer "In7.Cu")
		(net "SMB_BMC_MM1_SDA")
	)
	(segment
		(start 38.612572 -35.276028)
		(end 38.3032 -35.5854)
		(width 0.10668)
		(layer "In7.Cu")
		(net "SMB_BMC_MM1_SDA")
	)
	(segment
		(start 32.488632 -52.117498)
		(end 32.488632 -54.506876)
		(width 0.10668)
		(layer "In7.Cu")
		(net "SMB_BMC_MM1_SDA")
	)
	(segment
		(start 61.644784 -116.327936)
		(end 59.617864 -116.327936)
		(width 0.10668)
		(layer "In7.Cu")
		(net "SMB_BMC_MM1_SDA")
	)
	(segment
		(start 32.508698 -52.016406)
		(end 32.488632 -52.117498)
		(width 0.10668)
		(layer "In7.Cu")
		(net "SMB_BMC_MM1_SDA")
	)
	(segment
		(start 36.56584 -36.600892)
		(end 36.56584 -37.249608)
		(width 0.10668)
		(layer "In7.Cu")
		(net "SMB_BMC_MM1_SDA")
	)
	(segment
		(start 32.59074 -43.93946)
		(end 32.59074 -46.6471)
		(width 0.10668)
		(layer "In7.Cu")
		(net "SMB_BMC_MM1_SDA")
	)
	(segment
		(start 32.837882 -50.236628)
		(end 32.837882 -51.221894)
		(width 0.10668)
		(layer "In7.Cu")
		(net "SMB_BMC_MM1_SDA")
	)
	(segment
		(start 53.722524 -115.393724)
		(end 53.05552 -114.72672)
		(width 0.10668)
		(layer "In7.Cu")
		(net "SMB_BMC_MM1_SDA")
	)
	(segment
		(start 35.930586 -38.025324)
		(end 35.930586 -38.406324)
		(width 0.10668)
		(layer "In7.Cu")
		(net "SMB_BMC_MM1_SDA")
	)
	(segment
		(start 53.05552 -114.72672)
		(end 50.56632 -114.72672)
		(width 0.10668)
		(layer "In7.Cu")
		(net "SMB_BMC_MM1_SDA")
	)
	(segment
		(start 47.098966 -30.08376)
		(end 46.8884 -30.08376)
		(width 0.10668)
		(layer "In7.Cu")
		(net "SMB_BMC_MM1_SDA")
	)
	(segment
		(start 39.134796 -31.517336)
		(end 38.612572 -32.777938)
		(width 0.10668)
		(layer "In7.Cu")
		(net "SMB_BMC_MM1_SDA")
	)
	(segment
		(start 49.58334 -110.484412)
		(end 49.58334 -110.484158)
		(width 0.10668)
		(layer "In7.Cu")
		(net "SMB_BMC_MM1_SDA")
	)
	(segment
		(start 36.56584 -37.249608)
		(end 36.2204 -37.595048)
		(width 0.10668)
		(layer "In7.Cu")
		(net "SMB_BMC_MM1_SDA")
	)
	(segment
		(start 38.612572 -32.777938)
		(end 38.612572 -35.276028)
		(width 0.10668)
		(layer "In7.Cu")
		(net "SMB_BMC_MM1_SDA")
	)
	(segment
		(start 49.36236 -110.705392)
		(end 49.58334 -110.484412)
		(width 0.10668)
		(layer "In7.Cu")
		(net "SMB_BMC_MM1_SDA")
	)
	(segment
		(start 46.138592 -30.701488)
		(end 45.67174 -31.16834)
		(width 0.11684)
		(layer "F.Cu")
		(net "SMB_BMC_MM1_SCL")
	)
	(segment
		(start 46.10354 -31.68904)
		(end 45.777912 -31.68904)
		(width 0.11684)
		(layer "F.Cu")
		(net "SMB_BMC_MM1_SCL")
	)
	(segment
		(start 45.777912 -31.68904)
		(end 45.280326 -31.191454)
		(width 0.11684)
		(layer "F.Cu")
		(net "SMB_BMC_MM1_SCL")
	)
	(segment
		(start 46.138592 -29.858208)
		(end 46.138592 -30.701488)
		(width 0.11684)
		(layer "F.Cu")
		(net "SMB_BMC_MM1_SCL")
	)
	(segment
		(start 45.282358 -31.16834)
		(end 45.259244 -31.191454)
		(width 0.11684)
		(layer "F.Cu")
		(net "SMB_BMC_MM1_SCL")
	)
	(segment
		(start 45.67174 -31.16834)
		(end 45.282358 -31.16834)
		(width 0.11684)
		(layer "F.Cu")
		(net "SMB_BMC_MM1_SCL")
	)
	(segment
		(start 46.95698 -33.77438)
		(end 46.95698 -32.54248)
		(width 0.11684)
		(layer "F.Cu")
		(net "SMB_BMC_MM1_SCL")
	)
	(segment
		(start 46.228 -29.7688)
		(end 46.138592 -29.858208)
		(width 0.11684)
		(layer "F.Cu")
		(net "SMB_BMC_MM1_SCL")
	)
	(segment
		(start 47.42815 -34.24555)
		(end 46.95698 -33.77438)
		(width 0.11684)
		(layer "F.Cu")
		(net "SMB_BMC_MM1_SCL")
	)
	(segment
		(start 46.95698 -32.54248)
		(end 46.10354 -31.68904)
		(width 0.11684)
		(layer "F.Cu")
		(net "SMB_BMC_MM1_SCL")
	)
	(segment
		(start 47.752 -34.24555)
		(end 47.42815 -34.24555)
		(width 0.11684)
		(layer "F.Cu")
		(net "SMB_BMC_MM1_SCL")
	)
	(segment
		(start 45.280326 -31.191454)
		(end 45.259244 -31.191454)
		(width 0.11684)
		(layer "F.Cu")
		(net "SMB_BMC_MM1_SCL")
	)
	(via
		(at 46.228 -29.7688)
		(size 0.508)
		(drill 0.254)
		(layers "F.Cu" "B.Cu")
		(net "SMB_BMC_MM1_SCL")
	)
	(via
		(at 48.35398 -107.31246)
		(size 0.508)
		(drill 0.254)
		(layers "F.Cu" "B.Cu")
		(net "SMB_BMC_MM1_SCL")
	)
	(via
		(at 62.6618 -115.3414)
		(size 0.508)
		(drill 0.254)
		(layers "F.Cu" "B.Cu")
		(net "SMB_BMC_MM1_SCL")
	)
	(segment
		(start 62.6618 -115.3414)
		(end 62.6618 -116.101368)
		(width 0.11684)
		(layer "B.Cu")
		(net "SMB_BMC_MM1_SCL")
	)
	(segment
		(start 62.6618 -116.101368)
		(end 62.265052 -117.059202)
		(width 0.11684)
		(layer "B.Cu")
		(net "SMB_BMC_MM1_SCL")
	)
	(segment
		(start 62.265052 -117.059202)
		(end 62.265052 -118.460012)
		(width 0.11684)
		(layer "B.Cu")
		(net "SMB_BMC_MM1_SCL")
	)
	(segment
		(start 28.793694 -59.172094)
		(end 28.793694 -58.370724)
		(width 0.10668)
		(layer "In7.Cu")
		(net "SMB_BMC_MM1_SCL")
	)
	(segment
		(start 38.471094 -32.24276)
		(end 38.863778 -31.29534)
		(width 0.10668)
		(layer "In7.Cu")
		(net "SMB_BMC_MM1_SCL")
	)
	(segment
		(start 33.947608 -80.086708)
		(end 33.947608 -78.730348)
		(width 0.10668)
		(layer "In7.Cu")
		(net "SMB_BMC_MM1_SCL")
	)
	(segment
		(start 29.459428 -67.340226)
		(end 29.75864 -67.041014)
		(width 0.10668)
		(layer "In7.Cu")
		(net "SMB_BMC_MM1_SCL")
	)
	(segment
		(start 53.583586 -115.729004)
		(end 52.916582 -115.062)
		(width 0.10668)
		(layer "In7.Cu")
		(net "SMB_BMC_MM1_SCL")
	)
	(segment
		(start 62.6618 -115.883182)
		(end 61.881766 -116.663216)
		(width 0.10668)
		(layer "In7.Cu")
		(net "SMB_BMC_MM1_SCL")
	)
	(segment
		(start 42.09288 -29.9212)
		(end 44.45 -29.9212)
		(width 0.10668)
		(layer "In7.Cu")
		(net "SMB_BMC_MM1_SCL")
	)
	(segment
		(start 32.502602 -51.063398)
		(end 32.502602 -50.375566)
		(width 0.10668)
		(layer "In7.Cu")
		(net "SMB_BMC_MM1_SCL")
	)
	(segment
		(start 59.478926 -116.663216)
		(end 59.23915 -116.42344)
		(width 0.10668)
		(layer "In7.Cu")
		(net "SMB_BMC_MM1_SCL")
	)
	(segment
		(start 36.576 -35.8648)
		(end 37.5412 -34.8996)
		(width 0.10668)
		(layer "In7.Cu")
		(net "SMB_BMC_MM1_SCL")
	)
	(segment
		(start 28.05684 -60.66028)
		(end 28.95854 -59.75858)
		(width 0.10668)
		(layer "In7.Cu")
		(net "SMB_BMC_MM1_SCL")
	)
	(segment
		(start 29.337 -67.635882)
		(end 29.459428 -67.340226)
		(width 0.10668)
		(layer "In7.Cu")
		(net "SMB_BMC_MM1_SCL")
	)
	(segment
		(start 28.95854 -59.33694)
		(end 28.793694 -59.172094)
		(width 0.10668)
		(layer "In7.Cu")
		(net "SMB_BMC_MM1_SCL")
	)
	(segment
		(start 44.183808 -86.745572)
		(end 43.175936 -85.7377)
		(width 0.10668)
		(layer "In7.Cu")
		(net "SMB_BMC_MM1_SCL")
	)
	(segment
		(start 37.15766 -83.29676)
		(end 33.947608 -80.086708)
		(width 0.10668)
		(layer "In7.Cu")
		(net "SMB_BMC_MM1_SCL")
	)
	(segment
		(start 45.80636 -106.182922)
		(end 45.80636 -101.124258)
		(width 0.10668)
		(layer "In7.Cu")
		(net "SMB_BMC_MM1_SCL")
	)
	(segment
		(start 52.916582 -115.062)
		(end 50.427382 -115.062)
		(width 0.10668)
		(layer "In7.Cu")
		(net "SMB_BMC_MM1_SCL")
	)
	(segment
		(start 45.80636 -101.124258)
		(end 45.806614 -101.124004)
		(width 0.10668)
		(layer "In7.Cu")
		(net "SMB_BMC_MM1_SCL")
	)
	(segment
		(start 35.052 -40.457628)
		(end 35.052 -39.116)
		(width 0.10668)
		(layer "In7.Cu")
		(net "SMB_BMC_MM1_SCL")
	)
	(segment
		(start 40.12692 -30.505908)
		(end 40.26535 -30.448504)
		(width 0.10668)
		(layer "In7.Cu")
		(net "SMB_BMC_MM1_SCL")
	)
	(segment
		(start 28.72994 -69.339206)
		(end 29.337 -68.732146)
		(width 0.10668)
		(layer "In7.Cu")
		(net "SMB_BMC_MM1_SCL")
	)
	(segment
		(start 32.3977 -75.899264)
		(end 32.13608 -75.637644)
		(width 0.10668)
		(layer "In7.Cu")
		(net "SMB_BMC_MM1_SCL")
	)
	(segment
		(start 48.40732 -111.697262)
		(end 49.02708 -111.077502)
		(width 0.10668)
		(layer "In7.Cu")
		(net "SMB_BMC_MM1_SCL")
	)
	(segment
		(start 32.13608 -73.758044)
		(end 28.72994 -70.351904)
		(width 0.10668)
		(layer "In7.Cu")
		(net "SMB_BMC_MM1_SCL")
	)
	(segment
		(start 30.475428 -56.68899)
		(end 30.930342 -55.590948)
		(width 0.10668)
		(layer "In7.Cu")
		(net "SMB_BMC_MM1_SCL")
	)
	(segment
		(start 57.111138 -115.729004)
		(end 53.583586 -115.729004)
		(width 0.10668)
		(layer "In7.Cu")
		(net "SMB_BMC_MM1_SCL")
	)
	(segment
		(start 61.881766 -116.663216)
		(end 59.478926 -116.663216)
		(width 0.10668)
		(layer "In7.Cu")
		(net "SMB_BMC_MM1_SCL")
	)
	(segment
		(start 28.95854 -59.75858)
		(end 28.95854 -59.33694)
		(width 0.10668)
		(layer "In7.Cu")
		(net "SMB_BMC_MM1_SCL")
	)
	(segment
		(start 32.85998 -42.164762)
		(end 33.325562 -41.69918)
		(width 0.10668)
		(layer "In7.Cu")
		(net "SMB_BMC_MM1_SCL")
	)
	(segment
		(start 33.325562 -41.69918)
		(end 33.810448 -41.69918)
		(width 0.10668)
		(layer "In7.Cu")
		(net "SMB_BMC_MM1_SCL")
	)
	(segment
		(start 43.175936 -85.7377)
		(end 41.135554 -85.7377)
		(width 0.10668)
		(layer "In7.Cu")
		(net "SMB_BMC_MM1_SCL")
	)
	(segment
		(start 31.457392 -44.219114)
		(end 32.85998 -42.816526)
		(width 0.10668)
		(layer "In7.Cu")
		(net "SMB_BMC_MM1_SCL")
	)
	(segment
		(start 29.75864 -65.497456)
		(end 29.11475 -64.853566)
		(width 0.10668)
		(layer "In7.Cu")
		(net "SMB_BMC_MM1_SCL")
	)
	(segment
		(start 44.79036 -30.26156)
		(end 45.93844 -30.26156)
		(width 0.10668)
		(layer "In7.Cu")
		(net "SMB_BMC_MM1_SCL")
	)
	(segment
		(start 34.70402 -38.76802)
		(end 34.70402 -37.008816)
		(width 0.10668)
		(layer "In7.Cu")
		(net "SMB_BMC_MM1_SCL")
	)
	(segment
		(start 32.85998 -42.816526)
		(end 32.85998 -42.164762)
		(width 0.10668)
		(layer "In7.Cu")
		(net "SMB_BMC_MM1_SCL")
	)
	(segment
		(start 29.75864 -67.041014)
		(end 29.75864 -65.497456)
		(width 0.10668)
		(layer "In7.Cu")
		(net "SMB_BMC_MM1_SCL")
	)
	(segment
		(start 35.052 -39.116)
		(end 34.70402 -38.76802)
		(width 0.10668)
		(layer "In7.Cu")
		(net "SMB_BMC_MM1_SCL")
	)
	(segment
		(start 45.93844 -30.26156)
		(end 46.101 -30.099)
		(width 0.10668)
		(layer "In7.Cu")
		(net "SMB_BMC_MM1_SCL")
	)
	(segment
		(start 45.806614 -100.56876)
		(end 44.183808 -98.945954)
		(width 0.10668)
		(layer "In7.Cu")
		(net "SMB_BMC_MM1_SCL")
	)
	(segment
		(start 29.11475 -64.853566)
		(end 29.11475 -63.751968)
		(width 0.10668)
		(layer "In7.Cu")
		(net "SMB_BMC_MM1_SCL")
	)
	(segment
		(start 34.70402 -37.008816)
		(end 35.848036 -35.8648)
		(width 0.10668)
		(layer "In7.Cu")
		(net "SMB_BMC_MM1_SCL")
	)
	(segment
		(start 48.35398 -107.31246)
		(end 46.935898 -107.31246)
		(width 0.10668)
		(layer "In7.Cu")
		(net "SMB_BMC_MM1_SCL")
	)
	(segment
		(start 32.3977 -77.18044)
		(end 32.3977 -75.899264)
		(width 0.10668)
		(layer "In7.Cu")
		(net "SMB_BMC_MM1_SCL")
	)
	(segment
		(start 35.848036 -35.8648)
		(end 36.576 -35.8648)
		(width 0.10668)
		(layer "In7.Cu")
		(net "SMB_BMC_MM1_SCL")
	)
	(segment
		(start 30.930342 -55.590948)
		(end 32.153352 -54.367938)
		(width 0.10668)
		(layer "In7.Cu")
		(net "SMB_BMC_MM1_SCL")
	)
	(segment
		(start 44.45 -29.9212)
		(end 44.79036 -30.26156)
		(width 0.10668)
		(layer "In7.Cu")
		(net "SMB_BMC_MM1_SCL")
	)
	(segment
		(start 32.13608 -75.637644)
		(end 32.13608 -73.758044)
		(width 0.10668)
		(layer "In7.Cu")
		(net "SMB_BMC_MM1_SCL")
	)
	(segment
		(start 28.793694 -58.370724)
		(end 30.475428 -56.68899)
		(width 0.10668)
		(layer "In7.Cu")
		(net "SMB_BMC_MM1_SCL")
	)
	(segment
		(start 32.502602 -50.375566)
		(end 31.457392 -49.330356)
		(width 0.10668)
		(layer "In7.Cu")
		(net "SMB_BMC_MM1_SCL")
	)
	(segment
		(start 32.153352 -52.084224)
		(end 32.220154 -51.748182)
		(width 0.10668)
		(layer "In7.Cu")
		(net "SMB_BMC_MM1_SCL")
	)
	(segment
		(start 44.183808 -98.945954)
		(end 44.183808 -86.745572)
		(width 0.10668)
		(layer "In7.Cu")
		(net "SMB_BMC_MM1_SCL")
	)
	(segment
		(start 40.26535 -30.448504)
		(end 40.855138 -29.858716)
		(width 0.10668)
		(layer "In7.Cu")
		(net "SMB_BMC_MM1_SCL")
	)
	(segment
		(start 46.935898 -107.31246)
		(end 45.80636 -106.182922)
		(width 0.10668)
		(layer "In7.Cu")
		(net "SMB_BMC_MM1_SCL")
	)
	(segment
		(start 33.947608 -78.730348)
		(end 32.3977 -77.18044)
		(width 0.10668)
		(layer "In7.Cu")
		(net "SMB_BMC_MM1_SCL")
	)
	(segment
		(start 48.40732 -113.041938)
		(end 48.40732 -111.697262)
		(width 0.10668)
		(layer "In7.Cu")
		(net "SMB_BMC_MM1_SCL")
	)
	(segment
		(start 37.5412 -34.8996)
		(end 37.5412 -33.172654)
		(width 0.10668)
		(layer "In7.Cu")
		(net "SMB_BMC_MM1_SCL")
	)
	(segment
		(start 49.02708 -111.077502)
		(end 49.02708 -107.98556)
		(width 0.10668)
		(layer "In7.Cu")
		(net "SMB_BMC_MM1_SCL")
	)
	(segment
		(start 45.806614 -101.124004)
		(end 45.806614 -100.56876)
		(width 0.10668)
		(layer "In7.Cu")
		(net "SMB_BMC_MM1_SCL")
	)
	(segment
		(start 28.05684 -62.694058)
		(end 28.05684 -60.66028)
		(width 0.10668)
		(layer "In7.Cu")
		(net "SMB_BMC_MM1_SCL")
	)
	(segment
		(start 46.101 -29.8958)
		(end 46.228 -29.7688)
		(width 0.10668)
		(layer "In7.Cu")
		(net "SMB_BMC_MM1_SCL")
	)
	(segment
		(start 62.6618 -115.3414)
		(end 62.6618 -115.883182)
		(width 0.10668)
		(layer "In7.Cu")
		(net "SMB_BMC_MM1_SCL")
	)
	(segment
		(start 41.135554 -85.7377)
		(end 38.694614 -83.29676)
		(width 0.10668)
		(layer "In7.Cu")
		(net "SMB_BMC_MM1_SCL")
	)
	(segment
		(start 38.694614 -83.29676)
		(end 37.15766 -83.29676)
		(width 0.10668)
		(layer "In7.Cu")
		(net "SMB_BMC_MM1_SCL")
	)
	(segment
		(start 40.855138 -29.858716)
		(end 40.855138 -29.602938)
		(width 0.10668)
		(layer "In7.Cu")
		(net "SMB_BMC_MM1_SCL")
	)
	(segment
		(start 58.78703 -116.42344)
		(end 57.111138 -115.729004)
		(width 0.10668)
		(layer "In7.Cu")
		(net "SMB_BMC_MM1_SCL")
	)
	(segment
		(start 32.220154 -51.748182)
		(end 32.502602 -51.063398)
		(width 0.10668)
		(layer "In7.Cu")
		(net "SMB_BMC_MM1_SCL")
	)
	(segment
		(start 31.457392 -49.330356)
		(end 31.457392 -44.219114)
		(width 0.10668)
		(layer "In7.Cu")
		(net "SMB_BMC_MM1_SCL")
	)
	(segment
		(start 40.855138 -29.602938)
		(end 41.124378 -29.333698)
		(width 0.10668)
		(layer "In7.Cu")
		(net "SMB_BMC_MM1_SCL")
	)
	(segment
		(start 39.680388 -30.505908)
		(end 40.12692 -30.505908)
		(width 0.10668)
		(layer "In7.Cu")
		(net "SMB_BMC_MM1_SCL")
	)
	(segment
		(start 50.427382 -115.062)
		(end 48.40732 -113.041938)
		(width 0.10668)
		(layer "In7.Cu")
		(net "SMB_BMC_MM1_SCL")
	)
	(segment
		(start 28.72994 -70.351904)
		(end 28.72994 -69.339206)
		(width 0.10668)
		(layer "In7.Cu")
		(net "SMB_BMC_MM1_SCL")
	)
	(segment
		(start 29.337 -68.732146)
		(end 29.337 -67.635882)
		(width 0.10668)
		(layer "In7.Cu")
		(net "SMB_BMC_MM1_SCL")
	)
	(segment
		(start 41.505378 -29.333698)
		(end 42.09288 -29.9212)
		(width 0.10668)
		(layer "In7.Cu")
		(net "SMB_BMC_MM1_SCL")
	)
	(segment
		(start 38.946328 -31.239968)
		(end 39.680388 -30.505908)
		(width 0.10668)
		(layer "In7.Cu")
		(net "SMB_BMC_MM1_SCL")
	)
	(segment
		(start 29.11475 -63.751968)
		(end 28.05684 -62.694058)
		(width 0.10668)
		(layer "In7.Cu")
		(net "SMB_BMC_MM1_SCL")
	)
	(segment
		(start 49.02708 -107.98556)
		(end 48.35398 -107.31246)
		(width 0.10668)
		(layer "In7.Cu")
		(net "SMB_BMC_MM1_SCL")
	)
	(segment
		(start 59.23915 -116.42344)
		(end 58.78703 -116.42344)
		(width 0.10668)
		(layer "In7.Cu")
		(net "SMB_BMC_MM1_SCL")
	)
	(segment
		(start 41.124378 -29.333698)
		(end 41.505378 -29.333698)
		(width 0.10668)
		(layer "In7.Cu")
		(net "SMB_BMC_MM1_SCL")
	)
	(segment
		(start 38.863778 -31.29534)
		(end 38.946328 -31.239968)
		(width 0.10668)
		(layer "In7.Cu")
		(net "SMB_BMC_MM1_SCL")
	)
	(segment
		(start 32.153352 -54.367938)
		(end 32.153352 -52.084224)
		(width 0.10668)
		(layer "In7.Cu")
		(net "SMB_BMC_MM1_SCL")
	)
	(segment
		(start 33.810448 -41.69918)
		(end 35.052 -40.457628)
		(width 0.10668)
		(layer "In7.Cu")
		(net "SMB_BMC_MM1_SCL")
	)
	(segment
		(start 37.5412 -33.172654)
		(end 38.471094 -32.24276)
		(width 0.10668)
		(layer "In7.Cu")
		(net "SMB_BMC_MM1_SCL")
	)
	(segment
		(start 46.101 -30.099)
		(end 46.101 -29.8958)
		(width 0.10668)
		(layer "In7.Cu")
		(net "SMB_BMC_MM1_SCL")
	)
	(segment
		(start 48.817276 -35.588448)
		(end 48.768 -35.539172)
		(width 0.11684)
		(layer "F.Cu")
		(net "SMB_BMC_MM1_R_SDA")
	)
	(segment
		(start 48.768 -35.539172)
		(end 48.768 -35.04565)
		(width 0.11684)
		(layer "F.Cu")
		(net "SMB_BMC_MM1_R_SDA")
	)
	(segment
		(start 48.817276 -37.55644)
		(end 49.6951 -38.434264)
		(width 0.11684)
		(layer "F.Cu")
		(net "SMB_BMC_MM1_R_SDA")
	)
	(segment
		(start 48.817276 -36.248848)
		(end 48.817276 -35.588448)
		(width 0.11684)
		(layer "F.Cu")
		(net "SMB_BMC_MM1_R_SDA")
	)
	(segment
		(start 49.6951 -38.434264)
		(end 49.6951 -39.37127)
		(width 0.11684)
		(layer "F.Cu")
		(net "SMB_BMC_MM1_R_SDA")
	)
	(segment
		(start 48.817276 -36.248848)
		(end 48.817276 -37.55644)
		(width 0.11684)
		(layer "F.Cu")
		(net "SMB_BMC_MM1_R_SDA")
	)
	(via
		(at 48.817276 -36.248848)
		(size 0.762)
		(drill 0.381)
		(layers "F.Cu" "B.Cu")
		(net "SMB_BMC_MM1_R_SDA")
	)
	(segment
		(start 47.4472 -36.2712)
		(end 47.4472 -36.8046)
		(width 0.11684)
		(layer "F.Cu")
		(net "SMB_BMC_MM1_R_SCL")
	)
	(segment
		(start 49.290986 -38.648386)
		(end 49.290986 -39.767256)
		(width 0.11684)
		(layer "F.Cu")
		(net "SMB_BMC_MM1_R_SCL")
	)
	(segment
		(start 49.290986 -39.767256)
		(end 49.6951 -40.17137)
		(width 0.11684)
		(layer "F.Cu")
		(net "SMB_BMC_MM1_R_SCL")
	)
	(segment
		(start 47.4472 -36.8046)
		(end 49.290986 -38.648386)
		(width 0.11684)
		(layer "F.Cu")
		(net "SMB_BMC_MM1_R_SCL")
	)
	(segment
		(start 47.4472 -35.35045)
		(end 47.4472 -36.2712)
		(width 0.11684)
		(layer "F.Cu")
		(net "SMB_BMC_MM1_R_SCL")
	)
	(segment
		(start 47.752 -35.04565)
		(end 47.4472 -35.35045)
		(width 0.11684)
		(layer "F.Cu")
		(net "SMB_BMC_MM1_R_SCL")
	)
	(via
		(at 47.4472 -36.2712)
		(size 0.762)
		(drill 0.381)
		(layers "F.Cu" "B.Cu")
		(net "SMB_BMC_MM1_R_SCL")
	)
	(segment
		(start 46.494954 -46.571154)
		(end 46.09973 -46.17593)
		(width 0.11684)
		(layer "F.Cu")
		(net "SMB_BMC_MM12_R_SDA")
	)
	(via
		(at 43.546522 -46.623478)
		(size 0.6604)
		(drill 0.3302)
		(layers "F.Cu" "B.Cu")
		(net "SMB_BMC_MM12_R_SDA")
	)
	(via
		(at 46.09973 -46.17593)
		(size 0.4572)
		(drill 0.254)
		(layers "F.Cu" "B.Cu")
		(net "SMB_BMC_MM12_R_SDA")
	)
	(segment
		(start 43.060112 -46.514766)
		(end 42.399458 -46.2407)
		(width 0.11684)
		(layer "B.Cu")
		(net "SMB_BMC_MM12_R_SDA")
	)
	(segment
		(start 42.399458 -46.2407)
		(end 42.366184 -46.16069)
		(width 0.11684)
		(layer "B.Cu")
		(net "SMB_BMC_MM12_R_SDA")
	)
	(segment
		(start 44.654216 -46.17593)
		(end 46.09973 -46.17593)
		(width 0.11684)
		(layer "B.Cu")
		(net "SMB_BMC_MM12_R_SDA")
	)
	(segment
		(start 43.546522 -46.623478)
		(end 43.532806 -46.609508)
		(width 0.11684)
		(layer "B.Cu")
		(net "SMB_BMC_MM12_R_SDA")
	)
	(segment
		(start 44.206668 -46.623478)
		(end 44.654216 -46.17593)
		(width 0.11684)
		(layer "B.Cu")
		(net "SMB_BMC_MM12_R_SDA")
	)
	(segment
		(start 43.532806 -46.609508)
		(end 43.060112 -46.514766)
		(width 0.11684)
		(layer "B.Cu")
		(net "SMB_BMC_MM12_R_SDA")
	)
	(segment
		(start 43.546522 -46.623478)
		(end 44.206668 -46.623478)
		(width 0.11684)
		(layer "B.Cu")
		(net "SMB_BMC_MM12_R_SDA")
	)
	(segment
		(start 41.523666 -47.737522)
		(end 40.491156 -47.737522)
		(width 0.11684)
		(layer "F.Cu")
		(net "SMB_BMC_MM12_R_SCL")
	)
	(segment
		(start 44.483528 -47.371254)
		(end 44.895008 -47.371254)
		(width 0.11684)
		(layer "F.Cu")
		(net "SMB_BMC_MM12_R_SCL")
	)
	(segment
		(start 40.491156 -47.737522)
		(end 40.34155 -47.587916)
		(width 0.11684)
		(layer "F.Cu")
		(net "SMB_BMC_MM12_R_SCL")
	)
	(segment
		(start 42.167302 -47.093886)
		(end 44.20616 -47.093886)
		(width 0.11684)
		(layer "F.Cu")
		(net "SMB_BMC_MM12_R_SCL")
	)
	(segment
		(start 41.879266 -47.381922)
		(end 42.167302 -47.093886)
		(width 0.11684)
		(layer "F.Cu")
		(net "SMB_BMC_MM12_R_SCL")
	)
	(segment
		(start 41.879266 -47.381922)
		(end 41.523666 -47.737522)
		(width 0.11684)
		(layer "F.Cu")
		(net "SMB_BMC_MM12_R_SCL")
	)
	(segment
		(start 44.20616 -47.093886)
		(end 44.483528 -47.371254)
		(width 0.11684)
		(layer "F.Cu")
		(net "SMB_BMC_MM12_R_SCL")
	)
	(via
		(at 41.879266 -47.381922)
		(size 0.762)
		(drill 0.381)
		(layers "F.Cu" "B.Cu")
		(net "SMB_BMC_MM12_R_SCL")
	)
	(segment
		(start 57.222136 -33.602676)
		(end 57.222136 -34.237676)
		(width 0.11684)
		(layer "F.Cu")
		(net "SMB_BMC_MM10_SDA")
	)
	(segment
		(start 56.66994 -32.590994)
		(end 56.66994 -33.05048)
		(width 0.11684)
		(layer "F.Cu")
		(net "SMB_BMC_MM10_SDA")
	)
	(segment
		(start 54.473856 -31.267654)
		(end 55.489602 -32.2834)
		(width 0.11684)
		(layer "F.Cu")
		(net "SMB_BMC_MM10_SDA")
	)
	(segment
		(start 56.66994 -33.05048)
		(end 57.222136 -33.602676)
		(width 0.11684)
		(layer "F.Cu")
		(net "SMB_BMC_MM10_SDA")
	)
	(segment
		(start 56.362346 -32.2834)
		(end 56.66994 -32.590994)
		(width 0.11684)
		(layer "F.Cu")
		(net "SMB_BMC_MM10_SDA")
	)
	(segment
		(start 55.489602 -32.2834)
		(end 56.362346 -32.2834)
		(width 0.11684)
		(layer "F.Cu")
		(net "SMB_BMC_MM10_SDA")
	)
	(via
		(at 42.037 -110.0074)
		(size 0.508)
		(drill 0.254)
		(layers "F.Cu" "B.Cu")
		(net "SMB_BMC_MM10_SDA")
	)
	(via
		(at 57.222136 -33.602676)
		(size 0.508)
		(drill 0.254)
		(layers "F.Cu" "B.Cu")
		(net "SMB_BMC_MM10_SDA")
	)
	(segment
		(start 41.3004 -114.821462)
		(end 41.3004 -116.5606)
		(width 0.11684)
		(layer "B.Cu")
		(net "SMB_BMC_MM10_SDA")
	)
	(segment
		(start 41.3004 -116.5606)
		(end 41.455086 -116.715286)
		(width 0.11684)
		(layer "B.Cu")
		(net "SMB_BMC_MM10_SDA")
	)
	(segment
		(start 42.037 -113.042954)
		(end 41.3004 -114.821462)
		(width 0.11684)
		(layer "B.Cu")
		(net "SMB_BMC_MM10_SDA")
	)
	(segment
		(start 42.037 -110.0074)
		(end 42.037 -113.042954)
		(width 0.11684)
		(layer "B.Cu")
		(net "SMB_BMC_MM10_SDA")
	)
	(segment
		(start 41.455086 -116.715286)
		(end 41.455086 -118.460012)
		(width 0.11684)
		(layer "B.Cu")
		(net "SMB_BMC_MM10_SDA")
	)
	(segment
		(start 29.8704 -39.88562)
		(end 31.9532 -37.80282)
		(width 0.10668)
		(layer "In7.Cu")
		(net "SMB_BMC_MM10_SDA")
	)
	(segment
		(start 27.517344 -72.456294)
		(end 26.847546 -72.456294)
		(width 0.10668)
		(layer "In7.Cu")
		(net "SMB_BMC_MM10_SDA")
	)
	(segment
		(start 25.781 -61.595)
		(end 25.58542 -61.39942)
		(width 0.10668)
		(layer "In7.Cu")
		(net "SMB_BMC_MM10_SDA")
	)
	(segment
		(start 44.80052 -109.36478)
		(end 44.80052 -100.98532)
		(width 0.10668)
		(layer "In7.Cu")
		(net "SMB_BMC_MM10_SDA")
	)
	(segment
		(start 42.037 -110.0074)
		(end 44.1579 -110.0074)
		(width 0.10668)
		(layer "In7.Cu")
		(net "SMB_BMC_MM10_SDA")
	)
	(segment
		(start 28.847796 -72.953626)
		(end 28.014676 -72.953626)
		(width 0.10668)
		(layer "In7.Cu")
		(net "SMB_BMC_MM10_SDA")
	)
	(segment
		(start 23.17242 -46.204632)
		(end 23.764494 -44.775374)
		(width 0.10668)
		(layer "In7.Cu")
		(net "SMB_BMC_MM10_SDA")
	)
	(segment
		(start 39.702232 -89.31656)
		(end 36.88715 -86.501478)
		(width 0.10668)
		(layer "In7.Cu")
		(net "SMB_BMC_MM10_SDA")
	)
	(segment
		(start 26.011378 -71.220584)
		(end 25.5524 -70.761606)
		(width 0.10668)
		(layer "In7.Cu")
		(net "SMB_BMC_MM10_SDA")
	)
	(segment
		(start 31.9532 -37.80282)
		(end 31.9532 -32.98571)
		(width 0.10668)
		(layer "In7.Cu")
		(net "SMB_BMC_MM10_SDA")
	)
	(segment
		(start 47.975774 -27.64028)
		(end 49.53 -29.194506)
		(width 0.10668)
		(layer "In7.Cu")
		(net "SMB_BMC_MM10_SDA")
	)
	(segment
		(start 51.2826 -33.8582)
		(end 51.909726 -34.485326)
		(width 0.10668)
		(layer "In7.Cu")
		(net "SMB_BMC_MM10_SDA")
	)
	(segment
		(start 27.036268 -41.5036)
		(end 29.0322 -41.5036)
		(width 0.10668)
		(layer "In7.Cu")
		(net "SMB_BMC_MM10_SDA")
	)
	(segment
		(start 36.88715 -86.501478)
		(end 36.283138 -86.501478)
		(width 0.10668)
		(layer "In7.Cu")
		(net "SMB_BMC_MM10_SDA")
	)
	(segment
		(start 35.56508 -83.739228)
		(end 32.606488 -80.780636)
		(width 0.10668)
		(layer "In7.Cu")
		(net "SMB_BMC_MM10_SDA")
	)
	(segment
		(start 26.295096 -71.903844)
		(end 26.238962 -71.767954)
		(width 0.10668)
		(layer "In7.Cu")
		(net "SMB_BMC_MM10_SDA")
	)
	(segment
		(start 23.17242 -52.39258)
		(end 23.17242 -46.204632)
		(width 0.10668)
		(layer "In7.Cu")
		(net "SMB_BMC_MM10_SDA")
	)
	(segment
		(start 41.847262 -27.64028)
		(end 47.975774 -27.64028)
		(width 0.10668)
		(layer "In7.Cu")
		(net "SMB_BMC_MM10_SDA")
	)
	(segment
		(start 32.606488 -79.454248)
		(end 30.43936 -77.28712)
		(width 0.10668)
		(layer "In7.Cu")
		(net "SMB_BMC_MM10_SDA")
	)
	(segment
		(start 34.985706 -28.252166)
		(end 35.43046 -27.807412)
		(width 0.10668)
		(layer "In7.Cu")
		(net "SMB_BMC_MM10_SDA")
	)
	(segment
		(start 51.909726 -34.485326)
		(end 56.339486 -34.485326)
		(width 0.10668)
		(layer "In7.Cu")
		(net "SMB_BMC_MM10_SDA")
	)
	(segment
		(start 29.0322 -41.5036)
		(end 29.8704 -40.6654)
		(width 0.10668)
		(layer "In7.Cu")
		(net "SMB_BMC_MM10_SDA")
	)
	(segment
		(start 29.8704 -40.6654)
		(end 29.8704 -39.88562)
		(width 0.10668)
		(layer "In7.Cu")
		(net "SMB_BMC_MM10_SDA")
	)
	(segment
		(start 25.78608 -63.586614)
		(end 25.78608 -61.887862)
		(width 0.10668)
		(layer "In7.Cu")
		(net "SMB_BMC_MM10_SDA")
	)
	(segment
		(start 33.94964 -30.98927)
		(end 33.94964 -30.155896)
		(width 0.10668)
		(layer "In7.Cu")
		(net "SMB_BMC_MM10_SDA")
	)
	(segment
		(start 26.238962 -71.767954)
		(end 26.011378 -71.220584)
		(width 0.10668)
		(layer "In7.Cu")
		(net "SMB_BMC_MM10_SDA")
	)
	(segment
		(start 29.3751 -73.48093)
		(end 28.847796 -72.953626)
		(width 0.10668)
		(layer "In7.Cu")
		(net "SMB_BMC_MM10_SDA")
	)
	(segment
		(start 42.85488 -99.03968)
		(end 42.85488 -91.08948)
		(width 0.10668)
		(layer "In7.Cu")
		(net "SMB_BMC_MM10_SDA")
	)
	(segment
		(start 25.5524 -70.761606)
		(end 25.5524 -63.820294)
		(width 0.10668)
		(layer "In7.Cu")
		(net "SMB_BMC_MM10_SDA")
	)
	(segment
		(start 28.014676 -72.953626)
		(end 27.517344 -72.456294)
		(width 0.10668)
		(layer "In7.Cu")
		(net "SMB_BMC_MM10_SDA")
	)
	(segment
		(start 25.78608 -61.887862)
		(end 25.781 -61.882782)
		(width 0.10668)
		(layer "In7.Cu")
		(net "SMB_BMC_MM10_SDA")
	)
	(segment
		(start 35.43046 -27.807412)
		(end 36.294822 -27.807412)
		(width 0.10668)
		(layer "In7.Cu")
		(net "SMB_BMC_MM10_SDA")
	)
	(segment
		(start 33.94964 -30.155896)
		(end 34.985706 -29.11983)
		(width 0.10668)
		(layer "In7.Cu")
		(net "SMB_BMC_MM10_SDA")
	)
	(segment
		(start 30.43936 -77.28712)
		(end 30.43936 -77.020928)
		(width 0.10668)
		(layer "In7.Cu")
		(net "SMB_BMC_MM10_SDA")
	)
	(segment
		(start 23.764494 -44.775374)
		(end 27.036268 -41.5036)
		(width 0.10668)
		(layer "In7.Cu")
		(net "SMB_BMC_MM10_SDA")
	)
	(segment
		(start 32.606488 -80.780636)
		(end 32.606488 -79.454248)
		(width 0.10668)
		(layer "In7.Cu")
		(net "SMB_BMC_MM10_SDA")
	)
	(segment
		(start 29.3751 -75.956668)
		(end 29.3751 -73.48093)
		(width 0.10668)
		(layer "In7.Cu")
		(net "SMB_BMC_MM10_SDA")
	)
	(segment
		(start 35.56508 -85.78342)
		(end 35.56508 -83.739228)
		(width 0.10668)
		(layer "In7.Cu")
		(net "SMB_BMC_MM10_SDA")
	)
	(segment
		(start 37.655754 -26.44648)
		(end 40.653462 -26.44648)
		(width 0.10668)
		(layer "In7.Cu")
		(net "SMB_BMC_MM10_SDA")
	)
	(segment
		(start 51.2826 -32.511746)
		(end 51.2826 -33.8582)
		(width 0.10668)
		(layer "In7.Cu")
		(net "SMB_BMC_MM10_SDA")
	)
	(segment
		(start 31.9532 -32.98571)
		(end 33.94964 -30.98927)
		(width 0.10668)
		(layer "In7.Cu")
		(net "SMB_BMC_MM10_SDA")
	)
	(segment
		(start 56.339486 -34.485326)
		(end 57.222136 -33.602676)
		(width 0.10668)
		(layer "In7.Cu")
		(net "SMB_BMC_MM10_SDA")
	)
	(segment
		(start 30.43936 -77.020928)
		(end 29.3751 -75.956668)
		(width 0.10668)
		(layer "In7.Cu")
		(net "SMB_BMC_MM10_SDA")
	)
	(segment
		(start 25.781 -61.882782)
		(end 25.781 -61.595)
		(width 0.10668)
		(layer "In7.Cu")
		(net "SMB_BMC_MM10_SDA")
	)
	(segment
		(start 44.1579 -110.0074)
		(end 44.80052 -109.36478)
		(width 0.10668)
		(layer "In7.Cu")
		(net "SMB_BMC_MM10_SDA")
	)
	(segment
		(start 25.58542 -59.28233)
		(end 23.65756 -57.35447)
		(width 0.10668)
		(layer "In7.Cu")
		(net "SMB_BMC_MM10_SDA")
	)
	(segment
		(start 25.5524 -63.820294)
		(end 25.78608 -63.586614)
		(width 0.10668)
		(layer "In7.Cu")
		(net "SMB_BMC_MM10_SDA")
	)
	(segment
		(start 23.65756 -56.37276)
		(end 22.56028 -55.27548)
		(width 0.10668)
		(layer "In7.Cu")
		(net "SMB_BMC_MM10_SDA")
	)
	(segment
		(start 25.58542 -61.39942)
		(end 25.58542 -59.28233)
		(width 0.10668)
		(layer "In7.Cu")
		(net "SMB_BMC_MM10_SDA")
	)
	(segment
		(start 23.65756 -57.35447)
		(end 23.65756 -56.37276)
		(width 0.10668)
		(layer "In7.Cu")
		(net "SMB_BMC_MM10_SDA")
	)
	(segment
		(start 42.85488 -91.08948)
		(end 41.08196 -89.31656)
		(width 0.10668)
		(layer "In7.Cu")
		(net "SMB_BMC_MM10_SDA")
	)
	(segment
		(start 49.53 -30.759146)
		(end 51.2826 -32.511746)
		(width 0.10668)
		(layer "In7.Cu")
		(net "SMB_BMC_MM10_SDA")
	)
	(segment
		(start 36.283138 -86.501478)
		(end 35.56508 -85.78342)
		(width 0.10668)
		(layer "In7.Cu")
		(net "SMB_BMC_MM10_SDA")
	)
	(segment
		(start 22.56028 -53.00472)
		(end 23.17242 -52.39258)
		(width 0.10668)
		(layer "In7.Cu")
		(net "SMB_BMC_MM10_SDA")
	)
	(segment
		(start 36.294822 -27.807412)
		(end 37.655754 -26.44648)
		(width 0.10668)
		(layer "In7.Cu")
		(net "SMB_BMC_MM10_SDA")
	)
	(segment
		(start 49.53 -29.194506)
		(end 49.53 -30.759146)
		(width 0.10668)
		(layer "In7.Cu")
		(net "SMB_BMC_MM10_SDA")
	)
	(segment
		(start 34.985706 -29.11983)
		(end 34.985706 -28.252166)
		(width 0.10668)
		(layer "In7.Cu")
		(net "SMB_BMC_MM10_SDA")
	)
	(segment
		(start 26.847546 -72.456294)
		(end 26.295096 -71.903844)
		(width 0.10668)
		(layer "In7.Cu")
		(net "SMB_BMC_MM10_SDA")
	)
	(segment
		(start 40.653462 -26.44648)
		(end 41.847262 -27.64028)
		(width 0.10668)
		(layer "In7.Cu")
		(net "SMB_BMC_MM10_SDA")
	)
	(segment
		(start 41.08196 -89.31656)
		(end 39.702232 -89.31656)
		(width 0.10668)
		(layer "In7.Cu")
		(net "SMB_BMC_MM10_SDA")
	)
	(segment
		(start 44.80052 -100.98532)
		(end 42.85488 -99.03968)
		(width 0.10668)
		(layer "In7.Cu")
		(net "SMB_BMC_MM10_SDA")
	)
	(segment
		(start 22.56028 -55.27548)
		(end 22.56028 -53.00472)
		(width 0.10668)
		(layer "In7.Cu")
		(net "SMB_BMC_MM10_SDA")
	)
	(via
		(at 55.184548 -32.840676)
		(size 0.762)
		(drill 0.254)
		(layers "F.Cu" "B.Cu")
		(net "SMB_BMC_MM10_SCL")
	)
	(via
		(at 42.420032 -109.402372)
		(size 0.508)
		(drill 0.254)
		(layers "F.Cu" "B.Cu")
		(net "SMB_BMC_MM10_SCL")
	)
	(segment
		(start 42.66692 -112.579912)
		(end 41.7576 -114.775488)
		(width 0.11684)
		(layer "B.Cu")
		(net "SMB_BMC_MM10_SCL")
	)
	(segment
		(start 55.676292 -33.839658)
		(end 55.499 -34.01695)
		(width 0.11684)
		(layer "B.Cu")
		(net "SMB_BMC_MM10_SCL")
	)
	(segment
		(start 41.7576 -116.349526)
		(end 42.055034 -116.64696)
		(width 0.11684)
		(layer "B.Cu")
		(net "SMB_BMC_MM10_SCL")
	)
	(segment
		(start 42.66692 -109.64926)
		(end 42.66692 -112.579912)
		(width 0.11684)
		(layer "B.Cu")
		(net "SMB_BMC_MM10_SCL")
	)
	(segment
		(start 55.499 -34.01695)
		(end 55.499 -34.27095)
		(width 0.11684)
		(layer "B.Cu")
		(net "SMB_BMC_MM10_SCL")
	)
	(segment
		(start 41.7576 -114.775488)
		(end 41.7576 -116.349526)
		(width 0.11684)
		(layer "B.Cu")
		(net "SMB_BMC_MM10_SCL")
	)
	(segment
		(start 54.684676 -31.267654)
		(end 54.684676 -32.340804)
		(width 0.11684)
		(layer "B.Cu")
		(net "SMB_BMC_MM10_SCL")
	)
	(segment
		(start 42.420032 -109.402372)
		(end 42.66692 -109.64926)
		(width 0.11684)
		(layer "B.Cu")
		(net "SMB_BMC_MM10_SCL")
	)
	(segment
		(start 55.184548 -32.840676)
		(end 55.676292 -33.33242)
		(width 0.11684)
		(layer "B.Cu")
		(net "SMB_BMC_MM10_SCL")
	)
	(segment
		(start 54.684676 -32.340804)
		(end 55.184548 -32.840676)
		(width 0.11684)
		(layer "B.Cu")
		(net "SMB_BMC_MM10_SCL")
	)
	(segment
		(start 55.676292 -33.33242)
		(end 55.676292 -33.839658)
		(width 0.11684)
		(layer "B.Cu")
		(net "SMB_BMC_MM10_SCL")
	)
	(segment
		(start 42.055034 -116.64696)
		(end 42.055034 -118.25986)
		(width 0.11684)
		(layer "B.Cu")
		(net "SMB_BMC_MM10_SCL")
	)
	(segment
		(start 23.480268 -44.585128)
		(end 22.83714 -46.13783)
		(width 0.10668)
		(layer "In7.Cu")
		(net "SMB_BMC_MM10_SCL")
	)
	(segment
		(start 50.673 -31.242)
		(end 49.911 -30.48)
		(width 0.10668)
		(layer "In7.Cu")
		(net "SMB_BMC_MM10_SCL")
	)
	(segment
		(start 52.07 -31.242)
		(end 50.673 -31.242)
		(width 0.10668)
		(layer "In7.Cu")
		(net "SMB_BMC_MM10_SCL")
	)
	(segment
		(start 44.41444 -101.08184)
		(end 44.41444 -109.20476)
		(width 0.10668)
		(layer "In7.Cu")
		(net "SMB_BMC_MM10_SCL")
	)
	(segment
		(start 49.911 -30.48)
		(end 49.911 -29.083)
		(width 0.10668)
		(layer "In7.Cu")
		(net "SMB_BMC_MM10_SCL")
	)
	(segment
		(start 28.702254 -73.293478)
		(end 29.03982 -73.631044)
		(width 0.10668)
		(layer "In7.Cu")
		(net "SMB_BMC_MM10_SCL")
	)
	(segment
		(start 44.41444 -109.20476)
		(end 44.02328 -109.59592)
		(width 0.10668)
		(layer "In7.Cu")
		(net "SMB_BMC_MM10_SCL")
	)
	(segment
		(start 42.5196 -99.187)
		(end 44.41444 -101.08184)
		(width 0.10668)
		(layer "In7.Cu")
		(net "SMB_BMC_MM10_SCL")
	)
	(segment
		(start 54.155594 -34.1376)
		(end 52.7304 -34.1376)
		(width 0.10668)
		(layer "In7.Cu")
		(net "SMB_BMC_MM10_SCL")
	)
	(segment
		(start 55.184548 -32.840676)
		(end 54.616858 -33.408366)
		(width 0.10668)
		(layer "In7.Cu")
		(net "SMB_BMC_MM10_SCL")
	)
	(segment
		(start 25.1714 -70.854824)
		(end 25.727152 -71.410576)
		(width 0.10668)
		(layer "In7.Cu")
		(net "SMB_BMC_MM10_SCL")
	)
	(segment
		(start 33.087056 -30.542738)
		(end 32.77108 -30.542738)
		(width 0.10668)
		(layer "In7.Cu")
		(net "SMB_BMC_MM10_SCL")
	)
	(segment
		(start 42.61358 -109.59592)
		(end 42.420032 -109.402372)
		(width 0.10668)
		(layer "In7.Cu")
		(net "SMB_BMC_MM10_SCL")
	)
	(segment
		(start 35.291268 -27.472132)
		(end 34.650426 -28.112974)
		(width 0.10668)
		(layer "In7.Cu")
		(net "SMB_BMC_MM10_SCL")
	)
	(segment
		(start 24.3459 -58.720482)
		(end 24.3459 -60.9219)
		(width 0.10668)
		(layer "In7.Cu")
		(net "SMB_BMC_MM10_SCL")
	)
	(segment
		(start 22.225 -52.815236)
		(end 22.225 -56.599582)
		(width 0.10668)
		(layer "In7.Cu")
		(net "SMB_BMC_MM10_SCL")
	)
	(segment
		(start 30.80512 -79.878174)
		(end 35.2298 -84.302854)
		(width 0.10668)
		(layer "In7.Cu")
		(net "SMB_BMC_MM10_SCL")
	)
	(segment
		(start 42.5196 -92.608146)
		(end 42.5196 -99.187)
		(width 0.10668)
		(layer "In7.Cu")
		(net "SMB_BMC_MM10_SCL")
	)
	(segment
		(start 29.7434 -39.4716)
		(end 28.593796 -39.4716)
		(width 0.10668)
		(layer "In7.Cu")
		(net "SMB_BMC_MM10_SCL")
	)
	(segment
		(start 25.4508 -63.447676)
		(end 25.1714 -63.727076)
		(width 0.10668)
		(layer "In7.Cu")
		(net "SMB_BMC_MM10_SCL")
	)
	(segment
		(start 42.037 -27.305)
		(end 40.7416 -26.0096)
		(width 0.10668)
		(layer "In7.Cu")
		(net "SMB_BMC_MM10_SCL")
	)
	(segment
		(start 34.650426 -28.112974)
		(end 34.650426 -28.979368)
		(width 0.10668)
		(layer "In7.Cu")
		(net "SMB_BMC_MM10_SCL")
	)
	(segment
		(start 28.593796 -39.4716)
		(end 23.480268 -44.585128)
		(width 0.10668)
		(layer "In7.Cu")
		(net "SMB_BMC_MM10_SCL")
	)
	(segment
		(start 32.389572 -30.924246)
		(end 32.389572 -32.074866)
		(width 0.10668)
		(layer "In7.Cu")
		(net "SMB_BMC_MM10_SCL")
	)
	(segment
		(start 52.4002 -31.5722)
		(end 52.07 -31.242)
		(width 0.10668)
		(layer "In7.Cu")
		(net "SMB_BMC_MM10_SCL")
	)
	(segment
		(start 22.83714 -46.13783)
		(end 22.83714 -52.203096)
		(width 0.10668)
		(layer "In7.Cu")
		(net "SMB_BMC_MM10_SCL")
	)
	(segment
		(start 44.02328 -109.59592)
		(end 42.61358 -109.59592)
		(width 0.10668)
		(layer "In7.Cu")
		(net "SMB_BMC_MM10_SCL")
	)
	(segment
		(start 35.2298 -84.302854)
		(end 35.2298 -86.067138)
		(width 0.10668)
		(layer "In7.Cu")
		(net "SMB_BMC_MM10_SCL")
	)
	(segment
		(start 35.99942 -86.836758)
		(end 36.748212 -86.836758)
		(width 0.10668)
		(layer "In7.Cu")
		(net "SMB_BMC_MM10_SCL")
	)
	(segment
		(start 52.7304 -34.1376)
		(end 52.4002 -33.8074)
		(width 0.10668)
		(layer "In7.Cu")
		(net "SMB_BMC_MM10_SCL")
	)
	(segment
		(start 30.10408 -77.159866)
		(end 30.10408 -78.008226)
		(width 0.10668)
		(layer "In7.Cu")
		(net "SMB_BMC_MM10_SCL")
	)
	(segment
		(start 49.911 -29.083)
		(end 48.133 -27.305)
		(width 0.10668)
		(layer "In7.Cu")
		(net "SMB_BMC_MM10_SCL")
	)
	(segment
		(start 54.616858 -33.676336)
		(end 54.155594 -34.1376)
		(width 0.10668)
		(layer "In7.Cu")
		(net "SMB_BMC_MM10_SCL")
	)
	(segment
		(start 36.748212 -86.836758)
		(end 42.5196 -92.608146)
		(width 0.10668)
		(layer "In7.Cu")
		(net "SMB_BMC_MM10_SCL")
	)
	(segment
		(start 25.1714 -63.727076)
		(end 25.1714 -70.854824)
		(width 0.10668)
		(layer "In7.Cu")
		(net "SMB_BMC_MM10_SCL")
	)
	(segment
		(start 40.7416 -26.0096)
		(end 37.618416 -26.0096)
		(width 0.10668)
		(layer "In7.Cu")
		(net "SMB_BMC_MM10_SCL")
	)
	(segment
		(start 31.5722 -37.6428)
		(end 29.7434 -39.4716)
		(width 0.10668)
		(layer "In7.Cu")
		(net "SMB_BMC_MM10_SCL")
	)
	(segment
		(start 25.929082 -71.896732)
		(end 26.01087 -72.093836)
		(width 0.10668)
		(layer "In7.Cu")
		(net "SMB_BMC_MM10_SCL")
	)
	(segment
		(start 24.3459 -60.9219)
		(end 25.4508 -62.0268)
		(width 0.10668)
		(layer "In7.Cu")
		(net "SMB_BMC_MM10_SCL")
	)
	(segment
		(start 32.389572 -32.074866)
		(end 31.5722 -32.892238)
		(width 0.10668)
		(layer "In7.Cu")
		(net "SMB_BMC_MM10_SCL")
	)
	(segment
		(start 25.727152 -71.410576)
		(end 25.929082 -71.896732)
		(width 0.10668)
		(layer "In7.Cu")
		(net "SMB_BMC_MM10_SCL")
	)
	(segment
		(start 48.133 -27.305)
		(end 42.037 -27.305)
		(width 0.10668)
		(layer "In7.Cu")
		(net "SMB_BMC_MM10_SCL")
	)
	(segment
		(start 25.4508 -62.0268)
		(end 25.4508 -63.447676)
		(width 0.10668)
		(layer "In7.Cu")
		(net "SMB_BMC_MM10_SCL")
	)
	(segment
		(start 22.83714 -52.203096)
		(end 22.225 -52.815236)
		(width 0.10668)
		(layer "In7.Cu")
		(net "SMB_BMC_MM10_SCL")
	)
	(segment
		(start 34.650426 -28.979368)
		(end 33.087056 -30.542738)
		(width 0.10668)
		(layer "In7.Cu")
		(net "SMB_BMC_MM10_SCL")
	)
	(segment
		(start 29.03982 -76.095606)
		(end 30.10408 -77.159866)
		(width 0.10668)
		(layer "In7.Cu")
		(net "SMB_BMC_MM10_SCL")
	)
	(segment
		(start 31.5722 -32.892238)
		(end 31.5722 -37.6428)
		(width 0.10668)
		(layer "In7.Cu")
		(net "SMB_BMC_MM10_SCL")
	)
	(segment
		(start 32.77108 -30.542738)
		(end 32.389572 -30.924246)
		(width 0.10668)
		(layer "In7.Cu")
		(net "SMB_BMC_MM10_SCL")
	)
	(segment
		(start 36.155884 -27.472132)
		(end 35.291268 -27.472132)
		(width 0.10668)
		(layer "In7.Cu")
		(net "SMB_BMC_MM10_SCL")
	)
	(segment
		(start 52.4002 -33.8074)
		(end 52.4002 -31.5722)
		(width 0.10668)
		(layer "In7.Cu")
		(net "SMB_BMC_MM10_SCL")
	)
	(segment
		(start 26.01087 -72.093836)
		(end 27.210512 -73.293478)
		(width 0.10668)
		(layer "In7.Cu")
		(net "SMB_BMC_MM10_SCL")
	)
	(segment
		(start 54.616858 -33.408366)
		(end 54.616858 -33.676336)
		(width 0.10668)
		(layer "In7.Cu")
		(net "SMB_BMC_MM10_SCL")
	)
	(segment
		(start 22.225 -56.599582)
		(end 24.3459 -58.720482)
		(width 0.10668)
		(layer "In7.Cu")
		(net "SMB_BMC_MM10_SCL")
	)
	(segment
		(start 27.210512 -73.293478)
		(end 28.702254 -73.293478)
		(width 0.10668)
		(layer "In7.Cu")
		(net "SMB_BMC_MM10_SCL")
	)
	(segment
		(start 35.2298 -86.067138)
		(end 35.99942 -86.836758)
		(width 0.10668)
		(layer "In7.Cu")
		(net "SMB_BMC_MM10_SCL")
	)
	(segment
		(start 30.10408 -78.008226)
		(end 30.80512 -78.709266)
		(width 0.10668)
		(layer "In7.Cu")
		(net "SMB_BMC_MM10_SCL")
	)
	(segment
		(start 29.03982 -73.631044)
		(end 29.03982 -76.095606)
		(width 0.10668)
		(layer "In7.Cu")
		(net "SMB_BMC_MM10_SCL")
	)
	(segment
		(start 37.618416 -26.0096)
		(end 36.155884 -27.472132)
		(width 0.10668)
		(layer "In7.Cu")
		(net "SMB_BMC_MM10_SCL")
	)
	(segment
		(start 30.80512 -78.709266)
		(end 30.80512 -79.878174)
		(width 0.10668)
		(layer "In7.Cu")
		(net "SMB_BMC_MM10_SCL")
	)
	(segment
		(start 57.095136 -37.138864)
		(end 57.095136 -36.2204)
		(width 0.11684)
		(layer "F.Cu")
		(net "SMB_BMC_MM10_R_SDA")
	)
	(segment
		(start 57.095136 -35.164776)
		(end 57.222136 -35.037776)
		(width 0.11684)
		(layer "F.Cu")
		(net "SMB_BMC_MM10_R_SDA")
	)
	(segment
		(start 57.095136 -36.2204)
		(end 57.095136 -35.164776)
		(width 0.11684)
		(layer "F.Cu")
		(net "SMB_BMC_MM10_R_SDA")
	)
	(segment
		(start 56.062626 -38.171374)
		(end 57.095136 -37.138864)
		(width 0.11684)
		(layer "F.Cu")
		(net "SMB_BMC_MM10_R_SDA")
	)
	(segment
		(start 55.295038 -39.37127)
		(end 55.543958 -39.37127)
		(width 0.11684)
		(layer "F.Cu")
		(net "SMB_BMC_MM10_R_SDA")
	)
	(segment
		(start 55.543958 -39.37127)
		(end 56.062626 -38.852602)
		(width 0.11684)
		(layer "F.Cu")
		(net "SMB_BMC_MM10_R_SDA")
	)
	(segment
		(start 56.062626 -38.852602)
		(end 56.062626 -38.171374)
		(width 0.11684)
		(layer "F.Cu")
		(net "SMB_BMC_MM10_R_SDA")
	)
	(via
		(at 57.095136 -36.2204)
		(size 0.762)
		(drill 0.381)
		(layers "F.Cu" "B.Cu")
		(net "SMB_BMC_MM10_R_SDA")
	)
	(segment
		(start 53.695092 -42.571162)
		(end 53.299868 -42.175938)
		(width 0.11684)
		(layer "F.Cu")
		(net "SMB_BMC_MM10_R_SCL")
	)
	(via
		(at 53.299868 -42.175938)
		(size 0.4572)
		(drill 0.254)
		(layers "F.Cu" "B.Cu")
		(net "SMB_BMC_MM10_R_SCL")
	)
	(segment
		(start 55.05196 -36.7665)
		(end 55.05196 -36.465764)
		(width 0.11684)
		(layer "B.Cu")
		(net "SMB_BMC_MM10_R_SCL")
	)
	(segment
		(start 54.08676 -39.050722)
		(end 54.21376 -38.923722)
		(width 0.11684)
		(layer "B.Cu")
		(net "SMB_BMC_MM10_R_SCL")
	)
	(segment
		(start 53.695092 -41.199308)
		(end 54.08676 -40.80764)
		(width 0.11684)
		(layer "B.Cu")
		(net "SMB_BMC_MM10_R_SCL")
	)
	(segment
		(start 55.499 -35.356546)
		(end 55.499 -35.07105)
		(width 0.11684)
		(layer "B.Cu")
		(net "SMB_BMC_MM10_R_SCL")
	)
	(segment
		(start 53.695092 -41.780714)
		(end 53.695092 -41.199308)
		(width 0.11684)
		(layer "B.Cu")
		(net "SMB_BMC_MM10_R_SCL")
	)
	(segment
		(start 55.6006 -35.917124)
		(end 55.6006 -35.458146)
		(width 0.11684)
		(layer "B.Cu")
		(net "SMB_BMC_MM10_R_SCL")
	)
	(segment
		(start 54.21376 -38.923722)
		(end 54.21376 -37.890958)
		(width 0.11684)
		(layer "B.Cu")
		(net "SMB_BMC_MM10_R_SCL")
	)
	(segment
		(start 54.21376 -37.890958)
		(end 54.849268 -37.25545)
		(width 0.11684)
		(layer "B.Cu")
		(net "SMB_BMC_MM10_R_SCL")
	)
	(segment
		(start 55.6006 -35.458146)
		(end 55.499 -35.356546)
		(width 0.11684)
		(layer "B.Cu")
		(net "SMB_BMC_MM10_R_SCL")
	)
	(segment
		(start 53.299868 -42.175938)
		(end 53.695092 -41.780714)
		(width 0.11684)
		(layer "B.Cu")
		(net "SMB_BMC_MM10_R_SCL")
	)
	(segment
		(start 54.08676 -40.80764)
		(end 54.08676 -39.050722)
		(width 0.11684)
		(layer "B.Cu")
		(net "SMB_BMC_MM10_R_SCL")
	)
	(segment
		(start 55.05196 -36.465764)
		(end 55.6006 -35.917124)
		(width 0.11684)
		(layer "B.Cu")
		(net "SMB_BMC_MM10_R_SCL")
	)
	(segment
		(start 54.849268 -37.25545)
		(end 55.05196 -36.7665)
		(width 0.11684)
		(layer "B.Cu")
		(net "SMB_BMC_MM10_R_SCL")
	)
	(segment
		(start 21.62556 -52.13604)
		(end 21.62556 -49.0982)
		(width 0.11684)
		(layer "F.Cu")
		(net "SMB_BMC_ALERT4_N")
	)
	(segment
		(start 10.36574 -84.774786)
		(end 10.36574 -82.74304)
		(width 0.11684)
		(layer "F.Cu")
		(net "SMB_BMC_ALERT4_N")
	)
	(segment
		(start 38.136576 -42.86758)
		(end 37.68598 -43.318176)
		(width 0.11684)
		(layer "F.Cu")
		(net "SMB_BMC_ALERT4_N")
	)
	(segment
		(start 16.84909 -55.08371)
		(end 16.84909 -54.274212)
		(width 0.11684)
		(layer "F.Cu")
		(net "SMB_BMC_ALERT4_N")
	)
	(segment
		(start 20.193 -53.086)
		(end 20.6756 -53.086)
		(width 0.11684)
		(layer "F.Cu")
		(net "SMB_BMC_ALERT4_N")
	)
	(segment
		(start 16.84909 -54.274212)
		(end 18.560034 -52.563268)
		(width 0.11684)
		(layer "F.Cu")
		(net "SMB_BMC_ALERT4_N")
	)
	(segment
		(start 10.44829 -81.938876)
		(end 10.952226 -81.43494)
		(width 0.11684)
		(layer "F.Cu")
		(net "SMB_BMC_ALERT4_N")
	)
	(segment
		(start 14.0208 -72.7964)
		(end 13.5636 -72.3392)
		(width 0.11684)
		(layer "F.Cu")
		(net "SMB_BMC_ALERT4_N")
	)
	(segment
		(start 11.21791 -81.43494)
		(end 11.848846 -80.804004)
		(width 0.11684)
		(layer "F.Cu")
		(net "SMB_BMC_ALERT4_N")
	)
	(segment
		(start 14.3256 -68.040504)
		(end 14.3256 -65.292478)
		(width 0.11684)
		(layer "F.Cu")
		(net "SMB_BMC_ALERT4_N")
	)
	(segment
		(start 14.635734 -63.74257)
		(end 14.635734 -59.329066)
		(width 0.11684)
		(layer "F.Cu")
		(net "SMB_BMC_ALERT4_N")
	)
	(segment
		(start 20.6756 -53.086)
		(end 21.62556 -52.13604)
		(width 0.11684)
		(layer "F.Cu")
		(net "SMB_BMC_ALERT4_N")
	)
	(segment
		(start 14.0208 -77.724)
		(end 14.0208 -72.7964)
		(width 0.11684)
		(layer "F.Cu")
		(net "SMB_BMC_ALERT4_N")
	)
	(segment
		(start 11.91895 -86.327996)
		(end 10.36574 -84.774786)
		(width 0.11684)
		(layer "F.Cu")
		(net "SMB_BMC_ALERT4_N")
	)
	(segment
		(start 37.02431 -43.07078)
		(end 36.703 -43.07078)
		(width 0.11684)
		(layer "F.Cu")
		(net "SMB_BMC_ALERT4_N")
	)
	(segment
		(start 18.560034 -52.563268)
		(end 19.670268 -52.563268)
		(width 0.11684)
		(layer "F.Cu")
		(net "SMB_BMC_ALERT4_N")
	)
	(segment
		(start 13.3858 -79.6544)
		(end 13.3858 -78.359)
		(width 0.11684)
		(layer "F.Cu")
		(net "SMB_BMC_ALERT4_N")
	)
	(segment
		(start 10.36574 -82.74304)
		(end 10.44829 -82.66049)
		(width 0.11684)
		(layer "F.Cu")
		(net "SMB_BMC_ALERT4_N")
	)
	(segment
		(start 13.5636 -68.802504)
		(end 14.3256 -68.040504)
		(width 0.11684)
		(layer "F.Cu")
		(net "SMB_BMC_ALERT4_N")
	)
	(segment
		(start 19.670268 -52.563268)
		(end 20.193 -53.086)
		(width 0.11684)
		(layer "F.Cu")
		(net "SMB_BMC_ALERT4_N")
	)
	(segment
		(start 15.0622 -58.9026)
		(end 15.0622 -56.8706)
		(width 0.11684)
		(layer "F.Cu")
		(net "SMB_BMC_ALERT4_N")
	)
	(segment
		(start 39.65575 -42.4434)
		(end 39.23157 -42.86758)
		(width 0.11684)
		(layer "F.Cu")
		(net "SMB_BMC_ALERT4_N")
	)
	(segment
		(start 10.44829 -82.66049)
		(end 10.44829 -81.938876)
		(width 0.11684)
		(layer "F.Cu")
		(net "SMB_BMC_ALERT4_N")
	)
	(segment
		(start 39.23157 -42.86758)
		(end 38.136576 -42.86758)
		(width 0.11684)
		(layer "F.Cu")
		(net "SMB_BMC_ALERT4_N")
	)
	(segment
		(start 14.224 -64.154304)
		(end 14.635734 -63.74257)
		(width 0.11684)
		(layer "F.Cu")
		(net "SMB_BMC_ALERT4_N")
	)
	(segment
		(start 15.0622 -56.8706)
		(end 16.84909 -55.08371)
		(width 0.11684)
		(layer "F.Cu")
		(net "SMB_BMC_ALERT4_N")
	)
	(segment
		(start 37.68598 -43.318176)
		(end 37.68598 -43.73245)
		(width 0.11684)
		(layer "F.Cu")
		(net "SMB_BMC_ALERT4_N")
	)
	(segment
		(start 10.952226 -81.43494)
		(end 11.21791 -81.43494)
		(width 0.11684)
		(layer "F.Cu")
		(net "SMB_BMC_ALERT4_N")
	)
	(segment
		(start 14.3256 -65.292478)
		(end 14.224 -65.047114)
		(width 0.11684)
		(layer "F.Cu")
		(net "SMB_BMC_ALERT4_N")
	)
	(segment
		(start 13.5636 -72.3392)
		(end 13.5636 -68.802504)
		(width 0.11684)
		(layer "F.Cu")
		(net "SMB_BMC_ALERT4_N")
	)
	(segment
		(start 11.91895 -86.36)
		(end 11.91895 -86.327996)
		(width 0.11684)
		(layer "F.Cu")
		(net "SMB_BMC_ALERT4_N")
	)
	(segment
		(start 13.3858 -78.359)
		(end 14.0208 -77.724)
		(width 0.11684)
		(layer "F.Cu")
		(net "SMB_BMC_ALERT4_N")
	)
	(segment
		(start 37.68598 -43.73245)
		(end 37.02431 -43.07078)
		(width 0.11684)
		(layer "F.Cu")
		(net "SMB_BMC_ALERT4_N")
	)
	(segment
		(start 20.993608 -48.466248)
		(end 20.520152 -48.466248)
		(width 0.11684)
		(layer "F.Cu")
		(net "SMB_BMC_ALERT4_N")
	)
	(segment
		(start 11.848846 -80.804004)
		(end 12.236196 -80.804004)
		(width 0.11684)
		(layer "F.Cu")
		(net "SMB_BMC_ALERT4_N")
	)
	(segment
		(start 14.635734 -59.329066)
		(end 15.0622 -58.9026)
		(width 0.11684)
		(layer "F.Cu")
		(net "SMB_BMC_ALERT4_N")
	)
	(segment
		(start 21.62556 -49.0982)
		(end 20.993608 -48.466248)
		(width 0.11684)
		(layer "F.Cu")
		(net "SMB_BMC_ALERT4_N")
	)
	(segment
		(start 14.224 -65.047114)
		(end 14.224 -64.154304)
		(width 0.11684)
		(layer "F.Cu")
		(net "SMB_BMC_ALERT4_N")
	)
	(segment
		(start 12.236196 -80.804004)
		(end 13.3858 -79.6544)
		(width 0.11684)
		(layer "F.Cu")
		(net "SMB_BMC_ALERT4_N")
	)
	(via
		(at 20.520152 -48.466248)
		(size 0.508)
		(drill 0.254)
		(layers "F.Cu" "B.Cu")
		(net "SMB_BMC_ALERT4_N")
	)
	(via
		(at 36.703 -43.07078)
		(size 0.508)
		(drill 0.254)
		(layers "F.Cu" "B.Cu")
		(net "SMB_BMC_ALERT4_N")
	)
	(segment
		(start 20.825206 -48.466248)
		(end 20.520152 -48.466248)
		(width 0.08382)
		(layer "In2.Cu")
		(net "SMB_BMC_ALERT4_N")
	)
	(segment
		(start 36.703 -43.07078)
		(end 34.72942 -41.0972)
		(width 0.08382)
		(layer "In2.Cu")
		(net "SMB_BMC_ALERT4_N")
	)
	(segment
		(start 25.755854 -41.275)
		(end 24.977344 -41.275)
		(width 0.08382)
		(layer "In2.Cu")
		(net "SMB_BMC_ALERT4_N")
	)
	(segment
		(start 34.1884 -41.0972)
		(end 32.7152 -39.624)
		(width 0.08382)
		(layer "In2.Cu")
		(net "SMB_BMC_ALERT4_N")
	)
	(segment
		(start 24.977344 -41.275)
		(end 21.741892 -44.510452)
		(width 0.08382)
		(layer "In2.Cu")
		(net "SMB_BMC_ALERT4_N")
	)
	(segment
		(start 34.72942 -41.0972)
		(end 34.1884 -41.0972)
		(width 0.08382)
		(layer "In2.Cu")
		(net "SMB_BMC_ALERT4_N")
	)
	(segment
		(start 21.741892 -47.549562)
		(end 20.825206 -48.466248)
		(width 0.08382)
		(layer "In2.Cu")
		(net "SMB_BMC_ALERT4_N")
	)
	(segment
		(start 27.406854 -39.624)
		(end 25.755854 -41.275)
		(width 0.08382)
		(layer "In2.Cu")
		(net "SMB_BMC_ALERT4_N")
	)
	(segment
		(start 21.741892 -44.510452)
		(end 21.741892 -47.549562)
		(width 0.08382)
		(layer "In2.Cu")
		(net "SMB_BMC_ALERT4_N")
	)
	(segment
		(start 32.7152 -39.624)
		(end 27.406854 -39.624)
		(width 0.08382)
		(layer "In2.Cu")
		(net "SMB_BMC_ALERT4_N")
	)
	(segment
		(start 11.007852 -84.85632)
		(end 10.76198 -84.610448)
		(width 0.11684)
		(layer "F.Cu")
		(net "SMB_BMC_ALERT3_N")
	)
	(segment
		(start 12.632944 -81.200244)
		(end 12.6873 -81.2546)
		(width 0.11684)
		(layer "F.Cu")
		(net "SMB_BMC_ALERT3_N")
	)
	(segment
		(start 12.013184 -81.200244)
		(end 12.632944 -81.200244)
		(width 0.11684)
		(layer "F.Cu")
		(net "SMB_BMC_ALERT3_N")
	)
	(segment
		(start 14.9352 -65.728088)
		(end 14.62024 -64.967866)
		(width 0.11684)
		(layer "F.Cu")
		(net "SMB_BMC_ALERT3_N")
	)
	(segment
		(start 19.416268 -42.394378)
		(end 19.416268 -43.190922)
		(width 0.11684)
		(layer "F.Cu")
		(net "SMB_BMC_ALERT3_N")
	)
	(segment
		(start 35.4838 -40.8178)
		(end 36.45535 -41.78935)
		(width 0.11684)
		(layer "F.Cu")
		(net "SMB_BMC_ALERT3_N")
	)
	(segment
		(start 11.382248 -81.83118)
		(end 12.013184 -81.200244)
		(width 0.11684)
		(layer "F.Cu")
		(net "SMB_BMC_ALERT3_N")
	)
	(segment
		(start 24.938482 -42.25798)
		(end 30.89402 -42.25798)
		(width 0.11684)
		(layer "F.Cu")
		(net "SMB_BMC_ALERT3_N")
	)
	(segment
		(start 11.91895 -85.344)
		(end 11.91895 -85.197696)
		(width 0.11684)
		(layer "F.Cu")
		(net "SMB_BMC_ALERT3_N")
	)
	(segment
		(start 36.45535 -41.78935)
		(end 37.6936 -41.78935)
		(width 0.11684)
		(layer "F.Cu")
		(net "SMB_BMC_ALERT3_N")
	)
	(segment
		(start 15.031974 -60.070746)
		(end 15.2019 -59.90082)
		(width 0.11684)
		(layer "F.Cu")
		(net "SMB_BMC_ALERT3_N")
	)
	(segment
		(start 14.0208 -72.1868)
		(end 14.0208 -68.906136)
		(width 0.11684)
		(layer "F.Cu")
		(net "SMB_BMC_ALERT3_N")
	)
	(segment
		(start 11.116564 -81.83118)
		(end 11.382248 -81.83118)
		(width 0.11684)
		(layer "F.Cu")
		(net "SMB_BMC_ALERT3_N")
	)
	(segment
		(start 20.472146 -44.2468)
		(end 22.949662 -44.2468)
		(width 0.11684)
		(layer "F.Cu")
		(net "SMB_BMC_ALERT3_N")
	)
	(segment
		(start 14.62024 -64.318642)
		(end 15.031974 -63.906908)
		(width 0.11684)
		(layer "F.Cu")
		(net "SMB_BMC_ALERT3_N")
	)
	(segment
		(start 39.17569 -41.4782)
		(end 39.47795 -41.4782)
		(width 0.11684)
		(layer "F.Cu")
		(net "SMB_BMC_ALERT3_N")
	)
	(segment
		(start 13.7922 -80.772)
		(end 13.7922 -80.4164)
		(width 0.11684)
		(layer "F.Cu")
		(net "SMB_BMC_ALERT3_N")
	)
	(segment
		(start 14.9352 -67.991736)
		(end 14.9352 -67.31)
		(width 0.11684)
		(layer "F.Cu")
		(net "SMB_BMC_ALERT3_N")
	)
	(segment
		(start 10.76198 -84.610448)
		(end 10.76198 -82.907378)
		(width 0.11684)
		(layer "F.Cu")
		(net "SMB_BMC_ALERT3_N")
	)
	(segment
		(start 15.031974 -63.906908)
		(end 15.031974 -60.070746)
		(width 0.11684)
		(layer "F.Cu")
		(net "SMB_BMC_ALERT3_N")
	)
	(segment
		(start 14.62024 -64.967866)
		(end 14.62024 -64.318642)
		(width 0.11684)
		(layer "F.Cu")
		(net "SMB_BMC_ALERT3_N")
	)
	(segment
		(start 10.84453 -82.824828)
		(end 10.84453 -82.103214)
		(width 0.11684)
		(layer "F.Cu")
		(net "SMB_BMC_ALERT3_N")
	)
	(segment
		(start 19.416268 -43.190922)
		(end 20.472146 -44.2468)
		(width 0.11684)
		(layer "F.Cu")
		(net "SMB_BMC_ALERT3_N")
	)
	(segment
		(start 38.917372 -41.219882)
		(end 39.17569 -41.4782)
		(width 0.11684)
		(layer "F.Cu")
		(net "SMB_BMC_ALERT3_N")
	)
	(segment
		(start 12.6873 -81.2546)
		(end 13.3096 -81.2546)
		(width 0.11684)
		(layer "F.Cu")
		(net "SMB_BMC_ALERT3_N")
	)
	(segment
		(start 11.577574 -84.85632)
		(end 11.007852 -84.85632)
		(width 0.11684)
		(layer "F.Cu")
		(net "SMB_BMC_ALERT3_N")
	)
	(segment
		(start 38.263068 -41.219882)
		(end 38.917372 -41.219882)
		(width 0.11684)
		(layer "F.Cu")
		(net "SMB_BMC_ALERT3_N")
	)
	(segment
		(start 14.9352 -67.31)
		(end 14.9352 -65.728088)
		(width 0.11684)
		(layer "F.Cu")
		(net "SMB_BMC_ALERT3_N")
	)
	(segment
		(start 30.89402 -42.25798)
		(end 32.3342 -40.8178)
		(width 0.11684)
		(layer "F.Cu")
		(net "SMB_BMC_ALERT3_N")
	)
	(segment
		(start 39.47795 -41.4782)
		(end 39.50335 -41.5036)
		(width 0.11684)
		(layer "F.Cu")
		(net "SMB_BMC_ALERT3_N")
	)
	(segment
		(start 37.6936 -41.78935)
		(end 38.263068 -41.219882)
		(width 0.11684)
		(layer "F.Cu")
		(net "SMB_BMC_ALERT3_N")
	)
	(segment
		(start 14.0208 -68.906136)
		(end 14.9352 -67.991736)
		(width 0.11684)
		(layer "F.Cu")
		(net "SMB_BMC_ALERT3_N")
	)
	(segment
		(start 32.3342 -40.8178)
		(end 35.4838 -40.8178)
		(width 0.11684)
		(layer "F.Cu")
		(net "SMB_BMC_ALERT3_N")
	)
	(segment
		(start 22.949662 -44.2468)
		(end 24.938482 -42.25798)
		(width 0.11684)
		(layer "F.Cu")
		(net "SMB_BMC_ALERT3_N")
	)
	(segment
		(start 11.91895 -85.197696)
		(end 11.577574 -84.85632)
		(width 0.11684)
		(layer "F.Cu")
		(net "SMB_BMC_ALERT3_N")
	)
	(segment
		(start 10.84453 -82.103214)
		(end 11.116564 -81.83118)
		(width 0.11684)
		(layer "F.Cu")
		(net "SMB_BMC_ALERT3_N")
	)
	(segment
		(start 13.3096 -81.2546)
		(end 13.7922 -80.772)
		(width 0.11684)
		(layer "F.Cu")
		(net "SMB_BMC_ALERT3_N")
	)
	(segment
		(start 10.76198 -82.907378)
		(end 10.84453 -82.824828)
		(width 0.11684)
		(layer "F.Cu")
		(net "SMB_BMC_ALERT3_N")
	)
	(segment
		(start 14.4272 -79.7814)
		(end 14.4272 -72.5932)
		(width 0.11684)
		(layer "F.Cu")
		(net "SMB_BMC_ALERT3_N")
	)
	(segment
		(start 13.7922 -80.4164)
		(end 14.4272 -79.7814)
		(width 0.11684)
		(layer "F.Cu")
		(net "SMB_BMC_ALERT3_N")
	)
	(segment
		(start 14.4272 -72.5932)
		(end 14.0208 -72.1868)
		(width 0.11684)
		(layer "F.Cu")
		(net "SMB_BMC_ALERT3_N")
	)
	(via
		(at 19.416268 -42.394378)
		(size 0.508)
		(drill 0.254)
		(layers "F.Cu" "B.Cu")
		(net "SMB_BMC_ALERT3_N")
	)
	(via
		(at 15.2019 -59.90082)
		(size 0.508)
		(drill 0.254)
		(layers "F.Cu" "B.Cu")
		(net "SMB_BMC_ALERT3_N")
	)
	(via
		(at 14.9352 -67.31)
		(size 0.762)
		(drill 0.381)
		(layers "F.Cu" "B.Cu")
		(net "SMB_BMC_ALERT3_N")
	)
	(segment
		(start 17.13738 -50.266092)
		(end 16.919194 -50.047906)
		(width 0.10668)
		(layer "In4.Cu")
		(net "SMB_BMC_ALERT3_N")
	)
	(segment
		(start 17.0561 -46.09719)
		(end 17.0561 -43.690032)
		(width 0.10668)
		(layer "In4.Cu")
		(net "SMB_BMC_ALERT3_N")
	)
	(segment
		(start 15.791434 -47.361856)
		(end 17.0561 -46.09719)
		(width 0.10668)
		(layer "In4.Cu")
		(net "SMB_BMC_ALERT3_N")
	)
	(segment
		(start 17.820132 -42.926)
		(end 18.884646 -42.926)
		(width 0.10668)
		(layer "In4.Cu")
		(net "SMB_BMC_ALERT3_N")
	)
	(segment
		(start 15.2019 -59.90082)
		(end 15.987522 -59.115198)
		(width 0.10668)
		(layer "In4.Cu")
		(net "SMB_BMC_ALERT3_N")
	)
	(segment
		(start 15.791434 -48.320706)
		(end 15.791434 -47.361856)
		(width 0.10668)
		(layer "In4.Cu")
		(net "SMB_BMC_ALERT3_N")
	)
	(segment
		(start 16.919194 -49.679098)
		(end 16.321024 -49.080928)
		(width 0.10668)
		(layer "In4.Cu")
		(net "SMB_BMC_ALERT3_N")
	)
	(segment
		(start 17.0561 -43.690032)
		(end 17.820132 -42.926)
		(width 0.10668)
		(layer "In4.Cu")
		(net "SMB_BMC_ALERT3_N")
	)
	(segment
		(start 15.987522 -59.115198)
		(end 15.987522 -52.533804)
		(width 0.10668)
		(layer "In4.Cu")
		(net "SMB_BMC_ALERT3_N")
	)
	(segment
		(start 16.321024 -48.850296)
		(end 15.791434 -48.320706)
		(width 0.10668)
		(layer "In4.Cu")
		(net "SMB_BMC_ALERT3_N")
	)
	(segment
		(start 18.884646 -42.926)
		(end 19.416268 -42.394378)
		(width 0.10668)
		(layer "In4.Cu")
		(net "SMB_BMC_ALERT3_N")
	)
	(segment
		(start 16.321024 -49.080928)
		(end 16.321024 -48.850296)
		(width 0.10668)
		(layer "In4.Cu")
		(net "SMB_BMC_ALERT3_N")
	)
	(segment
		(start 15.987522 -52.533804)
		(end 17.13738 -51.383946)
		(width 0.10668)
		(layer "In4.Cu")
		(net "SMB_BMC_ALERT3_N")
	)
	(segment
		(start 16.919194 -50.047906)
		(end 16.919194 -49.679098)
		(width 0.10668)
		(layer "In4.Cu")
		(net "SMB_BMC_ALERT3_N")
	)
	(segment
		(start 17.13738 -51.383946)
		(end 17.13738 -50.266092)
		(width 0.10668)
		(layer "In4.Cu")
		(net "SMB_BMC_ALERT3_N")
	)
	(segment
		(start 15.864332 -88.791796)
		(end 16.259556 -89.18702)
		(width 0.11684)
		(layer "F.Cu")
		(net "VOL_SEN_ALERT_R")
	)
	(segment
		(start 15.314422 -88.791796)
		(end 15.864332 -88.791796)
		(width 0.11684)
		(layer "F.Cu")
		(net "VOL_SEN_ALERT_R")
	)
	(segment
		(start 14.5796 -88.056974)
		(end 15.314422 -88.791796)
		(width 0.11684)
		(layer "F.Cu")
		(net "VOL_SEN_ALERT_R")
	)
	(segment
		(start 14.5796 -87.7316)
		(end 14.5796 -88.056974)
		(width 0.11684)
		(layer "F.Cu")
		(net "VOL_SEN_ALERT_R")
	)
	(segment
		(start 47.295054 -46.571154)
		(end 46.89983 -46.17593)
		(width 0.11684)
		(layer "F.Cu")
		(net "VOL_SEN_ALERT_R")
	)
	(via
		(at 14.5796 -87.7316)
		(size 0.508)
		(drill 0.254)
		(layers "F.Cu" "B.Cu")
		(net "VOL_SEN_ALERT_R")
	)
	(via
		(at 46.89983 -46.17593)
		(size 0.4572)
		(drill 0.254)
		(layers "F.Cu" "B.Cu")
		(net "VOL_SEN_ALERT_R")
	)
	(via
		(at 18.1864 -51.0286)
		(size 0.508)
		(drill 0.254)
		(layers "F.Cu" "B.Cu")
		(net "VOL_SEN_ALERT_R")
	)
	(segment
		(start 44.850812 -46.58741)
		(end 44.118022 -47.3202)
		(width 0.11684)
		(layer "B.Cu")
		(net "VOL_SEN_ALERT_R")
	)
	(segment
		(start 43.3578 -47.3202)
		(end 42.93235 -46.89475)
		(width 0.11684)
		(layer "B.Cu")
		(net "VOL_SEN_ALERT_R")
	)
	(segment
		(start 42.351198 -46.653958)
		(end 40.814752 -46.653958)
		(width 0.11684)
		(layer "B.Cu")
		(net "VOL_SEN_ALERT_R")
	)
	(segment
		(start 44.118022 -47.3202)
		(end 43.3578 -47.3202)
		(width 0.11684)
		(layer "B.Cu")
		(net "VOL_SEN_ALERT_R")
	)
	(segment
		(start 46.89983 -46.17593)
		(end 46.48835 -46.58741)
		(width 0.11684)
		(layer "B.Cu")
		(net "VOL_SEN_ALERT_R")
	)
	(segment
		(start 46.48835 -46.58741)
		(end 44.850812 -46.58741)
		(width 0.11684)
		(layer "B.Cu")
		(net "VOL_SEN_ALERT_R")
	)
	(segment
		(start 42.93235 -46.89475)
		(end 42.351198 -46.653958)
		(width 0.11684)
		(layer "B.Cu")
		(net "VOL_SEN_ALERT_R")
	)
	(segment
		(start 40.814752 -46.653958)
		(end 40.330882 -47.137828)
		(width 0.11684)
		(layer "B.Cu")
		(net "VOL_SEN_ALERT_R")
	)
	(segment
		(start 31.68142 -47.716186)
		(end 30.8737 -46.908466)
		(width 0.08382)
		(layer "In2.Cu")
		(net "VOL_SEN_ALERT_R")
	)
	(segment
		(start 21.276564 -51.0286)
		(end 18.1864 -51.0286)
		(width 0.08382)
		(layer "In2.Cu")
		(net "VOL_SEN_ALERT_R")
	)
	(segment
		(start 41.91 -47.6504)
		(end 40.132 -47.6504)
		(width 0.08382)
		(layer "In2.Cu")
		(net "VOL_SEN_ALERT_R")
	)
	(segment
		(start 45.234606 -45.748194)
		(end 44.0309 -46.9519)
		(width 0.08382)
		(layer "In2.Cu")
		(net "VOL_SEN_ALERT_R")
	)
	(segment
		(start 25.500838 -42.5323)
		(end 22.999192 -45.033946)
		(width 0.08382)
		(layer "In2.Cu")
		(net "VOL_SEN_ALERT_R")
	)
	(segment
		(start 22.999192 -45.033946)
		(end 22.999192 -49.305972)
		(width 0.08382)
		(layer "In2.Cu")
		(net "VOL_SEN_ALERT_R")
	)
	(segment
		(start 36.689792 -48.382936)
		(end 36.023042 -47.716186)
		(width 0.08382)
		(layer "In2.Cu")
		(net "VOL_SEN_ALERT_R")
	)
	(segment
		(start 22.999192 -49.305972)
		(end 21.276564 -51.0286)
		(width 0.08382)
		(layer "In2.Cu")
		(net "VOL_SEN_ALERT_R")
	)
	(segment
		(start 40.132 -47.6504)
		(end 38.862 -48.9204)
		(width 0.08382)
		(layer "In2.Cu")
		(net "VOL_SEN_ALERT_R")
	)
	(segment
		(start 46.472094 -45.748194)
		(end 45.234606 -45.748194)
		(width 0.08382)
		(layer "In2.Cu")
		(net "VOL_SEN_ALERT_R")
	)
	(segment
		(start 36.023042 -47.716186)
		(end 31.68142 -47.716186)
		(width 0.08382)
		(layer "In2.Cu")
		(net "VOL_SEN_ALERT_R")
	)
	(segment
		(start 44.0309 -46.9519)
		(end 42.6085 -46.9519)
		(width 0.08382)
		(layer "In2.Cu")
		(net "VOL_SEN_ALERT_R")
	)
	(segment
		(start 30.8737 -46.908466)
		(end 30.8737 -44.886372)
		(width 0.08382)
		(layer "In2.Cu")
		(net "VOL_SEN_ALERT_R")
	)
	(segment
		(start 42.6085 -46.9519)
		(end 41.91 -47.6504)
		(width 0.08382)
		(layer "In2.Cu")
		(net "VOL_SEN_ALERT_R")
	)
	(segment
		(start 37.98697 -48.9204)
		(end 36.689792 -48.382936)
		(width 0.08382)
		(layer "In2.Cu")
		(net "VOL_SEN_ALERT_R")
	)
	(segment
		(start 38.862 -48.9204)
		(end 37.98697 -48.9204)
		(width 0.08382)
		(layer "In2.Cu")
		(net "VOL_SEN_ALERT_R")
	)
	(segment
		(start 28.519628 -42.5323)
		(end 25.500838 -42.5323)
		(width 0.08382)
		(layer "In2.Cu")
		(net "VOL_SEN_ALERT_R")
	)
	(segment
		(start 46.89983 -46.17593)
		(end 46.472094 -45.748194)
		(width 0.08382)
		(layer "In2.Cu")
		(net "VOL_SEN_ALERT_R")
	)
	(segment
		(start 30.8737 -44.886372)
		(end 28.519628 -42.5323)
		(width 0.08382)
		(layer "In2.Cu")
		(net "VOL_SEN_ALERT_R")
	)
	(segment
		(start 17.76984 -57.874662)
		(end 16.917162 -57.021984)
		(width 0.10668)
		(layer "In4.Cu")
		(net "VOL_SEN_ALERT_R")
	)
	(segment
		(start 18.5801 -63.87084)
		(end 17.41932 -62.71006)
		(width 0.10668)
		(layer "In4.Cu")
		(net "VOL_SEN_ALERT_R")
	)
	(segment
		(start 14.49324 -77.310234)
		(end 14.49324 -75.3491)
		(width 0.10668)
		(layer "In4.Cu")
		(net "VOL_SEN_ALERT_R")
	)
	(segment
		(start 16.95196 -71.119238)
		(end 16.95196 -68.23964)
		(width 0.10668)
		(layer "In4.Cu")
		(net "VOL_SEN_ALERT_R")
	)
	(segment
		(start 17.25422 -71.421498)
		(end 16.95196 -71.119238)
		(width 0.10668)
		(layer "In4.Cu")
		(net "VOL_SEN_ALERT_R")
	)
	(segment
		(start 16.95196 -68.23964)
		(end 18.5801 -66.6115)
		(width 0.10668)
		(layer "In4.Cu")
		(net "VOL_SEN_ALERT_R")
	)
	(segment
		(start 17.76984 -58.77814)
		(end 17.76984 -57.874662)
		(width 0.10668)
		(layer "In4.Cu")
		(net "VOL_SEN_ALERT_R")
	)
	(segment
		(start 17.80794 -51.40706)
		(end 18.1864 -51.0286)
		(width 0.10668)
		(layer "In4.Cu")
		(net "VOL_SEN_ALERT_R")
	)
	(segment
		(start 14.80312 -83.886802)
		(end 15.54226 -83.147662)
		(width 0.10668)
		(layer "In4.Cu")
		(net "VOL_SEN_ALERT_R")
	)
	(segment
		(start 16.917162 -53.378862)
		(end 17.80794 -52.488084)
		(width 0.10668)
		(layer "In4.Cu")
		(net "VOL_SEN_ALERT_R")
	)
	(segment
		(start 17.25422 -72.58812)
		(end 17.25422 -71.421498)
		(width 0.10668)
		(layer "In4.Cu")
		(net "VOL_SEN_ALERT_R")
	)
	(segment
		(start 15.345918 -78.53045)
		(end 15.345918 -78.162912)
		(width 0.10668)
		(layer "In4.Cu")
		(net "VOL_SEN_ALERT_R")
	)
	(segment
		(start 14.49324 -75.3491)
		(end 17.25422 -72.58812)
		(width 0.10668)
		(layer "In4.Cu")
		(net "VOL_SEN_ALERT_R")
	)
	(segment
		(start 16.917162 -57.021984)
		(end 16.917162 -53.378862)
		(width 0.10668)
		(layer "In4.Cu")
		(net "VOL_SEN_ALERT_R")
	)
	(segment
		(start 15.345918 -78.162912)
		(end 14.49324 -77.310234)
		(width 0.10668)
		(layer "In4.Cu")
		(net "VOL_SEN_ALERT_R")
	)
	(segment
		(start 15.54226 -81.91754)
		(end 15.93342 -81.52638)
		(width 0.10668)
		(layer "In4.Cu")
		(net "VOL_SEN_ALERT_R")
	)
	(segment
		(start 17.41932 -62.71006)
		(end 17.41932 -59.12866)
		(width 0.10668)
		(layer "In4.Cu")
		(net "VOL_SEN_ALERT_R")
	)
	(segment
		(start 15.93342 -79.117952)
		(end 15.345918 -78.53045)
		(width 0.10668)
		(layer "In4.Cu")
		(net "VOL_SEN_ALERT_R")
	)
	(segment
		(start 15.54226 -83.147662)
		(end 15.54226 -81.91754)
		(width 0.10668)
		(layer "In4.Cu")
		(net "VOL_SEN_ALERT_R")
	)
	(segment
		(start 18.5801 -66.6115)
		(end 18.5801 -63.87084)
		(width 0.10668)
		(layer "In4.Cu")
		(net "VOL_SEN_ALERT_R")
	)
	(segment
		(start 14.5796 -87.7316)
		(end 14.80312 -87.50808)
		(width 0.10668)
		(layer "In4.Cu")
		(net "VOL_SEN_ALERT_R")
	)
	(segment
		(start 15.93342 -81.52638)
		(end 15.93342 -79.117952)
		(width 0.10668)
		(layer "In4.Cu")
		(net "VOL_SEN_ALERT_R")
	)
	(segment
		(start 17.41932 -59.12866)
		(end 17.76984 -58.77814)
		(width 0.10668)
		(layer "In4.Cu")
		(net "VOL_SEN_ALERT_R")
	)
	(segment
		(start 17.80794 -52.488084)
		(end 17.80794 -51.40706)
		(width 0.10668)
		(layer "In4.Cu")
		(net "VOL_SEN_ALERT_R")
	)
	(segment
		(start 14.80312 -87.50808)
		(end 14.80312 -83.886802)
		(width 0.10668)
		(layer "In4.Cu")
		(net "VOL_SEN_ALERT_R")
	)
	(segment
		(start 18.264124 -87.99195)
		(end 18.659348 -88.387174)
		(width 0.11684)
		(layer "F.Cu")
		(net "SGPIO_PLD_LD_0")
	)
	(segment
		(start 17.145 -85.16747)
		(end 17.145 -86.2076)
		(width 0.11684)
		(layer "F.Cu")
		(net "SGPIO_PLD_LD_0")
	)
	(segment
		(start 16.4846 -84.09305)
		(end 16.4846 -84.50707)
		(width 0.11684)
		(layer "F.Cu")
		(net "SGPIO_PLD_LD_0")
	)
	(segment
		(start 18.264124 -87.326724)
		(end 18.264124 -87.99195)
		(width 0.11684)
		(layer "F.Cu")
		(net "SGPIO_PLD_LD_0")
	)
	(segment
		(start 17.145 -86.2076)
		(end 18.264124 -87.326724)
		(width 0.11684)
		(layer "F.Cu")
		(net "SGPIO_PLD_LD_0")
	)
	(segment
		(start 16.4846 -84.50707)
		(end 17.145 -85.16747)
		(width 0.11684)
		(layer "F.Cu")
		(net "SGPIO_PLD_LD_0")
	)
	(segment
		(start 18.264124 -88.791796)
		(end 18.659348 -89.18702)
		(width 0.11684)
		(layer "F.Cu")
		(net "SGPIO_PLD_DO_0")
	)
	(via
		(at 16.78178 -86.30412)
		(size 0.6604)
		(drill 0.3302)
		(layers "F.Cu" "B.Cu")
		(net "SGPIO_PLD_DO_0")
	)
	(via
		(at 18.264124 -88.791796)
		(size 0.4572)
		(drill 0.254)
		(layers "F.Cu" "B.Cu")
		(net "SGPIO_PLD_DO_0")
	)
	(segment
		(start 16.78178 -86.30412)
		(end 16.78178 -86.614)
		(width 0.11684)
		(layer "B.Cu")
		(net "SGPIO_PLD_DO_0")
	)
	(segment
		(start 16.1544 -84.759546)
		(end 16.1544 -85.98662)
		(width 0.11684)
		(layer "B.Cu")
		(net "SGPIO_PLD_DO_0")
	)
	(segment
		(start 18.264124 -88.096344)
		(end 18.264124 -88.791796)
		(width 0.11684)
		(layer "B.Cu")
		(net "SGPIO_PLD_DO_0")
	)
	(segment
		(start 16.4719 -86.30412)
		(end 16.78178 -86.30412)
		(width 0.11684)
		(layer "B.Cu")
		(net "SGPIO_PLD_DO_0")
	)
	(segment
		(start 16.1544 -85.98662)
		(end 16.4719 -86.30412)
		(width 0.11684)
		(layer "B.Cu")
		(net "SGPIO_PLD_DO_0")
	)
	(segment
		(start 15.24 -84.09305)
		(end 15.487904 -84.09305)
		(width 0.11684)
		(layer "B.Cu")
		(net "SGPIO_PLD_DO_0")
	)
	(segment
		(start 16.78178 -86.614)
		(end 18.264124 -88.096344)
		(width 0.11684)
		(layer "B.Cu")
		(net "SGPIO_PLD_DO_0")
	)
	(segment
		(start 15.487904 -84.09305)
		(end 16.1544 -84.759546)
		(width 0.11684)
		(layer "B.Cu")
		(net "SGPIO_PLD_DO_0")
	)
	(segment
		(start 14.5542 -86.09076)
		(end 15.17904 -86.7156)
		(width 0.11684)
		(layer "F.Cu")
		(net "SGPIO_PLD_DI_0")
	)
	(segment
		(start 16.664178 -87.403178)
		(end 16.664178 -87.99195)
		(width 0.11684)
		(layer "F.Cu")
		(net "SGPIO_PLD_DI_0")
	)
	(segment
		(start 14.5542 -85.125814)
		(end 14.5542 -86.09076)
		(width 0.11684)
		(layer "F.Cu")
		(net "SGPIO_PLD_DI_0")
	)
	(segment
		(start 13.462 -83.337654)
		(end 13.462 -84.530946)
		(width 0.11684)
		(layer "F.Cu")
		(net "SGPIO_PLD_DI_0")
	)
	(segment
		(start 15.9766 -86.7156)
		(end 16.664178 -87.403178)
		(width 0.11684)
		(layer "F.Cu")
		(net "SGPIO_PLD_DI_0")
	)
	(segment
		(start 12.71905 -82.296)
		(end 12.71905 -82.594704)
		(width 0.11684)
		(layer "F.Cu")
		(net "SGPIO_PLD_DI_0")
	)
	(segment
		(start 13.784834 -84.85378)
		(end 14.282166 -84.85378)
		(width 0.11684)
		(layer "F.Cu")
		(net "SGPIO_PLD_DI_0")
	)
	(segment
		(start 12.71905 -82.594704)
		(end 13.462 -83.337654)
		(width 0.11684)
		(layer "F.Cu")
		(net "SGPIO_PLD_DI_0")
	)
	(segment
		(start 16.664178 -87.99195)
		(end 17.059402 -88.387174)
		(width 0.11684)
		(layer "F.Cu")
		(net "SGPIO_PLD_DI_0")
	)
	(segment
		(start 14.282166 -84.85378)
		(end 14.5542 -85.125814)
		(width 0.11684)
		(layer "F.Cu")
		(net "SGPIO_PLD_DI_0")
	)
	(segment
		(start 13.462 -84.530946)
		(end 13.784834 -84.85378)
		(width 0.11684)
		(layer "F.Cu")
		(net "SGPIO_PLD_DI_0")
	)
	(segment
		(start 15.17904 -86.7156)
		(end 15.9766 -86.7156)
		(width 0.11684)
		(layer "F.Cu")
		(net "SGPIO_PLD_DI_0")
	)
	(segment
		(start 14.60881 -84.001864)
		(end 16.03756 -85.430614)
		(width 0.11684)
		(layer "F.Cu")
		(net "SGPIO_CLK_PLD_0")
	)
	(segment
		(start 14.60881 -83.410044)
		(end 14.60881 -84.001864)
		(width 0.11684)
		(layer "F.Cu")
		(net "SGPIO_CLK_PLD_0")
	)
	(segment
		(start 16.03756 -85.430614)
		(end 16.03756 -86.166706)
		(width 0.11684)
		(layer "F.Cu")
		(net "SGPIO_CLK_PLD_0")
	)
	(segment
		(start 14.491716 -83.29295)
		(end 14.60881 -83.410044)
		(width 0.11684)
		(layer "F.Cu")
		(net "SGPIO_CLK_PLD_0")
	)
	(segment
		(start 17.059402 -87.188548)
		(end 17.059402 -87.587074)
		(width 0.11684)
		(layer "F.Cu")
		(net "SGPIO_CLK_PLD_0")
	)
	(segment
		(start 16.03756 -86.166706)
		(end 17.059402 -87.188548)
		(width 0.11684)
		(layer "F.Cu")
		(net "SGPIO_CLK_PLD_0")
	)
	(segment
		(start 14.1732 -83.29295)
		(end 14.491716 -83.29295)
		(width 0.11684)
		(layer "F.Cu")
		(net "SGPIO_CLK_PLD_0")
	)
	(segment
		(start 50.53584 -30.46095)
		(end 50.8 -30.46095)
		(width 0.11684)
		(layer "F.Cu")
		(net "SGPIO_LD_1")
	)
	(segment
		(start 49.790096 -28.75915)
		(end 50.31994 -29.288994)
		(width 0.11684)
		(layer "F.Cu")
		(net "SGPIO_LD_1")
	)
	(segment
		(start 48.76165 -28.75915)
		(end 49.790096 -28.75915)
		(width 0.11684)
		(layer "F.Cu")
		(net "SGPIO_LD_1")
	)
	(segment
		(start 50.31994 -29.288994)
		(end 50.31994 -30.24505)
		(width 0.11684)
		(layer "F.Cu")
		(net "SGPIO_LD_1")
	)
	(segment
		(start 50.31994 -30.24505)
		(end 50.53584 -30.46095)
		(width 0.11684)
		(layer "F.Cu")
		(net "SGPIO_LD_1")
	)
	(segment
		(start 38.455092 -118.25986)
		(end 38.455092 -114.28222)
		(width 0.11684)
		(layer "F.Cu")
		(net "SGPIO_LD_1")
	)
	(segment
		(start 48.448976 -29.071824)
		(end 48.76165 -28.75915)
		(width 0.11684)
		(layer "F.Cu")
		(net "SGPIO_LD_1")
	)
	(via
		(at 38.455092 -114.28222)
		(size 0.508)
		(drill 0.254)
		(layers "F.Cu" "B.Cu")
		(net "SGPIO_LD_1")
	)
	(via
		(at 12.9413 -80.7847)
		(size 0.508)
		(drill 0.254)
		(layers "F.Cu" "B.Cu")
		(net "SGPIO_LD_1")
	)
	(via
		(at 48.448976 -29.071824)
		(size 0.508)
		(drill 0.254)
		(layers "F.Cu" "B.Cu")
		(net "SGPIO_LD_1")
	)
	(segment
		(start 38.90518 -114.28222)
		(end 38.455092 -114.28222)
		(width 0.11684)
		(layer "B.Cu")
		(net "SGPIO_LD_1")
	)
	(segment
		(start 39.108634 -107.751118)
		(end 39.108634 -114.078766)
		(width 0.11684)
		(layer "B.Cu")
		(net "SGPIO_LD_1")
	)
	(segment
		(start 39.108634 -114.078766)
		(end 38.90518 -114.28222)
		(width 0.11684)
		(layer "B.Cu")
		(net "SGPIO_LD_1")
	)
	(segment
		(start 39.116 -107.743752)
		(end 39.108634 -107.751118)
		(width 0.11684)
		(layer "B.Cu")
		(net "SGPIO_LD_1")
	)
	(segment
		(start 39.0652 -106.77525)
		(end 39.12362 -106.83367)
		(width 0.11684)
		(layer "B.Cu")
		(net "SGPIO_LD_1")
	)
	(segment
		(start 39.12362 -106.83367)
		(end 39.12362 -107.660186)
		(width 0.11684)
		(layer "B.Cu")
		(net "SGPIO_LD_1")
	)
	(segment
		(start 39.116 -107.667806)
		(end 39.116 -107.743752)
		(width 0.11684)
		(layer "B.Cu")
		(net "SGPIO_LD_1")
	)
	(segment
		(start 39.12362 -107.660186)
		(end 39.116 -107.667806)
		(width 0.11684)
		(layer "B.Cu")
		(net "SGPIO_LD_1")
	)
	(segment
		(start 36.5506 -27.55138)
		(end 32.78378 -27.55138)
		(width 0.10668)
		(layer "In4.Cu")
		(net "SGPIO_LD_1")
	)
	(segment
		(start 14.0208 -70.622414)
		(end 13.87729 -70.765924)
		(width 0.10668)
		(layer "In4.Cu")
		(net "SGPIO_LD_1")
	)
	(segment
		(start 13.3604 -70.132194)
		(end 13.50391 -70.275704)
		(width 0.10668)
		(layer "In4.Cu")
		(net "SGPIO_LD_1")
	)
	(segment
		(start 14.68628 -45.750988)
		(end 13.84808 -46.589188)
		(width 0.10668)
		(layer "In4.Cu")
		(net "SGPIO_LD_1")
	)
	(segment
		(start 13.50391 -69.295264)
		(end 13.87729 -69.295264)
		(width 0.10668)
		(layer "In4.Cu")
		(net "SGPIO_LD_1")
	)
	(segment
		(start 13.6271 -49.10836)
		(end 12.48664 -49.10836)
		(width 0.10668)
		(layer "In4.Cu")
		(net "SGPIO_LD_1")
	)
	(segment
		(start 26.64714 -24.36114)
		(end 26.04516 -23.75916)
		(width 0.10668)
		(layer "In4.Cu")
		(net "SGPIO_LD_1")
	)
	(segment
		(start 12.1158 -63.952628)
		(end 12.296648 -64.133476)
		(width 0.10668)
		(layer "In4.Cu")
		(net "SGPIO_LD_1")
	)
	(segment
		(start 12.1158 -64.931544)
		(end 12.1158 -66.065654)
		(width 0.10668)
		(layer "In4.Cu")
		(net "SGPIO_LD_1")
	)
	(segment
		(start 14.68628 -28.885896)
		(end 14.68628 -45.750988)
		(width 0.10668)
		(layer "In4.Cu")
		(net "SGPIO_LD_1")
	)
	(segment
		(start 11.63828 -55.40248)
		(end 12.2682 -56.922924)
		(width 0.10668)
		(layer "In4.Cu")
		(net "SGPIO_LD_1")
	)
	(segment
		(start 37.33038 -26.7716)
		(end 36.5506 -27.55138)
		(width 0.10668)
		(layer "In4.Cu")
		(net "SGPIO_LD_1")
	)
	(segment
		(start 12.1158 -62.047882)
		(end 12.296648 -62.22873)
		(width 0.10668)
		(layer "In4.Cu")
		(net "SGPIO_LD_1")
	)
	(segment
		(start 24.284178 -20.40001)
		(end 16.912336 -20.40001)
		(width 0.10668)
		(layer "In4.Cu")
		(net "SGPIO_LD_1")
	)
	(segment
		(start 13.208 -64.314324)
		(end 13.208 -64.569848)
		(width 0.10668)
		(layer "In4.Cu")
		(net "SGPIO_LD_1")
	)
	(segment
		(start 11.6332 -52.705)
		(end 11.63828 -52.71008)
		(width 0.10668)
		(layer "In4.Cu")
		(net "SGPIO_LD_1")
	)
	(segment
		(start 40.434768 -26.7716)
		(end 37.33038 -26.7716)
		(width 0.10668)
		(layer "In4.Cu")
		(net "SGPIO_LD_1")
	)
	(segment
		(start 14.0208 -70.419214)
		(end 14.0208 -70.622414)
		(width 0.10668)
		(layer "In4.Cu")
		(net "SGPIO_LD_1")
	)
	(segment
		(start 27.835606 -24.36114)
		(end 26.64714 -24.36114)
		(width 0.10668)
		(layer "In4.Cu")
		(net "SGPIO_LD_1")
	)
	(segment
		(start 13.208 -64.569848)
		(end 13.027152 -64.750696)
		(width 0.10668)
		(layer "In4.Cu")
		(net "SGPIO_LD_1")
	)
	(segment
		(start 16.912336 -20.40001)
		(end 15.621 -21.691346)
		(width 0.10668)
		(layer "In4.Cu")
		(net "SGPIO_LD_1")
	)
	(segment
		(start 14.224 -62.665102)
		(end 14.043152 -62.84595)
		(width 0.10668)
		(layer "In4.Cu")
		(net "SGPIO_LD_1")
	)
	(segment
		(start 12.48664 -49.10836)
		(end 11.6332 -49.9618)
		(width 0.10668)
		(layer "In4.Cu")
		(net "SGPIO_LD_1")
	)
	(segment
		(start 14.0208 -69.438774)
		(end 14.0208 -69.641974)
		(width 0.10668)
		(layer "In4.Cu")
		(net "SGPIO_LD_1")
	)
	(segment
		(start 14.043152 -62.22873)
		(end 14.224 -62.409578)
		(width 0.10668)
		(layer "In4.Cu")
		(net "SGPIO_LD_1")
	)
	(segment
		(start 12.98194 -80.28686)
		(end 12.9413 -80.3275)
		(width 0.10668)
		(layer "In4.Cu")
		(net "SGPIO_LD_1")
	)
	(segment
		(start 15.621 -27.951176)
		(end 14.68628 -28.885896)
		(width 0.10668)
		(layer "In4.Cu")
		(net "SGPIO_LD_1")
	)
	(segment
		(start 13.3604 -68.948554)
		(end 13.3604 -69.151754)
		(width 0.10668)
		(layer "In4.Cu")
		(net "SGPIO_LD_1")
	)
	(segment
		(start 12.1158 -63.026798)
		(end 12.1158 -63.952628)
		(width 0.10668)
		(layer "In4.Cu")
		(net "SGPIO_LD_1")
	)
	(segment
		(start 13.50391 -71.746364)
		(end 12.98194 -72.268334)
		(width 0.10668)
		(layer "In4.Cu")
		(net "SGPIO_LD_1")
	)
	(segment
		(start 14.0208 -69.641974)
		(end 13.87729 -69.785484)
		(width 0.10668)
		(layer "In4.Cu")
		(net "SGPIO_LD_1")
	)
	(segment
		(start 13.50391 -71.256144)
		(end 13.87729 -71.256144)
		(width 0.10668)
		(layer "In4.Cu")
		(net "SGPIO_LD_1")
	)
	(segment
		(start 13.84808 -48.88738)
		(end 13.6271 -49.10836)
		(width 0.10668)
		(layer "In4.Cu")
		(net "SGPIO_LD_1")
	)
	(segment
		(start 26.04516 -23.75916)
		(end 25.146 -21.588984)
		(width 0.10668)
		(layer "In4.Cu")
		(net "SGPIO_LD_1")
	)
	(segment
		(start 48.448976 -28.69565)
		(end 47.660306 -27.90698)
		(width 0.10668)
		(layer "In4.Cu")
		(net "SGPIO_LD_1")
	)
	(segment
		(start 13.87729 -69.295264)
		(end 14.0208 -69.438774)
		(width 0.10668)
		(layer "In4.Cu")
		(net "SGPIO_LD_1")
	)
	(segment
		(start 13.3604 -67.310254)
		(end 13.3604 -68.171314)
		(width 0.10668)
		(layer "In4.Cu")
		(net "SGPIO_LD_1")
	)
	(segment
		(start 13.3604 -69.151754)
		(end 13.50391 -69.295264)
		(width 0.10668)
		(layer "In4.Cu")
		(net "SGPIO_LD_1")
	)
	(segment
		(start 13.027152 -64.750696)
		(end 12.296648 -64.750696)
		(width 0.10668)
		(layer "In4.Cu")
		(net "SGPIO_LD_1")
	)
	(segment
		(start 12.296648 -62.22873)
		(end 14.043152 -62.22873)
		(width 0.10668)
		(layer "In4.Cu")
		(net "SGPIO_LD_1")
	)
	(segment
		(start 14.0208 -68.661534)
		(end 13.87729 -68.805044)
		(width 0.10668)
		(layer "In4.Cu")
		(net "SGPIO_LD_1")
	)
	(segment
		(start 13.3604 -68.171314)
		(end 13.50391 -68.314824)
		(width 0.10668)
		(layer "In4.Cu")
		(net "SGPIO_LD_1")
	)
	(segment
		(start 13.50391 -69.785484)
		(end 13.3604 -69.928994)
		(width 0.10668)
		(layer "In4.Cu")
		(net "SGPIO_LD_1")
	)
	(segment
		(start 47.660306 -27.90698)
		(end 41.570148 -27.90698)
		(width 0.10668)
		(layer "In4.Cu")
		(net "SGPIO_LD_1")
	)
	(segment
		(start 13.87729 -70.275704)
		(end 14.0208 -70.419214)
		(width 0.10668)
		(layer "In4.Cu")
		(net "SGPIO_LD_1")
	)
	(segment
		(start 13.50391 -68.805044)
		(end 13.3604 -68.948554)
		(width 0.10668)
		(layer "In4.Cu")
		(net "SGPIO_LD_1")
	)
	(segment
		(start 12.1158 -61.340746)
		(end 12.1158 -62.047882)
		(width 0.10668)
		(layer "In4.Cu")
		(net "SGPIO_LD_1")
	)
	(segment
		(start 12.296648 -64.133476)
		(end 13.027152 -64.133476)
		(width 0.10668)
		(layer "In4.Cu")
		(net "SGPIO_LD_1")
	)
	(segment
		(start 14.0208 -68.458334)
		(end 14.0208 -68.661534)
		(width 0.10668)
		(layer "In4.Cu")
		(net "SGPIO_LD_1")
	)
	(segment
		(start 11.63828 -52.71008)
		(end 11.63828 -55.40248)
		(width 0.10668)
		(layer "In4.Cu")
		(net "SGPIO_LD_1")
	)
	(segment
		(start 13.87729 -68.314824)
		(end 14.0208 -68.458334)
		(width 0.10668)
		(layer "In4.Cu")
		(net "SGPIO_LD_1")
	)
	(segment
		(start 14.0208 -71.602854)
		(end 13.87729 -71.746364)
		(width 0.10668)
		(layer "In4.Cu")
		(net "SGPIO_LD_1")
	)
	(segment
		(start 13.50391 -70.275704)
		(end 13.87729 -70.275704)
		(width 0.10668)
		(layer "In4.Cu")
		(net "SGPIO_LD_1")
	)
	(segment
		(start 13.87729 -68.805044)
		(end 13.50391 -68.805044)
		(width 0.10668)
		(layer "In4.Cu")
		(net "SGPIO_LD_1")
	)
	(segment
		(start 15.621 -21.691346)
		(end 15.621 -27.951176)
		(width 0.10668)
		(layer "In4.Cu")
		(net "SGPIO_LD_1")
	)
	(segment
		(start 13.50391 -68.314824)
		(end 13.87729 -68.314824)
		(width 0.10668)
		(layer "In4.Cu")
		(net "SGPIO_LD_1")
	)
	(segment
		(start 32.78378 -27.55138)
		(end 31.0134 -25.781)
		(width 0.10668)
		(layer "In4.Cu")
		(net "SGPIO_LD_1")
	)
	(segment
		(start 13.027152 -64.133476)
		(end 13.208 -64.314324)
		(width 0.10668)
		(layer "In4.Cu")
		(net "SGPIO_LD_1")
	)
	(segment
		(start 13.87729 -71.746364)
		(end 13.50391 -71.746364)
		(width 0.10668)
		(layer "In4.Cu")
		(net "SGPIO_LD_1")
	)
	(segment
		(start 41.570148 -27.90698)
		(end 40.434768 -26.7716)
		(width 0.10668)
		(layer "In4.Cu")
		(net "SGPIO_LD_1")
	)
	(segment
		(start 25.146 -21.588984)
		(end 25.146 -21.261832)
		(width 0.10668)
		(layer "In4.Cu")
		(net "SGPIO_LD_1")
	)
	(segment
		(start 13.84808 -46.589188)
		(end 13.84808 -48.88738)
		(width 0.10668)
		(layer "In4.Cu")
		(net "SGPIO_LD_1")
	)
	(segment
		(start 13.87729 -70.765924)
		(end 13.50391 -70.765924)
		(width 0.10668)
		(layer "In4.Cu")
		(net "SGPIO_LD_1")
	)
	(segment
		(start 13.3604 -69.928994)
		(end 13.3604 -70.132194)
		(width 0.10668)
		(layer "In4.Cu")
		(net "SGPIO_LD_1")
	)
	(segment
		(start 48.448976 -29.071824)
		(end 48.448976 -28.69565)
		(width 0.10668)
		(layer "In4.Cu")
		(net "SGPIO_LD_1")
	)
	(segment
		(start 25.146 -21.261832)
		(end 24.284178 -20.40001)
		(width 0.10668)
		(layer "In4.Cu")
		(net "SGPIO_LD_1")
	)
	(segment
		(start 14.043152 -62.84595)
		(end 12.296648 -62.84595)
		(width 0.10668)
		(layer "In4.Cu")
		(net "SGPIO_LD_1")
	)
	(segment
		(start 13.3604 -70.909434)
		(end 13.3604 -71.112634)
		(width 0.10668)
		(layer "In4.Cu")
		(net "SGPIO_LD_1")
	)
	(segment
		(start 11.6332 -49.9618)
		(end 11.6332 -52.705)
		(width 0.10668)
		(layer "In4.Cu")
		(net "SGPIO_LD_1")
	)
	(segment
		(start 13.87729 -71.256144)
		(end 14.0208 -71.399654)
		(width 0.10668)
		(layer "In4.Cu")
		(net "SGPIO_LD_1")
	)
	(segment
		(start 13.50391 -70.765924)
		(end 13.3604 -70.909434)
		(width 0.10668)
		(layer "In4.Cu")
		(net "SGPIO_LD_1")
	)
	(segment
		(start 12.98194 -72.268334)
		(end 12.98194 -80.28686)
		(width 0.10668)
		(layer "In4.Cu")
		(net "SGPIO_LD_1")
	)
	(segment
		(start 12.1158 -66.065654)
		(end 13.3604 -67.310254)
		(width 0.10668)
		(layer "In4.Cu")
		(net "SGPIO_LD_1")
	)
	(segment
		(start 31.0134 -25.781)
		(end 29.255466 -25.781)
		(width 0.10668)
		(layer "In4.Cu")
		(net "SGPIO_LD_1")
	)
	(segment
		(start 12.2682 -56.922924)
		(end 12.2682 -61.188346)
		(width 0.10668)
		(layer "In4.Cu")
		(net "SGPIO_LD_1")
	)
	(segment
		(start 14.0208 -71.399654)
		(end 14.0208 -71.602854)
		(width 0.10668)
		(layer "In4.Cu")
		(net "SGPIO_LD_1")
	)
	(segment
		(start 14.224 -62.409578)
		(end 14.224 -62.665102)
		(width 0.10668)
		(layer "In4.Cu")
		(net "SGPIO_LD_1")
	)
	(segment
		(start 13.3604 -71.112634)
		(end 13.50391 -71.256144)
		(width 0.10668)
		(layer "In4.Cu")
		(net "SGPIO_LD_1")
	)
	(segment
		(start 13.87729 -69.785484)
		(end 13.50391 -69.785484)
		(width 0.10668)
		(layer "In4.Cu")
		(net "SGPIO_LD_1")
	)
	(segment
		(start 12.2682 -61.188346)
		(end 12.1158 -61.340746)
		(width 0.10668)
		(layer "In4.Cu")
		(net "SGPIO_LD_1")
	)
	(segment
		(start 12.296648 -64.750696)
		(end 12.1158 -64.931544)
		(width 0.10668)
		(layer "In4.Cu")
		(net "SGPIO_LD_1")
	)
	(segment
		(start 12.9413 -80.3275)
		(end 12.9413 -80.7847)
		(width 0.10668)
		(layer "In4.Cu")
		(net "SGPIO_LD_1")
	)
	(segment
		(start 12.296648 -62.84595)
		(end 12.1158 -63.026798)
		(width 0.10668)
		(layer "In4.Cu")
		(net "SGPIO_LD_1")
	)
	(segment
		(start 29.255466 -25.781)
		(end 27.835606 -24.36114)
		(width 0.10668)
		(layer "In4.Cu")
		(net "SGPIO_LD_1")
	)
	(segment
		(start 23.335488 -110.252002)
		(end 23.579582 -110.252002)
		(width 0.10668)
		(layer "In7.Cu")
		(net "SGPIO_LD_1")
	)
	(segment
		(start 7.5438 -95.8342)
		(end 7.5438 -104.523032)
		(width 0.10668)
		(layer "In7.Cu")
		(net "SGPIO_LD_1")
	)
	(segment
		(start 21.694902 -111.995966)
		(end 21.694902 -111.751618)
		(width 0.10668)
		(layer "In7.Cu")
		(net "SGPIO_LD_1")
	)
	(segment
		(start 18.080228 -112.134396)
		(end 20.529804 -112.134396)
		(width 0.10668)
		(layer "In7.Cu")
		(net "SGPIO_LD_1")
	)
	(segment
		(start 27.051762 -110.7694)
		(end 27.113992 -110.619032)
		(width 0.10668)
		(layer "In7.Cu")
		(net "SGPIO_LD_1")
	)
	(segment
		(start 23.579582 -110.252002)
		(end 23.752302 -110.424722)
		(width 0.10668)
		(layer "In7.Cu")
		(net "SGPIO_LD_1")
	)
	(segment
		(start 8.382 -89.382346)
		(end 8.382 -90.800682)
		(width 0.10668)
		(layer "In7.Cu")
		(net "SGPIO_LD_1")
	)
	(segment
		(start 21.425916 -111.238284)
		(end 21.971 -110.6932)
		(width 0.10668)
		(layer "In7.Cu")
		(net "SGPIO_LD_1")
	)
	(segment
		(start 28.403042 -111.51616)
		(end 35.009328 -111.51616)
		(width 0.10668)
		(layer "In7.Cu")
		(net "SGPIO_LD_1")
	)
	(segment
		(start 27.56535 -110.619286)
		(end 27.658822 -110.844838)
		(width 0.10668)
		(layer "In7.Cu")
		(net "SGPIO_LD_1")
	)
	(segment
		(start 12.9413 -80.7847)
		(end 12.9413 -81.825846)
		(width 0.10668)
		(layer "In7.Cu")
		(net "SGPIO_LD_1")
	)
	(segment
		(start 11.11885 -81.83626)
		(end 10.35558 -82.59953)
		(width 0.10668)
		(layer "In7.Cu")
		(net "SGPIO_LD_1")
	)
	(segment
		(start 23.925022 -110.6932)
		(end 25.10282 -110.6932)
		(width 0.10668)
		(layer "In7.Cu")
		(net "SGPIO_LD_1")
	)
	(segment
		(start 37.775388 -114.28222)
		(end 38.455092 -114.28222)
		(width 0.10668)
		(layer "In7.Cu")
		(net "SGPIO_LD_1")
	)
	(segment
		(start 27.658822 -110.844838)
		(end 27.596592 -110.995206)
		(width 0.10668)
		(layer "In7.Cu")
		(net "SGPIO_LD_1")
	)
	(segment
		(start 12.572746 -82.1944)
		(end 12.014454 -82.1944)
		(width 0.10668)
		(layer "In7.Cu")
		(net "SGPIO_LD_1")
	)
	(segment
		(start 20.529804 -112.134396)
		(end 20.7645 -111.8997)
		(width 0.10668)
		(layer "In7.Cu")
		(net "SGPIO_LD_1")
	)
	(segment
		(start 10.35558 -88.069674)
		(end 9.510268 -88.914986)
		(width 0.10668)
		(layer "In7.Cu")
		(net "SGPIO_LD_1")
	)
	(segment
		(start 21.425916 -111.482632)
		(end 21.425916 -111.238284)
		(width 0.10668)
		(layer "In7.Cu")
		(net "SGPIO_LD_1")
	)
	(segment
		(start 21.277834 -112.168686)
		(end 21.522182 -112.168686)
		(width 0.10668)
		(layer "In7.Cu")
		(net "SGPIO_LD_1")
	)
	(segment
		(start 21.008848 -111.8997)
		(end 21.277834 -112.168686)
		(width 0.10668)
		(layer "In7.Cu")
		(net "SGPIO_LD_1")
	)
	(segment
		(start 12.014454 -82.1944)
		(end 11.656314 -81.83626)
		(width 0.10668)
		(layer "In7.Cu")
		(net "SGPIO_LD_1")
	)
	(segment
		(start 10.35558 -82.59953)
		(end 10.35558 -88.069674)
		(width 0.10668)
		(layer "In7.Cu")
		(net "SGPIO_LD_1")
	)
	(segment
		(start 25.692354 -111.48441)
		(end 25.865074 -111.31169)
		(width 0.10668)
		(layer "In7.Cu")
		(net "SGPIO_LD_1")
	)
	(segment
		(start 22.990048 -110.6932)
		(end 23.162768 -110.52048)
		(width 0.10668)
		(layer "In7.Cu")
		(net "SGPIO_LD_1")
	)
	(segment
		(start 35.009328 -111.51616)
		(end 37.775388 -114.28222)
		(width 0.10668)
		(layer "In7.Cu")
		(net "SGPIO_LD_1")
	)
	(segment
		(start 23.162768 -110.424722)
		(end 23.335488 -110.252002)
		(width 0.10668)
		(layer "In7.Cu")
		(net "SGPIO_LD_1")
	)
	(segment
		(start 8.001 -95.377)
		(end 7.5438 -95.8342)
		(width 0.10668)
		(layer "In7.Cu")
		(net "SGPIO_LD_1")
	)
	(segment
		(start 9.510268 -88.914986)
		(end 8.84936 -88.914986)
		(width 0.10668)
		(layer "In7.Cu")
		(net "SGPIO_LD_1")
	)
	(segment
		(start 21.971 -110.6932)
		(end 22.990048 -110.6932)
		(width 0.10668)
		(layer "In7.Cu")
		(net "SGPIO_LD_1")
	)
	(segment
		(start 27.596592 -110.995206)
		(end 27.690064 -111.220758)
		(width 0.10668)
		(layer "In7.Cu")
		(net "SGPIO_LD_1")
	)
	(segment
		(start 8.001 -91.181682)
		(end 8.001 -95.377)
		(width 0.10668)
		(layer "In7.Cu")
		(net "SGPIO_LD_1")
	)
	(segment
		(start 26.82621 -110.862872)
		(end 27.051762 -110.7694)
		(width 0.10668)
		(layer "In7.Cu")
		(net "SGPIO_LD_1")
	)
	(segment
		(start 25.865074 -110.86592)
		(end 26.037794 -110.6932)
		(width 0.10668)
		(layer "In7.Cu")
		(net "SGPIO_LD_1")
	)
	(segment
		(start 27.690064 -111.220758)
		(end 28.403042 -111.51616)
		(width 0.10668)
		(layer "In7.Cu")
		(net "SGPIO_LD_1")
	)
	(segment
		(start 23.752302 -110.52048)
		(end 23.925022 -110.6932)
		(width 0.10668)
		(layer "In7.Cu")
		(net "SGPIO_LD_1")
	)
	(segment
		(start 25.865074 -111.31169)
		(end 25.865074 -110.86592)
		(width 0.10668)
		(layer "In7.Cu")
		(net "SGPIO_LD_1")
	)
	(segment
		(start 25.27554 -110.86592)
		(end 25.27554 -111.31169)
		(width 0.10668)
		(layer "In7.Cu")
		(net "SGPIO_LD_1")
	)
	(segment
		(start 27.113992 -110.619032)
		(end 27.33929 -110.52556)
		(width 0.10668)
		(layer "In7.Cu")
		(net "SGPIO_LD_1")
	)
	(segment
		(start 14.001496 -110.980728)
		(end 16.92656 -110.980728)
		(width 0.10668)
		(layer "In7.Cu")
		(net "SGPIO_LD_1")
	)
	(segment
		(start 8.382 -90.800682)
		(end 8.001 -91.181682)
		(width 0.10668)
		(layer "In7.Cu")
		(net "SGPIO_LD_1")
	)
	(segment
		(start 25.27554 -111.31169)
		(end 25.44826 -111.48441)
		(width 0.10668)
		(layer "In7.Cu")
		(net "SGPIO_LD_1")
	)
	(segment
		(start 23.162768 -110.52048)
		(end 23.162768 -110.424722)
		(width 0.10668)
		(layer "In7.Cu")
		(net "SGPIO_LD_1")
	)
	(segment
		(start 16.92656 -110.980728)
		(end 18.080228 -112.134396)
		(width 0.10668)
		(layer "In7.Cu")
		(net "SGPIO_LD_1")
	)
	(segment
		(start 21.522182 -112.168686)
		(end 21.694902 -111.995966)
		(width 0.10668)
		(layer "In7.Cu")
		(net "SGPIO_LD_1")
	)
	(segment
		(start 20.7645 -111.8997)
		(end 21.008848 -111.8997)
		(width 0.10668)
		(layer "In7.Cu")
		(net "SGPIO_LD_1")
	)
	(segment
		(start 25.44826 -111.48441)
		(end 25.692354 -111.48441)
		(width 0.10668)
		(layer "In7.Cu")
		(net "SGPIO_LD_1")
	)
	(segment
		(start 25.10282 -110.6932)
		(end 25.27554 -110.86592)
		(width 0.10668)
		(layer "In7.Cu")
		(net "SGPIO_LD_1")
	)
	(segment
		(start 26.416254 -110.6932)
		(end 26.82621 -110.862872)
		(width 0.10668)
		(layer "In7.Cu")
		(net "SGPIO_LD_1")
	)
	(segment
		(start 12.9413 -81.825846)
		(end 12.572746 -82.1944)
		(width 0.10668)
		(layer "In7.Cu")
		(net "SGPIO_LD_1")
	)
	(segment
		(start 27.33929 -110.52556)
		(end 27.56535 -110.619286)
		(width 0.10668)
		(layer "In7.Cu")
		(net "SGPIO_LD_1")
	)
	(segment
		(start 23.752302 -110.424722)
		(end 23.752302 -110.52048)
		(width 0.10668)
		(layer "In7.Cu")
		(net "SGPIO_LD_1")
	)
	(segment
		(start 8.84936 -88.914986)
		(end 8.382 -89.382346)
		(width 0.10668)
		(layer "In7.Cu")
		(net "SGPIO_LD_1")
	)
	(segment
		(start 21.694902 -111.751618)
		(end 21.425916 -111.482632)
		(width 0.10668)
		(layer "In7.Cu")
		(net "SGPIO_LD_1")
	)
	(segment
		(start 11.656314 -81.83626)
		(end 11.11885 -81.83626)
		(width 0.10668)
		(layer "In7.Cu")
		(net "SGPIO_LD_1")
	)
	(segment
		(start 7.5438 -104.523032)
		(end 14.001496 -110.980728)
		(width 0.10668)
		(layer "In7.Cu")
		(net "SGPIO_LD_1")
	)
	(segment
		(start 26.037794 -110.6932)
		(end 26.416254 -110.6932)
		(width 0.10668)
		(layer "In7.Cu")
		(net "SGPIO_LD_1")
	)
	(segment
		(start 40.4876 -114.554)
		(end 40.657526 -114.723926)
		(width 0.11684)
		(layer "F.Cu")
		(net "SGPIO_LD_0")
	)
	(segment
		(start 16.4846 -83.29295)
		(end 16.002 -82.81035)
		(width 0.11684)
		(layer "F.Cu")
		(net "SGPIO_LD_0")
	)
	(segment
		(start 40.486584 -114.149632)
		(end 40.4876 -114.149632)
		(width 0.11684)
		(layer "F.Cu")
		(net "SGPIO_LD_0")
	)
	(segment
		(start 40.4876 -114.149632)
		(end 40.4876 -114.554)
		(width 0.11684)
		(layer "F.Cu")
		(net "SGPIO_LD_0")
	)
	(segment
		(start 40.657526 -114.723926)
		(end 41.455086 -116.6495)
		(width 0.11684)
		(layer "F.Cu")
		(net "SGPIO_LD_0")
	)
	(segment
		(start 16.002 -82.81035)
		(end 16.002 -82.3214)
		(width 0.11684)
		(layer "F.Cu")
		(net "SGPIO_LD_0")
	)
	(segment
		(start 41.455086 -116.6495)
		(end 41.455086 -118.460012)
		(width 0.11684)
		(layer "F.Cu")
		(net "SGPIO_LD_0")
	)
	(via
		(at 40.486584 -114.149632)
		(size 0.508)
		(drill 0.254)
		(layers "F.Cu" "B.Cu")
		(net "SGPIO_LD_0")
	)
	(via
		(at 29.9466 -108.19892)
		(size 0.6604)
		(drill 0.3302)
		(layers "F.Cu" "B.Cu")
		(net "SGPIO_LD_0")
	)
	(via
		(at 30.353 -110.1344)
		(size 0.508)
		(drill 0.254)
		(layers "F.Cu" "B.Cu")
		(net "SGPIO_LD_0")
	)
	(via
		(at 16.002 -82.3214)
		(size 0.508)
		(drill 0.254)
		(layers "F.Cu" "B.Cu")
		(net "SGPIO_LD_0")
	)
	(segment
		(start 29.9466 -108.19892)
		(end 29.9466 -107.189524)
		(width 0.11684)
		(layer "B.Cu")
		(net "SGPIO_LD_0")
	)
	(segment
		(start 29.8196 -107.062524)
		(end 29.8196 -106.64825)
		(width 0.11684)
		(layer "B.Cu")
		(net "SGPIO_LD_0")
	)
	(segment
		(start 30.353 -110.1344)
		(end 29.9466 -109.728)
		(width 0.11684)
		(layer "B.Cu")
		(net "SGPIO_LD_0")
	)
	(segment
		(start 29.9466 -107.189524)
		(end 29.8196 -107.062524)
		(width 0.11684)
		(layer "B.Cu")
		(net "SGPIO_LD_0")
	)
	(segment
		(start 29.9466 -109.728)
		(end 29.9466 -108.19892)
		(width 0.11684)
		(layer "B.Cu")
		(net "SGPIO_LD_0")
	)
	(segment
		(start 13.97762 -81.8896)
		(end 13.87094 -81.99628)
		(width 0.10668)
		(layer "In7.Cu")
		(net "SGPIO_LD_0")
	)
	(segment
		(start 14.01826 -103.68026)
		(end 14.01826 -104.191308)
		(width 0.10668)
		(layer "In7.Cu")
		(net "SGPIO_LD_0")
	)
	(segment
		(start 11.80084 -97.73031)
		(end 12.573 -99.595686)
		(width 0.10668)
		(layer "In7.Cu")
		(net "SGPIO_LD_0")
	)
	(segment
		(start 12.573 -102.235)
		(end 14.01826 -103.68026)
		(width 0.10668)
		(layer "In7.Cu")
		(net "SGPIO_LD_0")
	)
	(segment
		(start 30.353 -110.1344)
		(end 30.9118 -110.6932)
		(width 0.10668)
		(layer "In7.Cu")
		(net "SGPIO_LD_0")
	)
	(segment
		(start 13.04163 -83.12912)
		(end 13.041376 -83.12912)
		(width 0.10668)
		(layer "In7.Cu")
		(net "SGPIO_LD_0")
	)
	(segment
		(start 15.5702 -81.8896)
		(end 13.97762 -81.8896)
		(width 0.10668)
		(layer "In7.Cu")
		(net "SGPIO_LD_0")
	)
	(segment
		(start 35.350704 -110.6932)
		(end 37.204904 -112.5474)
		(width 0.10668)
		(layer "In7.Cu")
		(net "SGPIO_LD_0")
	)
	(segment
		(start 40.486838 -114.1476)
		(end 40.4876 -114.1476)
		(width 0.10668)
		(layer "In7.Cu")
		(net "SGPIO_LD_0")
	)
	(segment
		(start 40.184578 -114.022378)
		(end 40.486838 -114.1476)
		(width 0.10668)
		(layer "In7.Cu")
		(net "SGPIO_LD_0")
	)
	(segment
		(start 13.041376 -83.12912)
		(end 11.80084 -84.369656)
		(width 0.10668)
		(layer "In7.Cu")
		(net "SGPIO_LD_0")
	)
	(segment
		(start 30.9118 -110.6932)
		(end 35.350704 -110.6932)
		(width 0.10668)
		(layer "In7.Cu")
		(net "SGPIO_LD_0")
	)
	(segment
		(start 13.87094 -82.4992)
		(end 13.98524 -82.775552)
		(width 0.10668)
		(layer "In7.Cu")
		(net "SGPIO_LD_0")
	)
	(segment
		(start 13.98524 -82.92338)
		(end 13.8303 -83.07832)
		(width 0.10668)
		(layer "In7.Cu")
		(net "SGPIO_LD_0")
	)
	(segment
		(start 29.591 -109.3724)
		(end 30.353 -110.1344)
		(width 0.10668)
		(layer "In7.Cu")
		(net "SGPIO_LD_0")
	)
	(segment
		(start 13.87094 -81.99628)
		(end 13.87094 -82.4992)
		(width 0.10668)
		(layer "In7.Cu")
		(net "SGPIO_LD_0")
	)
	(segment
		(start 21.407628 -106.601768)
		(end 24.17826 -109.3724)
		(width 0.10668)
		(layer "In7.Cu")
		(net "SGPIO_LD_0")
	)
	(segment
		(start 40.4876 -114.149632)
		(end 40.486584 -114.149632)
		(width 0.10668)
		(layer "In7.Cu")
		(net "SGPIO_LD_0")
	)
	(segment
		(start 24.17826 -109.3724)
		(end 29.591 -109.3724)
		(width 0.10668)
		(layer "In7.Cu")
		(net "SGPIO_LD_0")
	)
	(segment
		(start 14.01826 -104.191308)
		(end 15.879572 -106.05262)
		(width 0.10668)
		(layer "In7.Cu")
		(net "SGPIO_LD_0")
	)
	(segment
		(start 39.8272 -113.665)
		(end 40.184578 -114.022378)
		(width 0.10668)
		(layer "In7.Cu")
		(net "SGPIO_LD_0")
	)
	(segment
		(start 19.708368 -106.601768)
		(end 21.407628 -106.601768)
		(width 0.10668)
		(layer "In7.Cu")
		(net "SGPIO_LD_0")
	)
	(segment
		(start 12.573 -99.595686)
		(end 12.573 -102.235)
		(width 0.10668)
		(layer "In7.Cu")
		(net "SGPIO_LD_0")
	)
	(segment
		(start 13.8303 -83.07832)
		(end 13.09243 -83.07832)
		(width 0.10668)
		(layer "In7.Cu")
		(net "SGPIO_LD_0")
	)
	(segment
		(start 37.204904 -112.5474)
		(end 38.9382 -112.5474)
		(width 0.10668)
		(layer "In7.Cu")
		(net "SGPIO_LD_0")
	)
	(segment
		(start 38.9382 -112.5474)
		(end 39.8272 -113.4364)
		(width 0.10668)
		(layer "In7.Cu")
		(net "SGPIO_LD_0")
	)
	(segment
		(start 16.002 -82.3214)
		(end 15.5702 -81.8896)
		(width 0.10668)
		(layer "In7.Cu")
		(net "SGPIO_LD_0")
	)
	(segment
		(start 40.4876 -114.1476)
		(end 40.4876 -114.149632)
		(width 0.10668)
		(layer "In7.Cu")
		(net "SGPIO_LD_0")
	)
	(segment
		(start 39.8272 -113.4364)
		(end 39.8272 -113.665)
		(width 0.10668)
		(layer "In7.Cu")
		(net "SGPIO_LD_0")
	)
	(segment
		(start 13.98524 -82.775552)
		(end 13.98524 -82.92338)
		(width 0.10668)
		(layer "In7.Cu")
		(net "SGPIO_LD_0")
	)
	(segment
		(start 19.15922 -106.05262)
		(end 19.708368 -106.601768)
		(width 0.10668)
		(layer "In7.Cu")
		(net "SGPIO_LD_0")
	)
	(segment
		(start 13.09243 -83.07832)
		(end 13.04163 -83.12912)
		(width 0.10668)
		(layer "In7.Cu")
		(net "SGPIO_LD_0")
	)
	(segment
		(start 11.80084 -84.369656)
		(end 11.80084 -97.73031)
		(width 0.10668)
		(layer "In7.Cu")
		(net "SGPIO_LD_0")
	)
	(segment
		(start 15.879572 -106.05262)
		(end 19.15922 -106.05262)
		(width 0.10668)
		(layer "In7.Cu")
		(net "SGPIO_LD_0")
	)
	(segment
		(start 40.254936 -117.303296)
		(end 40.254936 -118.25986)
		(width 0.11684)
		(layer "F.Cu")
		(net "SGPIO_DO_1")
	)
	(segment
		(start 40.005 -115.16106)
		(end 40.005 -116.699792)
		(width 0.11684)
		(layer "F.Cu")
		(net "SGPIO_DO_1")
	)
	(segment
		(start 39.8653 -113.017046)
		(end 39.8653 -114.4397)
		(width 0.11684)
		(layer "F.Cu")
		(net "SGPIO_DO_1")
	)
	(segment
		(start 40.005 -114.5794)
		(end 40.005 -115.16106)
		(width 0.11684)
		(layer "F.Cu")
		(net "SGPIO_DO_1")
	)
	(segment
		(start 39.8653 -114.4397)
		(end 40.005 -114.5794)
		(width 0.11684)
		(layer "F.Cu")
		(net "SGPIO_DO_1")
	)
	(segment
		(start 39.487856 -109.280198)
		(end 39.487856 -112.10544)
		(width 0.11684)
		(layer "F.Cu")
		(net "SGPIO_DO_1")
	)
	(segment
		(start 39.487856 -112.10544)
		(end 39.8653 -113.017046)
		(width 0.11684)
		(layer "F.Cu")
		(net "SGPIO_DO_1")
	)
	(segment
		(start 40.0304 -109.07395)
		(end 39.694104 -109.07395)
		(width 0.11684)
		(layer "F.Cu")
		(net "SGPIO_DO_1")
	)
	(segment
		(start 40.005 -116.699792)
		(end 40.254936 -117.303296)
		(width 0.11684)
		(layer "F.Cu")
		(net "SGPIO_DO_1")
	)
	(segment
		(start 39.694104 -109.07395)
		(end 39.487856 -109.280198)
		(width 0.11684)
		(layer "F.Cu")
		(net "SGPIO_DO_1")
	)
	(via
		(at 49.930558 -35.86099)
		(size 0.508)
		(drill 0.254)
		(layers "F.Cu" "B.Cu")
		(net "SGPIO_DO_1")
	)
	(via
		(at 40.005 -115.16106)
		(size 0.508)
		(drill 0.254)
		(layers "F.Cu" "B.Cu")
		(net "SGPIO_DO_1")
	)
	(via
		(at 13.4112 -81.8896)
		(size 0.508)
		(drill 0.254)
		(layers "F.Cu" "B.Cu")
		(net "SGPIO_DO_1")
	)
	(segment
		(start 49.930558 -36.473384)
		(end 49.868328 -36.535614)
		(width 0.11684)
		(layer "B.Cu")
		(net "SGPIO_DO_1")
	)
	(segment
		(start 49.930558 -35.86099)
		(end 49.930558 -36.473384)
		(width 0.11684)
		(layer "B.Cu")
		(net "SGPIO_DO_1")
	)
	(segment
		(start 49.17694 -31.32074)
		(end 47.983394 -30.127194)
		(width 0.10668)
		(layer "In4.Cu")
		(net "SGPIO_DO_1")
	)
	(segment
		(start 14.2494 -54.278022)
		(end 14.2494 -55.5244)
		(width 0.10668)
		(layer "In4.Cu")
		(net "SGPIO_DO_1")
	)
	(segment
		(start 24.73452 -21.759418)
		(end 24.73452 -21.43252)
		(width 0.10668)
		(layer "In4.Cu")
		(net "SGPIO_DO_1")
	)
	(segment
		(start 15.240762 -53.28666)
		(end 14.2494 -54.278022)
		(width 0.10668)
		(layer "In4.Cu")
		(net "SGPIO_DO_1")
	)
	(segment
		(start 32.613092 -27.96286)
		(end 31.828232 -27.178)
		(width 0.10668)
		(layer "In4.Cu")
		(net "SGPIO_DO_1")
	)
	(segment
		(start 24.73452 -21.43252)
		(end 24.11349 -20.81149)
		(width 0.10668)
		(layer "In4.Cu")
		(net "SGPIO_DO_1")
	)
	(segment
		(start 17.212056 -20.81149)
		(end 16.33728 -21.686266)
		(width 0.10668)
		(layer "In4.Cu")
		(net "SGPIO_DO_1")
	)
	(segment
		(start 15.044674 -48.630332)
		(end 15.574264 -49.159922)
		(width 0.10668)
		(layer "In4.Cu")
		(net "SGPIO_DO_1")
	)
	(segment
		(start 13.98651 -67.760342)
		(end 14.50467 -67.760342)
		(width 0.10668)
		(layer "In4.Cu")
		(net "SGPIO_DO_1")
	)
	(segment
		(start 41.39946 -28.31846)
		(end 40.3098 -27.2288)
		(width 0.10668)
		(layer "In4.Cu")
		(net "SGPIO_DO_1")
	)
	(segment
		(start 13.843 -67.616832)
		(end 13.98651 -67.760342)
		(width 0.10668)
		(layer "In4.Cu")
		(net "SGPIO_DO_1")
	)
	(segment
		(start 13.98651 -66.289682)
		(end 13.843 -66.433192)
		(width 0.10668)
		(layer "In4.Cu")
		(net "SGPIO_DO_1")
	)
	(segment
		(start 13.98651 -67.270122)
		(end 13.843 -67.413632)
		(width 0.10668)
		(layer "In4.Cu")
		(net "SGPIO_DO_1")
	)
	(segment
		(start 13.98651 -65.309242)
		(end 13.843 -65.452752)
		(width 0.10668)
		(layer "In4.Cu")
		(net "SGPIO_DO_1")
	)
	(segment
		(start 14.64818 -65.165732)
		(end 14.50467 -65.309242)
		(width 0.10668)
		(layer "In4.Cu")
		(net "SGPIO_DO_1")
	)
	(segment
		(start 14.2494 -55.5244)
		(end 14.859 -56.134)
		(width 0.10668)
		(layer "In4.Cu")
		(net "SGPIO_DO_1")
	)
	(segment
		(start 16.665448 -33.698688)
		(end 16.665448 -40.797988)
		(width 0.10668)
		(layer "In4.Cu")
		(net "SGPIO_DO_1")
	)
	(segment
		(start 24.11349 -20.81149)
		(end 17.212056 -20.81149)
		(width 0.10668)
		(layer "In4.Cu")
		(net "SGPIO_DO_1")
	)
	(segment
		(start 14.64818 -71.63562)
		(end 13.4112 -72.8726)
		(width 0.10668)
		(layer "In4.Cu")
		(net "SGPIO_DO_1")
	)
	(segment
		(start 13.98651 -66.779902)
		(end 14.50467 -66.779902)
		(width 0.10668)
		(layer "In4.Cu")
		(net "SGPIO_DO_1")
	)
	(segment
		(start 14.50467 -64.328802)
		(end 13.98651 -64.328802)
		(width 0.10668)
		(layer "In4.Cu")
		(net "SGPIO_DO_1")
	)
	(segment
		(start 16.665448 -40.797988)
		(end 16.2306 -41.232836)
		(width 0.10668)
		(layer "In4.Cu")
		(net "SGPIO_DO_1")
	)
	(segment
		(start 31.828232 -27.178)
		(end 27.79141 -27.178)
		(width 0.10668)
		(layer "In4.Cu")
		(net "SGPIO_DO_1")
	)
	(segment
		(start 14.64818 -67.126612)
		(end 14.50467 -67.270122)
		(width 0.10668)
		(layer "In4.Cu")
		(net "SGPIO_DO_1")
	)
	(segment
		(start 13.98651 -64.819022)
		(end 14.50467 -64.819022)
		(width 0.10668)
		(layer "In4.Cu")
		(net "SGPIO_DO_1")
	)
	(segment
		(start 13.843 -66.433192)
		(end 13.843 -66.636392)
		(width 0.10668)
		(layer "In4.Cu")
		(net "SGPIO_DO_1")
	)
	(segment
		(start 14.9098 -63.923672)
		(end 14.50467 -64.328802)
		(width 0.10668)
		(layer "In4.Cu")
		(net "SGPIO_DO_1")
	)
	(segment
		(start 47.983394 -28.812236)
		(end 47.489618 -28.31846)
		(width 0.10668)
		(layer "In4.Cu")
		(net "SGPIO_DO_1")
	)
	(segment
		(start 16.2306 -45.866304)
		(end 15.044674 -47.05223)
		(width 0.10668)
		(layer "In4.Cu")
		(net "SGPIO_DO_1")
	)
	(segment
		(start 14.50467 -67.760342)
		(end 14.64818 -67.903852)
		(width 0.10668)
		(layer "In4.Cu")
		(net "SGPIO_DO_1")
	)
	(segment
		(start 13.98651 -65.799462)
		(end 14.50467 -65.799462)
		(width 0.10668)
		(layer "In4.Cu")
		(net "SGPIO_DO_1")
	)
	(segment
		(start 15.044674 -47.05223)
		(end 15.044674 -48.630332)
		(width 0.10668)
		(layer "In4.Cu")
		(net "SGPIO_DO_1")
	)
	(segment
		(start 13.843 -66.636392)
		(end 13.98651 -66.779902)
		(width 0.10668)
		(layer "In4.Cu")
		(net "SGPIO_DO_1")
	)
	(segment
		(start 15.80134 -49.61763)
		(end 15.80134 -51.2826)
		(width 0.10668)
		(layer "In4.Cu")
		(net "SGPIO_DO_1")
	)
	(segment
		(start 14.64818 -67.903852)
		(end 14.64818 -71.63562)
		(width 0.10668)
		(layer "In4.Cu")
		(net "SGPIO_DO_1")
	)
	(segment
		(start 13.843 -64.472312)
		(end 13.843 -64.675512)
		(width 0.10668)
		(layer "In4.Cu")
		(net "SGPIO_DO_1")
	)
	(segment
		(start 13.843 -67.413632)
		(end 13.843 -67.616832)
		(width 0.10668)
		(layer "In4.Cu")
		(net "SGPIO_DO_1")
	)
	(segment
		(start 13.843 -65.655952)
		(end 13.98651 -65.799462)
		(width 0.10668)
		(layer "In4.Cu")
		(net "SGPIO_DO_1")
	)
	(segment
		(start 47.489618 -28.31846)
		(end 41.39946 -28.31846)
		(width 0.10668)
		(layer "In4.Cu")
		(net "SGPIO_DO_1")
	)
	(segment
		(start 16.2306 -41.232836)
		(end 16.2306 -45.866304)
		(width 0.10668)
		(layer "In4.Cu")
		(net "SGPIO_DO_1")
	)
	(segment
		(start 14.64818 -66.923412)
		(end 14.64818 -67.126612)
		(width 0.10668)
		(layer "In4.Cu")
		(net "SGPIO_DO_1")
	)
	(segment
		(start 14.64818 -64.962532)
		(end 14.64818 -65.165732)
		(width 0.10668)
		(layer "In4.Cu")
		(net "SGPIO_DO_1")
	)
	(segment
		(start 13.98651 -64.328802)
		(end 13.843 -64.472312)
		(width 0.10668)
		(layer "In4.Cu")
		(net "SGPIO_DO_1")
	)
	(segment
		(start 14.9098 -60.841128)
		(end 14.9098 -63.923672)
		(width 0.10668)
		(layer "In4.Cu")
		(net "SGPIO_DO_1")
	)
	(segment
		(start 14.50467 -66.779902)
		(end 14.64818 -66.923412)
		(width 0.10668)
		(layer "In4.Cu")
		(net "SGPIO_DO_1")
	)
	(segment
		(start 14.64818 -65.942972)
		(end 14.64818 -66.146172)
		(width 0.10668)
		(layer "In4.Cu")
		(net "SGPIO_DO_1")
	)
	(segment
		(start 37.5666 -27.2288)
		(end 36.83254 -27.96286)
		(width 0.10668)
		(layer "In4.Cu")
		(net "SGPIO_DO_1")
	)
	(segment
		(start 13.4112 -72.8726)
		(end 13.4112 -81.8896)
		(width 0.10668)
		(layer "In4.Cu")
		(net "SGPIO_DO_1")
	)
	(segment
		(start 27.79141 -27.178)
		(end 26.40457 -25.79116)
		(width 0.10668)
		(layer "In4.Cu")
		(net "SGPIO_DO_1")
	)
	(segment
		(start 15.574264 -49.159922)
		(end 15.574264 -49.390554)
		(width 0.10668)
		(layer "In4.Cu")
		(net "SGPIO_DO_1")
	)
	(segment
		(start 14.50467 -66.289682)
		(end 13.98651 -66.289682)
		(width 0.10668)
		(layer "In4.Cu")
		(net "SGPIO_DO_1")
	)
	(segment
		(start 49.17694 -35.107372)
		(end 49.17694 -31.32074)
		(width 0.10668)
		(layer "In4.Cu")
		(net "SGPIO_DO_1")
	)
	(segment
		(start 14.859 -59.011312)
		(end 14.33068 -59.539632)
		(width 0.10668)
		(layer "In4.Cu")
		(net "SGPIO_DO_1")
	)
	(segment
		(start 14.64818 -66.146172)
		(end 14.50467 -66.289682)
		(width 0.10668)
		(layer "In4.Cu")
		(net "SGPIO_DO_1")
	)
	(segment
		(start 16.33728 -33.37052)
		(end 16.665448 -33.698688)
		(width 0.10668)
		(layer "In4.Cu")
		(net "SGPIO_DO_1")
	)
	(segment
		(start 14.50467 -65.309242)
		(end 13.98651 -65.309242)
		(width 0.10668)
		(layer "In4.Cu")
		(net "SGPIO_DO_1")
	)
	(segment
		(start 36.83254 -27.96286)
		(end 32.613092 -27.96286)
		(width 0.10668)
		(layer "In4.Cu")
		(net "SGPIO_DO_1")
	)
	(segment
		(start 40.3098 -27.2288)
		(end 37.5666 -27.2288)
		(width 0.10668)
		(layer "In4.Cu")
		(net "SGPIO_DO_1")
	)
	(segment
		(start 26.40457 -25.79116)
		(end 24.73452 -21.759418)
		(width 0.10668)
		(layer "In4.Cu")
		(net "SGPIO_DO_1")
	)
	(segment
		(start 47.983394 -30.127194)
		(end 47.983394 -28.812236)
		(width 0.10668)
		(layer "In4.Cu")
		(net "SGPIO_DO_1")
	)
	(segment
		(start 13.843 -64.675512)
		(end 13.98651 -64.819022)
		(width 0.10668)
		(layer "In4.Cu")
		(net "SGPIO_DO_1")
	)
	(segment
		(start 13.843 -65.452752)
		(end 13.843 -65.655952)
		(width 0.10668)
		(layer "In4.Cu")
		(net "SGPIO_DO_1")
	)
	(segment
		(start 15.574264 -49.390554)
		(end 15.80134 -49.61763)
		(width 0.10668)
		(layer "In4.Cu")
		(net "SGPIO_DO_1")
	)
	(segment
		(start 15.240762 -51.843178)
		(end 15.240762 -53.28666)
		(width 0.10668)
		(layer "In4.Cu")
		(net "SGPIO_DO_1")
	)
	(segment
		(start 16.33728 -21.686266)
		(end 16.33728 -33.37052)
		(width 0.10668)
		(layer "In4.Cu")
		(net "SGPIO_DO_1")
	)
	(segment
		(start 14.50467 -65.799462)
		(end 14.64818 -65.942972)
		(width 0.10668)
		(layer "In4.Cu")
		(net "SGPIO_DO_1")
	)
	(segment
		(start 14.859 -56.134)
		(end 14.859 -59.011312)
		(width 0.10668)
		(layer "In4.Cu")
		(net "SGPIO_DO_1")
	)
	(segment
		(start 49.930558 -35.86099)
		(end 49.17694 -35.107372)
		(width 0.10668)
		(layer "In4.Cu")
		(net "SGPIO_DO_1")
	)
	(segment
		(start 14.33068 -59.539632)
		(end 14.33068 -60.262008)
		(width 0.10668)
		(layer "In4.Cu")
		(net "SGPIO_DO_1")
	)
	(segment
		(start 15.80134 -51.2826)
		(end 15.240762 -51.843178)
		(width 0.10668)
		(layer "In4.Cu")
		(net "SGPIO_DO_1")
	)
	(segment
		(start 14.33068 -60.262008)
		(end 14.9098 -60.841128)
		(width 0.10668)
		(layer "In4.Cu")
		(net "SGPIO_DO_1")
	)
	(segment
		(start 14.50467 -64.819022)
		(end 14.64818 -64.962532)
		(width 0.10668)
		(layer "In4.Cu")
		(net "SGPIO_DO_1")
	)
	(segment
		(start 14.50467 -67.270122)
		(end 13.98651 -67.270122)
		(width 0.10668)
		(layer "In4.Cu")
		(net "SGPIO_DO_1")
	)
	(segment
		(start 13.4112 -80.53324)
		(end 13.16736 -80.2894)
		(width 0.10668)
		(layer "In7.Cu")
		(net "SGPIO_DO_1")
	)
	(segment
		(start 9.9441 -84.6201)
		(end 9.9441 -87.185246)
		(width 0.10668)
		(layer "In7.Cu")
		(net "SGPIO_DO_1")
	)
	(segment
		(start 7.13232 -104.69372)
		(end 13.830808 -111.392208)
		(width 0.10668)
		(layer "In7.Cu")
		(net "SGPIO_DO_1")
	)
	(segment
		(start 7.97052 -89.158826)
		(end 7.97052 -90.629994)
		(width 0.10668)
		(layer "In7.Cu")
		(net "SGPIO_DO_1")
	)
	(segment
		(start 27.667712 -112.930686)
		(end 27.494992 -113.103406)
		(width 0.10668)
		(layer "In7.Cu")
		(net "SGPIO_DO_1")
	)
	(segment
		(start 9.3345 -84.0105)
		(end 9.9441 -84.6201)
		(width 0.10668)
		(layer "In7.Cu")
		(net "SGPIO_DO_1")
	)
	(segment
		(start 28.868878 -113.983516)
		(end 29.112972 -113.983516)
		(width 0.10668)
		(layer "In7.Cu")
		(net "SGPIO_DO_1")
	)
	(segment
		(start 7.58952 -91.010994)
		(end 7.58952 -95.206312)
		(width 0.10668)
		(layer "In7.Cu")
		(net "SGPIO_DO_1")
	)
	(segment
		(start 16.755872 -111.392208)
		(end 18.012664 -112.649)
		(width 0.10668)
		(layer "In7.Cu")
		(net "SGPIO_DO_1")
	)
	(segment
		(start 23.70836 -111.92764)
		(end 28.523438 -111.92764)
		(width 0.10668)
		(layer "In7.Cu")
		(net "SGPIO_DO_1")
	)
	(segment
		(start 29.112972 -113.983516)
		(end 29.285692 -113.810796)
		(width 0.10668)
		(layer "In7.Cu")
		(net "SGPIO_DO_1")
	)
	(segment
		(start 22.987 -112.649)
		(end 23.70836 -111.92764)
		(width 0.10668)
		(layer "In7.Cu")
		(net "SGPIO_DO_1")
	)
	(segment
		(start 11.64082 -81.42478)
		(end 10.947908 -81.42478)
		(width 0.10668)
		(layer "In7.Cu")
		(net "SGPIO_DO_1")
	)
	(segment
		(start 28.696158 -113.810796)
		(end 28.868878 -113.983516)
		(width 0.10668)
		(layer "In7.Cu")
		(net "SGPIO_DO_1")
	)
	(segment
		(start 28.523438 -111.92764)
		(end 28.696158 -112.10036)
		(width 0.10668)
		(layer "In7.Cu")
		(net "SGPIO_DO_1")
	)
	(segment
		(start 7.58952 -95.206312)
		(end 7.13232 -95.663512)
		(width 0.10668)
		(layer "In7.Cu")
		(net "SGPIO_DO_1")
	)
	(segment
		(start 39.42334 -115.16106)
		(end 40.005 -115.16106)
		(width 0.10668)
		(layer "In7.Cu")
		(net "SGPIO_DO_1")
	)
	(segment
		(start 10.226548 -82.14614)
		(end 9.44118 -82.14614)
		(width 0.10668)
		(layer "In7.Cu")
		(net "SGPIO_DO_1")
	)
	(segment
		(start 27.494992 -113.3475)
		(end 27.667712 -113.52022)
		(width 0.10668)
		(layer "In7.Cu")
		(net "SGPIO_DO_1")
	)
	(segment
		(start 27.494992 -113.103406)
		(end 27.494992 -113.3475)
		(width 0.10668)
		(layer "In7.Cu")
		(net "SGPIO_DO_1")
	)
	(segment
		(start 38.1762 -115.2652)
		(end 39.3192 -115.2652)
		(width 0.10668)
		(layer "In7.Cu")
		(net "SGPIO_DO_1")
	)
	(segment
		(start 29.285692 -112.10036)
		(end 29.458412 -111.92764)
		(width 0.10668)
		(layer "In7.Cu")
		(net "SGPIO_DO_1")
	)
	(segment
		(start 7.13232 -95.663512)
		(end 7.13232 -104.69372)
		(width 0.10668)
		(layer "In7.Cu")
		(net "SGPIO_DO_1")
	)
	(segment
		(start 10.947908 -81.42478)
		(end 10.226548 -82.14614)
		(width 0.10668)
		(layer "In7.Cu")
		(net "SGPIO_DO_1")
	)
	(segment
		(start 18.012664 -112.649)
		(end 22.987 -112.649)
		(width 0.10668)
		(layer "In7.Cu")
		(net "SGPIO_DO_1")
	)
	(segment
		(start 28.696158 -113.69294)
		(end 28.696158 -113.810796)
		(width 0.10668)
		(layer "In7.Cu")
		(net "SGPIO_DO_1")
	)
	(segment
		(start 7.97052 -90.629994)
		(end 7.58952 -91.010994)
		(width 0.10668)
		(layer "In7.Cu")
		(net "SGPIO_DO_1")
	)
	(segment
		(start 9.3345 -82.25282)
		(end 9.3345 -84.0105)
		(width 0.10668)
		(layer "In7.Cu")
		(net "SGPIO_DO_1")
	)
	(segment
		(start 13.830808 -111.392208)
		(end 16.755872 -111.392208)
		(width 0.10668)
		(layer "In7.Cu")
		(net "SGPIO_DO_1")
	)
	(segment
		(start 28.523438 -112.930686)
		(end 27.667712 -112.930686)
		(width 0.10668)
		(layer "In7.Cu")
		(net "SGPIO_DO_1")
	)
	(segment
		(start 9.9441 -87.185246)
		(end 7.97052 -89.158826)
		(width 0.10668)
		(layer "In7.Cu")
		(net "SGPIO_DO_1")
	)
	(segment
		(start 12.7762 -80.2894)
		(end 11.64082 -81.42478)
		(width 0.10668)
		(layer "In7.Cu")
		(net "SGPIO_DO_1")
	)
	(segment
		(start 29.285692 -113.810796)
		(end 29.285692 -112.10036)
		(width 0.10668)
		(layer "In7.Cu")
		(net "SGPIO_DO_1")
	)
	(segment
		(start 28.696158 -112.10036)
		(end 28.696158 -112.757966)
		(width 0.10668)
		(layer "In7.Cu")
		(net "SGPIO_DO_1")
	)
	(segment
		(start 39.3192 -115.2652)
		(end 39.42334 -115.16106)
		(width 0.10668)
		(layer "In7.Cu")
		(net "SGPIO_DO_1")
	)
	(segment
		(start 27.667712 -113.52022)
		(end 28.523438 -113.52022)
		(width 0.10668)
		(layer "In7.Cu")
		(net "SGPIO_DO_1")
	)
	(segment
		(start 28.523438 -113.52022)
		(end 28.696158 -113.69294)
		(width 0.10668)
		(layer "In7.Cu")
		(net "SGPIO_DO_1")
	)
	(segment
		(start 34.83864 -111.92764)
		(end 38.1762 -115.2652)
		(width 0.10668)
		(layer "In7.Cu")
		(net "SGPIO_DO_1")
	)
	(segment
		(start 13.4112 -81.8896)
		(end 13.4112 -80.53324)
		(width 0.10668)
		(layer "In7.Cu")
		(net "SGPIO_DO_1")
	)
	(segment
		(start 29.458412 -111.92764)
		(end 34.83864 -111.92764)
		(width 0.10668)
		(layer "In7.Cu")
		(net "SGPIO_DO_1")
	)
	(segment
		(start 13.16736 -80.2894)
		(end 12.7762 -80.2894)
		(width 0.10668)
		(layer "In7.Cu")
		(net "SGPIO_DO_1")
	)
	(segment
		(start 9.44118 -82.14614)
		(end 9.3345 -82.25282)
		(width 0.10668)
		(layer "In7.Cu")
		(net "SGPIO_DO_1")
	)
	(segment
		(start 28.696158 -112.757966)
		(end 28.523438 -112.930686)
		(width 0.10668)
		(layer "In7.Cu")
		(net "SGPIO_DO_1")
	)
	(segment
		(start 43.25493 -116.088414)
		(end 43.25493 -118.460012)
		(width 0.11684)
		(layer "F.Cu")
		(net "SGPIO_DO_0")
	)
	(segment
		(start 43.254676 -114.733324)
		(end 43.25493 -116.088414)
		(width 0.11684)
		(layer "F.Cu")
		(net "SGPIO_DO_0")
	)
	(segment
		(start 43.5356 -114.4524)
		(end 43.254676 -114.733324)
		(width 0.11684)
		(layer "F.Cu")
		(net "SGPIO_DO_0")
	)
	(via
		(at 14.3764 -82.3722)
		(size 0.508)
		(drill 0.254)
		(layers "F.Cu" "B.Cu")
		(net "SGPIO_DO_0")
	)
	(via
		(at 45.385228 -109.263942)
		(size 0.6604)
		(drill 0.3302)
		(layers "F.Cu" "B.Cu")
		(net "SGPIO_DO_0")
	)
	(via
		(at 43.5356 -114.4524)
		(size 0.508)
		(drill 0.254)
		(layers "F.Cu" "B.Cu")
		(net "SGPIO_DO_0")
	)
	(segment
		(start 43.5356 -114.4524)
		(end 43.812714 -113.060734)
		(width 0.11684)
		(layer "B.Cu")
		(net "SGPIO_DO_0")
	)
	(segment
		(start 45.385228 -109.263942)
		(end 46.151038 -107.415076)
		(width 0.11684)
		(layer "B.Cu")
		(net "SGPIO_DO_0")
	)
	(segment
		(start 14.992096 -83.29295)
		(end 14.3764 -82.677254)
		(width 0.11684)
		(layer "B.Cu")
		(net "SGPIO_DO_0")
	)
	(segment
		(start 14.3764 -82.677254)
		(end 14.3764 -82.3722)
		(width 0.11684)
		(layer "B.Cu")
		(net "SGPIO_DO_0")
	)
	(segment
		(start 43.812714 -113.060734)
		(end 45.385228 -109.263942)
		(width 0.11684)
		(layer "B.Cu")
		(net "SGPIO_DO_0")
	)
	(segment
		(start 46.151038 -107.415076)
		(end 46.20895 -107.3912)
		(width 0.11684)
		(layer "B.Cu")
		(net "SGPIO_DO_0")
	)
	(segment
		(start 15.24 -83.29295)
		(end 14.992096 -83.29295)
		(width 0.11684)
		(layer "B.Cu")
		(net "SGPIO_DO_0")
	)
	(segment
		(start 25.6794 -107.5944)
		(end 25.6794 -108.5088)
		(width 0.10668)
		(layer "In7.Cu")
		(net "SGPIO_DO_0")
	)
	(segment
		(start 14.9352 -82.545682)
		(end 14.9352 -82.8802)
		(width 0.10668)
		(layer "In7.Cu")
		(net "SGPIO_DO_0")
	)
	(segment
		(start 40.37838 -113.60658)
		(end 41.285414 -113.9825)
		(width 0.10668)
		(layer "In7.Cu")
		(net "SGPIO_DO_0")
	)
	(segment
		(start 37.3888 -112.0902)
		(end 39.0652 -112.0902)
		(width 0.10668)
		(layer "In7.Cu")
		(net "SGPIO_DO_0")
	)
	(segment
		(start 30.82544 -109.5248)
		(end 34.8234 -109.5248)
		(width 0.10668)
		(layer "In7.Cu")
		(net "SGPIO_DO_0")
	)
	(segment
		(start 13.260832 -83.492086)
		(end 13.212318 -83.5406)
		(width 0.10668)
		(layer "In7.Cu")
		(net "SGPIO_DO_0")
	)
	(segment
		(start 42.037 -114.293904)
		(end 42.45991 -114.46891)
		(width 0.10668)
		(layer "In7.Cu")
		(net "SGPIO_DO_0")
	)
	(segment
		(start 13.212064 -83.5406)
		(end 12.21232 -84.540344)
		(width 0.10668)
		(layer "In7.Cu")
		(net "SGPIO_DO_0")
	)
	(segment
		(start 14.3764 -82.3722)
		(end 14.761718 -82.3722)
		(width 0.10668)
		(layer "In7.Cu")
		(net "SGPIO_DO_0")
	)
	(segment
		(start 14.42974 -104.02062)
		(end 16.05026 -105.64114)
		(width 0.10668)
		(layer "In7.Cu")
		(net "SGPIO_DO_0")
	)
	(segment
		(start 12.21232 -97.648014)
		(end 12.98448 -99.512628)
		(width 0.10668)
		(layer "In7.Cu")
		(net "SGPIO_DO_0")
	)
	(segment
		(start 14.42974 -103.482394)
		(end 14.42974 -104.02062)
		(width 0.10668)
		(layer "In7.Cu")
		(net "SGPIO_DO_0")
	)
	(segment
		(start 41.95572 -114.097816)
		(end 42.037 -114.293904)
		(width 0.10668)
		(layer "In7.Cu")
		(net "SGPIO_DO_0")
	)
	(segment
		(start 19.879056 -106.190288)
		(end 24.275288 -106.190288)
		(width 0.10668)
		(layer "In7.Cu")
		(net "SGPIO_DO_0")
	)
	(segment
		(start 13.212318 -83.5406)
		(end 13.212064 -83.5406)
		(width 0.10668)
		(layer "In7.Cu")
		(net "SGPIO_DO_0")
	)
	(segment
		(start 40.259 -113.284)
		(end 40.259 -113.4872)
		(width 0.10668)
		(layer "In7.Cu")
		(net "SGPIO_DO_0")
	)
	(segment
		(start 30.26156 -108.96092)
		(end 30.82544 -109.5248)
		(width 0.10668)
		(layer "In7.Cu")
		(net "SGPIO_DO_0")
	)
	(segment
		(start 26.13152 -108.96092)
		(end 30.26156 -108.96092)
		(width 0.10668)
		(layer "In7.Cu")
		(net "SGPIO_DO_0")
	)
	(segment
		(start 25.6794 -108.5088)
		(end 26.13152 -108.96092)
		(width 0.10668)
		(layer "In7.Cu")
		(net "SGPIO_DO_0")
	)
	(segment
		(start 42.45991 -114.46891)
		(end 43.51909 -114.46891)
		(width 0.10668)
		(layer "In7.Cu")
		(net "SGPIO_DO_0")
	)
	(segment
		(start 12.21232 -84.540344)
		(end 12.21232 -97.648014)
		(width 0.10668)
		(layer "In7.Cu")
		(net "SGPIO_DO_0")
	)
	(segment
		(start 43.51909 -114.46891)
		(end 43.5356 -114.4524)
		(width 0.10668)
		(layer "In7.Cu")
		(net "SGPIO_DO_0")
	)
	(segment
		(start 34.8234 -109.5248)
		(end 37.3888 -112.0902)
		(width 0.10668)
		(layer "In7.Cu")
		(net "SGPIO_DO_0")
	)
	(segment
		(start 19.329908 -105.64114)
		(end 19.879056 -106.190288)
		(width 0.10668)
		(layer "In7.Cu")
		(net "SGPIO_DO_0")
	)
	(segment
		(start 14.761718 -82.3722)
		(end 14.9352 -82.545682)
		(width 0.10668)
		(layer "In7.Cu")
		(net "SGPIO_DO_0")
	)
	(segment
		(start 16.05026 -105.64114)
		(end 19.329908 -105.64114)
		(width 0.10668)
		(layer "In7.Cu")
		(net "SGPIO_DO_0")
	)
	(segment
		(start 41.285414 -113.9825)
		(end 41.481502 -113.90122)
		(width 0.10668)
		(layer "In7.Cu")
		(net "SGPIO_DO_0")
	)
	(segment
		(start 12.98448 -99.512628)
		(end 12.98448 -102.037134)
		(width 0.10668)
		(layer "In7.Cu")
		(net "SGPIO_DO_0")
	)
	(segment
		(start 39.0652 -112.0902)
		(end 40.259 -113.284)
		(width 0.10668)
		(layer "In7.Cu")
		(net "SGPIO_DO_0")
	)
	(segment
		(start 14.323314 -83.492086)
		(end 13.260832 -83.492086)
		(width 0.10668)
		(layer "In7.Cu")
		(net "SGPIO_DO_0")
	)
	(segment
		(start 42.31894 -112.829594)
		(end 42.40022 -113.025682)
		(width 0.10668)
		(layer "In7.Cu")
		(net "SGPIO_DO_0")
	)
	(segment
		(start 41.481502 -113.90122)
		(end 41.926002 -112.829086)
		(width 0.10668)
		(layer "In7.Cu")
		(net "SGPIO_DO_0")
	)
	(segment
		(start 42.12209 -112.747806)
		(end 42.31894 -112.829594)
		(width 0.10668)
		(layer "In7.Cu")
		(net "SGPIO_DO_0")
	)
	(segment
		(start 40.259 -113.4872)
		(end 40.37838 -113.60658)
		(width 0.10668)
		(layer "In7.Cu")
		(net "SGPIO_DO_0")
	)
	(segment
		(start 42.40022 -113.025682)
		(end 41.95572 -114.097816)
		(width 0.10668)
		(layer "In7.Cu")
		(net "SGPIO_DO_0")
	)
	(segment
		(start 12.98448 -102.037134)
		(end 14.42974 -103.482394)
		(width 0.10668)
		(layer "In7.Cu")
		(net "SGPIO_DO_0")
	)
	(segment
		(start 24.275288 -106.190288)
		(end 25.6794 -107.5944)
		(width 0.10668)
		(layer "In7.Cu")
		(net "SGPIO_DO_0")
	)
	(segment
		(start 41.926002 -112.829086)
		(end 42.12209 -112.747806)
		(width 0.10668)
		(layer "In7.Cu")
		(net "SGPIO_DO_0")
	)
	(segment
		(start 14.9352 -82.8802)
		(end 14.323314 -83.492086)
		(width 0.10668)
		(layer "In7.Cu")
		(net "SGPIO_DO_0")
	)
	(segment
		(start 36.922964 -109.06125)
		(end 36.8808 -109.06125)
		(width 0.11684)
		(layer "F.Cu")
		(net "SGPIO_DI_1")
	)
	(segment
		(start 38.771068 -112.837722)
		(end 39.05504 -113.523268)
		(width 0.11684)
		(layer "F.Cu")
		(net "SGPIO_DI_1")
	)
	(segment
		(start 36.3474 -110.414054)
		(end 38.771068 -112.837722)
		(width 0.11684)
		(layer "F.Cu")
		(net "SGPIO_DI_1")
	)
	(segment
		(start 37.602414 -108.3818)
		(end 36.922964 -109.06125)
		(width 0.11684)
		(layer "F.Cu")
		(net "SGPIO_DI_1")
	)
	(segment
		(start 47.470314 -28.953714)
		(end 48.153574 -28.2702)
		(width 0.11684)
		(layer "F.Cu")
		(net "SGPIO_DI_1")
	)
	(segment
		(start 39.05504 -113.523268)
		(end 39.05504 -118.25986)
		(width 0.11684)
		(layer "F.Cu")
		(net "SGPIO_DI_1")
	)
	(segment
		(start 36.8808 -109.06125)
		(end 36.3474 -109.59465)
		(width 0.11684)
		(layer "F.Cu")
		(net "SGPIO_DI_1")
	)
	(segment
		(start 36.3474 -109.59465)
		(end 36.3474 -110.414054)
		(width 0.11684)
		(layer "F.Cu")
		(net "SGPIO_DI_1")
	)
	(segment
		(start 48.153574 -28.2702)
		(end 48.82515 -28.2702)
		(width 0.11684)
		(layer "F.Cu")
		(net "SGPIO_DI_1")
	)
	(via
		(at 36.83 -23.0378)
		(size 0.508)
		(drill 0.254)
		(layers "F.Cu" "B.Cu")
		(net "SGPIO_DI_1")
	)
	(via
		(at 15.115794 -107.817158)
		(size 0.508)
		(drill 0.254)
		(layers "F.Cu" "B.Cu")
		(net "SGPIO_DI_1")
	)
	(via
		(at 47.470314 -28.953714)
		(size 0.508)
		(drill 0.254)
		(layers "F.Cu" "B.Cu")
		(net "SGPIO_DI_1")
	)
	(via
		(at 19.708368 -105.012998)
		(size 0.508)
		(drill 0.254)
		(layers "F.Cu" "B.Cu")
		(net "SGPIO_DI_1")
	)
	(via
		(at 37.602414 -108.3818)
		(size 0.508)
		(drill 0.254)
		(layers "F.Cu" "B.Cu")
		(net "SGPIO_DI_1")
	)
	(via
		(at 8.915654 -96.92894)
		(size 0.508)
		(drill 0.254)
		(layers "F.Cu" "B.Cu")
		(net "SGPIO_DI_1")
	)
	(segment
		(start 40.03294 -27.13228)
		(end 41.210484 -27.13228)
		(width 0.08382)
		(layer "In2.Cu")
		(net "SGPIO_DI_1")
	)
	(segment
		(start 37.460428 -24.559768)
		(end 40.03294 -27.13228)
		(width 0.08382)
		(layer "In2.Cu")
		(net "SGPIO_DI_1")
	)
	(segment
		(start 36.83 -23.0378)
		(end 37.460428 -24.559768)
		(width 0.08382)
		(layer "In2.Cu")
		(net "SGPIO_DI_1")
	)
	(segment
		(start 47.028354 -28.511754)
		(end 47.470314 -28.953714)
		(width 0.08382)
		(layer "In2.Cu")
		(net "SGPIO_DI_1")
	)
	(segment
		(start 41.210484 -27.13228)
		(end 41.723564 -27.64536)
		(width 0.08382)
		(layer "In2.Cu")
		(net "SGPIO_DI_1")
	)
	(segment
		(start 41.723564 -27.64536)
		(end 44.936918 -27.64536)
		(width 0.08382)
		(layer "In2.Cu")
		(net "SGPIO_DI_1")
	)
	(segment
		(start 44.936918 -27.64536)
		(end 47.028354 -28.511754)
		(width 0.08382)
		(layer "In2.Cu")
		(net "SGPIO_DI_1")
	)
	(segment
		(start 29.23794 -105.56494)
		(end 28.92806 -105.25506)
		(width 0.10668)
		(layer "In7.Cu")
		(net "SGPIO_DI_1")
	)
	(segment
		(start 31.166816 -108.70184)
		(end 30.602936 -108.13796)
		(width 0.10668)
		(layer "In7.Cu")
		(net "SGPIO_DI_1")
	)
	(segment
		(start 14.029436 -106.7308)
		(end 13.40104 -106.7308)
		(width 0.10668)
		(layer "In7.Cu")
		(net "SGPIO_DI_1")
	)
	(segment
		(start 28.92806 -105.25506)
		(end 25.75814 -105.25506)
		(width 0.10668)
		(layer "In7.Cu")
		(net "SGPIO_DI_1")
	)
	(segment
		(start 29.6418 -108.13796)
		(end 29.23794 -107.7341)
		(width 0.10668)
		(layer "In7.Cu")
		(net "SGPIO_DI_1")
	)
	(segment
		(start 12.4206 -105.75036)
		(end 12.4206 -104.75214)
		(width 0.10668)
		(layer "In7.Cu")
		(net "SGPIO_DI_1")
	)
	(segment
		(start 29.23794 -107.7341)
		(end 29.23794 -105.56494)
		(width 0.10668)
		(layer "In7.Cu")
		(net "SGPIO_DI_1")
	)
	(segment
		(start 10.74166 -104.4194)
		(end 9.17194 -104.4194)
		(width 0.10668)
		(layer "In7.Cu")
		(net "SGPIO_DI_1")
	)
	(segment
		(start 9.17194 -104.4194)
		(end 8.83666 -104.08412)
		(width 0.10668)
		(layer "In7.Cu")
		(net "SGPIO_DI_1")
	)
	(segment
		(start 8.83666 -104.08412)
		(end 8.83666 -103.5939)
		(width 0.10668)
		(layer "In7.Cu")
		(net "SGPIO_DI_1")
	)
	(segment
		(start 10.91946 -104.2416)
		(end 10.74166 -104.4194)
		(width 0.10668)
		(layer "In7.Cu")
		(net "SGPIO_DI_1")
	)
	(segment
		(start 37.602414 -108.3818)
		(end 37.282374 -108.70184)
		(width 0.10668)
		(layer "In7.Cu")
		(net "SGPIO_DI_1")
	)
	(segment
		(start 11.91006 -104.2416)
		(end 10.91946 -104.2416)
		(width 0.10668)
		(layer "In7.Cu")
		(net "SGPIO_DI_1")
	)
	(segment
		(start 15.115794 -107.817158)
		(end 14.029436 -106.7308)
		(width 0.10668)
		(layer "In7.Cu")
		(net "SGPIO_DI_1")
	)
	(segment
		(start 30.602936 -108.13796)
		(end 29.6418 -108.13796)
		(width 0.10668)
		(layer "In7.Cu")
		(net "SGPIO_DI_1")
	)
	(segment
		(start 13.40104 -106.7308)
		(end 12.4206 -105.75036)
		(width 0.10668)
		(layer "In7.Cu")
		(net "SGPIO_DI_1")
	)
	(segment
		(start 25.234392 -105.778808)
		(end 20.206208 -105.778808)
		(width 0.10668)
		(layer "In7.Cu")
		(net "SGPIO_DI_1")
	)
	(segment
		(start 37.282374 -108.70184)
		(end 31.166816 -108.70184)
		(width 0.10668)
		(layer "In7.Cu")
		(net "SGPIO_DI_1")
	)
	(segment
		(start 8.83666 -103.5939)
		(end 8.915654 -103.514906)
		(width 0.10668)
		(layer "In7.Cu")
		(net "SGPIO_DI_1")
	)
	(segment
		(start 25.75814 -105.25506)
		(end 25.234392 -105.778808)
		(width 0.10668)
		(layer "In7.Cu")
		(net "SGPIO_DI_1")
	)
	(segment
		(start 12.4206 -104.75214)
		(end 11.91006 -104.2416)
		(width 0.10668)
		(layer "In7.Cu")
		(net "SGPIO_DI_1")
	)
	(segment
		(start 20.206208 -105.778808)
		(end 19.708368 -105.280968)
		(width 0.10668)
		(layer "In7.Cu")
		(net "SGPIO_DI_1")
	)
	(segment
		(start 8.915654 -103.514906)
		(end 8.915654 -96.92894)
		(width 0.10668)
		(layer "In7.Cu")
		(net "SGPIO_DI_1")
	)
	(segment
		(start 19.708368 -105.280968)
		(end 19.708368 -105.012998)
		(width 0.10668)
		(layer "In7.Cu")
		(net "SGPIO_DI_1")
	)
	(segment
		(start 36.4998 -20.8788)
		(end 35.863784 -20.8788)
		(width 0.08382)
		(layer "In9.Cu")
		(net "SGPIO_DI_1")
	)
	(segment
		(start 13.429234 -60.16371)
		(end 12.65809 -60.16371)
		(width 0.08382)
		(layer "In9.Cu")
		(net "SGPIO_DI_1")
	)
	(segment
		(start 17.66062 -39.75862)
		(end 17.91589 -40.01389)
		(width 0.08382)
		(layer "In9.Cu")
		(net "SGPIO_DI_1")
	)
	(segment
		(start 35.863784 -20.8788)
		(end 29.4132 -14.428216)
		(width 0.08382)
		(layer "In9.Cu")
		(net "SGPIO_DI_1")
	)
	(segment
		(start 14.47546 -23.440644)
		(end 14.47546 -27.471116)
		(width 0.08382)
		(layer "In9.Cu")
		(net "SGPIO_DI_1")
	)
	(segment
		(start 17.83207 -40.87495)
		(end 17.15262 -40.87495)
		(width 0.08382)
		(layer "In9.Cu")
		(net "SGPIO_DI_1")
	)
	(segment
		(start 16.06296 -29.058616)
		(end 16.06296 -33.60674)
		(width 0.08382)
		(layer "In9.Cu")
		(net "SGPIO_DI_1")
	)
	(segment
		(start 7.55142 -89.689686)
		(end 7.55142 -96.83242)
		(width 0.08382)
		(layer "In9.Cu")
		(net "SGPIO_DI_1")
	)
	(segment
		(start 11.88593 -80.91932)
		(end 10.38987 -82.41538)
		(width 0.08382)
		(layer "In9.Cu")
		(net "SGPIO_DI_1")
	)
	(segment
		(start 17.224756 -39.75862)
		(end 17.66062 -39.75862)
		(width 0.08382)
		(layer "In9.Cu")
		(net "SGPIO_DI_1")
	)
	(segment
		(start 10.38987 -86.851236)
		(end 7.55142 -89.689686)
		(width 0.08382)
		(layer "In9.Cu")
		(net "SGPIO_DI_1")
	)
	(segment
		(start 12.36091 -16.786098)
		(end 12.14247 -17.004538)
		(width 0.08382)
		(layer "In9.Cu")
		(net "SGPIO_DI_1")
	)
	(segment
		(start 28.7782 -12.2682)
		(end 13.8684 -12.2682)
		(width 0.08382)
		(layer "In9.Cu")
		(net "SGPIO_DI_1")
	)
	(segment
		(start 29.4132 -12.9032)
		(end 28.7782 -12.2682)
		(width 0.08382)
		(layer "In9.Cu")
		(net "SGPIO_DI_1")
	)
	(segment
		(start 14.351 -52.173124)
		(end 14.351 -52.700936)
		(width 0.08382)
		(layer "In9.Cu")
		(net "SGPIO_DI_1")
	)
	(segment
		(start 12.65809 -60.16371)
		(end 12.039092 -60.782708)
		(width 0.08382)
		(layer "In9.Cu")
		(net "SGPIO_DI_1")
	)
	(segment
		(start 12.36091 -13.77569)
		(end 12.36091 -16.786098)
		(width 0.08382)
		(layer "In9.Cu")
		(net "SGPIO_DI_1")
	)
	(segment
		(start 29.4132 -14.428216)
		(end 29.4132 -12.9032)
		(width 0.08382)
		(layer "In9.Cu")
		(net "SGPIO_DI_1")
	)
	(segment
		(start 15.435834 -42.591736)
		(end 15.435834 -45.890434)
		(width 0.08382)
		(layer "In9.Cu")
		(net "SGPIO_DI_1")
	)
	(segment
		(start 13.8684 -12.2682)
		(end 12.36091 -13.77569)
		(width 0.08382)
		(layer "In9.Cu")
		(net "SGPIO_DI_1")
	)
	(segment
		(start 16.413734 -33.957514)
		(end 16.413734 -39.03599)
		(width 0.08382)
		(layer "In9.Cu")
		(net "SGPIO_DI_1")
	)
	(segment
		(start 12.039092 -67.385438)
		(end 12.93495 -68.281296)
		(width 0.08382)
		(layer "In9.Cu")
		(net "SGPIO_DI_1")
	)
	(segment
		(start 14.01445 -51.836574)
		(end 14.351 -52.173124)
		(width 0.08382)
		(layer "In9.Cu")
		(net "SGPIO_DI_1")
	)
	(segment
		(start 14.351 -52.700936)
		(end 14.04493 -53.007006)
		(width 0.08382)
		(layer "In9.Cu")
		(net "SGPIO_DI_1")
	)
	(segment
		(start 16.631412 -104.4956)
		(end 19.19097 -104.4956)
		(width 0.08382)
		(layer "In9.Cu")
		(net "SGPIO_DI_1")
	)
	(segment
		(start 12.039092 -60.782708)
		(end 12.039092 -67.385438)
		(width 0.08382)
		(layer "In9.Cu")
		(net "SGPIO_DI_1")
	)
	(segment
		(start 7.55142 -96.83242)
		(end 7.64794 -96.92894)
		(width 0.08382)
		(layer "In9.Cu")
		(net "SGPIO_DI_1")
	)
	(segment
		(start 15.435834 -45.890434)
		(end 14.492732 -46.833536)
		(width 0.08382)
		(layer "In9.Cu")
		(net "SGPIO_DI_1")
	)
	(segment
		(start 14.492732 -48.449992)
		(end 14.01445 -49.604422)
		(width 0.08382)
		(layer "In9.Cu")
		(net "SGPIO_DI_1")
	)
	(segment
		(start 17.91589 -40.01389)
		(end 17.91589 -40.79113)
		(width 0.08382)
		(layer "In9.Cu")
		(net "SGPIO_DI_1")
	)
	(segment
		(start 16.413734 -39.03599)
		(end 17.07388 -39.696136)
		(width 0.08382)
		(layer "In9.Cu")
		(net "SGPIO_DI_1")
	)
	(segment
		(start 17.91589 -40.79113)
		(end 17.83207 -40.87495)
		(width 0.08382)
		(layer "In9.Cu")
		(net "SGPIO_DI_1")
	)
	(segment
		(start 14.04493 -53.007006)
		(end 14.04493 -59.548014)
		(width 0.08382)
		(layer "In9.Cu")
		(net "SGPIO_DI_1")
	)
	(segment
		(start 14.47546 -27.471116)
		(end 16.06296 -29.058616)
		(width 0.08382)
		(layer "In9.Cu")
		(net "SGPIO_DI_1")
	)
	(segment
		(start 7.64794 -96.92894)
		(end 8.915654 -96.92894)
		(width 0.08382)
		(layer "In9.Cu")
		(net "SGPIO_DI_1")
	)
	(segment
		(start 11.88593 -80.621632)
		(end 11.88593 -80.91932)
		(width 0.08382)
		(layer "In9.Cu")
		(net "SGPIO_DI_1")
	)
	(segment
		(start 16.06296 -33.60674)
		(end 16.413734 -33.957514)
		(width 0.08382)
		(layer "In9.Cu")
		(net "SGPIO_DI_1")
	)
	(segment
		(start 12.14247 -17.004538)
		(end 12.14247 -21.107654)
		(width 0.08382)
		(layer "In9.Cu")
		(net "SGPIO_DI_1")
	)
	(segment
		(start 14.9606 -107.661964)
		(end 14.9606 -106.166412)
		(width 0.08382)
		(layer "In9.Cu")
		(net "SGPIO_DI_1")
	)
	(segment
		(start 12.93495 -79.572612)
		(end 11.88593 -80.621632)
		(width 0.08382)
		(layer "In9.Cu")
		(net "SGPIO_DI_1")
	)
	(segment
		(start 12.14247 -21.107654)
		(end 14.47546 -23.440644)
		(width 0.08382)
		(layer "In9.Cu")
		(net "SGPIO_DI_1")
	)
	(segment
		(start 14.9606 -106.166412)
		(end 16.631412 -104.4956)
		(width 0.08382)
		(layer "In9.Cu")
		(net "SGPIO_DI_1")
	)
	(segment
		(start 10.38987 -82.41538)
		(end 10.38987 -86.851236)
		(width 0.08382)
		(layer "In9.Cu")
		(net "SGPIO_DI_1")
	)
	(segment
		(start 15.115794 -107.817158)
		(end 14.9606 -107.661964)
		(width 0.08382)
		(layer "In9.Cu")
		(net "SGPIO_DI_1")
	)
	(segment
		(start 14.01445 -49.604422)
		(end 14.01445 -51.836574)
		(width 0.08382)
		(layer "In9.Cu")
		(net "SGPIO_DI_1")
	)
	(segment
		(start 17.15262 -40.87495)
		(end 15.435834 -42.591736)
		(width 0.08382)
		(layer "In9.Cu")
		(net "SGPIO_DI_1")
	)
	(segment
		(start 12.93495 -68.281296)
		(end 12.93495 -79.572612)
		(width 0.08382)
		(layer "In9.Cu")
		(net "SGPIO_DI_1")
	)
	(segment
		(start 19.19097 -104.4956)
		(end 19.708368 -105.012998)
		(width 0.08382)
		(layer "In9.Cu")
		(net "SGPIO_DI_1")
	)
	(segment
		(start 14.492732 -46.833536)
		(end 14.492732 -48.449992)
		(width 0.08382)
		(layer "In9.Cu")
		(net "SGPIO_DI_1")
	)
	(segment
		(start 37.338 -22.5298)
		(end 37.338 -21.717)
		(width 0.08382)
		(layer "In9.Cu")
		(net "SGPIO_DI_1")
	)
	(segment
		(start 37.338 -21.717)
		(end 36.4998 -20.8788)
		(width 0.08382)
		(layer "In9.Cu")
		(net "SGPIO_DI_1")
	)
	(segment
		(start 14.04493 -59.548014)
		(end 13.429234 -60.16371)
		(width 0.08382)
		(layer "In9.Cu")
		(net "SGPIO_DI_1")
	)
	(segment
		(start 17.07388 -39.696136)
		(end 17.224756 -39.75862)
		(width 0.08382)
		(layer "In9.Cu")
		(net "SGPIO_DI_1")
	)
	(segment
		(start 36.83 -23.0378)
		(end 37.338 -22.5298)
		(width 0.08382)
		(layer "In9.Cu")
		(net "SGPIO_DI_1")
	)
	(segment
		(start 41.809416 -110.618016)
		(end 42.394886 -110.618016)
		(width 0.11684)
		(layer "F.Cu")
		(net "SGPIO_DI_0")
	)
	(segment
		(start 40.39235 -108.458)
		(end 40.132254 -108.458)
		(width 0.11684)
		(layer "F.Cu")
		(net "SGPIO_DI_0")
	)
	(segment
		(start 41.0083 -109.07395)
		(end 41.38295 -109.07395)
		(width 0.11684)
		(layer "F.Cu")
		(net "SGPIO_DI_0")
	)
	(segment
		(start 41.435274 -114.660426)
		(end 42.055034 -116.15674)
		(width 0.11684)
		(layer "F.Cu")
		(net "SGPIO_DI_0")
	)
	(segment
		(start 42.5704 -112.240822)
		(end 42.394886 -112.416336)
		(width 0.11684)
		(layer "F.Cu")
		(net "SGPIO_DI_0")
	)
	(segment
		(start 41.0083 -109.07395)
		(end 40.39235 -108.458)
		(width 0.11684)
		(layer "F.Cu")
		(net "SGPIO_DI_0")
	)
	(segment
		(start 42.5704 -111.041942)
		(end 42.394886 -111.217456)
		(width 0.11684)
		(layer "F.Cu")
		(net "SGPIO_DI_0")
	)
	(segment
		(start 42.055034 -116.15674)
		(end 42.055034 -118.25986)
		(width 0.11684)
		(layer "F.Cu")
		(net "SGPIO_DI_0")
	)
	(segment
		(start 41.435274 -112.59185)
		(end 41.435274 -114.660426)
		(width 0.11684)
		(layer "F.Cu")
		(net "SGPIO_DI_0")
	)
	(segment
		(start 42.394886 -111.816896)
		(end 42.5704 -111.99241)
		(width 0.11684)
		(layer "F.Cu")
		(net "SGPIO_DI_0")
	)
	(segment
		(start 40.132254 -108.458)
		(end 39.649654 -107.9754)
		(width 0.11684)
		(layer "F.Cu")
		(net "SGPIO_DI_0")
	)
	(segment
		(start 42.394886 -112.416336)
		(end 41.610788 -112.416336)
		(width 0.11684)
		(layer "F.Cu")
		(net "SGPIO_DI_0")
	)
	(segment
		(start 41.56202 -109.25302)
		(end 41.56202 -110.37062)
		(width 0.11684)
		(layer "F.Cu")
		(net "SGPIO_DI_0")
	)
	(segment
		(start 41.610788 -111.816896)
		(end 42.394886 -111.816896)
		(width 0.11684)
		(layer "F.Cu")
		(net "SGPIO_DI_0")
	)
	(segment
		(start 42.394886 -111.217456)
		(end 41.610788 -111.217456)
		(width 0.11684)
		(layer "F.Cu")
		(net "SGPIO_DI_0")
	)
	(segment
		(start 42.394886 -110.618016)
		(end 42.5704 -110.79353)
		(width 0.11684)
		(layer "F.Cu")
		(net "SGPIO_DI_0")
	)
	(segment
		(start 42.5704 -110.79353)
		(end 42.5704 -111.041942)
		(width 0.11684)
		(layer "F.Cu")
		(net "SGPIO_DI_0")
	)
	(segment
		(start 41.435274 -111.641382)
		(end 41.610788 -111.816896)
		(width 0.11684)
		(layer "F.Cu")
		(net "SGPIO_DI_0")
	)
	(segment
		(start 41.435274 -111.39297)
		(end 41.435274 -111.641382)
		(width 0.11684)
		(layer "F.Cu")
		(net "SGPIO_DI_0")
	)
	(segment
		(start 41.610788 -112.416336)
		(end 41.435274 -112.59185)
		(width 0.11684)
		(layer "F.Cu")
		(net "SGPIO_DI_0")
	)
	(segment
		(start 42.5704 -111.99241)
		(end 42.5704 -112.240822)
		(width 0.11684)
		(layer "F.Cu")
		(net "SGPIO_DI_0")
	)
	(segment
		(start 41.56202 -110.37062)
		(end 41.809416 -110.618016)
		(width 0.11684)
		(layer "F.Cu")
		(net "SGPIO_DI_0")
	)
	(segment
		(start 41.38295 -109.07395)
		(end 41.56202 -109.25302)
		(width 0.11684)
		(layer "F.Cu")
		(net "SGPIO_DI_0")
	)
	(segment
		(start 41.610788 -111.217456)
		(end 41.435274 -111.39297)
		(width 0.11684)
		(layer "F.Cu")
		(net "SGPIO_DI_0")
	)
	(segment
		(start 11.91895 -82.296)
		(end 11.30935 -82.296)
		(width 0.11684)
		(layer "F.Cu")
		(net "SGPIO_DI_0")
	)
	(via
		(at 18.0848 -109.6518)
		(size 0.508)
		(drill 0.254)
		(layers "F.Cu" "B.Cu")
		(net "SGPIO_DI_0")
	)
	(via
		(at 39.649654 -107.9754)
		(size 0.508)
		(drill 0.254)
		(layers "F.Cu" "B.Cu")
		(net "SGPIO_DI_0")
	)
	(via
		(at 11.30935 -82.296)
		(size 0.508)
		(drill 0.254)
		(layers "F.Cu" "B.Cu")
		(net "SGPIO_DI_0")
	)
	(segment
		(start 39.649654 -107.9754)
		(end 39.649654 -107.465114)
		(width 0.08382)
		(layer "In2.Cu")
		(net "SGPIO_DI_0")
	)
	(segment
		(start 39.649654 -107.465114)
		(end 39.12108 -106.93654)
		(width 0.08382)
		(layer "In2.Cu")
		(net "SGPIO_DI_0")
	)
	(segment
		(start 30.840172 -108.5342)
		(end 28.509722 -110.86465)
		(width 0.08382)
		(layer "In2.Cu")
		(net "SGPIO_DI_0")
	)
	(segment
		(start 18.45691 -110.02391)
		(end 18.0848 -109.6518)
		(width 0.08382)
		(layer "In2.Cu")
		(net "SGPIO_DI_0")
	)
	(segment
		(start 35.647122 -108.5342)
		(end 30.840172 -108.5342)
		(width 0.08382)
		(layer "In2.Cu")
		(net "SGPIO_DI_0")
	)
	(segment
		(start 28.509722 -110.86465)
		(end 26.104596 -110.86465)
		(width 0.08382)
		(layer "In2.Cu")
		(net "SGPIO_DI_0")
	)
	(segment
		(start 25.263856 -110.02391)
		(end 18.45691 -110.02391)
		(width 0.08382)
		(layer "In2.Cu")
		(net "SGPIO_DI_0")
	)
	(segment
		(start 26.104596 -110.86465)
		(end 25.263856 -110.02391)
		(width 0.08382)
		(layer "In2.Cu")
		(net "SGPIO_DI_0")
	)
	(segment
		(start 37.244782 -106.93654)
		(end 35.647122 -108.5342)
		(width 0.08382)
		(layer "In2.Cu")
		(net "SGPIO_DI_0")
	)
	(segment
		(start 39.12108 -106.93654)
		(end 37.244782 -106.93654)
		(width 0.08382)
		(layer "In2.Cu")
		(net "SGPIO_DI_0")
	)
	(segment
		(start 10.77214 -88.54186)
		(end 10.77214 -85.83422)
		(width 0.10668)
		(layer "In7.Cu")
		(net "SGPIO_DI_0")
	)
	(segment
		(start 12.83208 -105.579672)
		(end 12.83208 -104.441752)
		(width 0.10668)
		(layer "In7.Cu")
		(net "SGPIO_DI_0")
	)
	(segment
		(start 10.76706 -85.82914)
		(end 10.76706 -82.83829)
		(width 0.10668)
		(layer "In7.Cu")
		(net "SGPIO_DI_0")
	)
	(segment
		(start 14.3002 -106.299)
		(end 13.551408 -106.299)
		(width 0.10668)
		(layer "In7.Cu")
		(net "SGPIO_DI_0")
	)
	(segment
		(start 12.83208 -104.441752)
		(end 12.174728 -103.7844)
		(width 0.10668)
		(layer "In7.Cu")
		(net "SGPIO_DI_0")
	)
	(segment
		(start 12.174728 -103.7844)
		(end 11.036808 -103.7844)
		(width 0.10668)
		(layer "In7.Cu")
		(net "SGPIO_DI_0")
	)
	(segment
		(start 10.77214 -85.83422)
		(end 10.76706 -85.82914)
		(width 0.10668)
		(layer "In7.Cu")
		(net "SGPIO_DI_0")
	)
	(segment
		(start 11.036808 -103.7844)
		(end 10.287 -103.034592)
		(width 0.10668)
		(layer "In7.Cu")
		(net "SGPIO_DI_0")
	)
	(segment
		(start 10.287 -89.027)
		(end 10.77214 -88.54186)
		(width 0.10668)
		(layer "In7.Cu")
		(net "SGPIO_DI_0")
	)
	(segment
		(start 10.76706 -82.83829)
		(end 11.30935 -82.296)
		(width 0.10668)
		(layer "In7.Cu")
		(net "SGPIO_DI_0")
	)
	(segment
		(start 13.551408 -106.299)
		(end 12.83208 -105.579672)
		(width 0.10668)
		(layer "In7.Cu")
		(net "SGPIO_DI_0")
	)
	(segment
		(start 17.653 -109.6518)
		(end 14.3002 -106.299)
		(width 0.10668)
		(layer "In7.Cu")
		(net "SGPIO_DI_0")
	)
	(segment
		(start 18.0848 -109.6518)
		(end 17.653 -109.6518)
		(width 0.10668)
		(layer "In7.Cu")
		(net "SGPIO_DI_0")
	)
	(segment
		(start 10.287 -103.034592)
		(end 10.287 -89.027)
		(width 0.10668)
		(layer "In7.Cu")
		(net "SGPIO_DI_0")
	)
	(segment
		(start 39.03345 -109.8804)
		(end 39.03345 -112.044226)
		(width 0.11684)
		(layer "F.Cu")
		(net "SGPIO_CLK_1")
	)
	(segment
		(start 39.654988 -117.354096)
		(end 39.654988 -118.460012)
		(width 0.11684)
		(layer "F.Cu")
		(net "SGPIO_CLK_1")
	)
	(segment
		(start 39.46906 -116.905024)
		(end 39.654988 -117.354096)
		(width 0.11684)
		(layer "F.Cu")
		(net "SGPIO_CLK_1")
	)
	(segment
		(start 39.03345 -112.044226)
		(end 39.46906 -113.09604)
		(width 0.11684)
		(layer "F.Cu")
		(net "SGPIO_CLK_1")
	)
	(segment
		(start 39.01186 -107.4674)
		(end 38.6588 -107.4674)
		(width 0.11684)
		(layer "F.Cu")
		(net "SGPIO_CLK_1")
	)
	(segment
		(start 39.03345 -109.8804)
		(end 39.03345 -108.9914)
		(width 0.11684)
		(layer "F.Cu")
		(net "SGPIO_CLK_1")
	)
	(segment
		(start 39.03345 -108.9914)
		(end 39.00805 -108.966)
		(width 0.11684)
		(layer "F.Cu")
		(net "SGPIO_CLK_1")
	)
	(segment
		(start 39.00805 -108.966)
		(end 39.1668 -108.80725)
		(width 0.11684)
		(layer "F.Cu")
		(net "SGPIO_CLK_1")
	)
	(segment
		(start 39.46906 -113.09604)
		(end 39.46906 -116.905024)
		(width 0.11684)
		(layer "F.Cu")
		(net "SGPIO_CLK_1")
	)
	(segment
		(start 39.1668 -107.62234)
		(end 39.01186 -107.4674)
		(width 0.11684)
		(layer "F.Cu")
		(net "SGPIO_CLK_1")
	)
	(segment
		(start 39.1668 -108.80725)
		(end 39.1668 -107.62234)
		(width 0.11684)
		(layer "F.Cu")
		(net "SGPIO_CLK_1")
	)
	(segment
		(start 50.79619 -34.237676)
		(end 50.79619 -33.602676)
		(width 0.11684)
		(layer "F.Cu")
		(net "SGPIO_CLK_1")
	)
	(via
		(at 50.79619 -33.602676)
		(size 0.508)
		(drill 0.254)
		(layers "F.Cu" "B.Cu")
		(net "SGPIO_CLK_1")
	)
	(via
		(at 27.698192 -108.166662)
		(size 0.508)
		(drill 0.254)
		(layers "F.Cu" "B.Cu")
		(net "SGPIO_CLK_1")
	)
	(via
		(at 38.6588 -107.4674)
		(size 0.508)
		(drill 0.254)
		(layers "F.Cu" "B.Cu")
		(net "SGPIO_CLK_1")
	)
	(segment
		(start 12.55268 -67.112134)
		(end 12.55268 -80.13192)
		(width 0.10668)
		(layer "In4.Cu")
		(net "SGPIO_CLK_1")
	)
	(segment
		(start 22.05736 -109.33938)
		(end 25.314402 -109.33938)
		(width 0.10668)
		(layer "In4.Cu")
		(net "SGPIO_CLK_1")
	)
	(segment
		(start 15.748 -108.455968)
		(end 14.550898 -109.65307)
		(width 0.10668)
		(layer "In4.Cu")
		(net "SGPIO_CLK_1")
	)
	(segment
		(start 25.601422 -109.6264)
		(end 26.9494 -109.6264)
		(width 0.10668)
		(layer "In4.Cu")
		(net "SGPIO_CLK_1")
	)
	(segment
		(start 12.3444 -80.924654)
		(end 12.90066 -81.480914)
		(width 0.10668)
		(layer "In4.Cu")
		(net "SGPIO_CLK_1")
	)
	(segment
		(start 11.2268 -52.880768)
		(end 11.2268 -55.484522)
		(width 0.10668)
		(layer "In4.Cu")
		(net "SGPIO_CLK_1")
	)
	(segment
		(start 25.314402 -109.33938)
		(end 25.601422 -109.6264)
		(width 0.10668)
		(layer "In4.Cu")
		(net "SGPIO_CLK_1")
	)
	(segment
		(start 15.18666 -20.678394)
		(end 15.18666 -27.803094)
		(width 0.10668)
		(layer "In4.Cu")
		(net "SGPIO_CLK_1")
	)
	(segment
		(start 36.2966 -27.1018)
		(end 33.4899 -27.1018)
		(width 0.10668)
		(layer "In4.Cu")
		(net "SGPIO_CLK_1")
	)
	(segment
		(start 6.3246 -100.1522)
		(end 7.812278 -101.639878)
		(width 0.10668)
		(layer "In4.Cu")
		(net "SGPIO_CLK_1")
	)
	(segment
		(start 20.95754 -109.75086)
		(end 20.95754 -109.15904)
		(width 0.10668)
		(layer "In4.Cu")
		(net "SGPIO_CLK_1")
	)
	(segment
		(start 11.236198 -48.618648)
		(end 11.22934 -48.628808)
		(width 0.10668)
		(layer "In4.Cu")
		(net "SGPIO_CLK_1")
	)
	(segment
		(start 11.22172 -52.875688)
		(end 11.2268 -52.880768)
		(width 0.10668)
		(layer "In4.Cu")
		(net "SGPIO_CLK_1")
	)
	(segment
		(start 26.543 -22.352)
		(end 25.5778 -21.3868)
		(width 0.10668)
		(layer "In4.Cu")
		(net "SGPIO_CLK_1")
	)
	(segment
		(start 20.95754 -109.15904)
		(end 21.22678 -108.8898)
		(width 0.10668)
		(layer "In4.Cu")
		(net "SGPIO_CLK_1")
	)
	(segment
		(start 19.9644 -110.744)
		(end 20.95754 -109.75086)
		(width 0.10668)
		(layer "In4.Cu")
		(net "SGPIO_CLK_1")
	)
	(segment
		(start 15.18666 -27.803094)
		(end 15.1384 -27.851354)
		(width 0.10668)
		(layer "In4.Cu")
		(net "SGPIO_CLK_1")
	)
	(segment
		(start 24.454866 -19.98853)
		(end 15.876524 -19.98853)
		(width 0.10668)
		(layer "In4.Cu")
		(net "SGPIO_CLK_1")
	)
	(segment
		(start 14.537436 -106.2228)
		(end 15.748 -107.433364)
		(width 0.10668)
		(layer "In4.Cu")
		(net "SGPIO_CLK_1")
	)
	(segment
		(start 33.4899 -27.1018)
		(end 30.9626 -24.5745)
		(width 0.10668)
		(layer "In4.Cu")
		(net "SGPIO_CLK_1")
	)
	(segment
		(start 8.42518 -102.69982)
		(end 8.42518 -104.145588)
		(width 0.10668)
		(layer "In4.Cu")
		(net "SGPIO_CLK_1")
	)
	(segment
		(start 12.141454 -82.7786)
		(end 10.922 -82.7786)
		(width 0.10668)
		(layer "In4.Cu")
		(net "SGPIO_CLK_1")
	)
	(segment
		(start 10.76706 -82.93354)
		(end 10.76706 -88.673686)
		(width 0.10668)
		(layer "In4.Cu")
		(net "SGPIO_CLK_1")
	)
	(segment
		(start 29.536136 -24.5745)
		(end 27.313636 -22.352)
		(width 0.10668)
		(layer "In4.Cu")
		(net "SGPIO_CLK_1")
	)
	(segment
		(start 7.812278 -101.639878)
		(end 7.812278 -102.086918)
		(width 0.10668)
		(layer "In4.Cu")
		(net "SGPIO_CLK_1")
	)
	(segment
		(start 27.697938 -108.166916)
		(end 27.698192 -108.166662)
		(width 0.10668)
		(layer "In4.Cu")
		(net "SGPIO_CLK_1")
	)
	(segment
		(start 14.2748 -45.580046)
		(end 11.236198 -48.618648)
		(width 0.10668)
		(layer "In4.Cu")
		(net "SGPIO_CLK_1")
	)
	(segment
		(start 11.22172 -49.791112)
		(end 11.22172 -52.875688)
		(width 0.10668)
		(layer "In4.Cu")
		(net "SGPIO_CLK_1")
	)
	(segment
		(start 7.812278 -102.086918)
		(end 8.42518 -102.69982)
		(width 0.10668)
		(layer "In4.Cu")
		(net "SGPIO_CLK_1")
	)
	(segment
		(start 50.79619 -33.602676)
		(end 50.79619 -33.363662)
		(width 0.10668)
		(layer "In4.Cu")
		(net "SGPIO_CLK_1")
	)
	(segment
		(start 50.28184 -32.849312)
		(end 50.28184 -31.841186)
		(width 0.10668)
		(layer "In4.Cu")
		(net "SGPIO_CLK_1")
	)
	(segment
		(start 49.53 -31.089346)
		(end 49.53 -29.194506)
		(width 0.10668)
		(layer "In4.Cu")
		(net "SGPIO_CLK_1")
	)
	(segment
		(start 27.697938 -108.877862)
		(end 27.697938 -108.166916)
		(width 0.10668)
		(layer "In4.Cu")
		(net "SGPIO_CLK_1")
	)
	(segment
		(start 11.2268 -48.641508)
		(end 11.2268 -49.786032)
		(width 0.10668)
		(layer "In4.Cu")
		(net "SGPIO_CLK_1")
	)
	(segment
		(start 27.313636 -22.352)
		(end 26.543 -22.352)
		(width 0.10668)
		(layer "In4.Cu")
		(net "SGPIO_CLK_1")
	)
	(segment
		(start 10.922 -82.7786)
		(end 10.76706 -82.93354)
		(width 0.10668)
		(layer "In4.Cu")
		(net "SGPIO_CLK_1")
	)
	(segment
		(start 15.748 -107.433364)
		(end 15.748 -108.455968)
		(width 0.10668)
		(layer "In4.Cu")
		(net "SGPIO_CLK_1")
	)
	(segment
		(start 9.7663 -90.04554)
		(end 8.064754 -90.04554)
		(width 0.10668)
		(layer "In4.Cu")
		(net "SGPIO_CLK_1")
	)
	(segment
		(start 11.2268 -55.484522)
		(end 11.811 -56.894984)
		(width 0.10668)
		(layer "In4.Cu")
		(net "SGPIO_CLK_1")
	)
	(segment
		(start 10.03554 -89.7763)
		(end 9.7663 -90.04554)
		(width 0.10668)
		(layer "In4.Cu")
		(net "SGPIO_CLK_1")
	)
	(segment
		(start 7.5184 -91.69019)
		(end 6.52399 -92.6846)
		(width 0.10668)
		(layer "In4.Cu")
		(net "SGPIO_CLK_1")
	)
	(segment
		(start 10.03554 -89.405206)
		(end 10.03554 -89.7763)
		(width 0.10668)
		(layer "In4.Cu")
		(net "SGPIO_CLK_1")
	)
	(segment
		(start 12.90066 -82.019394)
		(end 12.141454 -82.7786)
		(width 0.10668)
		(layer "In4.Cu")
		(net "SGPIO_CLK_1")
	)
	(segment
		(start 50.28184 -31.841186)
		(end 49.53 -31.089346)
		(width 0.10668)
		(layer "In4.Cu")
		(net "SGPIO_CLK_1")
	)
	(segment
		(start 11.2268 -49.786032)
		(end 11.22172 -49.791112)
		(width 0.10668)
		(layer "In4.Cu")
		(net "SGPIO_CLK_1")
	)
	(segment
		(start 5.0292 -99.695)
		(end 5.4864 -100.1522)
		(width 0.10668)
		(layer "In4.Cu")
		(net "SGPIO_CLK_1")
	)
	(segment
		(start 11.684 -61.1124)
		(end 11.684 -66.243454)
		(width 0.10668)
		(layer "In4.Cu")
		(net "SGPIO_CLK_1")
	)
	(segment
		(start 8.064754 -90.04554)
		(end 7.5184 -90.591894)
		(width 0.10668)
		(layer "In4.Cu")
		(net "SGPIO_CLK_1")
	)
	(segment
		(start 37.0586 -26.3398)
		(end 36.2966 -27.1018)
		(width 0.10668)
		(layer "In4.Cu")
		(net "SGPIO_CLK_1")
	)
	(segment
		(start 41.740836 -27.4955)
		(end 40.585136 -26.3398)
		(width 0.10668)
		(layer "In4.Cu")
		(net "SGPIO_CLK_1")
	)
	(segment
		(start 25.5778 -21.111464)
		(end 24.454866 -19.98853)
		(width 0.10668)
		(layer "In4.Cu")
		(net "SGPIO_CLK_1")
	)
	(segment
		(start 8.42518 -104.145588)
		(end 10.502392 -106.2228)
		(width 0.10668)
		(layer "In4.Cu")
		(net "SGPIO_CLK_1")
	)
	(segment
		(start 15.1384 -27.851354)
		(end 15.1384 -27.851608)
		(width 0.10668)
		(layer "In4.Cu")
		(net "SGPIO_CLK_1")
	)
	(segment
		(start 21.60778 -108.8898)
		(end 22.05736 -109.33938)
		(width 0.10668)
		(layer "In4.Cu")
		(net "SGPIO_CLK_1")
	)
	(segment
		(start 21.22678 -108.8898)
		(end 21.60778 -108.8898)
		(width 0.10668)
		(layer "In4.Cu")
		(net "SGPIO_CLK_1")
	)
	(segment
		(start 5.5626 -92.6846)
		(end 5.0292 -93.218)
		(width 0.10668)
		(layer "In4.Cu")
		(net "SGPIO_CLK_1")
	)
	(segment
		(start 6.52399 -92.6846)
		(end 5.5626 -92.6846)
		(width 0.10668)
		(layer "In4.Cu")
		(net "SGPIO_CLK_1")
	)
	(segment
		(start 40.585136 -26.3398)
		(end 37.0586 -26.3398)
		(width 0.10668)
		(layer "In4.Cu")
		(net "SGPIO_CLK_1")
	)
	(segment
		(start 49.53 -29.194506)
		(end 47.830994 -27.4955)
		(width 0.10668)
		(layer "In4.Cu")
		(net "SGPIO_CLK_1")
	)
	(segment
		(start 26.9494 -109.6264)
		(end 27.697938 -108.877862)
		(width 0.10668)
		(layer "In4.Cu")
		(net "SGPIO_CLK_1")
	)
	(segment
		(start 11.22934 -48.628808)
		(end 11.2268 -48.641508)
		(width 0.10668)
		(layer "In4.Cu")
		(net "SGPIO_CLK_1")
	)
	(segment
		(start 5.4864 -100.1522)
		(end 6.3246 -100.1522)
		(width 0.10668)
		(layer "In4.Cu")
		(net "SGPIO_CLK_1")
	)
	(segment
		(start 11.811 -60.9854)
		(end 11.684 -61.1124)
		(width 0.10668)
		(layer "In4.Cu")
		(net "SGPIO_CLK_1")
	)
	(segment
		(start 11.684 -66.243454)
		(end 12.55268 -67.112134)
		(width 0.10668)
		(layer "In4.Cu")
		(net "SGPIO_CLK_1")
	)
	(segment
		(start 25.5778 -21.3868)
		(end 25.5778 -21.111464)
		(width 0.10668)
		(layer "In4.Cu")
		(net "SGPIO_CLK_1")
	)
	(segment
		(start 12.90066 -81.480914)
		(end 12.90066 -82.019394)
		(width 0.10668)
		(layer "In4.Cu")
		(net "SGPIO_CLK_1")
	)
	(segment
		(start 10.76706 -88.673686)
		(end 10.03554 -89.405206)
		(width 0.10668)
		(layer "In4.Cu")
		(net "SGPIO_CLK_1")
	)
	(segment
		(start 5.0292 -93.218)
		(end 5.0292 -99.695)
		(width 0.10668)
		(layer "In4.Cu")
		(net "SGPIO_CLK_1")
	)
	(segment
		(start 12.55268 -80.13192)
		(end 12.3444 -80.3402)
		(width 0.10668)
		(layer "In4.Cu")
		(net "SGPIO_CLK_1")
	)
	(segment
		(start 14.934946 -110.744)
		(end 19.9644 -110.744)
		(width 0.10668)
		(layer "In4.Cu")
		(net "SGPIO_CLK_1")
	)
	(segment
		(start 30.9626 -24.5745)
		(end 29.536136 -24.5745)
		(width 0.10668)
		(layer "In4.Cu")
		(net "SGPIO_CLK_1")
	)
	(segment
		(start 12.3444 -80.3402)
		(end 12.3444 -80.924654)
		(width 0.10668)
		(layer "In4.Cu")
		(net "SGPIO_CLK_1")
	)
	(segment
		(start 14.550898 -110.359952)
		(end 14.934946 -110.744)
		(width 0.10668)
		(layer "In4.Cu")
		(net "SGPIO_CLK_1")
	)
	(segment
		(start 10.502392 -106.2228)
		(end 14.537436 -106.2228)
		(width 0.10668)
		(layer "In4.Cu")
		(net "SGPIO_CLK_1")
	)
	(segment
		(start 15.1384 -27.851608)
		(end 14.2748 -28.715208)
		(width 0.10668)
		(layer "In4.Cu")
		(net "SGPIO_CLK_1")
	)
	(segment
		(start 7.5184 -90.591894)
		(end 7.5184 -91.69019)
		(width 0.10668)
		(layer "In4.Cu")
		(net "SGPIO_CLK_1")
	)
	(segment
		(start 47.830994 -27.4955)
		(end 41.740836 -27.4955)
		(width 0.10668)
		(layer "In4.Cu")
		(net "SGPIO_CLK_1")
	)
	(segment
		(start 11.811 -56.894984)
		(end 11.811 -60.9854)
		(width 0.10668)
		(layer "In4.Cu")
		(net "SGPIO_CLK_1")
	)
	(segment
		(start 14.550898 -109.65307)
		(end 14.550898 -110.359952)
		(width 0.10668)
		(layer "In4.Cu")
		(net "SGPIO_CLK_1")
	)
	(segment
		(start 15.876524 -19.98853)
		(end 15.18666 -20.678394)
		(width 0.10668)
		(layer "In4.Cu")
		(net "SGPIO_CLK_1")
	)
	(segment
		(start 50.79619 -33.363662)
		(end 50.28184 -32.849312)
		(width 0.10668)
		(layer "In4.Cu")
		(net "SGPIO_CLK_1")
	)
	(segment
		(start 14.2748 -28.715208)
		(end 14.2748 -45.580046)
		(width 0.10668)
		(layer "In4.Cu")
		(net "SGPIO_CLK_1")
	)
	(segment
		(start 35.354768 -109.474)
		(end 37.1856 -109.474)
		(width 0.10668)
		(layer "In7.Cu")
		(net "SGPIO_CLK_1")
	)
	(segment
		(start 37.1856 -109.474)
		(end 38.1508 -108.5088)
		(width 0.10668)
		(layer "In7.Cu")
		(net "SGPIO_CLK_1")
	)
	(segment
		(start 28.080716 -108.54944)
		(end 30.432248 -108.54944)
		(width 0.10668)
		(layer "In7.Cu")
		(net "SGPIO_CLK_1")
	)
	(segment
		(start 38.1508 -108.5088)
		(end 38.1508 -107.96016)
		(width 0.10668)
		(layer "In7.Cu")
		(net "SGPIO_CLK_1")
	)
	(segment
		(start 38.4429 -107.66806)
		(end 38.45814 -107.66806)
		(width 0.10668)
		(layer "In7.Cu")
		(net "SGPIO_CLK_1")
	)
	(segment
		(start 30.996128 -109.11332)
		(end 34.994088 -109.11332)
		(width 0.10668)
		(layer "In7.Cu")
		(net "SGPIO_CLK_1")
	)
	(segment
		(start 34.994088 -109.11332)
		(end 35.354768 -109.474)
		(width 0.10668)
		(layer "In7.Cu")
		(net "SGPIO_CLK_1")
	)
	(segment
		(start 38.45814 -107.66806)
		(end 38.6588 -107.4674)
		(width 0.10668)
		(layer "In7.Cu")
		(net "SGPIO_CLK_1")
	)
	(segment
		(start 28.080716 -108.549186)
		(end 28.080716 -108.54944)
		(width 0.10668)
		(layer "In7.Cu")
		(net "SGPIO_CLK_1")
	)
	(segment
		(start 27.698192 -108.166662)
		(end 28.080716 -108.549186)
		(width 0.10668)
		(layer "In7.Cu")
		(net "SGPIO_CLK_1")
	)
	(segment
		(start 38.1508 -107.96016)
		(end 38.4429 -107.66806)
		(width 0.10668)
		(layer "In7.Cu")
		(net "SGPIO_CLK_1")
	)
	(segment
		(start 30.432248 -108.54944)
		(end 30.996128 -109.11332)
		(width 0.10668)
		(layer "In7.Cu")
		(net "SGPIO_CLK_1")
	)
	(segment
		(start 15.29715 -85.308186)
		(end 15.29715 -85.369146)
		(width 0.11684)
		(layer "F.Cu")
		(net "SGPIO_CLK_0")
	)
	(segment
		(start 46.03115 -109.8804)
		(end 46.0756 -109.92485)
		(width 0.11684)
		(layer "F.Cu")
		(net "SGPIO_CLK_0")
	)
	(segment
		(start 43.0784 -109.89818)
		(end 43.50258 -109.89818)
		(width 0.11684)
		(layer "F.Cu")
		(net "SGPIO_CLK_0")
	)
	(segment
		(start 42.679366 -115.99164)
		(end 42.679366 -113.114582)
		(width 0.11684)
		(layer "F.Cu")
		(net "SGPIO_CLK_0")
	)
	(segment
		(start 43.31589 -111.094774)
		(end 43.077892 -109.898942)
		(width 0.11684)
		(layer "F.Cu")
		(net "SGPIO_CLK_0")
	)
	(segment
		(start 43.50258 -109.89818)
		(end 44.0944 -110.49)
		(width 0.11684)
		(layer "F.Cu")
		(net "SGPIO_CLK_0")
	)
	(segment
		(start 42.679366 -113.114582)
		(end 43.131232 -112.023906)
		(width 0.11684)
		(layer "F.Cu")
		(net "SGPIO_CLK_0")
	)
	(segment
		(start 14.1732 -84.184236)
		(end 15.29715 -85.308186)
		(width 0.11684)
		(layer "F.Cu")
		(net "SGPIO_CLK_0")
	)
	(segment
		(start 45.10405 -109.8804)
		(end 46.03115 -109.8804)
		(width 0.11684)
		(layer "F.Cu")
		(net "SGPIO_CLK_0")
	)
	(segment
		(start 43.077892 -109.898942)
		(end 43.0784 -109.89818)
		(width 0.11684)
		(layer "F.Cu")
		(net "SGPIO_CLK_0")
	)
	(segment
		(start 42.654982 -116.016024)
		(end 42.654982 -118.25986)
		(width 0.11684)
		(layer "F.Cu")
		(net "SGPIO_CLK_0")
	)
	(segment
		(start 44.0944 -110.49)
		(end 44.754546 -110.49)
		(width 0.11684)
		(layer "F.Cu")
		(net "SGPIO_CLK_0")
	)
	(segment
		(start 45.10405 -110.140496)
		(end 45.10405 -109.8804)
		(width 0.11684)
		(layer "F.Cu")
		(net "SGPIO_CLK_0")
	)
	(segment
		(start 14.1732 -84.09305)
		(end 14.1732 -84.184236)
		(width 0.11684)
		(layer "F.Cu")
		(net "SGPIO_CLK_0")
	)
	(segment
		(start 43.131232 -112.023906)
		(end 43.31589 -111.094774)
		(width 0.11684)
		(layer "F.Cu")
		(net "SGPIO_CLK_0")
	)
	(segment
		(start 42.679366 -115.99164)
		(end 42.654982 -116.016024)
		(width 0.11684)
		(layer "F.Cu")
		(net "SGPIO_CLK_0")
	)
	(segment
		(start 44.754546 -110.49)
		(end 45.10405 -110.140496)
		(width 0.11684)
		(layer "F.Cu")
		(net "SGPIO_CLK_0")
	)
	(via
		(at 10.8966 -104.8766)
		(size 0.508)
		(drill 0.254)
		(layers "F.Cu" "B.Cu")
		(net "SGPIO_CLK_0")
	)
	(via
		(at 42.679366 -115.99164)
		(size 0.508)
		(drill 0.254)
		(layers "F.Cu" "B.Cu")
		(net "SGPIO_CLK_0")
	)
	(via
		(at 15.29715 -85.369146)
		(size 0.508)
		(drill 0.254)
		(layers "F.Cu" "B.Cu")
		(net "SGPIO_CLK_0")
	)
	(via
		(at 43.0784 -109.89818)
		(size 0.762)
		(drill 0.381)
		(layers "F.Cu" "B.Cu")
		(net "SGPIO_CLK_0")
	)
	(segment
		(start 20.359116 -111.722916)
		(end 22.2758 -109.806232)
		(width 0.10668)
		(layer "In7.Cu")
		(net "SGPIO_CLK_0")
	)
	(segment
		(start 12.3698 -108.766864)
		(end 14.172184 -110.569248)
		(width 0.10668)
		(layer "In7.Cu")
		(net "SGPIO_CLK_0")
	)
	(segment
		(start 10.8966 -104.8766)
		(end 10.8966 -105.537)
		(width 0.10668)
		(layer "In7.Cu")
		(net "SGPIO_CLK_0")
	)
	(segment
		(start 10.8966 -105.537)
		(end 12.3698 -107.0102)
		(width 0.10668)
		(layer "In7.Cu")
		(net "SGPIO_CLK_0")
	)
	(segment
		(start 40.422576 -114.70132)
		(end 41.279826 -115.056412)
		(width 0.10668)
		(layer "In7.Cu")
		(net "SGPIO_CLK_0")
	)
	(segment
		(start 22.2758 -109.806232)
		(end 29.364432 -109.806232)
		(width 0.10668)
		(layer "In7.Cu")
		(net "SGPIO_CLK_0")
	)
	(segment
		(start 30.66288 -111.10468)
		(end 35.180016 -111.10468)
		(width 0.10668)
		(layer "In7.Cu")
		(net "SGPIO_CLK_0")
	)
	(segment
		(start 41.279826 -115.056412)
		(end 42.679366 -115.99164)
		(width 0.10668)
		(layer "In7.Cu")
		(net "SGPIO_CLK_0")
	)
	(segment
		(start 39.3954 -114.097816)
		(end 39.998904 -114.70132)
		(width 0.10668)
		(layer "In7.Cu")
		(net "SGPIO_CLK_0")
	)
	(segment
		(start 35.180016 -111.10468)
		(end 37.130736 -113.0554)
		(width 0.10668)
		(layer "In7.Cu")
		(net "SGPIO_CLK_0")
	)
	(segment
		(start 39.3954 -113.6904)
		(end 39.3954 -114.097816)
		(width 0.10668)
		(layer "In7.Cu")
		(net "SGPIO_CLK_0")
	)
	(segment
		(start 37.130736 -113.0554)
		(end 38.7604 -113.0554)
		(width 0.10668)
		(layer "In7.Cu")
		(net "SGPIO_CLK_0")
	)
	(segment
		(start 12.3698 -107.0102)
		(end 12.3698 -108.766864)
		(width 0.10668)
		(layer "In7.Cu")
		(net "SGPIO_CLK_0")
	)
	(segment
		(start 17.097248 -110.569248)
		(end 18.250916 -111.722916)
		(width 0.10668)
		(layer "In7.Cu")
		(net "SGPIO_CLK_0")
	)
	(segment
		(start 38.7604 -113.0554)
		(end 39.3954 -113.6904)
		(width 0.10668)
		(layer "In7.Cu")
		(net "SGPIO_CLK_0")
	)
	(segment
		(start 39.998904 -114.70132)
		(end 40.422576 -114.70132)
		(width 0.10668)
		(layer "In7.Cu")
		(net "SGPIO_CLK_0")
	)
	(segment
		(start 14.172184 -110.569248)
		(end 17.097248 -110.569248)
		(width 0.10668)
		(layer "In7.Cu")
		(net "SGPIO_CLK_0")
	)
	(segment
		(start 29.364432 -109.806232)
		(end 30.66288 -111.10468)
		(width 0.10668)
		(layer "In7.Cu")
		(net "SGPIO_CLK_0")
	)
	(segment
		(start 18.250916 -111.722916)
		(end 20.359116 -111.722916)
		(width 0.10668)
		(layer "In7.Cu")
		(net "SGPIO_CLK_0")
	)
	(segment
		(start 11.912854 -104.3432)
		(end 11.43 -104.3432)
		(width 0.08382)
		(layer "In9.Cu")
		(net "SGPIO_CLK_0")
	)
	(segment
		(start 14.7574 -90.6526)
		(end 14.7574 -92.989654)
		(width 0.08382)
		(layer "In9.Cu")
		(net "SGPIO_CLK_0")
	)
	(segment
		(start 13.5636 -87.102696)
		(end 13.5636 -89.4588)
		(width 0.08382)
		(layer "In9.Cu")
		(net "SGPIO_CLK_0")
	)
	(segment
		(start 13.478002 -105.43921)
		(end 13.008864 -105.43921)
		(width 0.08382)
		(layer "In9.Cu")
		(net "SGPIO_CLK_0")
	)
	(segment
		(start 13.74013 -105.177082)
		(end 13.478002 -105.43921)
		(width 0.08382)
		(layer "In9.Cu")
		(net "SGPIO_CLK_0")
	)
	(segment
		(start 13.5636 -89.4588)
		(end 14.7574 -90.6526)
		(width 0.08382)
		(layer "In9.Cu")
		(net "SGPIO_CLK_0")
	)
	(segment
		(start 14.7574 -92.989654)
		(end 15.3924 -93.624654)
		(width 0.08382)
		(layer "In9.Cu")
		(net "SGPIO_CLK_0")
	)
	(segment
		(start 11.43 -104.3432)
		(end 10.8966 -104.8766)
		(width 0.08382)
		(layer "In9.Cu")
		(net "SGPIO_CLK_0")
	)
	(segment
		(start 13.008864 -105.43921)
		(end 11.912854 -104.3432)
		(width 0.08382)
		(layer "In9.Cu")
		(net "SGPIO_CLK_0")
	)
	(segment
		(start 15.29715 -85.369146)
		(end 13.5636 -87.102696)
		(width 0.08382)
		(layer "In9.Cu")
		(net "SGPIO_CLK_0")
	)
	(segment
		(start 15.3924 -93.624654)
		(end 15.3924 -97.8662)
		(width 0.08382)
		(layer "In9.Cu")
		(net "SGPIO_CLK_0")
	)
	(segment
		(start 13.74013 -99.51847)
		(end 13.74013 -105.177082)
		(width 0.08382)
		(layer "In9.Cu")
		(net "SGPIO_CLK_0")
	)
	(segment
		(start 15.3924 -97.8662)
		(end 13.74013 -99.51847)
		(width 0.08382)
		(layer "In9.Cu")
		(net "SGPIO_CLK_0")
	)
	(segment
		(start 50.292 -31.76905)
		(end 50.8 -31.26105)
		(width 0.11684)
		(layer "F.Cu")
		(net "SGPIO_BMC_M1_LD")
	)
	(segment
		(start 50.470562 -36.398708)
		(end 50.470562 -35.484562)
		(width 0.11684)
		(layer "F.Cu")
		(net "SGPIO_BMC_M1_LD")
	)
	(segment
		(start 50.292 -35.306)
		(end 50.292 -31.76905)
		(width 0.11684)
		(layer "F.Cu")
		(net "SGPIO_BMC_M1_LD")
	)
	(segment
		(start 50.470562 -37.705284)
		(end 50.896266 -38.130988)
		(width 0.11684)
		(layer "F.Cu")
		(net "SGPIO_BMC_M1_LD")
	)
	(segment
		(start 50.470562 -36.398708)
		(end 50.470562 -37.705284)
		(width 0.11684)
		(layer "F.Cu")
		(net "SGPIO_BMC_M1_LD")
	)
	(segment
		(start 50.896266 -38.130988)
		(end 50.896266 -39.77259)
		(width 0.11684)
		(layer "F.Cu")
		(net "SGPIO_BMC_M1_LD")
	)
	(segment
		(start 50.470562 -35.484562)
		(end 50.292 -35.306)
		(width 0.11684)
		(layer "F.Cu")
		(net "SGPIO_BMC_M1_LD")
	)
	(segment
		(start 50.896266 -39.77259)
		(end 51.295046 -40.17137)
		(width 0.11684)
		(layer "F.Cu")
		(net "SGPIO_BMC_M1_LD")
	)
	(via
		(at 50.470562 -36.398708)
		(size 0.762)
		(drill 0.381)
		(layers "F.Cu" "B.Cu")
		(net "SGPIO_BMC_M1_LD")
	)
	(segment
		(start 51.295046 -40.971216)
		(end 50.899822 -40.575992)
		(width 0.11684)
		(layer "F.Cu")
		(net "SGPIO_BMC_M1_DO")
	)
	(via
		(at 50.899822 -40.575992)
		(size 0.4572)
		(drill 0.254)
		(layers "F.Cu" "B.Cu")
		(net "SGPIO_BMC_M1_DO")
	)
	(segment
		(start 50.813716 -40.142668)
		(end 50.899822 -40.575992)
		(width 0.11684)
		(layer "B.Cu")
		(net "SGPIO_BMC_M1_DO")
	)
	(segment
		(start 49.868328 -37.335714)
		(end 49.868328 -37.396674)
		(width 0.11684)
		(layer "B.Cu")
		(net "SGPIO_BMC_M1_DO")
	)
	(segment
		(start 49.868328 -37.396674)
		(end 50.38344 -37.911786)
		(width 0.11684)
		(layer "B.Cu")
		(net "SGPIO_BMC_M1_DO")
	)
	(segment
		(start 50.38344 -37.911786)
		(end 50.38344 -38.978332)
		(width 0.11684)
		(layer "B.Cu")
		(net "SGPIO_BMC_M1_DO")
	)
	(segment
		(start 50.38344 -38.978332)
		(end 50.813716 -39.410894)
		(width 0.11684)
		(layer "B.Cu")
		(net "SGPIO_BMC_M1_DO")
	)
	(segment
		(start 50.813716 -39.410894)
		(end 50.813716 -40.142668)
		(width 0.11684)
		(layer "B.Cu")
		(net "SGPIO_BMC_M1_DO")
	)
	(segment
		(start 52.74056 -36.855908)
		(end 52.367434 -37.7571)
		(width 0.11684)
		(layer "F.Cu")
		(net "SGPIO_BMC_M1_DI")
	)
	(segment
		(start 51.0286 -28.1432)
		(end 51.4096 -28.5242)
		(width 0.11684)
		(layer "F.Cu")
		(net "SGPIO_BMC_M1_DI")
	)
	(segment
		(start 51.4096 -28.5242)
		(end 51.4096 -28.633674)
		(width 0.11684)
		(layer "F.Cu")
		(net "SGPIO_BMC_M1_DI")
	)
	(segment
		(start 51.4096 -28.633674)
		(end 52.47767 -29.701744)
		(width 0.11684)
		(layer "F.Cu")
		(net "SGPIO_BMC_M1_DI")
	)
	(segment
		(start 52.367434 -37.7571)
		(end 52.367434 -38.713156)
		(width 0.11684)
		(layer "F.Cu")
		(net "SGPIO_BMC_M1_DI")
	)
	(segment
		(start 52.47767 -29.701744)
		(end 52.47767 -35.110166)
		(width 0.11684)
		(layer "F.Cu")
		(net "SGPIO_BMC_M1_DI")
	)
	(segment
		(start 52.567332 -35.326574)
		(end 52.74056 -35.499802)
		(width 0.11684)
		(layer "F.Cu")
		(net "SGPIO_BMC_M1_DI")
	)
	(segment
		(start 52.47767 -35.110166)
		(end 52.567332 -35.326574)
		(width 0.11684)
		(layer "F.Cu")
		(net "SGPIO_BMC_M1_DI")
	)
	(segment
		(start 51.0286 -28.1432)
		(end 49.75225 -28.1432)
		(width 0.11684)
		(layer "F.Cu")
		(net "SGPIO_BMC_M1_DI")
	)
	(segment
		(start 52.367434 -38.713156)
		(end 52.094892 -39.37127)
		(width 0.11684)
		(layer "F.Cu")
		(net "SGPIO_BMC_M1_DI")
	)
	(segment
		(start 52.74056 -35.499802)
		(end 52.74056 -36.855908)
		(width 0.11684)
		(layer "F.Cu")
		(net "SGPIO_BMC_M1_DI")
	)
	(segment
		(start 49.75225 -28.1432)
		(end 49.62525 -28.2702)
		(width 0.11684)
		(layer "F.Cu")
		(net "SGPIO_BMC_M1_DI")
	)
	(via
		(at 51.0286 -28.1432)
		(size 0.762)
		(drill 0.381)
		(layers "F.Cu" "B.Cu")
		(net "SGPIO_BMC_M1_DI")
	)
	(segment
		(start 50.79619 -35.037776)
		(end 51.134772 -35.376358)
		(width 0.11684)
		(layer "F.Cu")
		(net "SGPIO_BMC_M1_CLK")
	)
	(segment
		(start 51.134772 -35.376358)
		(end 51.134772 -37.672518)
		(width 0.11684)
		(layer "F.Cu")
		(net "SGPIO_BMC_M1_CLK")
	)
	(segment
		(start 51.295046 -37.832792)
		(end 51.295046 -39.37127)
		(width 0.11684)
		(layer "F.Cu")
		(net "SGPIO_BMC_M1_CLK")
	)
	(segment
		(start 51.134772 -37.672518)
		(end 51.295046 -37.832792)
		(width 0.11684)
		(layer "F.Cu")
		(net "SGPIO_BMC_M1_CLK")
	)
	(segment
		(start 51.832002 -63.213488)
		(end 51.832002 -63.553594)
		(width 0.11684)
		(layer "F.Cu")
		(net "RST_RSMRST_R_N")
	)
	(segment
		(start 51.4604 -62.357)
		(end 51.4604 -62.841886)
		(width 0.11684)
		(layer "F.Cu")
		(net "RST_RSMRST_R_N")
	)
	(segment
		(start 54.494938 -59.37123)
		(end 54.44617 -59.37123)
		(width 0.11684)
		(layer "F.Cu")
		(net "RST_RSMRST_R_N")
	)
	(segment
		(start 54.44617 -59.37123)
		(end 51.4604 -62.357)
		(width 0.11684)
		(layer "F.Cu")
		(net "RST_RSMRST_R_N")
	)
	(segment
		(start 51.4604 -62.841886)
		(end 51.832002 -63.213488)
		(width 0.11684)
		(layer "F.Cu")
		(net "RST_RSMRST_R_N")
	)
	(via
		(at 51.4604 -62.357)
		(size 0.762)
		(drill 0.381)
		(layers "F.Cu" "B.Cu")
		(net "RST_RSMRST_R_N")
	)
	(segment
		(start 50.97272 -65.212976)
		(end 51.832002 -64.353694)
		(width 0.11684)
		(layer "F.Cu")
		(net "RST_RSMRST_N")
	)
	(segment
		(start 24.771604 -85.945472)
		(end 24.25954 -86.457536)
		(width 0.11684)
		(layer "F.Cu")
		(net "RST_RSMRST_N")
	)
	(segment
		(start 25.152604 -85.945472)
		(end 24.771604 -85.945472)
		(width 0.11684)
		(layer "F.Cu")
		(net "RST_RSMRST_N")
	)
	(segment
		(start 50.97272 -65.41516)
		(end 50.97272 -65.212976)
		(width 0.11684)
		(layer "F.Cu")
		(net "RST_RSMRST_N")
	)
	(segment
		(start 24.25954 -86.457536)
		(end 24.25954 -87.587074)
		(width 0.11684)
		(layer "F.Cu")
		(net "RST_RSMRST_N")
	)
	(via
		(at 28.3464 -72.136)
		(size 0.508)
		(drill 0.254)
		(layers "F.Cu" "B.Cu")
		(net "RST_RSMRST_N")
	)
	(via
		(at 25.152604 -85.945472)
		(size 0.508)
		(drill 0.254)
		(layers "F.Cu" "B.Cu")
		(net "RST_RSMRST_N")
	)
	(via
		(at 50.97272 -65.41516)
		(size 0.508)
		(drill 0.254)
		(layers "F.Cu" "B.Cu")
		(net "RST_RSMRST_N")
	)
	(segment
		(start 25.96134 -84.755736)
		(end 26.799286 -84.755736)
		(width 0.11684)
		(layer "B.Cu")
		(net "RST_RSMRST_N")
	)
	(segment
		(start 25.152604 -85.564472)
		(end 25.96134 -84.755736)
		(width 0.11684)
		(layer "B.Cu")
		(net "RST_RSMRST_N")
	)
	(segment
		(start 25.152604 -85.945472)
		(end 25.152604 -85.564472)
		(width 0.11684)
		(layer "B.Cu")
		(net "RST_RSMRST_N")
	)
	(segment
		(start 26.799286 -84.755736)
		(end 26.8224 -84.77885)
		(width 0.11684)
		(layer "B.Cu")
		(net "RST_RSMRST_N")
	)
	(segment
		(start 47.3202 -62.738)
		(end 43.688 -62.738)
		(width 0.08382)
		(layer "In2.Cu")
		(net "RST_RSMRST_N")
	)
	(segment
		(start 50.97272 -65.41516)
		(end 50.29327 -64.73571)
		(width 0.08382)
		(layer "In2.Cu")
		(net "RST_RSMRST_N")
	)
	(segment
		(start 31.878778 -64.50838)
		(end 31.313628 -65.07353)
		(width 0.08382)
		(layer "In2.Cu")
		(net "RST_RSMRST_N")
	)
	(segment
		(start 28.3464 -70.65899)
		(end 28.3464 -72.136)
		(width 0.08382)
		(layer "In2.Cu")
		(net "RST_RSMRST_N")
	)
	(segment
		(start 25.781 -66.141854)
		(end 25.781 -66.446654)
		(width 0.08382)
		(layer "In2.Cu")
		(net "RST_RSMRST_N")
	)
	(segment
		(start 37.67582 -63.64478)
		(end 33.702498 -63.64478)
		(width 0.08382)
		(layer "In2.Cu")
		(net "RST_RSMRST_N")
	)
	(segment
		(start 48.50511 -63.92291)
		(end 47.3202 -62.738)
		(width 0.08382)
		(layer "In2.Cu")
		(net "RST_RSMRST_N")
	)
	(segment
		(start 43.3578 -63.0682)
		(end 38.2524 -63.0682)
		(width 0.08382)
		(layer "In2.Cu")
		(net "RST_RSMRST_N")
	)
	(segment
		(start 31.313628 -65.07353)
		(end 28.809442 -65.07353)
		(width 0.08382)
		(layer "In2.Cu")
		(net "RST_RSMRST_N")
	)
	(segment
		(start 26.746454 -65.1764)
		(end 25.781 -66.141854)
		(width 0.08382)
		(layer "In2.Cu")
		(net "RST_RSMRST_N")
	)
	(segment
		(start 24.892 -67.335654)
		(end 24.892 -68.16725)
		(width 0.08382)
		(layer "In2.Cu")
		(net "RST_RSMRST_N")
	)
	(segment
		(start 28.706572 -65.1764)
		(end 26.746454 -65.1764)
		(width 0.08382)
		(layer "In2.Cu")
		(net "RST_RSMRST_N")
	)
	(segment
		(start 28.809442 -65.07353)
		(end 28.706572 -65.1764)
		(width 0.08382)
		(layer "In2.Cu")
		(net "RST_RSMRST_N")
	)
	(segment
		(start 25.781 -66.446654)
		(end 24.892 -67.335654)
		(width 0.08382)
		(layer "In2.Cu")
		(net "RST_RSMRST_N")
	)
	(segment
		(start 32.838898 -64.50838)
		(end 31.878778 -64.50838)
		(width 0.08382)
		(layer "In2.Cu")
		(net "RST_RSMRST_N")
	)
	(segment
		(start 33.702498 -63.64478)
		(end 32.838898 -64.50838)
		(width 0.08382)
		(layer "In2.Cu")
		(net "RST_RSMRST_N")
	)
	(segment
		(start 50.29327 -64.73571)
		(end 50.29327 -64.185038)
		(width 0.08382)
		(layer "In2.Cu")
		(net "RST_RSMRST_N")
	)
	(segment
		(start 26.65857 -68.97116)
		(end 28.3464 -70.65899)
		(width 0.08382)
		(layer "In2.Cu")
		(net "RST_RSMRST_N")
	)
	(segment
		(start 50.085244 -63.977012)
		(end 49.954688 -63.92291)
		(width 0.08382)
		(layer "In2.Cu")
		(net "RST_RSMRST_N")
	)
	(segment
		(start 50.29327 -64.185038)
		(end 50.085244 -63.977012)
		(width 0.08382)
		(layer "In2.Cu")
		(net "RST_RSMRST_N")
	)
	(segment
		(start 49.954688 -63.92291)
		(end 48.50511 -63.92291)
		(width 0.08382)
		(layer "In2.Cu")
		(net "RST_RSMRST_N")
	)
	(segment
		(start 38.2524 -63.0682)
		(end 37.67582 -63.64478)
		(width 0.08382)
		(layer "In2.Cu")
		(net "RST_RSMRST_N")
	)
	(segment
		(start 43.688 -62.738)
		(end 43.3578 -63.0682)
		(width 0.08382)
		(layer "In2.Cu")
		(net "RST_RSMRST_N")
	)
	(segment
		(start 25.69591 -68.97116)
		(end 26.65857 -68.97116)
		(width 0.08382)
		(layer "In2.Cu")
		(net "RST_RSMRST_N")
	)
	(segment
		(start 24.892 -68.16725)
		(end 25.69591 -68.97116)
		(width 0.08382)
		(layer "In2.Cu")
		(net "RST_RSMRST_N")
	)
	(segment
		(start 25.152604 -85.82152)
		(end 26.01722 -84.956904)
		(width 0.10668)
		(layer "In4.Cu")
		(net "RST_RSMRST_N")
	)
	(segment
		(start 28.3464 -73.3171)
		(end 28.3464 -72.136)
		(width 0.10668)
		(layer "In4.Cu")
		(net "RST_RSMRST_N")
	)
	(segment
		(start 27.9781 -77.06106)
		(end 28.74264 -76.29652)
		(width 0.10668)
		(layer "In4.Cu")
		(net "RST_RSMRST_N")
	)
	(segment
		(start 27.9781 -83.654646)
		(end 27.9781 -77.06106)
		(width 0.10668)
		(layer "In4.Cu")
		(net "RST_RSMRST_N")
	)
	(segment
		(start 28.74264 -73.71334)
		(end 28.3464 -73.3171)
		(width 0.10668)
		(layer "In4.Cu")
		(net "RST_RSMRST_N")
	)
	(segment
		(start 28.74264 -76.29652)
		(end 28.74264 -73.71334)
		(width 0.10668)
		(layer "In4.Cu")
		(net "RST_RSMRST_N")
	)
	(segment
		(start 26.675842 -84.956904)
		(end 27.9781 -83.654646)
		(width 0.10668)
		(layer "In4.Cu")
		(net "RST_RSMRST_N")
	)
	(segment
		(start 26.01722 -84.956904)
		(end 26.675842 -84.956904)
		(width 0.10668)
		(layer "In4.Cu")
		(net "RST_RSMRST_N")
	)
	(segment
		(start 25.152604 -85.945472)
		(end 25.152604 -85.82152)
		(width 0.10668)
		(layer "In4.Cu")
		(net "RST_RSMRST_N")
	)
	(segment
		(start 66.2432 -92.869004)
		(end 66.2432 -92.2528)
		(width 0.11684)
		(layer "F.Cu")
		(net "RST_PLTRST_TPM_N")
	)
	(segment
		(start 65.756282 -93.355922)
		(end 66.2432 -92.869004)
		(width 0.11684)
		(layer "F.Cu")
		(net "RST_PLTRST_TPM_N")
	)
	(segment
		(start 64.81191 -93.355922)
		(end 65.756282 -93.355922)
		(width 0.11684)
		(layer "F.Cu")
		(net "RST_PLTRST_TPM_N")
	)
	(segment
		(start 67.789044 -92.61094)
		(end 67.789044 -91.725496)
		(width 0.11684)
		(layer "F.Cu")
		(net "RST_PLTRST_TPM_N")
	)
	(segment
		(start 67.09664 -91.39936)
		(end 68.11518 -91.39936)
		(width 0.11684)
		(layer "F.Cu")
		(net "RST_PLTRST_TPM_N")
	)
	(segment
		(start 66.2432 -92.2528)
		(end 67.09664 -91.39936)
		(width 0.11684)
		(layer "F.Cu")
		(net "RST_PLTRST_TPM_N")
	)
	(segment
		(start 67.789044 -91.725496)
		(end 68.11518 -91.39936)
		(width 0.11684)
		(layer "F.Cu")
		(net "RST_PLTRST_TPM_N")
	)
	(via
		(at 68.11518 -91.39936)
		(size 0.762)
		(drill 0.381)
		(layers "F.Cu" "B.Cu")
		(net "RST_PLTRST_TPM_N")
	)
	(segment
		(start 46.494954 -44.971208)
		(end 46.09973 -44.575984)
		(width 0.11684)
		(layer "F.Cu")
		(net "RST_PLTRST_R_N")
	)
	(via
		(at 46.09973 -44.575984)
		(size 0.4572)
		(drill 0.254)
		(layers "F.Cu" "B.Cu")
		(net "RST_PLTRST_R_N")
	)
	(via
		(at 43.605958 -43.842178)
		(size 0.6604)
		(drill 0.3302)
		(layers "F.Cu" "B.Cu")
		(net "RST_PLTRST_R_N")
	)
	(segment
		(start 45.851826 -44.575984)
		(end 46.09973 -44.575984)
		(width 0.11684)
		(layer "B.Cu")
		(net "RST_PLTRST_R_N")
	)
	(segment
		(start 42.81678 -43.053)
		(end 43.605958 -43.842178)
		(width 0.11684)
		(layer "B.Cu")
		(net "RST_PLTRST_R_N")
	)
	(segment
		(start 45.454824 -44.178982)
		(end 45.851826 -44.575984)
		(width 0.11684)
		(layer "B.Cu")
		(net "RST_PLTRST_R_N")
	)
	(segment
		(start 42.31005 -43.053)
		(end 42.81678 -43.053)
		(width 0.11684)
		(layer "B.Cu")
		(net "RST_PLTRST_R_N")
	)
	(segment
		(start 43.605958 -43.842178)
		(end 43.990768 -44.099226)
		(width 0.11684)
		(layer "B.Cu")
		(net "RST_PLTRST_R_N")
	)
	(segment
		(start 43.990768 -44.099226)
		(end 44.390818 -44.178982)
		(width 0.11684)
		(layer "B.Cu")
		(net "RST_PLTRST_R_N")
	)
	(segment
		(start 44.390818 -44.178982)
		(end 45.454824 -44.178982)
		(width 0.11684)
		(layer "B.Cu")
		(net "RST_PLTRST_R_N")
	)
	(segment
		(start 70.14083 -93.07957)
		(end 69.88048 -92.81922)
		(width 0.11684)
		(layer "F.Cu")
		(net "RST_PLTRST_N")
	)
	(segment
		(start 30.95625 -86.995)
		(end 30.95625 -86.70925)
		(width 0.11684)
		(layer "F.Cu")
		(net "RST_PLTRST_N")
	)
	(segment
		(start 26.162 -82.423254)
		(end 26.162 -82.2452)
		(width 0.11684)
		(layer "F.Cu")
		(net "RST_PLTRST_N")
	)
	(segment
		(start 39.138098 -81.05648)
		(end 38.9001 -81.294478)
		(width 0.11684)
		(layer "F.Cu")
		(net "RST_PLTRST_N")
	)
	(segment
		(start 38.9001 -81.294478)
		(end 38.9001 -81.925922)
		(width 0.11684)
		(layer "F.Cu")
		(net "RST_PLTRST_N")
	)
	(segment
		(start 39.52494 -81.05648)
		(end 39.138098 -81.05648)
		(width 0.11684)
		(layer "F.Cu")
		(net "RST_PLTRST_N")
	)
	(segment
		(start 69.88048 -92.81922)
		(end 68.797424 -92.81922)
		(width 0.11684)
		(layer "F.Cu")
		(net "RST_PLTRST_N")
	)
	(segment
		(start 29.0576 -86.4108)
		(end 27.766772 -85.119972)
		(width 0.11684)
		(layer "F.Cu")
		(net "RST_PLTRST_N")
	)
	(segment
		(start 26.514552 -82.775806)
		(end 26.162 -82.423254)
		(width 0.11684)
		(layer "F.Cu")
		(net "RST_PLTRST_N")
	)
	(segment
		(start 60.2234 -38.960552)
		(end 60.094876 -39.089076)
		(width 0.11684)
		(layer "F.Cu")
		(net "RST_PLTRST_N")
	)
	(segment
		(start 33.0708 -86.106)
		(end 32.1818 -86.995)
		(width 0.11684)
		(layer "F.Cu")
		(net "RST_PLTRST_N")
	)
	(segment
		(start 61.51753 -35.814762)
		(end 61.651642 -35.948874)
		(width 0.11684)
		(layer "F.Cu")
		(net "RST_PLTRST_N")
	)
	(segment
		(start 61.651642 -35.948874)
		(end 61.651642 -36.839906)
		(width 0.11684)
		(layer "F.Cu")
		(net "RST_PLTRST_N")
	)
	(segment
		(start 47.83074 -90.09634)
		(end 44.9072 -87.1728)
		(width 0.11684)
		(layer "F.Cu")
		(net "RST_PLTRST_N")
	)
	(segment
		(start 60.094876 -39.089076)
		(end 60.094876 -39.37127)
		(width 0.11684)
		(layer "F.Cu")
		(net "RST_PLTRST_N")
	)
	(segment
		(start 30.6578 -86.4108)
		(end 29.0576 -86.4108)
		(width 0.11684)
		(layer "F.Cu")
		(net "RST_PLTRST_N")
	)
	(segment
		(start 27.766772 -85.119972)
		(end 27.766772 -83.101688)
		(width 0.11684)
		(layer "F.Cu")
		(net "RST_PLTRST_N")
	)
	(segment
		(start 39.99484 -84.670138)
		(end 38.282118 -86.38286)
		(width 0.11684)
		(layer "F.Cu")
		(net "RST_PLTRST_N")
	)
	(segment
		(start 27.766772 -83.101688)
		(end 27.44089 -82.775806)
		(width 0.11684)
		(layer "F.Cu")
		(net "RST_PLTRST_N")
	)
	(segment
		(start 38.282118 -86.38286)
		(end 35.15106 -86.38286)
		(width 0.11684)
		(layer "F.Cu")
		(net "RST_PLTRST_N")
	)
	(segment
		(start 61.651642 -36.839906)
		(end 60.2234 -38.268148)
		(width 0.11684)
		(layer "F.Cu")
		(net "RST_PLTRST_N")
	)
	(segment
		(start 34.8742 -86.106)
		(end 33.0708 -86.106)
		(width 0.11684)
		(layer "F.Cu")
		(net "RST_PLTRST_N")
	)
	(segment
		(start 32.1818 -86.995)
		(end 30.95625 -86.995)
		(width 0.11684)
		(layer "F.Cu")
		(net "RST_PLTRST_N")
	)
	(segment
		(start 60.2234 -38.268148)
		(end 60.2234 -38.960552)
		(width 0.11684)
		(layer "F.Cu")
		(net "RST_PLTRST_N")
	)
	(segment
		(start 38.9001 -81.925922)
		(end 39.99484 -83.020662)
		(width 0.11684)
		(layer "F.Cu")
		(net "RST_PLTRST_N")
	)
	(segment
		(start 30.95625 -86.70925)
		(end 30.6578 -86.4108)
		(width 0.11684)
		(layer "F.Cu")
		(net "RST_PLTRST_N")
	)
	(segment
		(start 27.44089 -82.775806)
		(end 26.514552 -82.775806)
		(width 0.11684)
		(layer "F.Cu")
		(net "RST_PLTRST_N")
	)
	(segment
		(start 44.9072 -87.1728)
		(end 44.9072 -86.43874)
		(width 0.11684)
		(layer "F.Cu")
		(net "RST_PLTRST_N")
	)
	(segment
		(start 68.797424 -92.81922)
		(end 68.589144 -92.61094)
		(width 0.11684)
		(layer "F.Cu")
		(net "RST_PLTRST_N")
	)
	(segment
		(start 61.51753 -35.037776)
		(end 61.51753 -35.814762)
		(width 0.11684)
		(layer "F.Cu")
		(net "RST_PLTRST_N")
	)
	(segment
		(start 39.99484 -83.020662)
		(end 39.99484 -84.670138)
		(width 0.11684)
		(layer "F.Cu")
		(net "RST_PLTRST_N")
	)
	(segment
		(start 48.62068 -90.09634)
		(end 47.83074 -90.09634)
		(width 0.11684)
		(layer "F.Cu")
		(net "RST_PLTRST_N")
	)
	(segment
		(start 35.15106 -86.38286)
		(end 34.8742 -86.106)
		(width 0.11684)
		(layer "F.Cu")
		(net "RST_PLTRST_N")
	)
	(segment
		(start 44.9072 -86.43874)
		(end 39.52494 -81.05648)
		(width 0.11684)
		(layer "F.Cu")
		(net "RST_PLTRST_N")
	)
	(via
		(at 70.14083 -93.07957)
		(size 0.508)
		(drill 0.254)
		(layers "F.Cu" "B.Cu")
		(net "RST_PLTRST_N")
	)
	(via
		(at 49.3268 -89.39022)
		(size 0.6604)
		(drill 0.3302)
		(layers "F.Cu" "B.Cu")
		(net "RST_PLTRST_N")
	)
	(via
		(at 26.162 -82.2452)
		(size 0.508)
		(drill 0.254)
		(layers "F.Cu" "B.Cu")
		(net "RST_PLTRST_N")
	)
	(via
		(at 61.51753 -35.814762)
		(size 0.508)
		(drill 0.254)
		(layers "F.Cu" "B.Cu")
		(net "RST_PLTRST_N")
	)
	(via
		(at 33.95726 -40.1574)
		(size 0.508)
		(drill 0.254)
		(layers "F.Cu" "B.Cu")
		(net "RST_PLTRST_N")
	)
	(via
		(at 70.715886 -110.165388)
		(size 0.508)
		(drill 0.254)
		(layers "F.Cu" "B.Cu")
		(net "RST_PLTRST_N")
	)
	(via
		(at 27.1018 -113.72342)
		(size 0.508)
		(drill 0.254)
		(layers "F.Cu" "B.Cu")
		(net "RST_PLTRST_N")
	)
	(via
		(at 41.254426 -33.282128)
		(size 0.508)
		(drill 0.254)
		(layers "F.Cu" "B.Cu")
		(net "RST_PLTRST_N")
	)
	(via
		(at 48.62068 -90.09634)
		(size 0.508)
		(drill 0.254)
		(layers "F.Cu" "B.Cu")
		(net "RST_PLTRST_N")
	)
	(via
		(at 43.1038 -25.9715)
		(size 0.508)
		(drill 0.254)
		(layers "F.Cu" "B.Cu")
		(net "RST_PLTRST_N")
	)
	(segment
		(start 49.3268 -89.39022)
		(end 48.62068 -90.09634)
		(width 0.11684)
		(layer "B.Cu")
		(net "RST_PLTRST_N")
	)
	(segment
		(start 26.8986 -114.8334)
		(end 26.0604 -115.6716)
		(width 0.11684)
		(layer "B.Cu")
		(net "RST_PLTRST_N")
	)
	(segment
		(start 49.2252 -88.926924)
		(end 49.3268 -89.028524)
		(width 0.11684)
		(layer "B.Cu")
		(net "RST_PLTRST_N")
	)
	(segment
		(start 26.0604 -115.6716)
		(end 26.0604 -116.8654)
		(width 0.11684)
		(layer "B.Cu")
		(net "RST_PLTRST_N")
	)
	(segment
		(start 41.55694 -27.06624)
		(end 41.55694 -26.3906)
		(width 0.11684)
		(layer "B.Cu")
		(net "RST_PLTRST_N")
	)
	(segment
		(start 41.79824 -29.98216)
		(end 41.783 -29.96692)
		(width 0.11684)
		(layer "B.Cu")
		(net "RST_PLTRST_N")
	)
	(segment
		(start 26.0604 -116.8654)
		(end 25.744932 -117.180868)
		(width 0.11684)
		(layer "B.Cu")
		(net "RST_PLTRST_N")
	)
	(segment
		(start 41.97604 -25.9715)
		(end 43.1038 -25.9715)
		(width 0.11684)
		(layer "B.Cu")
		(net "RST_PLTRST_N")
	)
	(segment
		(start 49.75352 -87.686134)
		(end 49.75352 -87.931498)
		(width 0.11684)
		(layer "B.Cu")
		(net "RST_PLTRST_N")
	)
	(segment
		(start 35.65144 -42.10304)
		(end 37.453062 -42.10304)
		(width 0.11684)
		(layer "B.Cu")
		(net "RST_PLTRST_N")
	)
	(segment
		(start 26.8986 -113.92662)
		(end 26.8986 -114.8334)
		(width 0.11684)
		(layer "B.Cu")
		(net "RST_PLTRST_N")
	)
	(segment
		(start 49.3268 -89.028524)
		(end 49.3268 -89.39022)
		(width 0.11684)
		(layer "B.Cu")
		(net "RST_PLTRST_N")
	)
	(segment
		(start 49.657 -88.028018)
		(end 49.657 -88.08085)
		(width 0.11684)
		(layer "B.Cu")
		(net "RST_PLTRST_N")
	)
	(segment
		(start 49.75352 -87.931498)
		(end 49.657 -88.028018)
		(width 0.11684)
		(layer "B.Cu")
		(net "RST_PLTRST_N")
	)
	(segment
		(start 41.79824 -32.200342)
		(end 41.79824 -29.98216)
		(width 0.11684)
		(layer "B.Cu")
		(net "RST_PLTRST_N")
	)
	(segment
		(start 41.55694 -26.3906)
		(end 41.97604 -25.9715)
		(width 0.11684)
		(layer "B.Cu")
		(net "RST_PLTRST_N")
	)
	(segment
		(start 49.657 -88.08085)
		(end 49.2252 -88.51265)
		(width 0.11684)
		(layer "B.Cu")
		(net "RST_PLTRST_N")
	)
	(segment
		(start 39.320978 -42.5704)
		(end 39.803578 -43.053)
		(width 0.11684)
		(layer "B.Cu")
		(net "RST_PLTRST_N")
	)
	(segment
		(start 33.95726 -40.1574)
		(end 33.95726 -40.40886)
		(width 0.11684)
		(layer "B.Cu")
		(net "RST_PLTRST_N")
	)
	(segment
		(start 33.95726 -40.40886)
		(end 35.65144 -42.10304)
		(width 0.11684)
		(layer "B.Cu")
		(net "RST_PLTRST_N")
	)
	(segment
		(start 50.508154 -86.9315)
		(end 49.75352 -87.686134)
		(width 0.11684)
		(layer "B.Cu")
		(net "RST_PLTRST_N")
	)
	(segment
		(start 27.1018 -113.72342)
		(end 26.8986 -113.92662)
		(width 0.11684)
		(layer "B.Cu")
		(net "RST_PLTRST_N")
	)
	(segment
		(start 37.920422 -42.5704)
		(end 39.320978 -42.5704)
		(width 0.11684)
		(layer "B.Cu")
		(net "RST_PLTRST_N")
	)
	(segment
		(start 41.3258 -32.672782)
		(end 41.79824 -32.200342)
		(width 0.11684)
		(layer "B.Cu")
		(net "RST_PLTRST_N")
	)
	(segment
		(start 41.783 -29.96692)
		(end 41.783 -27.2923)
		(width 0.11684)
		(layer "B.Cu")
		(net "RST_PLTRST_N")
	)
	(segment
		(start 25.744932 -117.180868)
		(end 25.744932 -118.25986)
		(width 0.11684)
		(layer "B.Cu")
		(net "RST_PLTRST_N")
	)
	(segment
		(start 41.254426 -33.282128)
		(end 41.3258 -33.210754)
		(width 0.11684)
		(layer "B.Cu")
		(net "RST_PLTRST_N")
	)
	(segment
		(start 49.2252 -88.51265)
		(end 49.2252 -88.926924)
		(width 0.11684)
		(layer "B.Cu")
		(net "RST_PLTRST_N")
	)
	(segment
		(start 50.97145 -86.9315)
		(end 50.508154 -86.9315)
		(width 0.11684)
		(layer "B.Cu")
		(net "RST_PLTRST_N")
	)
	(segment
		(start 41.3258 -33.210754)
		(end 41.3258 -32.672782)
		(width 0.11684)
		(layer "B.Cu")
		(net "RST_PLTRST_N")
	)
	(segment
		(start 39.803578 -43.053)
		(end 41.50995 -43.053)
		(width 0.11684)
		(layer "B.Cu")
		(net "RST_PLTRST_N")
	)
	(segment
		(start 37.453062 -42.10304)
		(end 37.920422 -42.5704)
		(width 0.11684)
		(layer "B.Cu")
		(net "RST_PLTRST_N")
	)
	(segment
		(start 41.783 -27.2923)
		(end 41.55694 -27.06624)
		(width 0.11684)
		(layer "B.Cu")
		(net "RST_PLTRST_N")
	)
	(segment
		(start 61.333634 -112.40262)
		(end 62.80912 -112.40262)
		(width 0.08382)
		(layer "In2.Cu")
		(net "RST_PLTRST_N")
	)
	(segment
		(start 58.038238 -112.77473)
		(end 60.961524 -112.77473)
		(width 0.08382)
		(layer "In2.Cu")
		(net "RST_PLTRST_N")
	)
	(segment
		(start 29.63926 -112.19434)
		(end 36.39058 -112.19434)
		(width 0.08382)
		(layer "In2.Cu")
		(net "RST_PLTRST_N")
	)
	(segment
		(start 62.80912 -112.40262)
		(end 64.03086 -111.18088)
		(width 0.08382)
		(layer "In2.Cu")
		(net "RST_PLTRST_N")
	)
	(segment
		(start 59.71794 -92.18422)
		(end 60.57392 -91.32824)
		(width 0.08382)
		(layer "In2.Cu")
		(net "RST_PLTRST_N")
	)
	(segment
		(start 48.43399 -113.56467)
		(end 49.808384 -113.56467)
		(width 0.08382)
		(layer "In2.Cu")
		(net "RST_PLTRST_N")
	)
	(segment
		(start 56.464708 -113.426494)
		(end 58.038238 -112.77473)
		(width 0.08382)
		(layer "In2.Cu")
		(net "RST_PLTRST_N")
	)
	(segment
		(start 53.2638 -90.9574)
		(end 53.27904 -90.9574)
		(width 0.08382)
		(layer "In2.Cu")
		(net "RST_PLTRST_N")
	)
	(segment
		(start 60.961524 -112.77473)
		(end 61.333634 -112.40262)
		(width 0.08382)
		(layer "In2.Cu")
		(net "RST_PLTRST_N")
	)
	(segment
		(start 52.11191 -89.80551)
		(end 53.2638 -90.9574)
		(width 0.08382)
		(layer "In2.Cu")
		(net "RST_PLTRST_N")
	)
	(segment
		(start 36.39058 -112.19434)
		(end 37.81425 -113.61801)
		(width 0.08382)
		(layer "In2.Cu")
		(net "RST_PLTRST_N")
	)
	(segment
		(start 58.31586 -92.18422)
		(end 59.71794 -92.18422)
		(width 0.08382)
		(layer "In2.Cu")
		(net "RST_PLTRST_N")
	)
	(segment
		(start 48.62068 -90.09634)
		(end 48.91151 -89.80551)
		(width 0.08382)
		(layer "In2.Cu")
		(net "RST_PLTRST_N")
	)
	(segment
		(start 60.57392 -91.32824)
		(end 66.08318 -91.32824)
		(width 0.08382)
		(layer "In2.Cu")
		(net "RST_PLTRST_N")
	)
	(segment
		(start 57.42686 -91.29522)
		(end 58.31586 -92.18422)
		(width 0.08382)
		(layer "In2.Cu")
		(net "RST_PLTRST_N")
	)
	(segment
		(start 53.27904 -90.9574)
		(end 53.61686 -91.29522)
		(width 0.08382)
		(layer "In2.Cu")
		(net "RST_PLTRST_N")
	)
	(segment
		(start 50.612294 -114.36858)
		(end 55.522622 -114.36858)
		(width 0.08382)
		(layer "In2.Cu")
		(net "RST_PLTRST_N")
	)
	(segment
		(start 42.47007 -113.61801)
		(end 44.16552 -111.92256)
		(width 0.08382)
		(layer "In2.Cu")
		(net "RST_PLTRST_N")
	)
	(segment
		(start 44.16552 -111.92256)
		(end 46.79188 -111.92256)
		(width 0.08382)
		(layer "In2.Cu")
		(net "RST_PLTRST_N")
	)
	(segment
		(start 37.81425 -113.61801)
		(end 42.47007 -113.61801)
		(width 0.08382)
		(layer "In2.Cu")
		(net "RST_PLTRST_N")
	)
	(segment
		(start 28.11018 -113.72342)
		(end 29.63926 -112.19434)
		(width 0.08382)
		(layer "In2.Cu")
		(net "RST_PLTRST_N")
	)
	(segment
		(start 69.700394 -111.18088)
		(end 70.715886 -110.165388)
		(width 0.08382)
		(layer "In2.Cu")
		(net "RST_PLTRST_N")
	)
	(segment
		(start 53.61686 -91.29522)
		(end 57.42686 -91.29522)
		(width 0.08382)
		(layer "In2.Cu")
		(net "RST_PLTRST_N")
	)
	(segment
		(start 46.79188 -111.92256)
		(end 48.43399 -113.56467)
		(width 0.08382)
		(layer "In2.Cu")
		(net "RST_PLTRST_N")
	)
	(segment
		(start 48.91151 -89.80551)
		(end 52.11191 -89.80551)
		(width 0.08382)
		(layer "In2.Cu")
		(net "RST_PLTRST_N")
	)
	(segment
		(start 64.03086 -111.18088)
		(end 69.700394 -111.18088)
		(width 0.08382)
		(layer "In2.Cu")
		(net "RST_PLTRST_N")
	)
	(segment
		(start 55.522622 -114.36858)
		(end 56.464708 -113.426494)
		(width 0.08382)
		(layer "In2.Cu")
		(net "RST_PLTRST_N")
	)
	(segment
		(start 67.83451 -93.07957)
		(end 70.14083 -93.07957)
		(width 0.08382)
		(layer "In2.Cu")
		(net "RST_PLTRST_N")
	)
	(segment
		(start 66.08318 -91.32824)
		(end 67.83451 -93.07957)
		(width 0.08382)
		(layer "In2.Cu")
		(net "RST_PLTRST_N")
	)
	(segment
		(start 27.1018 -113.72342)
		(end 28.11018 -113.72342)
		(width 0.08382)
		(layer "In2.Cu")
		(net "RST_PLTRST_N")
	)
	(segment
		(start 49.808384 -113.56467)
		(end 50.612294 -114.36858)
		(width 0.08382)
		(layer "In2.Cu")
		(net "RST_PLTRST_N")
	)
	(segment
		(start 68.2498 -102.739952)
		(end 68.2498 -93.59646)
		(width 0.10668)
		(layer "In4.Cu")
		(net "RST_PLTRST_N")
	)
	(segment
		(start 70.715886 -108.155486)
		(end 69.42074 -106.86034)
		(width 0.10668)
		(layer "In4.Cu")
		(net "RST_PLTRST_N")
	)
	(segment
		(start 26.20264 -76.938886)
		(end 26.03754 -76.773786)
		(width 0.10668)
		(layer "In4.Cu")
		(net "RST_PLTRST_N")
	)
	(segment
		(start 21.62302 -57.211722)
		(end 21.62302 -51.056794)
		(width 0.10668)
		(layer "In4.Cu")
		(net "RST_PLTRST_N")
	)
	(segment
		(start 41.244774 -33.29178)
		(end 41.254426 -33.282128)
		(width 0.10668)
		(layer "In4.Cu")
		(net "RST_PLTRST_N")
	)
	(segment
		(start 26.03754 -74.3839)
		(end 25.2349 -73.58126)
		(width 0.10668)
		(layer "In4.Cu")
		(net "RST_PLTRST_N")
	)
	(segment
		(start 21.62302 -51.056794)
		(end 21.86432 -50.474118)
		(width 0.10668)
		(layer "In4.Cu")
		(net "RST_PLTRST_N")
	)
	(segment
		(start 38.55466 -35.41776)
		(end 38.55466 -34.24936)
		(width 0.10668)
		(layer "In4.Cu")
		(net "RST_PLTRST_N")
	)
	(segment
		(start 21.86432 -50.474118)
		(end 21.86432 -46.127924)
		(width 0.10668)
		(layer "In4.Cu")
		(net "RST_PLTRST_N")
	)
	(segment
		(start 39.12108 -33.68294)
		(end 40.4114 -33.68294)
		(width 0.10668)
		(layer "In4.Cu")
		(net "RST_PLTRST_N")
	)
	(segment
		(start 25.2349 -73.58126)
		(end 25.2349 -71.866506)
		(width 0.10668)
		(layer "In4.Cu")
		(net "RST_PLTRST_N")
	)
	(segment
		(start 26.03754 -76.773786)
		(end 26.03754 -74.3839)
		(width 0.10668)
		(layer "In4.Cu")
		(net "RST_PLTRST_N")
	)
	(segment
		(start 24.27986 -59.868562)
		(end 21.62302 -57.211722)
		(width 0.10668)
		(layer "In4.Cu")
		(net "RST_PLTRST_N")
	)
	(segment
		(start 22.74062 -44.01185)
		(end 27.50185 -39.25062)
		(width 0.10668)
		(layer "In4.Cu")
		(net "RST_PLTRST_N")
	)
	(segment
		(start 33.95726 -40.1574)
		(end 33.95726 -39.27094)
		(width 0.10668)
		(layer "In4.Cu")
		(net "RST_PLTRST_N")
	)
	(segment
		(start 40.80256 -33.29178)
		(end 41.244774 -33.29178)
		(width 0.10668)
		(layer "In4.Cu")
		(net "RST_PLTRST_N")
	)
	(segment
		(start 21.86432 -46.127924)
		(end 22.74062 -44.01185)
		(width 0.10668)
		(layer "In4.Cu")
		(net "RST_PLTRST_N")
	)
	(segment
		(start 28.51277 -38.62324)
		(end 31.807658 -38.62324)
		(width 0.10668)
		(layer "In4.Cu")
		(net "RST_PLTRST_N")
	)
	(segment
		(start 26.162 -82.2452)
		(end 26.20264 -82.20456)
		(width 0.10668)
		(layer "In4.Cu")
		(net "RST_PLTRST_N")
	)
	(segment
		(start 27.88539 -39.25062)
		(end 28.51277 -38.62324)
		(width 0.10668)
		(layer "In4.Cu")
		(net "RST_PLTRST_N")
	)
	(segment
		(start 38.42766 -35.54476)
		(end 38.55466 -35.41776)
		(width 0.10668)
		(layer "In4.Cu")
		(net "RST_PLTRST_N")
	)
	(segment
		(start 27.50185 -39.25062)
		(end 27.88539 -39.25062)
		(width 0.10668)
		(layer "In4.Cu")
		(net "RST_PLTRST_N")
	)
	(segment
		(start 35.77844 -35.54476)
		(end 38.42766 -35.54476)
		(width 0.10668)
		(layer "In4.Cu")
		(net "RST_PLTRST_N")
	)
	(segment
		(start 33.95726 -39.27094)
		(end 34.36874 -38.85946)
		(width 0.10668)
		(layer "In4.Cu")
		(net "RST_PLTRST_N")
	)
	(segment
		(start 25.2603 -65.497202)
		(end 25.2603 -62.23762)
		(width 0.10668)
		(layer "In4.Cu")
		(net "RST_PLTRST_N")
	)
	(segment
		(start 38.55466 -34.24936)
		(end 39.12108 -33.68294)
		(width 0.10668)
		(layer "In4.Cu")
		(net "RST_PLTRST_N")
	)
	(segment
		(start 69.42074 -104.6734)
		(end 69.1388 -104.39146)
		(width 0.10668)
		(layer "In4.Cu")
		(net "RST_PLTRST_N")
	)
	(segment
		(start 69.1388 -103.628952)
		(end 68.2498 -102.739952)
		(width 0.10668)
		(layer "In4.Cu")
		(net "RST_PLTRST_N")
	)
	(segment
		(start 40.4114 -33.68294)
		(end 40.80256 -33.29178)
		(width 0.10668)
		(layer "In4.Cu")
		(net "RST_PLTRST_N")
	)
	(segment
		(start 70.715886 -110.165388)
		(end 70.715886 -108.155486)
		(width 0.10668)
		(layer "In4.Cu")
		(net "RST_PLTRST_N")
	)
	(segment
		(start 34.36874 -38.85946)
		(end 34.36874 -36.95446)
		(width 0.10668)
		(layer "In4.Cu")
		(net "RST_PLTRST_N")
	)
	(segment
		(start 69.42074 -106.86034)
		(end 69.42074 -104.6734)
		(width 0.10668)
		(layer "In4.Cu")
		(net "RST_PLTRST_N")
	)
	(segment
		(start 31.807658 -38.62324)
		(end 33.341818 -40.1574)
		(width 0.10668)
		(layer "In4.Cu")
		(net "RST_PLTRST_N")
	)
	(segment
		(start 33.341818 -40.1574)
		(end 33.95726 -40.1574)
		(width 0.10668)
		(layer "In4.Cu")
		(net "RST_PLTRST_N")
	)
	(segment
		(start 69.1388 -104.39146)
		(end 69.1388 -103.628952)
		(width 0.10668)
		(layer "In4.Cu")
		(net "RST_PLTRST_N")
	)
	(segment
		(start 24.03602 -66.721482)
		(end 25.2603 -65.497202)
		(width 0.10668)
		(layer "In4.Cu")
		(net "RST_PLTRST_N")
	)
	(segment
		(start 24.27986 -61.25718)
		(end 24.27986 -59.868562)
		(width 0.10668)
		(layer "In4.Cu")
		(net "RST_PLTRST_N")
	)
	(segment
		(start 26.20264 -82.20456)
		(end 26.20264 -76.938886)
		(width 0.10668)
		(layer "In4.Cu")
		(net "RST_PLTRST_N")
	)
	(segment
		(start 34.36874 -36.95446)
		(end 35.77844 -35.54476)
		(width 0.10668)
		(layer "In4.Cu")
		(net "RST_PLTRST_N")
	)
	(segment
		(start 25.2349 -71.866506)
		(end 24.03602 -70.667626)
		(width 0.10668)
		(layer "In4.Cu")
		(net "RST_PLTRST_N")
	)
	(segment
		(start 25.2603 -62.23762)
		(end 24.27986 -61.25718)
		(width 0.10668)
		(layer "In4.Cu")
		(net "RST_PLTRST_N")
	)
	(segment
		(start 68.2498 -93.59646)
		(end 68.76669 -93.07957)
		(width 0.10668)
		(layer "In4.Cu")
		(net "RST_PLTRST_N")
	)
	(segment
		(start 24.03602 -70.667626)
		(end 24.03602 -66.721482)
		(width 0.10668)
		(layer "In4.Cu")
		(net "RST_PLTRST_N")
	)
	(segment
		(start 68.76669 -93.07957)
		(end 70.14083 -93.07957)
		(width 0.10668)
		(layer "In4.Cu")
		(net "RST_PLTRST_N")
	)
	(segment
		(start 43.45559 -25.9715)
		(end 44.08551 -26.60142)
		(width 0.08382)
		(layer "In9.Cu")
		(net "RST_PLTRST_N")
	)
	(segment
		(start 54.979316 -26.49093)
		(end 59.12358 -26.49093)
		(width 0.08382)
		(layer "In9.Cu")
		(net "RST_PLTRST_N")
	)
	(segment
		(start 48.420528 -26.60142)
		(end 49.748948 -25.273)
		(width 0.08382)
		(layer "In9.Cu")
		(net "RST_PLTRST_N")
	)
	(segment
		(start 63.579756 -28.4607)
		(end 64.7446 -29.625544)
		(width 0.08382)
		(layer "In9.Cu")
		(net "RST_PLTRST_N")
	)
	(segment
		(start 49.748948 -25.273)
		(end 53.761386 -25.273)
		(width 0.08382)
		(layer "In9.Cu")
		(net "RST_PLTRST_N")
	)
	(segment
		(start 59.38774 -27.060398)
		(end 60.395612 -28.06827)
		(width 0.08382)
		(layer "In9.Cu")
		(net "RST_PLTRST_N")
	)
	(segment
		(start 61.51753 -35.25647)
		(end 61.51753 -35.814762)
		(width 0.08382)
		(layer "In9.Cu")
		(net "RST_PLTRST_N")
	)
	(segment
		(start 60.395612 -28.06827)
		(end 62.82309 -28.06827)
		(width 0.08382)
		(layer "In9.Cu")
		(net "RST_PLTRST_N")
	)
	(segment
		(start 64.7446 -32.0294)
		(end 61.51753 -35.25647)
		(width 0.08382)
		(layer "In9.Cu")
		(net "RST_PLTRST_N")
	)
	(segment
		(start 53.761386 -25.273)
		(end 54.979316 -26.49093)
		(width 0.08382)
		(layer "In9.Cu")
		(net "RST_PLTRST_N")
	)
	(segment
		(start 62.82309 -28.06827)
		(end 63.21552 -28.4607)
		(width 0.08382)
		(layer "In9.Cu")
		(net "RST_PLTRST_N")
	)
	(segment
		(start 64.7446 -29.625544)
		(end 64.7446 -32.0294)
		(width 0.08382)
		(layer "In9.Cu")
		(net "RST_PLTRST_N")
	)
	(segment
		(start 59.38774 -26.75509)
		(end 59.38774 -27.060398)
		(width 0.08382)
		(layer "In9.Cu")
		(net "RST_PLTRST_N")
	)
	(segment
		(start 59.12358 -26.49093)
		(end 59.38774 -26.75509)
		(width 0.08382)
		(layer "In9.Cu")
		(net "RST_PLTRST_N")
	)
	(segment
		(start 44.08551 -26.60142)
		(end 48.420528 -26.60142)
		(width 0.08382)
		(layer "In9.Cu")
		(net "RST_PLTRST_N")
	)
	(segment
		(start 63.21552 -28.4607)
		(end 63.579756 -28.4607)
		(width 0.08382)
		(layer "In9.Cu")
		(net "RST_PLTRST_N")
	)
	(segment
		(start 43.1038 -25.9715)
		(end 43.45559 -25.9715)
		(width 0.08382)
		(layer "In9.Cu")
		(net "RST_PLTRST_N")
	)
	(segment
		(start 59.29503 -57.771284)
		(end 58.899806 -57.37606)
		(width 0.11684)
		(layer "F.Cu")
		(net "RST_ESPI_LPC_BMC_N")
	)
	(via
		(at 61.261752 -70.954138)
		(size 0.508)
		(drill 0.254)
		(layers "F.Cu" "B.Cu")
		(net "RST_ESPI_LPC_BMC_N")
	)
	(via
		(at 58.899806 -57.37606)
		(size 0.4572)
		(drill 0.254)
		(layers "F.Cu" "B.Cu")
		(net "RST_ESPI_LPC_BMC_N")
	)
	(segment
		(start 61.261752 -70.954138)
		(end 61.725556 -70.954138)
		(width 0.11684)
		(layer "B.Cu")
		(net "RST_ESPI_LPC_BMC_N")
	)
	(segment
		(start 61.725556 -70.954138)
		(end 62.08903 -71.317612)
		(width 0.11684)
		(layer "B.Cu")
		(net "RST_ESPI_LPC_BMC_N")
	)
	(segment
		(start 62.08903 -71.317612)
		(end 63.564008 -71.317612)
		(width 0.11684)
		(layer "B.Cu")
		(net "RST_ESPI_LPC_BMC_N")
	)
	(segment
		(start 60.9854 -65.1256)
		(end 59.258962 -63.399162)
		(width 0.10668)
		(layer "In4.Cu")
		(net "RST_ESPI_LPC_BMC_N")
	)
	(segment
		(start 61.05652 -67.5386)
		(end 61.1632 -67.43192)
		(width 0.10668)
		(layer "In4.Cu")
		(net "RST_ESPI_LPC_BMC_N")
	)
	(segment
		(start 58.473848 -57.802018)
		(end 58.899806 -57.37606)
		(width 0.10668)
		(layer "In4.Cu")
		(net "RST_ESPI_LPC_BMC_N")
	)
	(segment
		(start 58.0644 -60.438284)
		(end 58.0644 -58.73496)
		(width 0.10668)
		(layer "In4.Cu")
		(net "RST_ESPI_LPC_BMC_N")
	)
	(segment
		(start 61.1632 -65.913)
		(end 60.9854 -65.7352)
		(width 0.10668)
		(layer "In4.Cu")
		(net "RST_ESPI_LPC_BMC_N")
	)
	(segment
		(start 58.35396 -60.727844)
		(end 58.0644 -60.438284)
		(width 0.10668)
		(layer "In4.Cu")
		(net "RST_ESPI_LPC_BMC_N")
	)
	(segment
		(start 58.473848 -58.325512)
		(end 58.473848 -57.802018)
		(width 0.10668)
		(layer "In4.Cu")
		(net "RST_ESPI_LPC_BMC_N")
	)
	(segment
		(start 58.0644 -58.73496)
		(end 58.473848 -58.325512)
		(width 0.10668)
		(layer "In4.Cu")
		(net "RST_ESPI_LPC_BMC_N")
	)
	(segment
		(start 60.2234 -67.5386)
		(end 61.05652 -67.5386)
		(width 0.10668)
		(layer "In4.Cu")
		(net "RST_ESPI_LPC_BMC_N")
	)
	(segment
		(start 61.1632 -67.43192)
		(end 61.1632 -65.913)
		(width 0.10668)
		(layer "In4.Cu")
		(net "RST_ESPI_LPC_BMC_N")
	)
	(segment
		(start 58.35396 -61.199014)
		(end 58.35396 -60.727844)
		(width 0.10668)
		(layer "In4.Cu")
		(net "RST_ESPI_LPC_BMC_N")
	)
	(segment
		(start 61.0616 -70.612)
		(end 60.1218 -69.6722)
		(width 0.10668)
		(layer "In4.Cu")
		(net "RST_ESPI_LPC_BMC_N")
	)
	(segment
		(start 60.9854 -65.7352)
		(end 60.9854 -65.1256)
		(width 0.10668)
		(layer "In4.Cu")
		(net "RST_ESPI_LPC_BMC_N")
	)
	(segment
		(start 60.1218 -67.6402)
		(end 60.2234 -67.5386)
		(width 0.10668)
		(layer "In4.Cu")
		(net "RST_ESPI_LPC_BMC_N")
	)
	(segment
		(start 59.258962 -62.104016)
		(end 58.35396 -61.199014)
		(width 0.10668)
		(layer "In4.Cu")
		(net "RST_ESPI_LPC_BMC_N")
	)
	(segment
		(start 60.1218 -69.6722)
		(end 60.1218 -67.6402)
		(width 0.10668)
		(layer "In4.Cu")
		(net "RST_ESPI_LPC_BMC_N")
	)
	(segment
		(start 61.0616 -70.753986)
		(end 61.0616 -70.612)
		(width 0.10668)
		(layer "In4.Cu")
		(net "RST_ESPI_LPC_BMC_N")
	)
	(segment
		(start 59.258962 -63.399162)
		(end 59.258962 -62.104016)
		(width 0.10668)
		(layer "In4.Cu")
		(net "RST_ESPI_LPC_BMC_N")
	)
	(segment
		(start 61.261752 -70.954138)
		(end 61.0616 -70.753986)
		(width 0.10668)
		(layer "In4.Cu")
		(net "RST_ESPI_LPC_BMC_N")
	)
	(segment
		(start 37.084 -58.42)
		(end 37.084 -59.256676)
		(width 0.11684)
		(layer "F.Cu")
		(net "ID_RST_BTN_BMC_N")
	)
	(segment
		(start 37.084 -59.256676)
		(end 36.9824 -59.358276)
		(width 0.11684)
		(layer "F.Cu")
		(net "ID_RST_BTN_BMC_N")
	)
	(segment
		(start 36.957 -57.8358)
		(end 36.957 -58.293)
		(width 0.11684)
		(layer "F.Cu")
		(net "ID_RST_BTN_BMC_N")
	)
	(segment
		(start 79.18958 -22.35962)
		(end 79.18958 -19.89582)
		(width 0.11684)
		(layer "F.Cu")
		(net "ID_RST_BTN_BMC_N")
	)
	(segment
		(start 79.9338 -18.8468)
		(end 80.223614 -18.556986)
		(width 0.11684)
		(layer "F.Cu")
		(net "ID_RST_BTN_BMC_N")
	)
	(segment
		(start 72.53986 -22.47646)
		(end 79.07274 -22.47646)
		(width 0.11684)
		(layer "F.Cu")
		(net "ID_RST_BTN_BMC_N")
	)
	(segment
		(start 65.4812 -21.0312)
		(end 67.8942 -21.0312)
		(width 0.11684)
		(layer "F.Cu")
		(net "ID_RST_BTN_BMC_N")
	)
	(segment
		(start 80.223614 -18.556986)
		(end 80.66532 -18.556986)
		(width 0.11684)
		(layer "F.Cu")
		(net "ID_RST_BTN_BMC_N")
	)
	(segment
		(start 36.9824 -59.358276)
		(end 36.9824 -59.77255)
		(width 0.11684)
		(layer "F.Cu")
		(net "ID_RST_BTN_BMC_N")
	)
	(segment
		(start 67.8942 -21.0312)
		(end 68.6054 -21.7424)
		(width 0.11684)
		(layer "F.Cu")
		(net "ID_RST_BTN_BMC_N")
	)
	(segment
		(start 79.18958 -19.89582)
		(end 79.9338 -19.1516)
		(width 0.11684)
		(layer "F.Cu")
		(net "ID_RST_BTN_BMC_N")
	)
	(segment
		(start 68.6054 -21.7424)
		(end 71.8058 -21.7424)
		(width 0.11684)
		(layer "F.Cu")
		(net "ID_RST_BTN_BMC_N")
	)
	(segment
		(start 79.07274 -22.47646)
		(end 79.18958 -22.35962)
		(width 0.11684)
		(layer "F.Cu")
		(net "ID_RST_BTN_BMC_N")
	)
	(segment
		(start 36.957 -58.293)
		(end 37.084 -58.42)
		(width 0.11684)
		(layer "F.Cu")
		(net "ID_RST_BTN_BMC_N")
	)
	(segment
		(start 79.9338 -19.1516)
		(end 79.9338 -18.8468)
		(width 0.11684)
		(layer "F.Cu")
		(net "ID_RST_BTN_BMC_N")
	)
	(segment
		(start 71.8058 -21.7424)
		(end 72.53986 -22.47646)
		(width 0.11684)
		(layer "F.Cu")
		(net "ID_RST_BTN_BMC_N")
	)
	(via
		(at 35.74542 -18.4404)
		(size 0.508)
		(drill 0.254)
		(layers "F.Cu" "B.Cu")
		(net "ID_RST_BTN_BMC_N")
	)
	(via
		(at 18.415 -54.356)
		(size 0.508)
		(drill 0.254)
		(layers "F.Cu" "B.Cu")
		(net "ID_RST_BTN_BMC_N")
	)
	(via
		(at 36.957 -57.8358)
		(size 0.508)
		(drill 0.254)
		(layers "F.Cu" "B.Cu")
		(net "ID_RST_BTN_BMC_N")
	)
	(via
		(at 65.4812 -21.0312)
		(size 0.508)
		(drill 0.254)
		(layers "F.Cu" "B.Cu")
		(net "ID_RST_BTN_BMC_N")
	)
	(segment
		(start 25.648666 -58.40984)
		(end 27.652472 -58.40984)
		(width 0.08382)
		(layer "In2.Cu")
		(net "ID_RST_BTN_BMC_N")
	)
	(segment
		(start 36.112196 -57.410604)
		(end 36.531804 -57.410604)
		(width 0.08382)
		(layer "In2.Cu")
		(net "ID_RST_BTN_BMC_N")
	)
	(segment
		(start 18.758154 -55.646066)
		(end 20.977098 -55.646066)
		(width 0.08382)
		(layer "In2.Cu")
		(net "ID_RST_BTN_BMC_N")
	)
	(segment
		(start 35.132772 -57.4294)
		(end 36.0934 -57.4294)
		(width 0.08382)
		(layer "In2.Cu")
		(net "ID_RST_BTN_BMC_N")
	)
	(segment
		(start 33.798256 -57.023)
		(end 34.076132 -56.745124)
		(width 0.08382)
		(layer "In2.Cu")
		(net "ID_RST_BTN_BMC_N")
	)
	(segment
		(start 28.676346 -57.985914)
		(end 29.543248 -57.40654)
		(width 0.08382)
		(layer "In2.Cu")
		(net "ID_RST_BTN_BMC_N")
	)
	(segment
		(start 34.448496 -56.745124)
		(end 35.132772 -57.4294)
		(width 0.08382)
		(layer "In2.Cu")
		(net "ID_RST_BTN_BMC_N")
	)
	(segment
		(start 22.658832 -57.3278)
		(end 23.810976 -57.3278)
		(width 0.08382)
		(layer "In2.Cu")
		(net "ID_RST_BTN_BMC_N")
	)
	(segment
		(start 32.283908 -56.134)
		(end 33.172908 -57.023)
		(width 0.08382)
		(layer "In2.Cu")
		(net "ID_RST_BTN_BMC_N")
	)
	(segment
		(start 20.977098 -55.646066)
		(end 22.658832 -57.3278)
		(width 0.08382)
		(layer "In2.Cu")
		(net "ID_RST_BTN_BMC_N")
	)
	(segment
		(start 29.543248 -57.40654)
		(end 30.815788 -56.134)
		(width 0.08382)
		(layer "In2.Cu")
		(net "ID_RST_BTN_BMC_N")
	)
	(segment
		(start 33.172908 -57.023)
		(end 33.798256 -57.023)
		(width 0.08382)
		(layer "In2.Cu")
		(net "ID_RST_BTN_BMC_N")
	)
	(segment
		(start 18.415 -55.302912)
		(end 18.758154 -55.646066)
		(width 0.08382)
		(layer "In2.Cu")
		(net "ID_RST_BTN_BMC_N")
	)
	(segment
		(start 30.815788 -56.134)
		(end 32.283908 -56.134)
		(width 0.08382)
		(layer "In2.Cu")
		(net "ID_RST_BTN_BMC_N")
	)
	(segment
		(start 27.652472 -58.40984)
		(end 28.676346 -57.985914)
		(width 0.08382)
		(layer "In2.Cu")
		(net "ID_RST_BTN_BMC_N")
	)
	(segment
		(start 34.076132 -56.745124)
		(end 34.448496 -56.745124)
		(width 0.08382)
		(layer "In2.Cu")
		(net "ID_RST_BTN_BMC_N")
	)
	(segment
		(start 36.531804 -57.410604)
		(end 36.957 -57.8358)
		(width 0.08382)
		(layer "In2.Cu")
		(net "ID_RST_BTN_BMC_N")
	)
	(segment
		(start 24.358854 -57.875678)
		(end 25.648666 -58.40984)
		(width 0.08382)
		(layer "In2.Cu")
		(net "ID_RST_BTN_BMC_N")
	)
	(segment
		(start 18.415 -54.356)
		(end 18.415 -55.302912)
		(width 0.08382)
		(layer "In2.Cu")
		(net "ID_RST_BTN_BMC_N")
	)
	(segment
		(start 36.0934 -57.4294)
		(end 36.112196 -57.410604)
		(width 0.08382)
		(layer "In2.Cu")
		(net "ID_RST_BTN_BMC_N")
	)
	(segment
		(start 23.810976 -57.3278)
		(end 24.358854 -57.875678)
		(width 0.08382)
		(layer "In2.Cu")
		(net "ID_RST_BTN_BMC_N")
	)
	(segment
		(start 64.4017 -18.06448)
		(end 65.4812 -19.14398)
		(width 0.10668)
		(layer "In4.Cu")
		(net "ID_RST_BTN_BMC_N")
	)
	(segment
		(start 60.476384 -18.484342)
		(end 61.624718 -18.484342)
		(width 0.10668)
		(layer "In4.Cu")
		(net "ID_RST_BTN_BMC_N")
	)
	(segment
		(start 61.624718 -18.484342)
		(end 62.04458 -18.06448)
		(width 0.10668)
		(layer "In4.Cu")
		(net "ID_RST_BTN_BMC_N")
	)
	(segment
		(start 36.67506 -18.4404)
		(end 39.221664 -15.893796)
		(width 0.10668)
		(layer "In4.Cu")
		(net "ID_RST_BTN_BMC_N")
	)
	(segment
		(start 62.04458 -18.06448)
		(end 64.4017 -18.06448)
		(width 0.10668)
		(layer "In4.Cu")
		(net "ID_RST_BTN_BMC_N")
	)
	(segment
		(start 60.069222 -18.07718)
		(end 60.476384 -18.484342)
		(width 0.10668)
		(layer "In4.Cu")
		(net "ID_RST_BTN_BMC_N")
	)
	(segment
		(start 52.035202 -18.07718)
		(end 60.069222 -18.07718)
		(width 0.10668)
		(layer "In4.Cu")
		(net "ID_RST_BTN_BMC_N")
	)
	(segment
		(start 39.221664 -15.893796)
		(end 49.851818 -15.893796)
		(width 0.10668)
		(layer "In4.Cu")
		(net "ID_RST_BTN_BMC_N")
	)
	(segment
		(start 65.4812 -19.14398)
		(end 65.4812 -21.0312)
		(width 0.10668)
		(layer "In4.Cu")
		(net "ID_RST_BTN_BMC_N")
	)
	(segment
		(start 35.74542 -18.4404)
		(end 36.67506 -18.4404)
		(width 0.10668)
		(layer "In4.Cu")
		(net "ID_RST_BTN_BMC_N")
	)
	(segment
		(start 49.851818 -15.893796)
		(end 52.035202 -18.07718)
		(width 0.10668)
		(layer "In4.Cu")
		(net "ID_RST_BTN_BMC_N")
	)
	(segment
		(start 25.5524 -33.0708)
		(end 25.5524 -38.321742)
		(width 0.10668)
		(layer "In7.Cu")
		(net "ID_RST_BTN_BMC_N")
	)
	(segment
		(start 19.10842 -50.89398)
		(end 19.10842 -52.266088)
		(width 0.10668)
		(layer "In7.Cu")
		(net "ID_RST_BTN_BMC_N")
	)
	(segment
		(start 19.10842 -52.266088)
		(end 18.415 -52.959508)
		(width 0.10668)
		(layer "In7.Cu")
		(net "ID_RST_BTN_BMC_N")
	)
	(segment
		(start 28.194 -21.971)
		(end 28.194 -23.749)
		(width 0.10668)
		(layer "In7.Cu")
		(net "ID_RST_BTN_BMC_N")
	)
	(segment
		(start 29.083 -19.177)
		(end 29.337 -19.431)
		(width 0.10668)
		(layer "In7.Cu")
		(net "ID_RST_BTN_BMC_N")
	)
	(segment
		(start 26.94178 -30.682184)
		(end 26.22804 -31.395924)
		(width 0.10668)
		(layer "In7.Cu")
		(net "ID_RST_BTN_BMC_N")
	)
	(segment
		(start 26.94178 -28.921202)
		(end 26.94178 -30.682184)
		(width 0.10668)
		(layer "In7.Cu")
		(net "ID_RST_BTN_BMC_N")
	)
	(segment
		(start 19.58594 -46.889162)
		(end 18.8468 -48.673766)
		(width 0.10668)
		(layer "In7.Cu")
		(net "ID_RST_BTN_BMC_N")
	)
	(segment
		(start 19.58594 -45.736764)
		(end 19.58594 -46.889162)
		(width 0.10668)
		(layer "In7.Cu")
		(net "ID_RST_BTN_BMC_N")
	)
	(segment
		(start 26.7716 -26.966164)
		(end 27.40152 -27.596084)
		(width 0.10668)
		(layer "In7.Cu")
		(net "ID_RST_BTN_BMC_N")
	)
	(segment
		(start 27.40152 -27.596084)
		(end 27.40152 -28.461462)
		(width 0.10668)
		(layer "In7.Cu")
		(net "ID_RST_BTN_BMC_N")
	)
	(segment
		(start 18.8468 -48.673766)
		(end 18.8468 -50.262282)
		(width 0.10668)
		(layer "In7.Cu")
		(net "ID_RST_BTN_BMC_N")
	)
	(segment
		(start 19.5072 -45.658024)
		(end 19.58594 -45.736764)
		(width 0.10668)
		(layer "In7.Cu")
		(net "ID_RST_BTN_BMC_N")
	)
	(segment
		(start 29.55798 -18.17878)
		(end 29.083 -18.65376)
		(width 0.10668)
		(layer "In7.Cu")
		(net "ID_RST_BTN_BMC_N")
	)
	(segment
		(start 26.22804 -32.39516)
		(end 25.5524 -33.0708)
		(width 0.10668)
		(layer "In7.Cu")
		(net "ID_RST_BTN_BMC_N")
	)
	(segment
		(start 29.337 -20.828)
		(end 28.194 -21.971)
		(width 0.10668)
		(layer "In7.Cu")
		(net "ID_RST_BTN_BMC_N")
	)
	(segment
		(start 34.81578 -18.17878)
		(end 29.55798 -18.17878)
		(width 0.10668)
		(layer "In7.Cu")
		(net "ID_RST_BTN_BMC_N")
	)
	(segment
		(start 35.0774 -18.4404)
		(end 34.81578 -18.17878)
		(width 0.10668)
		(layer "In7.Cu")
		(net "ID_RST_BTN_BMC_N")
	)
	(segment
		(start 25.5524 -38.321742)
		(end 19.5072 -44.366942)
		(width 0.10668)
		(layer "In7.Cu")
		(net "ID_RST_BTN_BMC_N")
	)
	(segment
		(start 28.194 -23.749)
		(end 26.7716 -25.1714)
		(width 0.10668)
		(layer "In7.Cu")
		(net "ID_RST_BTN_BMC_N")
	)
	(segment
		(start 29.337 -19.431)
		(end 29.337 -20.828)
		(width 0.10668)
		(layer "In7.Cu")
		(net "ID_RST_BTN_BMC_N")
	)
	(segment
		(start 35.74542 -18.4404)
		(end 35.0774 -18.4404)
		(width 0.10668)
		(layer "In7.Cu")
		(net "ID_RST_BTN_BMC_N")
	)
	(segment
		(start 29.083 -18.65376)
		(end 29.083 -19.177)
		(width 0.10668)
		(layer "In7.Cu")
		(net "ID_RST_BTN_BMC_N")
	)
	(segment
		(start 26.22804 -31.395924)
		(end 26.22804 -32.39516)
		(width 0.10668)
		(layer "In7.Cu")
		(net "ID_RST_BTN_BMC_N")
	)
	(segment
		(start 27.40152 -28.461462)
		(end 26.94178 -28.921202)
		(width 0.10668)
		(layer "In7.Cu")
		(net "ID_RST_BTN_BMC_N")
	)
	(segment
		(start 18.415 -52.959508)
		(end 18.415 -54.356)
		(width 0.10668)
		(layer "In7.Cu")
		(net "ID_RST_BTN_BMC_N")
	)
	(segment
		(start 26.7716 -25.1714)
		(end 26.7716 -26.966164)
		(width 0.10668)
		(layer "In7.Cu")
		(net "ID_RST_BTN_BMC_N")
	)
	(segment
		(start 19.5072 -44.366942)
		(end 19.5072 -45.658024)
		(width 0.10668)
		(layer "In7.Cu")
		(net "ID_RST_BTN_BMC_N")
	)
	(segment
		(start 18.8468 -50.262282)
		(end 19.10842 -50.89398)
		(width 0.10668)
		(layer "In7.Cu")
		(net "ID_RST_BTN_BMC_N")
	)
	(segment
		(start 57.037986 -90.3732)
		(end 55.0672 -90.3732)
		(width 0.11684)
		(layer "F.Cu")
		(net "RST_BMC_SRST_N")
	)
	(segment
		(start 54.2798 -91.1606)
		(end 54.2798 -92.2274)
		(width 0.11684)
		(layer "F.Cu")
		(net "RST_BMC_SRST_N")
	)
	(segment
		(start 54.22646 -92.28074)
		(end 54.22646 -94.91726)
		(width 0.11684)
		(layer "F.Cu")
		(net "RST_BMC_SRST_N")
	)
	(segment
		(start 54.229 -95.61195)
		(end 54.229 -94.9198)
		(width 0.11684)
		(layer "F.Cu")
		(net "RST_BMC_SRST_N")
	)
	(segment
		(start 11.32205 -106.6038)
		(end 11.0744 -106.85145)
		(width 0.11684)
		(layer "F.Cu")
		(net "RST_BMC_SRST_N")
	)
	(segment
		(start 11.0744 -106.85145)
		(end 11.0744 -107.3912)
		(width 0.11684)
		(layer "F.Cu")
		(net "RST_BMC_SRST_N")
	)
	(segment
		(start 58.547 -89.789)
		(end 57.622186 -89.789)
		(width 0.11684)
		(layer "F.Cu")
		(net "RST_BMC_SRST_N")
	)
	(segment
		(start 54.229 -94.9198)
		(end 54.22646 -94.91726)
		(width 0.11684)
		(layer "F.Cu")
		(net "RST_BMC_SRST_N")
	)
	(segment
		(start 58.801 -89.535)
		(end 58.547 -89.789)
		(width 0.11684)
		(layer "F.Cu")
		(net "RST_BMC_SRST_N")
	)
	(segment
		(start 57.695084 -42.571162)
		(end 58.090308 -42.175938)
		(width 0.11684)
		(layer "F.Cu")
		(net "RST_BMC_SRST_N")
	)
	(segment
		(start 55.0672 -90.3732)
		(end 54.2798 -91.1606)
		(width 0.11684)
		(layer "F.Cu")
		(net "RST_BMC_SRST_N")
	)
	(segment
		(start 54.2798 -92.2274)
		(end 54.22646 -92.28074)
		(width 0.11684)
		(layer "F.Cu")
		(net "RST_BMC_SRST_N")
	)
	(segment
		(start 57.622186 -89.789)
		(end 57.037986 -90.3732)
		(width 0.11684)
		(layer "F.Cu")
		(net "RST_BMC_SRST_N")
	)
	(via
		(at 54.2798 -92.2274)
		(size 0.762)
		(drill 0.381)
		(layers "F.Cu" "B.Cu")
		(net "RST_BMC_SRST_N")
	)
	(via
		(at 58.801 -89.535)
		(size 0.508)
		(drill 0.254)
		(layers "F.Cu" "B.Cu")
		(net "RST_BMC_SRST_N")
	)
	(via
		(at 11.0744 -107.3912)
		(size 0.508)
		(drill 0.254)
		(layers "F.Cu" "B.Cu")
		(net "RST_BMC_SRST_N")
	)
	(via
		(at 58.090308 -42.175938)
		(size 0.4572)
		(drill 0.254)
		(layers "F.Cu" "B.Cu")
		(net "RST_BMC_SRST_N")
	)
	(via
		(at 54.22646 -94.91726)
		(size 0.508)
		(drill 0.254)
		(layers "F.Cu" "B.Cu")
		(net "RST_BMC_SRST_N")
	)
	(via
		(at 62.357 -32.4612)
		(size 0.508)
		(drill 0.254)
		(layers "F.Cu" "B.Cu")
		(net "RST_BMC_SRST_N")
	)
	(via
		(at 50.8 -103.38816)
		(size 0.508)
		(drill 0.254)
		(layers "F.Cu" "B.Cu")
		(net "RST_BMC_SRST_N")
	)
	(segment
		(start 62.47384 -31.76905)
		(end 62.865 -31.76905)
		(width 0.11684)
		(layer "B.Cu")
		(net "RST_BMC_SRST_N")
	)
	(segment
		(start 62.357 -32.4612)
		(end 62.357 -31.88589)
		(width 0.11684)
		(layer "B.Cu")
		(net "RST_BMC_SRST_N")
	)
	(segment
		(start 62.357 -31.88589)
		(end 62.47384 -31.76905)
		(width 0.11684)
		(layer "B.Cu")
		(net "RST_BMC_SRST_N")
	)
	(segment
		(start 28.348432 -108.80852)
		(end 26.162 -108.80852)
		(width 0.08382)
		(layer "In2.Cu")
		(net "RST_BMC_SRST_N")
	)
	(segment
		(start 34.41573 -104.67467)
		(end 33.688528 -104.67467)
		(width 0.08382)
		(layer "In2.Cu")
		(net "RST_BMC_SRST_N")
	)
	(segment
		(start 25.41778 -108.0643)
		(end 25.41778 -107.442762)
		(width 0.08382)
		(layer "In2.Cu")
		(net "RST_BMC_SRST_N")
	)
	(segment
		(start 49.60366 -104.5845)
		(end 47.85106 -104.5845)
		(width 0.08382)
		(layer "In2.Cu")
		(net "RST_BMC_SRST_N")
	)
	(segment
		(start 30.415992 -105.5243)
		(end 29.52623 -106.414062)
		(width 0.08382)
		(layer "In2.Cu")
		(net "RST_BMC_SRST_N")
	)
	(segment
		(start 31.93034 -105.5243)
		(end 30.415992 -105.5243)
		(width 0.08382)
		(layer "In2.Cu")
		(net "RST_BMC_SRST_N")
	)
	(segment
		(start 25.41778 -107.442762)
		(end 24.547068 -106.57205)
		(width 0.08382)
		(layer "In2.Cu")
		(net "RST_BMC_SRST_N")
	)
	(segment
		(start 33.565846 -104.797352)
		(end 32.657288 -104.797352)
		(width 0.08382)
		(layer "In2.Cu")
		(net "RST_BMC_SRST_N")
	)
	(segment
		(start 50.8 -103.38816)
		(end 49.60366 -104.5845)
		(width 0.08382)
		(layer "In2.Cu")
		(net "RST_BMC_SRST_N")
	)
	(segment
		(start 12.7762 -105.6894)
		(end 11.0744 -107.3912)
		(width 0.08382)
		(layer "In2.Cu")
		(net "RST_BMC_SRST_N")
	)
	(segment
		(start 38.696138 -104.19969)
		(end 38.433756 -104.462072)
		(width 0.08382)
		(layer "In2.Cu")
		(net "RST_BMC_SRST_N")
	)
	(segment
		(start 26.162 -108.80852)
		(end 25.41778 -108.0643)
		(width 0.08382)
		(layer "In2.Cu")
		(net "RST_BMC_SRST_N")
	)
	(segment
		(start 38.433756 -104.465882)
		(end 38.158928 -104.74071)
		(width 0.08382)
		(layer "In2.Cu")
		(net "RST_BMC_SRST_N")
	)
	(segment
		(start 47.85106 -104.5845)
		(end 47.46625 -104.19969)
		(width 0.08382)
		(layer "In2.Cu")
		(net "RST_BMC_SRST_N")
	)
	(segment
		(start 17.791938 -105.6894)
		(end 12.7762 -105.6894)
		(width 0.08382)
		(layer "In2.Cu")
		(net "RST_BMC_SRST_N")
	)
	(segment
		(start 34.95929 -104.13111)
		(end 34.41573 -104.67467)
		(width 0.08382)
		(layer "In2.Cu")
		(net "RST_BMC_SRST_N")
	)
	(segment
		(start 24.547068 -106.57205)
		(end 18.674588 -106.57205)
		(width 0.08382)
		(layer "In2.Cu")
		(net "RST_BMC_SRST_N")
	)
	(segment
		(start 47.46625 -104.19969)
		(end 38.696138 -104.19969)
		(width 0.08382)
		(layer "In2.Cu")
		(net "RST_BMC_SRST_N")
	)
	(segment
		(start 29.52623 -107.630722)
		(end 28.348432 -108.80852)
		(width 0.08382)
		(layer "In2.Cu")
		(net "RST_BMC_SRST_N")
	)
	(segment
		(start 18.674588 -106.57205)
		(end 17.791938 -105.6894)
		(width 0.08382)
		(layer "In2.Cu")
		(net "RST_BMC_SRST_N")
	)
	(segment
		(start 32.657288 -104.797352)
		(end 31.93034 -105.5243)
		(width 0.08382)
		(layer "In2.Cu")
		(net "RST_BMC_SRST_N")
	)
	(segment
		(start 36.210748 -104.13111)
		(end 34.95929 -104.13111)
		(width 0.08382)
		(layer "In2.Cu")
		(net "RST_BMC_SRST_N")
	)
	(segment
		(start 29.52623 -106.414062)
		(end 29.52623 -107.630722)
		(width 0.08382)
		(layer "In2.Cu")
		(net "RST_BMC_SRST_N")
	)
	(segment
		(start 38.433756 -104.462072)
		(end 38.433756 -104.465882)
		(width 0.08382)
		(layer "In2.Cu")
		(net "RST_BMC_SRST_N")
	)
	(segment
		(start 33.688528 -104.67467)
		(end 33.565846 -104.797352)
		(width 0.08382)
		(layer "In2.Cu")
		(net "RST_BMC_SRST_N")
	)
	(segment
		(start 38.158928 -104.74071)
		(end 36.820348 -104.74071)
		(width 0.08382)
		(layer "In2.Cu")
		(net "RST_BMC_SRST_N")
	)
	(segment
		(start 36.820348 -104.74071)
		(end 36.210748 -104.13111)
		(width 0.08382)
		(layer "In2.Cu")
		(net "RST_BMC_SRST_N")
	)
	(segment
		(start 51.79822 -102.38613)
		(end 51.799236 -102.388924)
		(width 0.10668)
		(layer "In4.Cu")
		(net "RST_BMC_SRST_N")
	)
	(segment
		(start 54.22646 -94.91726)
		(end 54.22646 -96.524064)
		(width 0.10668)
		(layer "In4.Cu")
		(net "RST_BMC_SRST_N")
	)
	(segment
		(start 51.799236 -102.388924)
		(end 50.8 -103.38816)
		(width 0.10668)
		(layer "In4.Cu")
		(net "RST_BMC_SRST_N")
	)
	(segment
		(start 54.22646 -96.524064)
		(end 51.79822 -102.38613)
		(width 0.10668)
		(layer "In4.Cu")
		(net "RST_BMC_SRST_N")
	)
	(segment
		(start 55.30342 -39.49954)
		(end 57.6961 -37.10686)
		(width 0.08382)
		(layer "In9.Cu")
		(net "RST_BMC_SRST_N")
	)
	(segment
		(start 58.463688 -45.916088)
		(end 58.3184 -45.7708)
		(width 0.08382)
		(layer "In9.Cu")
		(net "RST_BMC_SRST_N")
	)
	(segment
		(start 57.91962 -45.7708)
		(end 57.67324 -45.52442)
		(width 0.08382)
		(layer "In9.Cu")
		(net "RST_BMC_SRST_N")
	)
	(segment
		(start 57.66816 -63.1698)
		(end 57.66816 -61.6077)
		(width 0.08382)
		(layer "In9.Cu")
		(net "RST_BMC_SRST_N")
	)
	(segment
		(start 59.12358 -71.081646)
		(end 59.3598 -70.845426)
		(width 0.08382)
		(layer "In9.Cu")
		(net "RST_BMC_SRST_N")
	)
	(segment
		(start 59.3598 -68.8848)
		(end 59.65952 -68.58508)
		(width 0.08382)
		(layer "In9.Cu")
		(net "RST_BMC_SRST_N")
	)
	(segment
		(start 57.6961 -37.10686)
		(end 57.6961 -32.174434)
		(width 0.08382)
		(layer "In9.Cu")
		(net "RST_BMC_SRST_N")
	)
	(segment
		(start 57.6961 -32.174434)
		(end 58.651394 -31.21914)
		(width 0.08382)
		(layer "In9.Cu")
		(net "RST_BMC_SRST_N")
	)
	(segment
		(start 58.67527 -76.2508)
		(end 58.67527 -73.66381)
		(width 0.08382)
		(layer "In9.Cu")
		(net "RST_BMC_SRST_N")
	)
	(segment
		(start 58.463688 -49.398428)
		(end 58.463688 -45.916088)
		(width 0.08382)
		(layer "In9.Cu")
		(net "RST_BMC_SRST_N")
	)
	(segment
		(start 60.343796 -33.128204)
		(end 60.343796 -35.682936)
		(width 0.08382)
		(layer "In9.Cu")
		(net "RST_BMC_SRST_N")
	)
	(segment
		(start 55.625238 -43.43908)
		(end 55.30342 -43.117262)
		(width 0.08382)
		(layer "In9.Cu")
		(net "RST_BMC_SRST_N")
	)
	(segment
		(start 58.43524 -66.1416)
		(end 58.88228 -65.69456)
		(width 0.08382)
		(layer "In9.Cu")
		(net "RST_BMC_SRST_N")
	)
	(segment
		(start 57.716928 -39.514272)
		(end 57.716928 -41.802558)
		(width 0.08382)
		(layer "In9.Cu")
		(net "RST_BMC_SRST_N")
	)
	(segment
		(start 56.335422 -55.393082)
		(end 58.599578 -55.393082)
		(width 0.08382)
		(layer "In9.Cu")
		(net "RST_BMC_SRST_N")
	)
	(segment
		(start 59.39536 -82.002122)
		(end 58.87593 -81.482692)
		(width 0.08382)
		(layer "In9.Cu")
		(net "RST_BMC_SRST_N")
	)
	(segment
		(start 58.651394 -31.21914)
		(end 62.354968 -31.21914)
		(width 0.08382)
		(layer "In9.Cu")
		(net "RST_BMC_SRST_N")
	)
	(segment
		(start 59.65952 -67.27698)
		(end 59.44362 -67.06108)
		(width 0.08382)
		(layer "In9.Cu")
		(net "RST_BMC_SRST_N")
	)
	(segment
		(start 56.916828 -60.856368)
		(end 56.916828 -57.981088)
		(width 0.08382)
		(layer "In9.Cu")
		(net "RST_BMC_SRST_N")
	)
	(segment
		(start 56.0959 -55.632604)
		(end 56.335422 -55.393082)
		(width 0.08382)
		(layer "In9.Cu")
		(net "RST_BMC_SRST_N")
	)
	(segment
		(start 57.716928 -41.802558)
		(end 58.090308 -42.175938)
		(width 0.08382)
		(layer "In9.Cu")
		(net "RST_BMC_SRST_N")
	)
	(segment
		(start 56.728868 -57.793128)
		(end 56.398414 -57.793128)
		(width 0.08382)
		(layer "In9.Cu")
		(net "RST_BMC_SRST_N")
	)
	(segment
		(start 58.801 -89.535)
		(end 58.801 -85.9536)
		(width 0.08382)
		(layer "In9.Cu")
		(net "RST_BMC_SRST_N")
	)
	(segment
		(start 58.67527 -73.66381)
		(end 59.12358 -73.2155)
		(width 0.08382)
		(layer "In9.Cu")
		(net "RST_BMC_SRST_N")
	)
	(segment
		(start 58.322464 -83.7184)
		(end 59.080146 -83.7184)
		(width 0.08382)
		(layer "In9.Cu")
		(net "RST_BMC_SRST_N")
	)
	(segment
		(start 62.968886 -31.833058)
		(end 62.968886 -32.37738)
		(width 0.08382)
		(layer "In9.Cu")
		(net "RST_BMC_SRST_N")
	)
	(segment
		(start 58.1914 -85.344)
		(end 58.1914 -83.849464)
		(width 0.08382)
		(layer "In9.Cu")
		(net "RST_BMC_SRST_N")
	)
	(segment
		(start 58.87593 -76.45146)
		(end 58.67527 -76.2508)
		(width 0.08382)
		(layer "In9.Cu")
		(net "RST_BMC_SRST_N")
	)
	(segment
		(start 62.1538 -32.258)
		(end 61.214 -32.258)
		(width 0.08382)
		(layer "In9.Cu")
		(net "RST_BMC_SRST_N")
	)
	(segment
		(start 59.3598 -70.845426)
		(end 59.3598 -68.8848)
		(width 0.08382)
		(layer "In9.Cu")
		(net "RST_BMC_SRST_N")
	)
	(segment
		(start 59.080146 -83.7184)
		(end 59.39536 -83.403186)
		(width 0.08382)
		(layer "In9.Cu")
		(net "RST_BMC_SRST_N")
	)
	(segment
		(start 56.2737 -43.43908)
		(end 55.625238 -43.43908)
		(width 0.08382)
		(layer "In9.Cu")
		(net "RST_BMC_SRST_N")
	)
	(segment
		(start 59.65952 -68.58508)
		(end 59.65952 -67.27698)
		(width 0.08382)
		(layer "In9.Cu")
		(net "RST_BMC_SRST_N")
	)
	(segment
		(start 58.28538 -38.94582)
		(end 57.716928 -39.514272)
		(width 0.08382)
		(layer "In9.Cu")
		(net "RST_BMC_SRST_N")
	)
	(segment
		(start 56.0959 -57.490614)
		(end 56.0959 -55.632604)
		(width 0.08382)
		(layer "In9.Cu")
		(net "RST_BMC_SRST_N")
	)
	(segment
		(start 58.87593 -81.482692)
		(end 58.87593 -76.45146)
		(width 0.08382)
		(layer "In9.Cu")
		(net "RST_BMC_SRST_N")
	)
	(segment
		(start 59.29376 -50.2285)
		(end 58.463688 -49.398428)
		(width 0.08382)
		(layer "In9.Cu")
		(net "RST_BMC_SRST_N")
	)
	(segment
		(start 59.00674 -67.06108)
		(end 58.43524 -66.48958)
		(width 0.08382)
		(layer "In9.Cu")
		(net "RST_BMC_SRST_N")
	)
	(segment
		(start 61.214 -32.258)
		(end 60.343796 -33.128204)
		(width 0.08382)
		(layer "In9.Cu")
		(net "RST_BMC_SRST_N")
	)
	(segment
		(start 58.599578 -55.393082)
		(end 59.29376 -54.6989)
		(width 0.08382)
		(layer "In9.Cu")
		(net "RST_BMC_SRST_N")
	)
	(segment
		(start 59.39536 -83.403186)
		(end 59.39536 -82.002122)
		(width 0.08382)
		(layer "In9.Cu")
		(net "RST_BMC_SRST_N")
	)
	(segment
		(start 56.398414 -57.793128)
		(end 56.0959 -57.490614)
		(width 0.08382)
		(layer "In9.Cu")
		(net "RST_BMC_SRST_N")
	)
	(segment
		(start 56.916828 -57.981088)
		(end 56.728868 -57.793128)
		(width 0.08382)
		(layer "In9.Cu")
		(net "RST_BMC_SRST_N")
	)
	(segment
		(start 58.43524 -66.48958)
		(end 58.43524 -66.1416)
		(width 0.08382)
		(layer "In9.Cu")
		(net "RST_BMC_SRST_N")
	)
	(segment
		(start 58.1914 -83.849464)
		(end 58.322464 -83.7184)
		(width 0.08382)
		(layer "In9.Cu")
		(net "RST_BMC_SRST_N")
	)
	(segment
		(start 58.801 -85.9536)
		(end 58.1914 -85.344)
		(width 0.08382)
		(layer "In9.Cu")
		(net "RST_BMC_SRST_N")
	)
	(segment
		(start 58.88228 -64.38392)
		(end 57.66816 -63.1698)
		(width 0.08382)
		(layer "In9.Cu")
		(net "RST_BMC_SRST_N")
	)
	(segment
		(start 60.343796 -35.682936)
		(end 58.28538 -37.741352)
		(width 0.08382)
		(layer "In9.Cu")
		(net "RST_BMC_SRST_N")
	)
	(segment
		(start 57.67324 -44.83862)
		(end 56.2737 -43.43908)
		(width 0.08382)
		(layer "In9.Cu")
		(net "RST_BMC_SRST_N")
	)
	(segment
		(start 59.12358 -73.2155)
		(end 59.12358 -71.081646)
		(width 0.08382)
		(layer "In9.Cu")
		(net "RST_BMC_SRST_N")
	)
	(segment
		(start 57.66816 -61.6077)
		(end 56.916828 -60.856368)
		(width 0.08382)
		(layer "In9.Cu")
		(net "RST_BMC_SRST_N")
	)
	(segment
		(start 59.29376 -54.6989)
		(end 59.29376 -50.2285)
		(width 0.08382)
		(layer "In9.Cu")
		(net "RST_BMC_SRST_N")
	)
	(segment
		(start 62.357 -32.4612)
		(end 62.1538 -32.258)
		(width 0.08382)
		(layer "In9.Cu")
		(net "RST_BMC_SRST_N")
	)
	(segment
		(start 62.968886 -32.37738)
		(end 62.885066 -32.4612)
		(width 0.08382)
		(layer "In9.Cu")
		(net "RST_BMC_SRST_N")
	)
	(segment
		(start 57.67324 -45.52442)
		(end 57.67324 -44.83862)
		(width 0.08382)
		(layer "In9.Cu")
		(net "RST_BMC_SRST_N")
	)
	(segment
		(start 58.28538 -37.741352)
		(end 58.28538 -38.94582)
		(width 0.08382)
		(layer "In9.Cu")
		(net "RST_BMC_SRST_N")
	)
	(segment
		(start 62.354968 -31.21914)
		(end 62.968886 -31.833058)
		(width 0.08382)
		(layer "In9.Cu")
		(net "RST_BMC_SRST_N")
	)
	(segment
		(start 59.44362 -67.06108)
		(end 59.00674 -67.06108)
		(width 0.08382)
		(layer "In9.Cu")
		(net "RST_BMC_SRST_N")
	)
	(segment
		(start 62.885066 -32.4612)
		(end 62.357 -32.4612)
		(width 0.08382)
		(layer "In9.Cu")
		(net "RST_BMC_SRST_N")
	)
	(segment
		(start 58.88228 -65.69456)
		(end 58.88228 -64.38392)
		(width 0.08382)
		(layer "In9.Cu")
		(net "RST_BMC_SRST_N")
	)
	(segment
		(start 58.3184 -45.7708)
		(end 57.91962 -45.7708)
		(width 0.08382)
		(layer "In9.Cu")
		(net "RST_BMC_SRST_N")
	)
	(segment
		(start 55.30342 -43.117262)
		(end 55.30342 -39.49954)
		(width 0.08382)
		(layer "In9.Cu")
		(net "RST_BMC_SRST_N")
	)
	(segment
		(start 46.494954 -55.371238)
		(end 46.09973 -55.766462)
		(width 0.11684)
		(layer "F.Cu")
		(net "RST_BMC_RSTBTN_OUT_R_N")
	)
	(via
		(at 41.529 -58.212736)
		(size 0.762)
		(drill 0.254)
		(layers "F.Cu" "B.Cu")
		(net "RST_BMC_RSTBTN_OUT_R_N")
	)
	(via
		(at 46.09973 -55.766462)
		(size 0.4572)
		(drill 0.254)
		(layers "F.Cu" "B.Cu")
		(net "RST_BMC_RSTBTN_OUT_R_N")
	)
	(segment
		(start 41.529 -58.212736)
		(end 40.934386 -58.212736)
		(width 0.11684)
		(layer "B.Cu")
		(net "RST_BMC_RSTBTN_OUT_R_N")
	)
	(segment
		(start 40.819578 -58.097928)
		(end 40.81145 -58.097928)
		(width 0.11684)
		(layer "B.Cu")
		(net "RST_BMC_RSTBTN_OUT_R_N")
	)
	(segment
		(start 40.934386 -58.212736)
		(end 40.819578 -58.097928)
		(width 0.11684)
		(layer "B.Cu")
		(net "RST_BMC_RSTBTN_OUT_R_N")
	)
	(segment
		(start 44.628054 -56.515)
		(end 45.376592 -55.766462)
		(width 0.08382)
		(layer "In2.Cu")
		(net "RST_BMC_RSTBTN_OUT_R_N")
	)
	(segment
		(start 42.758868 -56.017922)
		(end 43.255946 -56.515)
		(width 0.08382)
		(layer "In2.Cu")
		(net "RST_BMC_RSTBTN_OUT_R_N")
	)
	(segment
		(start 41.529 -58.212736)
		(end 41.529 -56.827928)
		(width 0.08382)
		(layer "In2.Cu")
		(net "RST_BMC_RSTBTN_OUT_R_N")
	)
	(segment
		(start 41.529 -56.827928)
		(end 42.339006 -56.017922)
		(width 0.08382)
		(layer "In2.Cu")
		(net "RST_BMC_RSTBTN_OUT_R_N")
	)
	(segment
		(start 45.376592 -55.766462)
		(end 46.09973 -55.766462)
		(width 0.08382)
		(layer "In2.Cu")
		(net "RST_BMC_RSTBTN_OUT_R_N")
	)
	(segment
		(start 43.255946 -56.515)
		(end 44.628054 -56.515)
		(width 0.08382)
		(layer "In2.Cu")
		(net "RST_BMC_RSTBTN_OUT_R_N")
	)
	(segment
		(start 42.339006 -56.017922)
		(end 42.758868 -56.017922)
		(width 0.08382)
		(layer "In2.Cu")
		(net "RST_BMC_RSTBTN_OUT_R_N")
	)
	(segment
		(start 23.054564 -88.791796)
		(end 22.65934 -89.18702)
		(width 0.11684)
		(layer "F.Cu")
		(net "RST_BMC_RSTBTN_OUT_N")
	)
	(via
		(at 23.1902 -64.2366)
		(size 0.508)
		(drill 0.254)
		(layers "F.Cu" "B.Cu")
		(net "RST_BMC_RSTBTN_OUT_N")
	)
	(via
		(at 23.054564 -88.791796)
		(size 0.4572)
		(drill 0.254)
		(layers "F.Cu" "B.Cu")
		(net "RST_BMC_RSTBTN_OUT_N")
	)
	(via
		(at 38.20922 -58.674)
		(size 0.6604)
		(drill 0.3302)
		(layers "F.Cu" "B.Cu")
		(net "RST_BMC_RSTBTN_OUT_N")
	)
	(via
		(at 36.08959 -58.559446)
		(size 0.508)
		(drill 0.254)
		(layers "F.Cu" "B.Cu")
		(net "RST_BMC_RSTBTN_OUT_N")
	)
	(segment
		(start 39.0398 -59.0042)
		(end 38.7096 -58.674)
		(width 0.11684)
		(layer "B.Cu")
		(net "RST_BMC_RSTBTN_OUT_N")
	)
	(segment
		(start 39.4081 -59.0042)
		(end 39.0398 -59.0042)
		(width 0.11684)
		(layer "B.Cu")
		(net "RST_BMC_RSTBTN_OUT_N")
	)
	(segment
		(start 39.4081 -58.286904)
		(end 39.4081 -59.0042)
		(width 0.11684)
		(layer "B.Cu")
		(net "RST_BMC_RSTBTN_OUT_N")
	)
	(segment
		(start 38.7096 -58.674)
		(end 38.20922 -58.674)
		(width 0.11684)
		(layer "B.Cu")
		(net "RST_BMC_RSTBTN_OUT_N")
	)
	(segment
		(start 40.01135 -58.097928)
		(end 39.597076 -58.097928)
		(width 0.11684)
		(layer "B.Cu")
		(net "RST_BMC_RSTBTN_OUT_N")
	)
	(segment
		(start 39.597076 -58.097928)
		(end 39.4081 -58.286904)
		(width 0.11684)
		(layer "B.Cu")
		(net "RST_BMC_RSTBTN_OUT_N")
	)
	(segment
		(start 36.08959 -58.559446)
		(end 36.204144 -58.674)
		(width 0.11684)
		(layer "B.Cu")
		(net "RST_BMC_RSTBTN_OUT_N")
	)
	(segment
		(start 36.204144 -58.674)
		(end 38.20922 -58.674)
		(width 0.11684)
		(layer "B.Cu")
		(net "RST_BMC_RSTBTN_OUT_N")
	)
	(segment
		(start 35.905694 -58.627518)
		(end 35.488118 -58.627518)
		(width 0.08382)
		(layer "In2.Cu")
		(net "RST_BMC_RSTBTN_OUT_N")
	)
	(segment
		(start 35.973766 -58.559446)
		(end 35.905694 -58.627518)
		(width 0.08382)
		(layer "In2.Cu")
		(net "RST_BMC_RSTBTN_OUT_N")
	)
	(segment
		(start 24.21509 -63.21171)
		(end 23.1902 -64.2366)
		(width 0.08382)
		(layer "In2.Cu")
		(net "RST_BMC_RSTBTN_OUT_N")
	)
	(segment
		(start 29.402278 -62.357)
		(end 29.004768 -62.75451)
		(width 0.08382)
		(layer "In2.Cu")
		(net "RST_BMC_RSTBTN_OUT_N")
	)
	(segment
		(start 32.55391 -58.885836)
		(end 32.258 -59.181746)
		(width 0.08382)
		(layer "In2.Cu")
		(net "RST_BMC_RSTBTN_OUT_N")
	)
	(segment
		(start 32.258 -59.181746)
		(end 32.258 -61.8998)
		(width 0.08382)
		(layer "In2.Cu")
		(net "RST_BMC_RSTBTN_OUT_N")
	)
	(segment
		(start 28.447238 -62.502796)
		(end 25.101296 -62.502796)
		(width 0.08382)
		(layer "In2.Cu")
		(net "RST_BMC_RSTBTN_OUT_N")
	)
	(segment
		(start 24.392382 -63.21171)
		(end 24.21509 -63.21171)
		(width 0.08382)
		(layer "In2.Cu")
		(net "RST_BMC_RSTBTN_OUT_N")
	)
	(segment
		(start 35.488118 -58.627518)
		(end 35.2298 -58.885836)
		(width 0.08382)
		(layer "In2.Cu")
		(net "RST_BMC_RSTBTN_OUT_N")
	)
	(segment
		(start 31.40329 -62.75451)
		(end 31.024322 -62.75451)
		(width 0.08382)
		(layer "In2.Cu")
		(net "RST_BMC_RSTBTN_OUT_N")
	)
	(segment
		(start 25.101296 -62.502796)
		(end 24.392382 -63.21171)
		(width 0.08382)
		(layer "In2.Cu")
		(net "RST_BMC_RSTBTN_OUT_N")
	)
	(segment
		(start 35.2298 -58.885836)
		(end 32.55391 -58.885836)
		(width 0.08382)
		(layer "In2.Cu")
		(net "RST_BMC_RSTBTN_OUT_N")
	)
	(segment
		(start 29.004768 -62.75451)
		(end 28.698952 -62.75451)
		(width 0.08382)
		(layer "In2.Cu")
		(net "RST_BMC_RSTBTN_OUT_N")
	)
	(segment
		(start 30.626812 -62.357)
		(end 29.402278 -62.357)
		(width 0.08382)
		(layer "In2.Cu")
		(net "RST_BMC_RSTBTN_OUT_N")
	)
	(segment
		(start 36.08959 -58.559446)
		(end 35.973766 -58.559446)
		(width 0.08382)
		(layer "In2.Cu")
		(net "RST_BMC_RSTBTN_OUT_N")
	)
	(segment
		(start 32.258 -61.8998)
		(end 31.40329 -62.75451)
		(width 0.08382)
		(layer "In2.Cu")
		(net "RST_BMC_RSTBTN_OUT_N")
	)
	(segment
		(start 31.024322 -62.75451)
		(end 30.626812 -62.357)
		(width 0.08382)
		(layer "In2.Cu")
		(net "RST_BMC_RSTBTN_OUT_N")
	)
	(segment
		(start 28.698952 -62.75451)
		(end 28.447238 -62.502796)
		(width 0.08382)
		(layer "In2.Cu")
		(net "RST_BMC_RSTBTN_OUT_N")
	)
	(segment
		(start 23.06574 -75.31862)
		(end 21.6408 -73.89368)
		(width 0.10668)
		(layer "In4.Cu")
		(net "RST_BMC_RSTBTN_OUT_N")
	)
	(segment
		(start 23.054564 -88.484964)
		(end 22.61108 -88.04148)
		(width 0.10668)
		(layer "In4.Cu")
		(net "RST_BMC_RSTBTN_OUT_N")
	)
	(segment
		(start 22.61108 -88.04148)
		(end 22.61108 -84.796122)
		(width 0.10668)
		(layer "In4.Cu")
		(net "RST_BMC_RSTBTN_OUT_N")
	)
	(segment
		(start 20.35048 -67.550538)
		(end 20.73656 -67.164458)
		(width 0.10668)
		(layer "In4.Cu")
		(net "RST_BMC_RSTBTN_OUT_N")
	)
	(segment
		(start 20.73656 -65.27038)
		(end 21.768562 -64.238378)
		(width 0.10668)
		(layer "In4.Cu")
		(net "RST_BMC_RSTBTN_OUT_N")
	)
	(segment
		(start 21.768562 -64.238378)
		(end 22.145498 -64.238378)
		(width 0.10668)
		(layer "In4.Cu")
		(net "RST_BMC_RSTBTN_OUT_N")
	)
	(segment
		(start 22.61108 -81.5594)
		(end 23.06574 -81.10474)
		(width 0.10668)
		(layer "In4.Cu")
		(net "RST_BMC_RSTBTN_OUT_N")
	)
	(segment
		(start 20.58162 -70.882002)
		(end 20.58162 -69.444362)
		(width 0.10668)
		(layer "In4.Cu")
		(net "RST_BMC_RSTBTN_OUT_N")
	)
	(segment
		(start 21.06676 -71.367142)
		(end 20.58162 -70.882002)
		(width 0.10668)
		(layer "In4.Cu")
		(net "RST_BMC_RSTBTN_OUT_N")
	)
	(segment
		(start 20.73656 -67.164458)
		(end 20.73656 -65.27038)
		(width 0.10668)
		(layer "In4.Cu")
		(net "RST_BMC_RSTBTN_OUT_N")
	)
	(segment
		(start 20.58162 -69.444362)
		(end 20.35048 -69.213222)
		(width 0.10668)
		(layer "In4.Cu")
		(net "RST_BMC_RSTBTN_OUT_N")
	)
	(segment
		(start 22.61108 -83.224878)
		(end 22.61108 -81.5594)
		(width 0.10668)
		(layer "In4.Cu")
		(net "RST_BMC_RSTBTN_OUT_N")
	)
	(segment
		(start 20.35048 -69.213222)
		(end 20.35048 -67.550538)
		(width 0.10668)
		(layer "In4.Cu")
		(net "RST_BMC_RSTBTN_OUT_N")
	)
	(segment
		(start 23.054564 -88.791796)
		(end 23.054564 -88.484964)
		(width 0.10668)
		(layer "In4.Cu")
		(net "RST_BMC_RSTBTN_OUT_N")
	)
	(segment
		(start 22.37232 -83.463638)
		(end 22.61108 -83.224878)
		(width 0.10668)
		(layer "In4.Cu")
		(net "RST_BMC_RSTBTN_OUT_N")
	)
	(segment
		(start 23.06574 -81.10474)
		(end 23.06574 -75.31862)
		(width 0.10668)
		(layer "In4.Cu")
		(net "RST_BMC_RSTBTN_OUT_N")
	)
	(segment
		(start 21.6408 -73.89368)
		(end 21.6408 -73.0504)
		(width 0.10668)
		(layer "In4.Cu")
		(net "RST_BMC_RSTBTN_OUT_N")
	)
	(segment
		(start 21.06676 -72.47636)
		(end 21.06676 -71.367142)
		(width 0.10668)
		(layer "In4.Cu")
		(net "RST_BMC_RSTBTN_OUT_N")
	)
	(segment
		(start 22.61108 -84.796122)
		(end 22.37232 -84.557362)
		(width 0.10668)
		(layer "In4.Cu")
		(net "RST_BMC_RSTBTN_OUT_N")
	)
	(segment
		(start 22.37232 -84.557362)
		(end 22.37232 -83.463638)
		(width 0.10668)
		(layer "In4.Cu")
		(net "RST_BMC_RSTBTN_OUT_N")
	)
	(segment
		(start 21.6408 -73.0504)
		(end 21.06676 -72.47636)
		(width 0.10668)
		(layer "In4.Cu")
		(net "RST_BMC_RSTBTN_OUT_N")
	)
	(segment
		(start 22.145498 -64.238378)
		(end 23.1902 -64.2366)
		(width 0.10668)
		(layer "In4.Cu")
		(net "RST_BMC_RSTBTN_OUT_N")
	)
	(segment
		(start 52.1208 -113.792)
		(end 53.7972 -115.4684)
		(width 0.11684)
		(layer "F.Cu")
		(net "RMII_OCP_RCLKI")
	)
	(segment
		(start 31.2674 -43.2054)
		(end 31.5214 -43.4594)
		(width 0.11684)
		(layer "F.Cu")
		(net "RMII_OCP_RCLKI")
	)
	(segment
		(start 53.7972 -116.4336)
		(end 53.26507 -116.96573)
		(width 0.11684)
		(layer "F.Cu")
		(net "RMII_OCP_RCLKI")
	)
	(segment
		(start 34.4424 -45.6184)
		(end 34.4424 -46.99)
		(width 0.11684)
		(layer "F.Cu")
		(net "RMII_OCP_RCLKI")
	)
	(segment
		(start 40.0558 -27.4066)
		(end 40.24884 -27.21356)
		(width 0.11684)
		(layer "F.Cu")
		(net "RMII_OCP_RCLKI")
	)
	(segment
		(start 31.2166 -43.2054)
		(end 31.2674 -43.2054)
		(width 0.11684)
		(layer "F.Cu")
		(net "RMII_OCP_RCLKI")
	)
	(segment
		(start 32.3088 -47.9044)
		(end 32.3088 -49.022)
		(width 0.11684)
		(layer "F.Cu")
		(net "RMII_OCP_RCLKI")
	)
	(segment
		(start 31.5214 -44.9834)
		(end 32.0294 -45.4914)
		(width 0.11684)
		(layer "F.Cu")
		(net "RMII_OCP_RCLKI")
	)
	(segment
		(start 34.3154 -45.4914)
		(end 34.4424 -45.6184)
		(width 0.11684)
		(layer "F.Cu")
		(net "RMII_OCP_RCLKI")
	)
	(segment
		(start 33.5534 -49.4792)
		(end 34.12998 -48.90262)
		(width 0.11684)
		(layer "F.Cu")
		(net "RMII_OCP_RCLKI")
	)
	(segment
		(start 34.4424 -46.99)
		(end 34.0614 -47.371)
		(width 0.11684)
		(layer "F.Cu")
		(net "RMII_OCP_RCLKI")
	)
	(segment
		(start 39.6748 -28.3464)
		(end 40.0558 -27.9654)
		(width 0.11684)
		(layer "F.Cu")
		(net "RMII_OCP_RCLKI")
	)
	(segment
		(start 40.0558 -27.9654)
		(end 40.0558 -27.4066)
		(width 0.11684)
		(layer "F.Cu")
		(net "RMII_OCP_RCLKI")
	)
	(segment
		(start 32.766 -49.4792)
		(end 33.5534 -49.4792)
		(width 0.11684)
		(layer "F.Cu")
		(net "RMII_OCP_RCLKI")
	)
	(segment
		(start 53.7972 -115.4684)
		(end 53.7972 -116.4336)
		(width 0.11684)
		(layer "F.Cu")
		(net "RMII_OCP_RCLKI")
	)
	(segment
		(start 40.24884 -27.21356)
		(end 41.116758 -27.21356)
		(width 0.11684)
		(layer "F.Cu")
		(net "RMII_OCP_RCLKI")
	)
	(segment
		(start 34.0614 -47.371)
		(end 32.8422 -47.371)
		(width 0.11684)
		(layer "F.Cu")
		(net "RMII_OCP_RCLKI")
	)
	(segment
		(start 32.3088 -49.022)
		(end 32.766 -49.4792)
		(width 0.11684)
		(layer "F.Cu")
		(net "RMII_OCP_RCLKI")
	)
	(segment
		(start 34.12998 -48.90262)
		(end 35.77082 -48.90262)
		(width 0.11684)
		(layer "F.Cu")
		(net "RMII_OCP_RCLKI")
	)
	(segment
		(start 31.5214 -43.4594)
		(end 31.5214 -44.9834)
		(width 0.11684)
		(layer "F.Cu")
		(net "RMII_OCP_RCLKI")
	)
	(segment
		(start 53.26507 -116.96573)
		(end 53.26507 -118.25986)
		(width 0.11684)
		(layer "F.Cu")
		(net "RMII_OCP_RCLKI")
	)
	(segment
		(start 52.1208 -113.1316)
		(end 52.1208 -113.792)
		(width 0.11684)
		(layer "F.Cu")
		(net "RMII_OCP_RCLKI")
	)
	(segment
		(start 32.0294 -45.4914)
		(end 34.3154 -45.4914)
		(width 0.11684)
		(layer "F.Cu")
		(net "RMII_OCP_RCLKI")
	)
	(segment
		(start 32.8422 -47.371)
		(end 32.3088 -47.9044)
		(width 0.11684)
		(layer "F.Cu")
		(net "RMII_OCP_RCLKI")
	)
	(via
		(at 36.97732 -63.012828)
		(size 0.508)
		(drill 0.254)
		(layers "F.Cu" "B.Cu")
		(net "RMII_OCP_RCLKI")
	)
	(via
		(at 35.77082 -48.90262)
		(size 0.508)
		(drill 0.254)
		(layers "F.Cu" "B.Cu")
		(net "RMII_OCP_RCLKI")
	)
	(via
		(at 52.1208 -113.1316)
		(size 0.508)
		(drill 0.254)
		(layers "F.Cu" "B.Cu")
		(net "RMII_OCP_RCLKI")
	)
	(via
		(at 31.2166 -43.2054)
		(size 0.508)
		(drill 0.254)
		(layers "F.Cu" "B.Cu")
		(net "RMII_OCP_RCLKI")
	)
	(via
		(at 39.6748 -28.3464)
		(size 0.508)
		(drill 0.254)
		(layers "F.Cu" "B.Cu")
		(net "RMII_OCP_RCLKI")
	)
	(via
		(at 65.48374 -110.5154)
		(size 0.508)
		(drill 0.254)
		(layers "F.Cu" "B.Cu")
		(net "RMII_OCP_RCLKI")
	)
	(segment
		(start 52.1208 -113.7412)
		(end 52.43576 -114.05616)
		(width 0.08382)
		(layer "In2.Cu")
		(net "RMII_OCP_RCLKI")
	)
	(segment
		(start 60.791344 -112.46231)
		(end 61.186314 -112.06734)
		(width 0.08382)
		(layer "In2.Cu")
		(net "RMII_OCP_RCLKI")
	)
	(segment
		(start 56.28767 -113.161572)
		(end 57.976008 -112.46231)
		(width 0.08382)
		(layer "In2.Cu")
		(net "RMII_OCP_RCLKI")
	)
	(segment
		(start 52.1208 -113.1316)
		(end 52.1208 -113.7412)
		(width 0.08382)
		(layer "In2.Cu")
		(net "RMII_OCP_RCLKI")
	)
	(segment
		(start 55.393082 -114.05616)
		(end 56.28767 -113.161572)
		(width 0.08382)
		(layer "In2.Cu")
		(net "RMII_OCP_RCLKI")
	)
	(segment
		(start 61.186314 -112.06734)
		(end 62.634114 -112.06734)
		(width 0.08382)
		(layer "In2.Cu")
		(net "RMII_OCP_RCLKI")
	)
	(segment
		(start 52.43576 -114.05616)
		(end 55.393082 -114.05616)
		(width 0.08382)
		(layer "In2.Cu")
		(net "RMII_OCP_RCLKI")
	)
	(segment
		(start 57.976008 -112.46231)
		(end 60.791344 -112.46231)
		(width 0.08382)
		(layer "In2.Cu")
		(net "RMII_OCP_RCLKI")
	)
	(segment
		(start 62.634114 -112.06734)
		(end 64.186054 -110.5154)
		(width 0.08382)
		(layer "In2.Cu")
		(net "RMII_OCP_RCLKI")
	)
	(segment
		(start 64.186054 -110.5154)
		(end 65.48374 -110.5154)
		(width 0.08382)
		(layer "In2.Cu")
		(net "RMII_OCP_RCLKI")
	)
	(segment
		(start 36.1442 -49.95672)
		(end 36.25088 -50.0634)
		(width 0.10668)
		(layer "In4.Cu")
		(net "RMII_OCP_RCLKI")
	)
	(segment
		(start 38.1254 -51.943)
		(end 37.4396 -52.6288)
		(width 0.10668)
		(layer "In4.Cu")
		(net "RMII_OCP_RCLKI")
	)
	(segment
		(start 36.25088 -50.0634)
		(end 37.7444 -50.0634)
		(width 0.10668)
		(layer "In4.Cu")
		(net "RMII_OCP_RCLKI")
	)
	(segment
		(start 36.8046 -62.840108)
		(end 36.97732 -63.012828)
		(width 0.10668)
		(layer "In4.Cu")
		(net "RMII_OCP_RCLKI")
	)
	(segment
		(start 35.77082 -48.90262)
		(end 36.0172 -49.149)
		(width 0.10668)
		(layer "In4.Cu")
		(net "RMII_OCP_RCLKI")
	)
	(segment
		(start 36.8046 -59.9186)
		(end 36.8046 -62.840108)
		(width 0.10668)
		(layer "In4.Cu")
		(net "RMII_OCP_RCLKI")
	)
	(segment
		(start 37.7444 -50.0634)
		(end 38.1254 -50.4444)
		(width 0.10668)
		(layer "In4.Cu")
		(net "RMII_OCP_RCLKI")
	)
	(segment
		(start 36.0172 -49.5046)
		(end 36.1442 -49.6316)
		(width 0.10668)
		(layer "In4.Cu")
		(net "RMII_OCP_RCLKI")
	)
	(segment
		(start 37.973 -54.991)
		(end 37.973 -58.7502)
		(width 0.10668)
		(layer "In4.Cu")
		(net "RMII_OCP_RCLKI")
	)
	(segment
		(start 36.0172 -49.149)
		(end 36.0172 -49.5046)
		(width 0.10668)
		(layer "In4.Cu")
		(net "RMII_OCP_RCLKI")
	)
	(segment
		(start 37.4396 -52.6288)
		(end 37.4396 -54.4576)
		(width 0.10668)
		(layer "In4.Cu")
		(net "RMII_OCP_RCLKI")
	)
	(segment
		(start 37.973 -58.7502)
		(end 36.8046 -59.9186)
		(width 0.10668)
		(layer "In4.Cu")
		(net "RMII_OCP_RCLKI")
	)
	(segment
		(start 38.1254 -50.4444)
		(end 38.1254 -51.943)
		(width 0.10668)
		(layer "In4.Cu")
		(net "RMII_OCP_RCLKI")
	)
	(segment
		(start 37.4396 -54.4576)
		(end 37.973 -54.991)
		(width 0.10668)
		(layer "In4.Cu")
		(net "RMII_OCP_RCLKI")
	)
	(segment
		(start 36.1442 -49.6316)
		(end 36.1442 -49.95672)
		(width 0.10668)
		(layer "In4.Cu")
		(net "RMII_OCP_RCLKI")
	)
	(segment
		(start 38.04412 -63.31712)
		(end 37.7444 -63.0174)
		(width 0.10668)
		(layer "In7.Cu")
		(net "RMII_OCP_RCLKI")
	)
	(segment
		(start 55.2196 -93.837252)
		(end 55.2196 -89.06891)
		(width 0.10668)
		(layer "In7.Cu")
		(net "RMII_OCP_RCLKI")
	)
	(segment
		(start 63.9318 -103.832152)
		(end 61.69152 -101.591872)
		(width 0.10668)
		(layer "In7.Cu")
		(net "RMII_OCP_RCLKI")
	)
	(segment
		(start 64.34328 -106.108754)
		(end 63.63716 -105.402634)
		(width 0.10668)
		(layer "In7.Cu")
		(net "RMII_OCP_RCLKI")
	)
	(segment
		(start 33.9852 -36.7792)
		(end 33.5534 -36.7792)
		(width 0.10668)
		(layer "In7.Cu")
		(net "RMII_OCP_RCLKI")
	)
	(segment
		(start 36.957 -31.4706)
		(end 36.0934 -32.3342)
		(width 0.10668)
		(layer "In7.Cu")
		(net "RMII_OCP_RCLKI")
	)
	(segment
		(start 52.103274 -83.617816)
		(end 48.01362 -79.520796)
		(width 0.10668)
		(layer "In7.Cu")
		(net "RMII_OCP_RCLKI")
	)
	(segment
		(start 63.63716 -105.402634)
		(end 63.63716 -104.6734)
		(width 0.10668)
		(layer "In7.Cu")
		(net "RMII_OCP_RCLKI")
	)
	(segment
		(start 32.2326 -41.1988)
		(end 31.8262 -41.1988)
		(width 0.10668)
		(layer "In7.Cu")
		(net "RMII_OCP_RCLKI")
	)
	(segment
		(start 31.0896 -41.9354)
		(end 31.0896 -43.0784)
		(width 0.10668)
		(layer "In7.Cu")
		(net "RMII_OCP_RCLKI")
	)
	(segment
		(start 48.01362 -79.520796)
		(end 48.01362 -77.699362)
		(width 0.10668)
		(layer "In7.Cu")
		(net "RMII_OCP_RCLKI")
	)
	(segment
		(start 39.6748 -28.067)
		(end 39.3954 -27.7876)
		(width 0.10668)
		(layer "In7.Cu")
		(net "RMII_OCP_RCLKI")
	)
	(segment
		(start 31.8262 -41.1988)
		(end 31.0896 -41.9354)
		(width 0.10668)
		(layer "In7.Cu")
		(net "RMII_OCP_RCLKI")
	)
	(segment
		(start 54.386988 -87.0585)
		(end 52.925472 -85.596984)
		(width 0.10668)
		(layer "In7.Cu")
		(net "RMII_OCP_RCLKI")
	)
	(segment
		(start 37.7444 -63.0174)
		(end 36.981892 -63.0174)
		(width 0.10668)
		(layer "In7.Cu")
		(net "RMII_OCP_RCLKI")
	)
	(segment
		(start 55.2196 -89.06891)
		(end 54.386988 -87.0585)
		(width 0.10668)
		(layer "In7.Cu")
		(net "RMII_OCP_RCLKI")
	)
	(segment
		(start 61.69152 -99.09302)
		(end 59.23788 -96.63938)
		(width 0.10668)
		(layer "In7.Cu")
		(net "RMII_OCP_RCLKI")
	)
	(segment
		(start 36.957 -29.2608)
		(end 36.957 -31.4706)
		(width 0.10668)
		(layer "In7.Cu")
		(net "RMII_OCP_RCLKI")
	)
	(segment
		(start 52.925472 -85.596984)
		(end 52.103274 -83.617816)
		(width 0.10668)
		(layer "In7.Cu")
		(net "RMII_OCP_RCLKI")
	)
	(segment
		(start 38.4302 -27.7876)
		(end 36.957 -29.2608)
		(width 0.10668)
		(layer "In7.Cu")
		(net "RMII_OCP_RCLKI")
	)
	(segment
		(start 59.23788 -96.63938)
		(end 58.021728 -96.63938)
		(width 0.10668)
		(layer "In7.Cu")
		(net "RMII_OCP_RCLKI")
	)
	(segment
		(start 36.0934 -32.3342)
		(end 36.0934 -33.1724)
		(width 0.10668)
		(layer "In7.Cu")
		(net "RMII_OCP_RCLKI")
	)
	(segment
		(start 65.48374 -110.5154)
		(end 64.34328 -109.37494)
		(width 0.10668)
		(layer "In7.Cu")
		(net "RMII_OCP_RCLKI")
	)
	(segment
		(start 36.0934 -33.1724)
		(end 35.1536 -34.1122)
		(width 0.10668)
		(layer "In7.Cu")
		(net "RMII_OCP_RCLKI")
	)
	(segment
		(start 33.02 -38.7096)
		(end 33.02 -40.4114)
		(width 0.10668)
		(layer "In7.Cu")
		(net "RMII_OCP_RCLKI")
	)
	(segment
		(start 42.742104 -73.532746)
		(end 37.4396 -68.230242)
		(width 0.10668)
		(layer "In7.Cu")
		(net "RMII_OCP_RCLKI")
	)
	(segment
		(start 33.5534 -36.7792)
		(end 33.4264 -36.9062)
		(width 0.10668)
		(layer "In7.Cu")
		(net "RMII_OCP_RCLKI")
	)
	(segment
		(start 39.6748 -28.3464)
		(end 39.6748 -28.067)
		(width 0.10668)
		(layer "In7.Cu")
		(net "RMII_OCP_RCLKI")
	)
	(segment
		(start 37.4396 -66.429382)
		(end 38.04412 -65.824862)
		(width 0.10668)
		(layer "In7.Cu")
		(net "RMII_OCP_RCLKI")
	)
	(segment
		(start 37.4396 -68.230242)
		(end 37.4396 -66.429382)
		(width 0.10668)
		(layer "In7.Cu")
		(net "RMII_OCP_RCLKI")
	)
	(segment
		(start 61.69152 -101.591872)
		(end 61.69152 -99.09302)
		(width 0.10668)
		(layer "In7.Cu")
		(net "RMII_OCP_RCLKI")
	)
	(segment
		(start 47.245524 -77.23378)
		(end 43.54449 -73.532746)
		(width 0.10668)
		(layer "In7.Cu")
		(net "RMII_OCP_RCLKI")
	)
	(segment
		(start 33.02 -40.4114)
		(end 32.2326 -41.1988)
		(width 0.10668)
		(layer "In7.Cu")
		(net "RMII_OCP_RCLKI")
	)
	(segment
		(start 58.021728 -96.63938)
		(end 55.2196 -93.837252)
		(width 0.10668)
		(layer "In7.Cu")
		(net "RMII_OCP_RCLKI")
	)
	(segment
		(start 47.548038 -77.23378)
		(end 47.245524 -77.23378)
		(width 0.10668)
		(layer "In7.Cu")
		(net "RMII_OCP_RCLKI")
	)
	(segment
		(start 38.04412 -65.824862)
		(end 38.04412 -63.31712)
		(width 0.10668)
		(layer "In7.Cu")
		(net "RMII_OCP_RCLKI")
	)
	(segment
		(start 63.9318 -104.37876)
		(end 63.9318 -103.832152)
		(width 0.10668)
		(layer "In7.Cu")
		(net "RMII_OCP_RCLKI")
	)
	(segment
		(start 63.63716 -104.6734)
		(end 63.9318 -104.37876)
		(width 0.10668)
		(layer "In7.Cu")
		(net "RMII_OCP_RCLKI")
	)
	(segment
		(start 35.1536 -34.1122)
		(end 35.1536 -35.6108)
		(width 0.10668)
		(layer "In7.Cu")
		(net "RMII_OCP_RCLKI")
	)
	(segment
		(start 35.1536 -35.6108)
		(end 33.9852 -36.7792)
		(width 0.10668)
		(layer "In7.Cu")
		(net "RMII_OCP_RCLKI")
	)
	(segment
		(start 64.34328 -109.37494)
		(end 64.34328 -106.108754)
		(width 0.10668)
		(layer "In7.Cu")
		(net "RMII_OCP_RCLKI")
	)
	(segment
		(start 33.4264 -38.3032)
		(end 33.02 -38.7096)
		(width 0.10668)
		(layer "In7.Cu")
		(net "RMII_OCP_RCLKI")
	)
	(segment
		(start 48.01362 -77.699362)
		(end 47.548038 -77.23378)
		(width 0.10668)
		(layer "In7.Cu")
		(net "RMII_OCP_RCLKI")
	)
	(segment
		(start 39.3954 -27.7876)
		(end 38.4302 -27.7876)
		(width 0.10668)
		(layer "In7.Cu")
		(net "RMII_OCP_RCLKI")
	)
	(segment
		(start 36.981892 -63.0174)
		(end 36.97732 -63.012828)
		(width 0.10668)
		(layer "In7.Cu")
		(net "RMII_OCP_RCLKI")
	)
	(segment
		(start 31.0896 -43.0784)
		(end 31.2166 -43.2054)
		(width 0.10668)
		(layer "In7.Cu")
		(net "RMII_OCP_RCLKI")
	)
	(segment
		(start 33.4264 -36.9062)
		(end 33.4264 -38.3032)
		(width 0.10668)
		(layer "In7.Cu")
		(net "RMII_OCP_RCLKI")
	)
	(segment
		(start 43.54449 -73.532746)
		(end 42.742104 -73.532746)
		(width 0.10668)
		(layer "In7.Cu")
		(net "RMII_OCP_RCLKI")
	)
	(segment
		(start 47.295054 -42.571162)
		(end 46.89983 -42.175938)
		(width 0.11684)
		(layer "F.Cu")
		(net "RMII_TXEN_R")
	)
	(via
		(at 46.89983 -42.175938)
		(size 0.4572)
		(drill 0.254)
		(layers "F.Cu" "B.Cu")
		(net "RMII_TXEN_R")
	)
	(segment
		(start 43.107356 -40.438832)
		(end 43.639232 -40.438832)
		(width 0.11684)
		(layer "B.Cu")
		(net "RMII_TXEN_R")
	)
	(segment
		(start 44.9834 -41.783)
		(end 46.2788 -41.783)
		(width 0.11684)
		(layer "B.Cu")
		(net "RMII_TXEN_R")
	)
	(segment
		(start 46.510448 -42.014648)
		(end 46.89983 -42.175938)
		(width 0.11684)
		(layer "B.Cu")
		(net "RMII_TXEN_R")
	)
	(segment
		(start 43.639232 -40.438832)
		(end 44.9834 -41.783)
		(width 0.11684)
		(layer "B.Cu")
		(net "RMII_TXEN_R")
	)
	(segment
		(start 46.2788 -41.783)
		(end 46.510448 -42.014648)
		(width 0.11684)
		(layer "B.Cu")
		(net "RMII_TXEN_R")
	)
	(segment
		(start 42.620184 -39.95166)
		(end 43.107356 -40.438832)
		(width 0.11684)
		(layer "B.Cu")
		(net "RMII_TXEN_R")
	)
	(segment
		(start 51.12512 -112.642904)
		(end 51.270916 -112.497108)
		(width 0.11684)
		(layer "F.Cu")
		(net "RMII_TXEN")
	)
	(segment
		(start 50.64887 -110.1852)
		(end 50.64887 -109.811058)
		(width 0.11684)
		(layer "F.Cu")
		(net "RMII_TXEN")
	)
	(segment
		(start 51.76266 -114.842036)
		(end 51.12512 -114.204496)
		(width 0.11684)
		(layer "F.Cu")
		(net "RMII_TXEN")
	)
	(segment
		(start 51.12512 -114.204496)
		(end 51.12512 -112.642904)
		(width 0.11684)
		(layer "F.Cu")
		(net "RMII_TXEN")
	)
	(segment
		(start 51.76266 -117.04066)
		(end 51.76266 -114.842036)
		(width 0.11684)
		(layer "F.Cu")
		(net "RMII_TXEN")
	)
	(segment
		(start 50.39487 -110.4392)
		(end 50.64887 -110.1852)
		(width 0.11684)
		(layer "F.Cu")
		(net "RMII_TXEN")
	)
	(segment
		(start 51.270916 -111.315246)
		(end 50.39487 -110.4392)
		(width 0.11684)
		(layer "F.Cu")
		(net "RMII_TXEN")
	)
	(segment
		(start 51.94935 -118.14429)
		(end 51.94935 -117.22735)
		(width 0.11684)
		(layer "F.Cu")
		(net "RMII_TXEN")
	)
	(segment
		(start 52.06492 -118.25986)
		(end 51.94935 -118.14429)
		(width 0.11684)
		(layer "F.Cu")
		(net "RMII_TXEN")
	)
	(segment
		(start 51.270916 -112.497108)
		(end 51.270916 -111.315246)
		(width 0.11684)
		(layer "F.Cu")
		(net "RMII_TXEN")
	)
	(segment
		(start 51.94935 -117.22735)
		(end 51.76266 -117.04066)
		(width 0.11684)
		(layer "F.Cu")
		(net "RMII_TXEN")
	)
	(via
		(at 50.39487 -110.4392)
		(size 0.508)
		(drill 0.254)
		(layers "F.Cu" "B.Cu")
		(net "RMII_TXEN")
	)
	(via
		(at 52.97551 -102.743254)
		(size 0.508)
		(drill 0.254)
		(layers "F.Cu" "B.Cu")
		(net "RMII_TXEN")
	)
	(via
		(at 41.1988 -40.1828)
		(size 0.508)
		(drill 0.254)
		(layers "F.Cu" "B.Cu")
		(net "RMII_TXEN")
	)
	(segment
		(start 41.588944 -40.1828)
		(end 41.1988 -40.1828)
		(width 0.11684)
		(layer "B.Cu")
		(net "RMII_TXEN")
	)
	(segment
		(start 41.820084 -39.95166)
		(end 41.588944 -40.1828)
		(width 0.11684)
		(layer "B.Cu")
		(net "RMII_TXEN")
	)
	(segment
		(start 50.32502 -106.376978)
		(end 51.737768 -104.96423)
		(width 0.10668)
		(layer "In4.Cu")
		(net "RMII_TXEN")
	)
	(segment
		(start 52.432712 -103.286052)
		(end 52.97551 -102.743254)
		(width 0.10668)
		(layer "In4.Cu")
		(net "RMII_TXEN")
	)
	(segment
		(start 50.32502 -107.756198)
		(end 50.32502 -106.376978)
		(width 0.10668)
		(layer "In4.Cu")
		(net "RMII_TXEN")
	)
	(segment
		(start 50.06594 -109.577886)
		(end 49.8348 -109.346746)
		(width 0.10668)
		(layer "In4.Cu")
		(net "RMII_TXEN")
	)
	(segment
		(start 50.39487 -110.4392)
		(end 50.0634 -110.10773)
		(width 0.10668)
		(layer "In4.Cu")
		(net "RMII_TXEN")
	)
	(segment
		(start 50.0634 -110.004098)
		(end 50.06594 -110.001558)
		(width 0.10668)
		(layer "In4.Cu")
		(net "RMII_TXEN")
	)
	(segment
		(start 49.8348 -109.346746)
		(end 49.8348 -108.246418)
		(width 0.10668)
		(layer "In4.Cu")
		(net "RMII_TXEN")
	)
	(segment
		(start 49.8348 -108.246418)
		(end 50.32502 -107.756198)
		(width 0.10668)
		(layer "In4.Cu")
		(net "RMII_TXEN")
	)
	(segment
		(start 50.0634 -110.10773)
		(end 50.0634 -110.004098)
		(width 0.10668)
		(layer "In4.Cu")
		(net "RMII_TXEN")
	)
	(segment
		(start 50.06594 -110.001558)
		(end 50.06594 -109.577886)
		(width 0.10668)
		(layer "In4.Cu")
		(net "RMII_TXEN")
	)
	(segment
		(start 51.737768 -104.96423)
		(end 52.432712 -103.286052)
		(width 0.10668)
		(layer "In4.Cu")
		(net "RMII_TXEN")
	)
	(segment
		(start 53.5432 -101.535992)
		(end 52.980844 -102.098348)
		(width 0.10668)
		(layer "In7.Cu")
		(net "RMII_TXEN")
	)
	(segment
		(start 53.0352 -88.612218)
		(end 52.847748 -88.79967)
		(width 0.10668)
		(layer "In7.Cu")
		(net "RMII_TXEN")
	)
	(segment
		(start 38.415214 -49.16424)
		(end 38.028118 -49.551336)
		(width 0.10668)
		(layer "In7.Cu")
		(net "RMII_TXEN")
	)
	(segment
		(start 39.19474 -73.32345)
		(end 39.19474 -73.408794)
		(width 0.10668)
		(layer "In7.Cu")
		(net "RMII_TXEN")
	)
	(segment
		(start 52.847748 -89.43975)
		(end 53.0352 -89.627202)
		(width 0.10668)
		(layer "In7.Cu")
		(net "RMII_TXEN")
	)
	(segment
		(start 42.813732 -75.209146)
		(end 45.70476 -78.100174)
		(width 0.10668)
		(layer "In7.Cu")
		(net "RMII_TXEN")
	)
	(segment
		(start 54.391052 -98.649028)
		(end 54.651148 -98.649028)
		(width 0.10668)
		(layer "In7.Cu")
		(net "RMII_TXEN")
	)
	(segment
		(start 52.847748 -90.07983)
		(end 52.409852 -90.07983)
		(width 0.10668)
		(layer "In7.Cu")
		(net "RMII_TXEN")
	)
	(segment
		(start 53.0352 -89.892378)
		(end 52.847748 -90.07983)
		(width 0.10668)
		(layer "In7.Cu")
		(net "RMII_TXEN")
	)
	(segment
		(start 52.847748 -88.79967)
		(end 52.409852 -88.79967)
		(width 0.10668)
		(layer "In7.Cu")
		(net "RMII_TXEN")
	)
	(segment
		(start 52.2224 -91.547442)
		(end 52.2224 -94.996)
		(width 0.10668)
		(layer "In7.Cu")
		(net "RMII_TXEN")
	)
	(segment
		(start 38.415214 -47.397416)
		(end 38.415214 -49.16424)
		(width 0.10668)
		(layer "In7.Cu")
		(net "RMII_TXEN")
	)
	(segment
		(start 39.19474 -73.408794)
		(end 40.995092 -75.209146)
		(width 0.10668)
		(layer "In7.Cu")
		(net "RMII_TXEN")
	)
	(segment
		(start 35.0901 -64.773302)
		(end 35.0901 -68.363846)
		(width 0.10668)
		(layer "In7.Cu")
		(net "RMII_TXEN")
	)
	(segment
		(start 38.56101 -46.927008)
		(end 38.56101 -47.25162)
		(width 0.10668)
		(layer "In7.Cu")
		(net "RMII_TXEN")
	)
	(segment
		(start 38.56101 -47.25162)
		(end 38.415214 -47.397416)
		(width 0.10668)
		(layer "In7.Cu")
		(net "RMII_TXEN")
	)
	(segment
		(start 52.409852 -90.07983)
		(end 52.2224 -90.267282)
		(width 0.10668)
		(layer "In7.Cu")
		(net "RMII_TXEN")
	)
	(segment
		(start 35.904932 -69.178678)
		(end 36.02228 -69.462142)
		(width 0.10668)
		(layer "In7.Cu")
		(net "RMII_TXEN")
	)
	(segment
		(start 54.2036 -96.9772)
		(end 54.2036 -97.181416)
		(width 0.10668)
		(layer "In7.Cu")
		(net "RMII_TXEN")
	)
	(segment
		(start 35.097212 -64.765936)
		(end 35.0901 -64.773302)
		(width 0.10668)
		(layer "In7.Cu")
		(net "RMII_TXEN")
	)
	(segment
		(start 54.391052 -98.008948)
		(end 54.2036 -98.1964)
		(width 0.10668)
		(layer "In7.Cu")
		(net "RMII_TXEN")
	)
	(segment
		(start 52.2224 -88.987122)
		(end 52.2224 -89.252298)
		(width 0.10668)
		(layer "In7.Cu")
		(net "RMII_TXEN")
	)
	(segment
		(start 52.2224 -87.972138)
		(end 52.409852 -88.15959)
		(width 0.10668)
		(layer "In7.Cu")
		(net "RMII_TXEN")
	)
	(segment
		(start 51.59883 -86.77783)
		(end 52.2224 -87.4014)
		(width 0.10668)
		(layer "In7.Cu")
		(net "RMII_TXEN")
	)
	(segment
		(start 38.33368 -73.05421)
		(end 38.9255 -73.05421)
		(width 0.10668)
		(layer "In7.Cu")
		(net "RMII_TXEN")
	)
	(segment
		(start 54.2036 -98.1964)
		(end 54.2036 -98.461576)
		(width 0.10668)
		(layer "In7.Cu")
		(net "RMII_TXEN")
	)
	(segment
		(start 35.0901 -68.363846)
		(end 35.904932 -69.178678)
		(width 0.10668)
		(layer "In7.Cu")
		(net "RMII_TXEN")
	)
	(segment
		(start 53.5432 -100.13696)
		(end 53.5432 -101.535992)
		(width 0.10668)
		(layer "In7.Cu")
		(net "RMII_TXEN")
	)
	(segment
		(start 52.2224 -89.252298)
		(end 52.409852 -89.43975)
		(width 0.10668)
		(layer "In7.Cu")
		(net "RMII_TXEN")
	)
	(segment
		(start 53.0352 -90.907362)
		(end 53.0352 -91.172538)
		(width 0.10668)
		(layer "In7.Cu")
		(net "RMII_TXEN")
	)
	(segment
		(start 40.007794 -41.609264)
		(end 39.82466 -41.792398)
		(width 0.10668)
		(layer "In7.Cu")
		(net "RMII_TXEN")
	)
	(segment
		(start 53.0352 -91.172538)
		(end 52.847748 -91.35999)
		(width 0.10668)
		(layer "In7.Cu")
		(net "RMII_TXEN")
	)
	(segment
		(start 40.461946 -40.1828)
		(end 40.007794 -40.636952)
		(width 0.10668)
		(layer "In7.Cu")
		(net "RMII_TXEN")
	)
	(segment
		(start 52.409852 -91.35999)
		(end 52.2224 -91.547442)
		(width 0.10668)
		(layer "In7.Cu")
		(net "RMII_TXEN")
	)
	(segment
		(start 54.651148 -98.649028)
		(end 54.8386 -98.83648)
		(width 0.10668)
		(layer "In7.Cu")
		(net "RMII_TXEN")
	)
	(segment
		(start 40.007794 -40.636952)
		(end 40.007794 -41.609264)
		(width 0.10668)
		(layer "In7.Cu")
		(net "RMII_TXEN")
	)
	(segment
		(start 52.2224 -94.996)
		(end 54.2036 -96.9772)
		(width 0.10668)
		(layer "In7.Cu")
		(net "RMII_TXEN")
	)
	(segment
		(start 54.651148 -99.289108)
		(end 54.391052 -99.289108)
		(width 0.10668)
		(layer "In7.Cu")
		(net "RMII_TXEN")
	)
	(segment
		(start 49.17186 -83.890866)
		(end 51.272694 -85.9917)
		(width 0.10668)
		(layer "In7.Cu")
		(net "RMII_TXEN")
	)
	(segment
		(start 41.1988 -40.1828)
		(end 40.461946 -40.1828)
		(width 0.10668)
		(layer "In7.Cu")
		(net "RMII_TXEN")
	)
	(segment
		(start 52.409852 -88.79967)
		(end 52.2224 -88.987122)
		(width 0.10668)
		(layer "In7.Cu")
		(net "RMII_TXEN")
	)
	(segment
		(start 37.920676 -58.023506)
		(end 34.57956 -61.364622)
		(width 0.10668)
		(layer "In7.Cu")
		(net "RMII_TXEN")
	)
	(segment
		(start 38.028118 -51.027584)
		(end 37.4523 -52.416456)
		(width 0.10668)
		(layer "In7.Cu")
		(net "RMII_TXEN")
	)
	(segment
		(start 54.391052 -97.368868)
		(end 54.651148 -97.368868)
		(width 0.10668)
		(layer "In7.Cu")
		(net "RMII_TXEN")
	)
	(segment
		(start 37.4523 -52.416456)
		(end 37.4523 -54.621176)
		(width 0.10668)
		(layer "In7.Cu")
		(net "RMII_TXEN")
	)
	(segment
		(start 36.02228 -69.462142)
		(end 36.02228 -70.74281)
		(width 0.10668)
		(layer "In7.Cu")
		(net "RMII_TXEN")
	)
	(segment
		(start 52.980844 -102.098348)
		(end 52.980844 -102.73792)
		(width 0.10668)
		(layer "In7.Cu")
		(net "RMII_TXEN")
	)
	(segment
		(start 52.980844 -102.73792)
		(end 52.97551 -102.743254)
		(width 0.10668)
		(layer "In7.Cu")
		(net "RMII_TXEN")
	)
	(segment
		(start 52.2224 -90.267282)
		(end 52.2224 -90.532458)
		(width 0.10668)
		(layer "In7.Cu")
		(net "RMII_TXEN")
	)
	(segment
		(start 53.0352 -88.347042)
		(end 53.0352 -88.612218)
		(width 0.10668)
		(layer "In7.Cu")
		(net "RMII_TXEN")
	)
	(segment
		(start 54.8386 -97.821496)
		(end 54.651148 -98.008948)
		(width 0.10668)
		(layer "In7.Cu")
		(net "RMII_TXEN")
	)
	(segment
		(start 51.272694 -85.9917)
		(end 51.59883 -86.77783)
		(width 0.10668)
		(layer "In7.Cu")
		(net "RMII_TXEN")
	)
	(segment
		(start 52.847748 -90.71991)
		(end 53.0352 -90.907362)
		(width 0.10668)
		(layer "In7.Cu")
		(net "RMII_TXEN")
	)
	(segment
		(start 54.651148 -98.008948)
		(end 54.391052 -98.008948)
		(width 0.10668)
		(layer "In7.Cu")
		(net "RMII_TXEN")
	)
	(segment
		(start 38.028118 -49.551336)
		(end 38.028118 -51.027584)
		(width 0.10668)
		(layer "In7.Cu")
		(net "RMII_TXEN")
	)
	(segment
		(start 45.70476 -79.85506)
		(end 49.17186 -83.32216)
		(width 0.10668)
		(layer "In7.Cu")
		(net "RMII_TXEN")
	)
	(segment
		(start 37.4523 -54.621176)
		(end 37.920676 -55.089552)
		(width 0.10668)
		(layer "In7.Cu")
		(net "RMII_TXEN")
	)
	(segment
		(start 52.2224 -87.4014)
		(end 52.2224 -87.972138)
		(width 0.10668)
		(layer "In7.Cu")
		(net "RMII_TXEN")
	)
	(segment
		(start 54.8386 -97.55632)
		(end 54.8386 -97.821496)
		(width 0.10668)
		(layer "In7.Cu")
		(net "RMII_TXEN")
	)
	(segment
		(start 52.409852 -90.71991)
		(end 52.847748 -90.71991)
		(width 0.10668)
		(layer "In7.Cu")
		(net "RMII_TXEN")
	)
	(segment
		(start 39.82466 -41.792398)
		(end 39.82466 -45.663358)
		(width 0.10668)
		(layer "In7.Cu")
		(net "RMII_TXEN")
	)
	(segment
		(start 49.17186 -83.32216)
		(end 49.17186 -83.890866)
		(width 0.10668)
		(layer "In7.Cu")
		(net "RMII_TXEN")
	)
	(segment
		(start 36.02228 -70.74281)
		(end 38.33368 -73.05421)
		(width 0.10668)
		(layer "In7.Cu")
		(net "RMII_TXEN")
	)
	(segment
		(start 34.57956 -61.364622)
		(end 34.57956 -64.248284)
		(width 0.10668)
		(layer "In7.Cu")
		(net "RMII_TXEN")
	)
	(segment
		(start 52.847748 -88.15959)
		(end 53.0352 -88.347042)
		(width 0.10668)
		(layer "In7.Cu")
		(net "RMII_TXEN")
	)
	(segment
		(start 52.847748 -91.35999)
		(end 52.409852 -91.35999)
		(width 0.10668)
		(layer "In7.Cu")
		(net "RMII_TXEN")
	)
	(segment
		(start 54.651148 -97.368868)
		(end 54.8386 -97.55632)
		(width 0.10668)
		(layer "In7.Cu")
		(net "RMII_TXEN")
	)
	(segment
		(start 54.2036 -97.181416)
		(end 54.391052 -97.368868)
		(width 0.10668)
		(layer "In7.Cu")
		(net "RMII_TXEN")
	)
	(segment
		(start 45.70476 -78.100174)
		(end 45.70476 -79.85506)
		(width 0.10668)
		(layer "In7.Cu")
		(net "RMII_TXEN")
	)
	(segment
		(start 52.409852 -89.43975)
		(end 52.847748 -89.43975)
		(width 0.10668)
		(layer "In7.Cu")
		(net "RMII_TXEN")
	)
	(segment
		(start 54.8386 -99.101656)
		(end 54.651148 -99.289108)
		(width 0.10668)
		(layer "In7.Cu")
		(net "RMII_TXEN")
	)
	(segment
		(start 52.2224 -90.532458)
		(end 52.409852 -90.71991)
		(width 0.10668)
		(layer "In7.Cu")
		(net "RMII_TXEN")
	)
	(segment
		(start 38.9255 -73.05421)
		(end 39.19474 -73.32345)
		(width 0.10668)
		(layer "In7.Cu")
		(net "RMII_TXEN")
	)
	(segment
		(start 54.2036 -98.461576)
		(end 54.391052 -98.649028)
		(width 0.10668)
		(layer "In7.Cu")
		(net "RMII_TXEN")
	)
	(segment
		(start 54.391052 -99.289108)
		(end 53.5432 -100.13696)
		(width 0.10668)
		(layer "In7.Cu")
		(net "RMII_TXEN")
	)
	(segment
		(start 37.920676 -55.089552)
		(end 37.920676 -58.023506)
		(width 0.10668)
		(layer "In7.Cu")
		(net "RMII_TXEN")
	)
	(segment
		(start 53.0352 -89.627202)
		(end 53.0352 -89.892378)
		(width 0.10668)
		(layer "In7.Cu")
		(net "RMII_TXEN")
	)
	(segment
		(start 52.409852 -88.15959)
		(end 52.847748 -88.15959)
		(width 0.10668)
		(layer "In7.Cu")
		(net "RMII_TXEN")
	)
	(segment
		(start 40.995092 -75.209146)
		(end 42.813732 -75.209146)
		(width 0.10668)
		(layer "In7.Cu")
		(net "RMII_TXEN")
	)
	(segment
		(start 39.82466 -45.663358)
		(end 38.56101 -46.927008)
		(width 0.10668)
		(layer "In7.Cu")
		(net "RMII_TXEN")
	)
	(segment
		(start 34.57956 -64.248284)
		(end 35.097212 -64.765936)
		(width 0.10668)
		(layer "In7.Cu")
		(net "RMII_TXEN")
	)
	(segment
		(start 54.8386 -98.83648)
		(end 54.8386 -99.101656)
		(width 0.10668)
		(layer "In7.Cu")
		(net "RMII_TXEN")
	)
	(segment
		(start 44.733972 -42.159936)
		(end 45.113702 -42.159936)
		(width 0.11684)
		(layer "F.Cu")
		(net "RMII_TXD1_R")
	)
	(segment
		(start 43.459146 -40.463724)
		(end 43.8658 -41.446196)
		(width 0.11684)
		(layer "F.Cu")
		(net "RMII_TXD1_R")
	)
	(segment
		(start 45.113702 -42.159936)
		(end 45.404532 -42.280332)
		(width 0.11684)
		(layer "F.Cu")
		(net "RMII_TXD1_R")
	)
	(segment
		(start 41.293542 -38.881558)
		(end 41.58742 -38.58768)
		(width 0.11684)
		(layer "F.Cu")
		(net "RMII_TXD1_R")
	)
	(segment
		(start 45.404532 -42.280332)
		(end 45.695108 -42.571162)
		(width 0.11684)
		(layer "F.Cu")
		(net "RMII_TXD1_R")
	)
	(segment
		(start 41.58742 -38.58768)
		(end 41.58742 -37.66566)
		(width 0.11684)
		(layer "F.Cu")
		(net "RMII_TXD1_R")
	)
	(segment
		(start 43.8658 -41.446196)
		(end 44.47032 -42.050716)
		(width 0.11684)
		(layer "F.Cu")
		(net "RMII_TXD1_R")
	)
	(segment
		(start 43.044872 -39.071804)
		(end 43.044872 -40.04945)
		(width 0.11684)
		(layer "F.Cu")
		(net "RMII_TXD1_R")
	)
	(segment
		(start 42.481754 -37.588952)
		(end 42.997628 -38.834822)
		(width 0.11684)
		(layer "F.Cu")
		(net "RMII_TXD1_R")
	)
	(segment
		(start 43.044872 -40.04945)
		(end 43.459146 -40.463724)
		(width 0.11684)
		(layer "F.Cu")
		(net "RMII_TXD1_R")
	)
	(segment
		(start 44.47032 -42.050716)
		(end 44.733972 -42.159936)
		(width 0.11684)
		(layer "F.Cu")
		(net "RMII_TXD1_R")
	)
	(segment
		(start 42.997628 -38.834822)
		(end 43.044872 -39.071804)
		(width 0.11684)
		(layer "F.Cu")
		(net "RMII_TXD1_R")
	)
	(segment
		(start 41.58742 -37.66566)
		(end 41.82618 -37.4269)
		(width 0.11684)
		(layer "F.Cu")
		(net "RMII_TXD1_R")
	)
	(segment
		(start 41.82618 -37.4269)
		(end 42.239438 -37.4269)
		(width 0.11684)
		(layer "F.Cu")
		(net "RMII_TXD1_R")
	)
	(segment
		(start 40.50792 -38.881558)
		(end 41.293542 -38.881558)
		(width 0.11684)
		(layer "F.Cu")
		(net "RMII_TXD1_R")
	)
	(segment
		(start 42.239438 -37.4269)
		(end 42.481754 -37.588952)
		(width 0.11684)
		(layer "F.Cu")
		(net "RMII_TXD1_R")
	)
	(segment
		(start 50.21072 -115.865656)
		(end 50.21072 -115.223544)
		(width 0.11684)
		(layer "F.Cu")
		(net "RMII_TXD1")
	)
	(segment
		(start 49.7586 -112.962436)
		(end 50.419 -112.302036)
		(width 0.11684)
		(layer "F.Cu")
		(net "RMII_TXD1")
	)
	(segment
		(start 50.419 -112.302036)
		(end 50.419 -111.56696)
		(width 0.11684)
		(layer "F.Cu")
		(net "RMII_TXD1")
	)
	(segment
		(start 39.70782 -38.881558)
		(end 39.746174 -38.919912)
		(width 0.11684)
		(layer "F.Cu")
		(net "RMII_TXD1")
	)
	(segment
		(start 52.01031 -104.51084)
		(end 52.714906 -103.806244)
		(width 0.11684)
		(layer "F.Cu")
		(net "RMII_TXD1")
	)
	(segment
		(start 50.8508 -105.23982)
		(end 51.57978 -104.51084)
		(width 0.11684)
		(layer "F.Cu")
		(net "RMII_TXD1")
	)
	(segment
		(start 49.8094 -108.1024)
		(end 50.292 -107.6198)
		(width 0.11684)
		(layer "F.Cu")
		(net "RMII_TXD1")
	)
	(segment
		(start 49.7586 -113.23066)
		(end 49.7586 -112.962436)
		(width 0.11684)
		(layer "F.Cu")
		(net "RMII_TXD1")
	)
	(segment
		(start 50.419 -111.56696)
		(end 49.896776 -111.044736)
		(width 0.11684)
		(layer "F.Cu")
		(net "RMII_TXD1")
	)
	(segment
		(start 50.7746 -118.369588)
		(end 50.7746 -117.361716)
		(width 0.11684)
		(layer "F.Cu")
		(net "RMII_TXD1")
	)
	(segment
		(start 50.7238 -116.378736)
		(end 50.21072 -115.865656)
		(width 0.11684)
		(layer "F.Cu")
		(net "RMII_TXD1")
	)
	(segment
		(start 49.896776 -111.044736)
		(end 49.896776 -110.233206)
		(width 0.11684)
		(layer "F.Cu")
		(net "RMII_TXD1")
	)
	(segment
		(start 50.865024 -118.460012)
		(end 50.7746 -118.369588)
		(width 0.11684)
		(layer "F.Cu")
		(net "RMII_TXD1")
	)
	(segment
		(start 50.7746 -117.361716)
		(end 50.7238 -117.310916)
		(width 0.11684)
		(layer "F.Cu")
		(net "RMII_TXD1")
	)
	(segment
		(start 50.292 -107.6198)
		(end 50.292 -106.8578)
		(width 0.11684)
		(layer "F.Cu")
		(net "RMII_TXD1")
	)
	(segment
		(start 49.9364 -110.193582)
		(end 49.9364 -110.184946)
		(width 0.11684)
		(layer "F.Cu")
		(net "RMII_TXD1")
	)
	(segment
		(start 49.896776 -110.233206)
		(end 49.9364 -110.193582)
		(width 0.11684)
		(layer "F.Cu")
		(net "RMII_TXD1")
	)
	(segment
		(start 49.9872 -115.000024)
		(end 49.9872 -113.45926)
		(width 0.11684)
		(layer "F.Cu")
		(net "RMII_TXD1")
	)
	(segment
		(start 49.8094 -109.313218)
		(end 49.8094 -108.1024)
		(width 0.11684)
		(layer "F.Cu")
		(net "RMII_TXD1")
	)
	(segment
		(start 50.7238 -117.310916)
		(end 50.7238 -116.378736)
		(width 0.11684)
		(layer "F.Cu")
		(net "RMII_TXD1")
	)
	(segment
		(start 49.812448 -109.313218)
		(end 49.8094 -109.313218)
		(width 0.11684)
		(layer "F.Cu")
		(net "RMII_TXD1")
	)
	(segment
		(start 49.9872 -113.45926)
		(end 49.7586 -113.23066)
		(width 0.11684)
		(layer "F.Cu")
		(net "RMII_TXD1")
	)
	(segment
		(start 49.9364 -110.184946)
		(end 50.10404 -110.017306)
		(width 0.11684)
		(layer "F.Cu")
		(net "RMII_TXD1")
	)
	(segment
		(start 51.57978 -104.51084)
		(end 52.01031 -104.51084)
		(width 0.11684)
		(layer "F.Cu")
		(net "RMII_TXD1")
	)
	(segment
		(start 50.10404 -110.017306)
		(end 50.10404 -109.60481)
		(width 0.11684)
		(layer "F.Cu")
		(net "RMII_TXD1")
	)
	(segment
		(start 50.8508 -106.299)
		(end 50.8508 -105.23982)
		(width 0.11684)
		(layer "F.Cu")
		(net "RMII_TXD1")
	)
	(segment
		(start 50.292 -106.8578)
		(end 50.812192 -106.337608)
		(width 0.11684)
		(layer "F.Cu")
		(net "RMII_TXD1")
	)
	(segment
		(start 50.21072 -115.223544)
		(end 49.9872 -115.000024)
		(width 0.11684)
		(layer "F.Cu")
		(net "RMII_TXD1")
	)
	(segment
		(start 50.10404 -109.60481)
		(end 49.812448 -109.313218)
		(width 0.11684)
		(layer "F.Cu")
		(net "RMII_TXD1")
	)
	(segment
		(start 50.812192 -106.337608)
		(end 50.8508 -106.299)
		(width 0.11684)
		(layer "F.Cu")
		(net "RMII_TXD1")
	)
	(segment
		(start 39.746174 -38.919912)
		(end 39.746174 -39.606982)
		(width 0.11684)
		(layer "F.Cu")
		(net "RMII_TXD1")
	)
	(via
		(at 52.714906 -103.806244)
		(size 0.508)
		(drill 0.254)
		(layers "F.Cu" "B.Cu")
		(net "RMII_TXD1")
	)
	(via
		(at 39.746174 -39.606982)
		(size 0.508)
		(drill 0.254)
		(layers "F.Cu" "B.Cu")
		(net "RMII_TXD1")
	)
	(via
		(at 50.812192 -106.337608)
		(size 0.762)
		(drill 0.381)
		(layers "F.Cu" "B.Cu")
		(net "RMII_TXD1")
	)
	(segment
		(start 46.8884 -82.957416)
		(end 48.368204 -84.43722)
		(width 0.10668)
		(layer "In7.Cu")
		(net "RMII_TXD1")
	)
	(segment
		(start 50.988468 -86.181692)
		(end 51.79568 -88.129872)
		(width 0.10668)
		(layer "In7.Cu")
		(net "RMII_TXD1")
	)
	(segment
		(start 34.75482 -64.897762)
		(end 34.75482 -65.571116)
		(width 0.10668)
		(layer "In7.Cu")
		(net "RMII_TXD1")
	)
	(segment
		(start 52.70754 -103.125524)
		(end 52.70754 -103.798878)
		(width 0.10668)
		(layer "In7.Cu")
		(net "RMII_TXD1")
	)
	(segment
		(start 37.838634 -46.3804)
		(end 36.445444 -47.77359)
		(width 0.10668)
		(layer "In7.Cu")
		(net "RMII_TXD1")
	)
	(segment
		(start 51.8668 -95.114618)
		(end 53.86832 -97.116138)
		(width 0.10668)
		(layer "In7.Cu")
		(net "RMII_TXD1")
	)
	(segment
		(start 35.5473 -54.67604)
		(end 35.5473 -56.714898)
		(width 0.10668)
		(layer "In7.Cu")
		(net "RMII_TXD1")
	)
	(segment
		(start 37.05606 -51.98745)
		(end 36.827714 -52.215796)
		(width 0.10668)
		(layer "In7.Cu")
		(net "RMII_TXD1")
	)
	(segment
		(start 34.75482 -65.571116)
		(end 34.73196 -65.593976)
		(width 0.10668)
		(layer "In7.Cu")
		(net "RMII_TXD1")
	)
	(segment
		(start 41.9608 -76.953618)
		(end 42.46118 -77.453998)
		(width 0.10668)
		(layer "In7.Cu")
		(net "RMII_TXD1")
	)
	(segment
		(start 35.687 -71.02856)
		(end 38.27526 -73.61682)
		(width 0.10668)
		(layer "In7.Cu")
		(net "RMII_TXD1")
	)
	(segment
		(start 45.66412 -80.869282)
		(end 45.398436 -81.13522)
		(width 0.10668)
		(layer "In7.Cu")
		(net "RMII_TXD1")
	)
	(segment
		(start 38.27526 -73.70445)
		(end 38.5445 -73.97369)
		(width 0.10668)
		(layer "In7.Cu")
		(net "RMII_TXD1")
	)
	(segment
		(start 38.27526 -73.61682)
		(end 38.27526 -73.70445)
		(width 0.10668)
		(layer "In7.Cu")
		(net "RMII_TXD1")
	)
	(segment
		(start 52.5018 -102.919784)
		(end 52.70754 -103.125524)
		(width 0.10668)
		(layer "In7.Cu")
		(net "RMII_TXD1")
	)
	(segment
		(start 36.45662 -48.165766)
		(end 36.45662 -48.546766)
		(width 0.10668)
		(layer "In7.Cu")
		(net "RMII_TXD1")
	)
	(segment
		(start 38.6334 -46.3804)
		(end 37.838634 -46.3804)
		(width 0.10668)
		(layer "In7.Cu")
		(net "RMII_TXD1")
	)
	(segment
		(start 39.746174 -39.606982)
		(end 39.672514 -39.680642)
		(width 0.10668)
		(layer "In7.Cu")
		(net "RMII_TXD1")
	)
	(segment
		(start 51.79568 -88.38438)
		(end 51.8668 -88.4555)
		(width 0.10668)
		(layer "In7.Cu")
		(net "RMII_TXD1")
	)
	(segment
		(start 38.5445 -73.97369)
		(end 38.94709 -73.97369)
		(width 0.10668)
		(layer "In7.Cu")
		(net "RMII_TXD1")
	)
	(segment
		(start 45.833284 -81.570068)
		(end 46.098968 -81.30413)
		(width 0.10668)
		(layer "In7.Cu")
		(net "RMII_TXD1")
	)
	(segment
		(start 36.068 -52.65039)
		(end 36.248086 -52.830476)
		(width 0.10668)
		(layer "In7.Cu")
		(net "RMII_TXD1")
	)
	(segment
		(start 44.27982 -80.298798)
		(end 44.27982 -80.305402)
		(width 0.10668)
		(layer "In7.Cu")
		(net "RMII_TXD1")
	)
	(segment
		(start 36.445444 -47.77359)
		(end 36.445444 -48.15459)
		(width 0.10668)
		(layer "In7.Cu")
		(net "RMII_TXD1")
	)
	(segment
		(start 39.672514 -39.680642)
		(end 39.672514 -41.470326)
		(width 0.10668)
		(layer "In7.Cu")
		(net "RMII_TXD1")
	)
	(segment
		(start 51.8668 -88.4555)
		(end 51.8668 -95.114618)
		(width 0.10668)
		(layer "In7.Cu")
		(net "RMII_TXD1")
	)
	(segment
		(start 45.398436 -81.389728)
		(end 45.578776 -81.570068)
		(width 0.10668)
		(layer "In7.Cu")
		(net "RMII_TXD1")
	)
	(segment
		(start 53.86832 -97.116138)
		(end 53.86832 -98.260662)
		(width 0.10668)
		(layer "In7.Cu")
		(net "RMII_TXD1")
	)
	(segment
		(start 53.86832 -98.260662)
		(end 53.20792 -98.921062)
		(width 0.10668)
		(layer "In7.Cu")
		(net "RMII_TXD1")
	)
	(segment
		(start 51.79568 -88.129872)
		(end 51.79568 -88.38438)
		(width 0.10668)
		(layer "In7.Cu")
		(net "RMII_TXD1")
	)
	(segment
		(start 46.8884 -81.839054)
		(end 46.8884 -82.957416)
		(width 0.10668)
		(layer "In7.Cu")
		(net "RMII_TXD1")
	)
	(segment
		(start 39.48938 -45.52442)
		(end 38.6334 -46.3804)
		(width 0.10668)
		(layer "In7.Cu")
		(net "RMII_TXD1")
	)
	(segment
		(start 36.068 -52.395882)
		(end 36.068 -52.65039)
		(width 0.10668)
		(layer "In7.Cu")
		(net "RMII_TXD1")
	)
	(segment
		(start 39.48938 -41.65346)
		(end 39.48938 -45.52442)
		(width 0.10668)
		(layer "In7.Cu")
		(net "RMII_TXD1")
	)
	(segment
		(start 40.288464 -75.315064)
		(end 41.461944 -75.80249)
		(width 0.10668)
		(layer "In7.Cu")
		(net "RMII_TXD1")
	)
	(segment
		(start 36.248086 -52.215796)
		(end 36.068 -52.395882)
		(width 0.10668)
		(layer "In7.Cu")
		(net "RMII_TXD1")
	)
	(segment
		(start 42.46118 -78.825344)
		(end 43.409616 -79.77378)
		(width 0.10668)
		(layer "In7.Cu")
		(net "RMII_TXD1")
	)
	(segment
		(start 46.353476 -81.30413)
		(end 46.8884 -81.839054)
		(width 0.10668)
		(layer "In7.Cu")
		(net "RMII_TXD1")
	)
	(segment
		(start 34.24428 -64.387222)
		(end 34.75482 -64.897762)
		(width 0.10668)
		(layer "In7.Cu")
		(net "RMII_TXD1")
	)
	(segment
		(start 52.5018 -102.10292)
		(end 52.5018 -102.919784)
		(width 0.10668)
		(layer "In7.Cu")
		(net "RMII_TXD1")
	)
	(segment
		(start 41.9608 -76.301346)
		(end 41.9608 -76.953618)
		(width 0.10668)
		(layer "In7.Cu")
		(net "RMII_TXD1")
	)
	(segment
		(start 37.2618 -49.6824)
		(end 37.05606 -49.88814)
		(width 0.10668)
		(layer "In7.Cu")
		(net "RMII_TXD1")
	)
	(segment
		(start 35.207956 -57.054242)
		(end 35.207956 -60.118752)
		(width 0.10668)
		(layer "In7.Cu")
		(net "RMII_TXD1")
	)
	(segment
		(start 37.0078 -53.010562)
		(end 37.0078 -53.21554)
		(width 0.10668)
		(layer "In7.Cu")
		(net "RMII_TXD1")
	)
	(segment
		(start 53.20792 -98.921062)
		(end 53.20792 -101.3968)
		(width 0.10668)
		(layer "In7.Cu")
		(net "RMII_TXD1")
	)
	(segment
		(start 53.20792 -101.3968)
		(end 52.5018 -102.10292)
		(width 0.10668)
		(layer "In7.Cu")
		(net "RMII_TXD1")
	)
	(segment
		(start 43.754802 -79.77378)
		(end 44.27982 -80.298798)
		(width 0.10668)
		(layer "In7.Cu")
		(net "RMII_TXD1")
	)
	(segment
		(start 35.687 -69.528944)
		(end 35.687 -71.02856)
		(width 0.10668)
		(layer "In7.Cu")
		(net "RMII_TXD1")
	)
	(segment
		(start 44.27982 -80.305402)
		(end 44.467018 -80.4926)
		(width 0.10668)
		(layer "In7.Cu")
		(net "RMII_TXD1")
	)
	(segment
		(start 36.45662 -48.546766)
		(end 37.2618 -49.351946)
		(width 0.10668)
		(layer "In7.Cu")
		(net "RMII_TXD1")
	)
	(segment
		(start 45.578776 -81.570068)
		(end 45.833284 -81.570068)
		(width 0.10668)
		(layer "In7.Cu")
		(net "RMII_TXD1")
	)
	(segment
		(start 45.66412 -80.614774)
		(end 45.66412 -80.869282)
		(width 0.10668)
		(layer "In7.Cu")
		(net "RMII_TXD1")
	)
	(segment
		(start 49.243996 -84.43722)
		(end 50.988468 -86.181692)
		(width 0.10668)
		(layer "In7.Cu")
		(net "RMII_TXD1")
	)
	(segment
		(start 35.5473 -56.714898)
		(end 35.207956 -57.054242)
		(width 0.10668)
		(layer "In7.Cu")
		(net "RMII_TXD1")
	)
	(segment
		(start 36.827714 -52.215796)
		(end 36.248086 -52.215796)
		(width 0.10668)
		(layer "In7.Cu")
		(net "RMII_TXD1")
	)
	(segment
		(start 36.827714 -52.830476)
		(end 37.0078 -53.010562)
		(width 0.10668)
		(layer "In7.Cu")
		(net "RMII_TXD1")
	)
	(segment
		(start 35.207956 -60.118752)
		(end 34.24428 -61.082428)
		(width 0.10668)
		(layer "In7.Cu")
		(net "RMII_TXD1")
	)
	(segment
		(start 34.24428 -61.082428)
		(end 34.24428 -64.387222)
		(width 0.10668)
		(layer "In7.Cu")
		(net "RMII_TXD1")
	)
	(segment
		(start 36.445444 -48.15459)
		(end 36.45662 -48.165766)
		(width 0.10668)
		(layer "In7.Cu")
		(net "RMII_TXD1")
	)
	(segment
		(start 37.05606 -49.88814)
		(end 37.05606 -51.98745)
		(width 0.10668)
		(layer "In7.Cu")
		(net "RMII_TXD1")
	)
	(segment
		(start 38.94709 -73.97369)
		(end 40.288464 -75.315064)
		(width 0.10668)
		(layer "In7.Cu")
		(net "RMII_TXD1")
	)
	(segment
		(start 52.70754 -103.798878)
		(end 52.714906 -103.806244)
		(width 0.10668)
		(layer "In7.Cu")
		(net "RMII_TXD1")
	)
	(segment
		(start 34.73196 -65.593976)
		(end 34.73196 -68.479924)
		(width 0.10668)
		(layer "In7.Cu")
		(net "RMII_TXD1")
	)
	(segment
		(start 43.409616 -79.77378)
		(end 43.754802 -79.77378)
		(width 0.10668)
		(layer "In7.Cu")
		(net "RMII_TXD1")
	)
	(segment
		(start 37.0078 -53.21554)
		(end 35.5473 -54.67604)
		(width 0.10668)
		(layer "In7.Cu")
		(net "RMII_TXD1")
	)
	(segment
		(start 35.497516 -69.24548)
		(end 35.687 -69.528944)
		(width 0.10668)
		(layer "In7.Cu")
		(net "RMII_TXD1")
	)
	(segment
		(start 45.398436 -81.13522)
		(end 45.398436 -81.389728)
		(width 0.10668)
		(layer "In7.Cu")
		(net "RMII_TXD1")
	)
	(segment
		(start 46.098968 -81.30413)
		(end 46.353476 -81.30413)
		(width 0.10668)
		(layer "In7.Cu")
		(net "RMII_TXD1")
	)
	(segment
		(start 39.672514 -41.470326)
		(end 39.48938 -41.65346)
		(width 0.10668)
		(layer "In7.Cu")
		(net "RMII_TXD1")
	)
	(segment
		(start 34.73196 -68.479924)
		(end 35.497516 -69.24548)
		(width 0.10668)
		(layer "In7.Cu")
		(net "RMII_TXD1")
	)
	(segment
		(start 36.248086 -52.830476)
		(end 36.827714 -52.830476)
		(width 0.10668)
		(layer "In7.Cu")
		(net "RMII_TXD1")
	)
	(segment
		(start 41.461944 -75.80249)
		(end 41.9608 -76.301346)
		(width 0.10668)
		(layer "In7.Cu")
		(net "RMII_TXD1")
	)
	(segment
		(start 37.2618 -49.351946)
		(end 37.2618 -49.6824)
		(width 0.10668)
		(layer "In7.Cu")
		(net "RMII_TXD1")
	)
	(segment
		(start 44.467018 -80.4926)
		(end 45.541946 -80.4926)
		(width 0.10668)
		(layer "In7.Cu")
		(net "RMII_TXD1")
	)
	(segment
		(start 45.541946 -80.4926)
		(end 45.66412 -80.614774)
		(width 0.10668)
		(layer "In7.Cu")
		(net "RMII_TXD1")
	)
	(segment
		(start 42.46118 -77.453998)
		(end 42.46118 -78.825344)
		(width 0.10668)
		(layer "In7.Cu")
		(net "RMII_TXD1")
	)
	(segment
		(start 48.368204 -84.43722)
		(end 49.243996 -84.43722)
		(width 0.10668)
		(layer "In7.Cu")
		(net "RMII_TXD1")
	)
	(segment
		(start 46.494954 -42.571162)
		(end 46.09973 -42.175938)
		(width 0.11684)
		(layer "F.Cu")
		(net "RMII_TXD0_R")
	)
	(via
		(at 43.562778 -41.374568)
		(size 0.6604)
		(drill 0.3302)
		(layers "F.Cu" "B.Cu")
		(net "RMII_TXD0_R")
	)
	(via
		(at 46.09973 -42.175938)
		(size 0.4572)
		(drill 0.254)
		(layers "F.Cu" "B.Cu")
		(net "RMII_TXD0_R")
	)
	(segment
		(start 43.562778 -41.374568)
		(end 44.364148 -42.175938)
		(width 0.11684)
		(layer "B.Cu")
		(net "RMII_TXD0_R")
	)
	(segment
		(start 42.48785 -41.021)
		(end 43.20159 -41.021)
		(width 0.11684)
		(layer "B.Cu")
		(net "RMII_TXD0_R")
	)
	(segment
		(start 43.20159 -41.021)
		(end 43.555158 -41.374568)
		(width 0.11684)
		(layer "B.Cu")
		(net "RMII_TXD0_R")
	)
	(segment
		(start 42.39895 -40.9321)
		(end 42.48785 -41.021)
		(width 0.11684)
		(layer "B.Cu")
		(net "RMII_TXD0_R")
	)
	(segment
		(start 44.364148 -42.175938)
		(end 46.09973 -42.175938)
		(width 0.11684)
		(layer "B.Cu")
		(net "RMII_TXD0_R")
	)
	(segment
		(start 43.555158 -41.374568)
		(end 43.562778 -41.374568)
		(width 0.11684)
		(layer "B.Cu")
		(net "RMII_TXD0_R")
	)
	(segment
		(start 51.26482 -117.249702)
		(end 51.3588 -117.343682)
		(width 0.11684)
		(layer "F.Cu")
		(net "RMII_TXD0")
	)
	(segment
		(start 51.3588 -117.343682)
		(end 51.3588 -118.153688)
		(width 0.11684)
		(layer "F.Cu")
		(net "RMII_TXD0")
	)
	(segment
		(start 51.26482 -115.45062)
		(end 51.26482 -117.249702)
		(width 0.11684)
		(layer "F.Cu")
		(net "RMII_TXD0")
	)
	(segment
		(start 50.546 -114.298222)
		(end 50.852578 -115.038378)
		(width 0.11684)
		(layer "F.Cu")
		(net "RMII_TXD0")
	)
	(segment
		(start 51.3588 -118.153688)
		(end 51.464972 -118.25986)
		(width 0.11684)
		(layer "F.Cu")
		(net "RMII_TXD0")
	)
	(segment
		(start 50.852578 -115.038378)
		(end 51.26482 -115.45062)
		(width 0.11684)
		(layer "F.Cu")
		(net "RMII_TXD0")
	)
	(segment
		(start 50.546 -112.903)
		(end 50.546 -114.298222)
		(width 0.11684)
		(layer "F.Cu")
		(net "RMII_TXD0")
	)
	(via
		(at 40.469312 -40.855138)
		(size 0.508)
		(drill 0.254)
		(layers "F.Cu" "B.Cu")
		(net "RMII_TXD0")
	)
	(via
		(at 50.546 -112.903)
		(size 0.508)
		(drill 0.254)
		(layers "F.Cu" "B.Cu")
		(net "RMII_TXD0")
	)
	(via
		(at 60.1726 -111.90351)
		(size 0.508)
		(drill 0.254)
		(layers "F.Cu" "B.Cu")
		(net "RMII_TXD0")
	)
	(segment
		(start 41.521888 -40.855138)
		(end 40.469312 -40.855138)
		(width 0.11684)
		(layer "B.Cu")
		(net "RMII_TXD0")
	)
	(segment
		(start 41.59885 -40.9321)
		(end 41.521888 -40.855138)
		(width 0.11684)
		(layer "B.Cu")
		(net "RMII_TXD0")
	)
	(segment
		(start 53.018436 -113.064036)
		(end 53.724302 -113.35639)
		(width 0.08382)
		(layer "In2.Cu")
		(net "RMII_TXD0")
	)
	(segment
		(start 50.76571 -112.68329)
		(end 52.394104 -112.68329)
		(width 0.08382)
		(layer "In2.Cu")
		(net "RMII_TXD0")
	)
	(segment
		(start 50.546 -112.903)
		(end 50.76571 -112.68329)
		(width 0.08382)
		(layer "In2.Cu")
		(net "RMII_TXD0")
	)
	(segment
		(start 55.579518 -113.35639)
		(end 55.988712 -112.947196)
		(width 0.08382)
		(layer "In2.Cu")
		(net "RMII_TXD0")
	)
	(segment
		(start 60.0456 -112.14989)
		(end 60.1726 -112.02289)
		(width 0.08382)
		(layer "In2.Cu")
		(net "RMII_TXD0")
	)
	(segment
		(start 53.724302 -113.35639)
		(end 55.579518 -113.35639)
		(width 0.08382)
		(layer "In2.Cu")
		(net "RMII_TXD0")
	)
	(segment
		(start 55.988712 -112.947196)
		(end 57.913778 -112.14989)
		(width 0.08382)
		(layer "In2.Cu")
		(net "RMII_TXD0")
	)
	(segment
		(start 52.809902 -112.855502)
		(end 53.018436 -113.064036)
		(width 0.08382)
		(layer "In2.Cu")
		(net "RMII_TXD0")
	)
	(segment
		(start 52.394104 -112.68329)
		(end 52.809902 -112.855502)
		(width 0.08382)
		(layer "In2.Cu")
		(net "RMII_TXD0")
	)
	(segment
		(start 57.913778 -112.14989)
		(end 60.0456 -112.14989)
		(width 0.08382)
		(layer "In2.Cu")
		(net "RMII_TXD0")
	)
	(segment
		(start 60.1726 -112.02289)
		(end 60.1726 -111.90351)
		(width 0.08382)
		(layer "In2.Cu")
		(net "RMII_TXD0")
	)
	(segment
		(start 36.189158 -68.988686)
		(end 36.35756 -69.39534)
		(width 0.10668)
		(layer "In7.Cu")
		(net "RMII_TXD0")
	)
	(segment
		(start 41.950132 -74.873866)
		(end 42.95267 -74.873866)
		(width 0.10668)
		(layer "In7.Cu")
		(net "RMII_TXD0")
	)
	(segment
		(start 46.04004 -79.716122)
		(end 49.50714 -83.183222)
		(width 0.10668)
		(layer "In7.Cu")
		(net "RMII_TXD0")
	)
	(segment
		(start 40.71366 -73.8759)
		(end 40.71366 -74.2569)
		(width 0.10668)
		(layer "In7.Cu")
		(net "RMII_TXD0")
	)
	(segment
		(start 40.520112 -41.623488)
		(end 40.15994 -41.98366)
		(width 0.10668)
		(layer "In7.Cu")
		(net "RMII_TXD0")
	)
	(segment
		(start 40.469312 -40.855138)
		(end 40.520112 -40.905938)
		(width 0.10668)
		(layer "In7.Cu")
		(net "RMII_TXD0")
	)
	(segment
		(start 35.51174 -61.550042)
		(end 35.51174 -64.82588)
		(width 0.10668)
		(layer "In7.Cu")
		(net "RMII_TXD0")
	)
	(segment
		(start 38.4048 -51.2064)
		(end 38.25494 -51.35626)
		(width 0.10668)
		(layer "In7.Cu")
		(net "RMII_TXD0")
	)
	(segment
		(start 35.42538 -68.224908)
		(end 36.189158 -68.988686)
		(width 0.10668)
		(layer "In7.Cu")
		(net "RMII_TXD0")
	)
	(segment
		(start 63.2968 -106.828082)
		(end 63.2968 -109.852714)
		(width 0.10668)
		(layer "In7.Cu")
		(net "RMII_TXD0")
	)
	(segment
		(start 39.2176 -49.205896)
		(end 39.2176 -50.927254)
		(width 0.10668)
		(layer "In7.Cu")
		(net "RMII_TXD0")
	)
	(segment
		(start 63.2968 -109.852714)
		(end 60.382658 -111.799878)
		(width 0.10668)
		(layer "In7.Cu")
		(net "RMII_TXD0")
	)
	(segment
		(start 53.3908 -88.190832)
		(end 53.3908 -94.9706)
		(width 0.10668)
		(layer "In7.Cu")
		(net "RMII_TXD0")
	)
	(segment
		(start 40.15994 -45.802296)
		(end 39.3446 -46.617636)
		(width 0.10668)
		(layer "In7.Cu")
		(net "RMII_TXD0")
	)
	(segment
		(start 53.322982 -88.02751)
		(end 53.3908 -88.190832)
		(width 0.10668)
		(layer "In7.Cu")
		(net "RMII_TXD0")
	)
	(segment
		(start 37.88918 -71.820532)
		(end 37.88918 -72.10298)
		(width 0.10668)
		(layer "In7.Cu")
		(net "RMII_TXD0")
	)
	(segment
		(start 53.8734 -95.4532)
		(end 54.3814 -95.4532)
		(width 0.10668)
		(layer "In7.Cu")
		(net "RMII_TXD0")
	)
	(segment
		(start 40.71366 -74.2569)
		(end 40.9829 -74.52614)
		(width 0.10668)
		(layer "In7.Cu")
		(net "RMII_TXD0")
	)
	(segment
		(start 57.3278 -98.3996)
		(end 57.3278 -98.945446)
		(width 0.10668)
		(layer "In7.Cu")
		(net "RMII_TXD0")
	)
	(segment
		(start 49.50714 -83.751928)
		(end 51.55692 -85.801708)
		(width 0.10668)
		(layer "In7.Cu")
		(net "RMII_TXD0")
	)
	(segment
		(start 60.382658 -111.799878)
		(end 60.1726 -111.887)
		(width 0.10668)
		(layer "In7.Cu")
		(net "RMII_TXD0")
	)
	(segment
		(start 41.602406 -74.52614)
		(end 41.950132 -74.873866)
		(width 0.10668)
		(layer "In7.Cu")
		(net "RMII_TXD0")
	)
	(segment
		(start 39.3446 -46.617636)
		(end 39.3446 -49.078896)
		(width 0.10668)
		(layer "In7.Cu")
		(net "RMII_TXD0")
	)
	(segment
		(start 36.35756 -69.39534)
		(end 36.35756 -70.288912)
		(width 0.10668)
		(layer "In7.Cu")
		(net "RMII_TXD0")
	)
	(segment
		(start 51.883056 -86.587838)
		(end 53.322982 -88.02751)
		(width 0.10668)
		(layer "In7.Cu")
		(net "RMII_TXD0")
	)
	(segment
		(start 38.25494 -51.35626)
		(end 37.78758 -52.483512)
		(width 0.10668)
		(layer "In7.Cu")
		(net "RMII_TXD0")
	)
	(segment
		(start 49.50714 -83.183222)
		(end 49.50714 -83.751928)
		(width 0.10668)
		(layer "In7.Cu")
		(net "RMII_TXD0")
	)
	(segment
		(start 38.255956 -54.950614)
		(end 38.255956 -58.162444)
		(width 0.10668)
		(layer "In7.Cu")
		(net "RMII_TXD0")
	)
	(segment
		(start 39.056818 -72.71004)
		(end 39.854124 -73.507346)
		(width 0.10668)
		(layer "In7.Cu")
		(net "RMII_TXD0")
	)
	(segment
		(start 37.78758 -54.482238)
		(end 38.255956 -54.950614)
		(width 0.10668)
		(layer "In7.Cu")
		(net "RMII_TXD0")
	)
	(segment
		(start 35.42538 -64.91224)
		(end 35.42538 -68.224908)
		(width 0.10668)
		(layer "In7.Cu")
		(net "RMII_TXD0")
	)
	(segment
		(start 36.49726 -59.92114)
		(end 36.49726 -60.564522)
		(width 0.10668)
		(layer "In7.Cu")
		(net "RMII_TXD0")
	)
	(segment
		(start 40.9829 -74.52614)
		(end 41.602406 -74.52614)
		(width 0.10668)
		(layer "In7.Cu")
		(net "RMII_TXD0")
	)
	(segment
		(start 38.255956 -58.162444)
		(end 36.49726 -59.92114)
		(width 0.10668)
		(layer "In7.Cu")
		(net "RMII_TXD0")
	)
	(segment
		(start 35.51174 -64.82588)
		(end 35.42538 -64.91224)
		(width 0.10668)
		(layer "In7.Cu")
		(net "RMII_TXD0")
	)
	(segment
		(start 36.35756 -70.288912)
		(end 37.88918 -71.820532)
		(width 0.10668)
		(layer "In7.Cu")
		(net "RMII_TXD0")
	)
	(segment
		(start 54.3814 -95.4532)
		(end 57.3278 -98.3996)
		(width 0.10668)
		(layer "In7.Cu")
		(net "RMII_TXD0")
	)
	(segment
		(start 40.345106 -73.507346)
		(end 40.71366 -73.8759)
		(width 0.10668)
		(layer "In7.Cu")
		(net "RMII_TXD0")
	)
	(segment
		(start 60.4774 -104.4194)
		(end 61.231272 -104.4194)
		(width 0.10668)
		(layer "In7.Cu")
		(net "RMII_TXD0")
	)
	(segment
		(start 40.520112 -40.905938)
		(end 40.520112 -41.623488)
		(width 0.10668)
		(layer "In7.Cu")
		(net "RMII_TXD0")
	)
	(segment
		(start 37.78758 -52.483512)
		(end 37.78758 -54.482238)
		(width 0.10668)
		(layer "In7.Cu")
		(net "RMII_TXD0")
	)
	(segment
		(start 51.55692 -85.801708)
		(end 51.883056 -86.587838)
		(width 0.10668)
		(layer "In7.Cu")
		(net "RMII_TXD0")
	)
	(segment
		(start 36.49726 -60.564522)
		(end 35.51174 -61.550042)
		(width 0.10668)
		(layer "In7.Cu")
		(net "RMII_TXD0")
	)
	(segment
		(start 38.938454 -51.2064)
		(end 38.4048 -51.2064)
		(width 0.10668)
		(layer "In7.Cu")
		(net "RMII_TXD0")
	)
	(segment
		(start 58.971434 -102.913434)
		(end 60.4774 -104.4194)
		(width 0.10668)
		(layer "In7.Cu")
		(net "RMII_TXD0")
	)
	(segment
		(start 46.04004 -77.961236)
		(end 46.04004 -79.716122)
		(width 0.10668)
		(layer "In7.Cu")
		(net "RMII_TXD0")
	)
	(segment
		(start 39.2176 -50.927254)
		(end 38.938454 -51.2064)
		(width 0.10668)
		(layer "In7.Cu")
		(net "RMII_TXD0")
	)
	(segment
		(start 61.231272 -104.4194)
		(end 63.05423 -106.242358)
		(width 0.10668)
		(layer "In7.Cu")
		(net "RMII_TXD0")
	)
	(segment
		(start 53.3908 -94.9706)
		(end 53.8734 -95.4532)
		(width 0.10668)
		(layer "In7.Cu")
		(net "RMII_TXD0")
	)
	(segment
		(start 39.854124 -73.507346)
		(end 40.345106 -73.507346)
		(width 0.10668)
		(layer "In7.Cu")
		(net "RMII_TXD0")
	)
	(segment
		(start 40.15994 -41.98366)
		(end 40.15994 -45.802296)
		(width 0.10668)
		(layer "In7.Cu")
		(net "RMII_TXD0")
	)
	(segment
		(start 60.1726 -111.887)
		(end 60.1726 -111.90351)
		(width 0.10668)
		(layer "In7.Cu")
		(net "RMII_TXD0")
	)
	(segment
		(start 38.49624 -72.71004)
		(end 39.056818 -72.71004)
		(width 0.10668)
		(layer "In7.Cu")
		(net "RMII_TXD0")
	)
	(segment
		(start 63.05423 -106.242358)
		(end 63.2968 -106.828082)
		(width 0.10668)
		(layer "In7.Cu")
		(net "RMII_TXD0")
	)
	(segment
		(start 39.3446 -49.078896)
		(end 39.2176 -49.205896)
		(width 0.10668)
		(layer "In7.Cu")
		(net "RMII_TXD0")
	)
	(segment
		(start 37.88918 -72.10298)
		(end 38.49624 -72.71004)
		(width 0.10668)
		(layer "In7.Cu")
		(net "RMII_TXD0")
	)
	(segment
		(start 42.95267 -74.873866)
		(end 46.04004 -77.961236)
		(width 0.10668)
		(layer "In7.Cu")
		(net "RMII_TXD0")
	)
	(segment
		(start 57.3278 -98.945446)
		(end 58.971434 -102.913434)
		(width 0.10668)
		(layer "In7.Cu")
		(net "RMII_TXD0")
	)
	(segment
		(start 48.852836 -112.55756)
		(end 49.3776 -113.824258)
		(width 0.11684)
		(layer "F.Cu")
		(net "RMII_RXER")
	)
	(segment
		(start 49.3776 -115.094512)
		(end 49.71288 -115.429792)
		(width 0.11684)
		(layer "F.Cu")
		(net "RMII_RXER")
	)
	(segment
		(start 50.1142 -116.473224)
		(end 50.1142 -116.974112)
		(width 0.11684)
		(layer "F.Cu")
		(net "RMII_RXER")
	)
	(segment
		(start 46.494954 -40.17137)
		(end 46.09973 -39.776146)
		(width 0.11684)
		(layer "F.Cu")
		(net "RMII_RXER")
	)
	(segment
		(start 50.2158 -118.210584)
		(end 50.265076 -118.25986)
		(width 0.11684)
		(layer "F.Cu")
		(net "RMII_RXER")
	)
	(segment
		(start 49.3776 -113.824258)
		(end 49.3776 -115.094512)
		(width 0.11684)
		(layer "F.Cu")
		(net "RMII_RXER")
	)
	(segment
		(start 50.2158 -117.075712)
		(end 50.2158 -118.210584)
		(width 0.11684)
		(layer "F.Cu")
		(net "RMII_RXER")
	)
	(segment
		(start 48.852836 -109.811058)
		(end 48.852836 -112.55756)
		(width 0.11684)
		(layer "F.Cu")
		(net "RMII_RXER")
	)
	(segment
		(start 49.71288 -115.429792)
		(end 49.71288 -116.071904)
		(width 0.11684)
		(layer "F.Cu")
		(net "RMII_RXER")
	)
	(segment
		(start 49.71288 -116.071904)
		(end 50.1142 -116.473224)
		(width 0.11684)
		(layer "F.Cu")
		(net "RMII_RXER")
	)
	(segment
		(start 50.1142 -116.974112)
		(end 50.2158 -117.075712)
		(width 0.11684)
		(layer "F.Cu")
		(net "RMII_RXER")
	)
	(segment
		(start 48.852836 -109.811058)
		(end 49.6062 -109.811058)
		(width 0.11684)
		(layer "F.Cu")
		(net "RMII_RXER")
	)
	(via
		(at 58.3946 -110.8964)
		(size 0.508)
		(drill 0.254)
		(layers "F.Cu" "B.Cu")
		(net "RMII_RXER")
	)
	(via
		(at 46.09973 -39.776146)
		(size 0.4572)
		(drill 0.254)
		(layers "F.Cu" "B.Cu")
		(net "RMII_RXER")
	)
	(via
		(at 49.6062 -109.811058)
		(size 0.508)
		(drill 0.254)
		(layers "F.Cu" "B.Cu")
		(net "RMII_RXER")
	)
	(segment
		(start 58.2295 -110.7313)
		(end 58.3946 -110.8964)
		(width 0.08382)
		(layer "In2.Cu")
		(net "RMII_RXER")
	)
	(segment
		(start 50.18151 -110.88751)
		(end 51.598322 -110.88751)
		(width 0.08382)
		(layer "In2.Cu")
		(net "RMII_RXER")
	)
	(segment
		(start 57.2262 -109.4486)
		(end 58.2295 -110.4519)
		(width 0.08382)
		(layer "In2.Cu")
		(net "RMII_RXER")
	)
	(segment
		(start 51.811682 -110.799118)
		(end 53.1622 -109.4486)
		(width 0.08382)
		(layer "In2.Cu")
		(net "RMII_RXER")
	)
	(segment
		(start 53.1622 -109.4486)
		(end 57.2262 -109.4486)
		(width 0.08382)
		(layer "In2.Cu")
		(net "RMII_RXER")
	)
	(segment
		(start 58.2295 -110.4519)
		(end 58.2295 -110.7313)
		(width 0.08382)
		(layer "In2.Cu")
		(net "RMII_RXER")
	)
	(segment
		(start 49.960784 -110.666784)
		(end 50.18151 -110.88751)
		(width 0.08382)
		(layer "In2.Cu")
		(net "RMII_RXER")
	)
	(segment
		(start 49.6062 -109.811058)
		(end 49.960784 -110.666784)
		(width 0.08382)
		(layer "In2.Cu")
		(net "RMII_RXER")
	)
	(segment
		(start 51.598322 -110.88751)
		(end 51.811682 -110.799118)
		(width 0.08382)
		(layer "In2.Cu")
		(net "RMII_RXER")
	)
	(segment
		(start 41.961816 -40.715184)
		(end 41.961816 -39.899844)
		(width 0.10668)
		(layer "In7.Cu")
		(net "RMII_RXER")
	)
	(segment
		(start 39.67988 -46.756574)
		(end 40.49522 -45.941234)
		(width 0.10668)
		(layer "In7.Cu")
		(net "RMII_RXER")
	)
	(segment
		(start 36.83254 -60.060078)
		(end 38.591236 -58.301382)
		(width 0.10668)
		(layer "In7.Cu")
		(net "RMII_RXER")
	)
	(segment
		(start 38.591236 -58.301382)
		(end 38.591236 -54.811676)
		(width 0.10668)
		(layer "In7.Cu")
		(net "RMII_RXER")
	)
	(segment
		(start 37.87648 -71.26224)
		(end 36.852098 -70.237858)
		(width 0.10668)
		(layer "In7.Cu")
		(net "RMII_RXER")
	)
	(segment
		(start 36.83254 -60.70346)
		(end 36.83254 -60.060078)
		(width 0.10668)
		(layer "In7.Cu")
		(net "RMII_RXER")
	)
	(segment
		(start 39.993062 -73.172066)
		(end 39.52748 -72.706484)
		(width 0.10668)
		(layer "In7.Cu")
		(net "RMII_RXER")
	)
	(segment
		(start 58.008266 -98.048572)
		(end 54.17312 -94.213426)
		(width 0.10668)
		(layer "In7.Cu")
		(net "RMII_RXER")
	)
	(segment
		(start 36.852098 -70.237858)
		(end 36.852098 -69.71284)
		(width 0.10668)
		(layer "In7.Cu")
		(net "RMII_RXER")
	)
	(segment
		(start 39.140892 -52.702968)
		(end 39.140892 -51.762914)
		(width 0.10668)
		(layer "In7.Cu")
		(net "RMII_RXER")
	)
	(segment
		(start 46.37532 -79.577184)
		(end 46.37532 -77.78623)
		(width 0.10668)
		(layer "In7.Cu")
		(net "RMII_RXER")
	)
	(segment
		(start 43.127676 -74.538586)
		(end 42.295826 -74.538586)
		(width 0.10668)
		(layer "In7.Cu")
		(net "RMII_RXER")
	)
	(segment
		(start 46.37532 -77.78623)
		(end 43.127676 -74.538586)
		(width 0.10668)
		(layer "In7.Cu")
		(net "RMII_RXER")
	)
	(segment
		(start 63.396368 -106.110278)
		(end 61.92774 -104.64165)
		(width 0.10668)
		(layer "In7.Cu")
		(net "RMII_RXER")
	)
	(segment
		(start 36.473384 -68.798694)
		(end 35.7632 -68.08851)
		(width 0.10668)
		(layer "In7.Cu")
		(net "RMII_RXER")
	)
	(segment
		(start 45.71619 -39.392606)
		(end 46.09973 -39.776146)
		(width 0.10668)
		(layer "In7.Cu")
		(net "RMII_RXER")
	)
	(segment
		(start 54.17312 -89.172796)
		(end 53.617368 -87.830152)
		(width 0.10668)
		(layer "In7.Cu")
		(net "RMII_RXER")
	)
	(segment
		(start 40.49522 -42.18178)
		(end 41.961816 -40.715184)
		(width 0.10668)
		(layer "In7.Cu")
		(net "RMII_RXER")
	)
	(segment
		(start 35.7632 -68.08851)
		(end 35.7632 -66.26606)
		(width 0.10668)
		(layer "In7.Cu")
		(net "RMII_RXER")
	)
	(segment
		(start 35.7632 -66.26606)
		(end 36.3474 -65.68186)
		(width 0.10668)
		(layer "In7.Cu")
		(net "RMII_RXER")
	)
	(segment
		(start 60.424822 -112.36325)
		(end 63.127128 -110.558072)
		(width 0.10668)
		(layer "In7.Cu")
		(net "RMII_RXER")
	)
	(segment
		(start 63.127128 -110.558072)
		(end 63.6524 -110.0328)
		(width 0.10668)
		(layer "In7.Cu")
		(net "RMII_RXER")
	)
	(segment
		(start 36.3474 -64.2366)
		(end 35.84702 -63.73622)
		(width 0.10668)
		(layer "In7.Cu")
		(net "RMII_RXER")
	)
	(segment
		(start 42.469054 -39.392606)
		(end 45.71619 -39.392606)
		(width 0.10668)
		(layer "In7.Cu")
		(net "RMII_RXER")
	)
	(segment
		(start 42.295826 -74.538586)
		(end 40.929306 -73.172066)
		(width 0.10668)
		(layer "In7.Cu")
		(net "RMII_RXER")
	)
	(segment
		(start 35.84702 -61.68898)
		(end 36.83254 -60.70346)
		(width 0.10668)
		(layer "In7.Cu")
		(net "RMII_RXER")
	)
	(segment
		(start 40.929306 -73.172066)
		(end 39.993062 -73.172066)
		(width 0.10668)
		(layer "In7.Cu")
		(net "RMII_RXER")
	)
	(segment
		(start 58.738262 -111.12246)
		(end 59.979052 -112.36325)
		(width 0.10668)
		(layer "In7.Cu")
		(net "RMII_RXER")
	)
	(segment
		(start 63.6524 -106.728514)
		(end 63.396368 -106.110278)
		(width 0.10668)
		(layer "In7.Cu")
		(net "RMII_RXER")
	)
	(segment
		(start 59.979052 -112.36325)
		(end 60.424822 -112.36325)
		(width 0.10668)
		(layer "In7.Cu")
		(net "RMII_RXER")
	)
	(segment
		(start 38.12286 -53.721)
		(end 39.140892 -52.702968)
		(width 0.10668)
		(layer "In7.Cu")
		(net "RMII_RXER")
	)
	(segment
		(start 41.961816 -39.899844)
		(end 42.469054 -39.392606)
		(width 0.10668)
		(layer "In7.Cu")
		(net "RMII_RXER")
	)
	(segment
		(start 52.15509 -86.367874)
		(end 51.841146 -85.611716)
		(width 0.10668)
		(layer "In7.Cu")
		(net "RMII_RXER")
	)
	(segment
		(start 39.140892 -51.762914)
		(end 39.342568 -51.276504)
		(width 0.10668)
		(layer "In7.Cu")
		(net "RMII_RXER")
	)
	(segment
		(start 39.67988 -49.217834)
		(end 39.67988 -46.756574)
		(width 0.10668)
		(layer "In7.Cu")
		(net "RMII_RXER")
	)
	(segment
		(start 58.915554 -100.23856)
		(end 58.008266 -98.048572)
		(width 0.10668)
		(layer "In7.Cu")
		(net "RMII_RXER")
	)
	(segment
		(start 38.12286 -54.3433)
		(end 38.12286 -53.721)
		(width 0.10668)
		(layer "In7.Cu")
		(net "RMII_RXER")
	)
	(segment
		(start 54.17312 -94.213426)
		(end 54.17312 -89.172796)
		(width 0.10668)
		(layer "In7.Cu")
		(net "RMII_RXER")
	)
	(segment
		(start 53.617368 -87.830152)
		(end 52.15509 -86.367874)
		(width 0.10668)
		(layer "In7.Cu")
		(net "RMII_RXER")
	)
	(segment
		(start 58.62066 -111.12246)
		(end 58.738262 -111.12246)
		(width 0.10668)
		(layer "In7.Cu")
		(net "RMII_RXER")
	)
	(segment
		(start 36.852098 -69.71284)
		(end 36.473384 -68.798694)
		(width 0.10668)
		(layer "In7.Cu")
		(net "RMII_RXER")
	)
	(segment
		(start 58.3946 -110.8964)
		(end 58.62066 -111.12246)
		(width 0.10668)
		(layer "In7.Cu")
		(net "RMII_RXER")
	)
	(segment
		(start 39.52748 -72.706484)
		(end 39.52748 -71.998586)
		(width 0.10668)
		(layer "In7.Cu")
		(net "RMII_RXER")
	)
	(segment
		(start 38.791134 -71.26224)
		(end 37.87648 -71.26224)
		(width 0.10668)
		(layer "In7.Cu")
		(net "RMII_RXER")
	)
	(segment
		(start 35.84702 -63.73622)
		(end 35.84702 -61.68898)
		(width 0.10668)
		(layer "In7.Cu")
		(net "RMII_RXER")
	)
	(segment
		(start 61.92774 -104.64165)
		(end 61.92774 -103.250746)
		(width 0.10668)
		(layer "In7.Cu")
		(net "RMII_RXER")
	)
	(segment
		(start 51.841146 -85.611716)
		(end 49.88814 -83.65871)
		(width 0.10668)
		(layer "In7.Cu")
		(net "RMII_RXER")
	)
	(segment
		(start 63.6524 -110.0328)
		(end 63.6524 -106.728514)
		(width 0.10668)
		(layer "In7.Cu")
		(net "RMII_RXER")
	)
	(segment
		(start 49.88814 -83.090004)
		(end 46.37532 -79.577184)
		(width 0.10668)
		(layer "In7.Cu")
		(net "RMII_RXER")
	)
	(segment
		(start 36.3474 -65.68186)
		(end 36.3474 -64.2366)
		(width 0.10668)
		(layer "In7.Cu")
		(net "RMII_RXER")
	)
	(segment
		(start 39.55288 -49.344834)
		(end 39.67988 -49.217834)
		(width 0.10668)
		(layer "In7.Cu")
		(net "RMII_RXER")
	)
	(segment
		(start 39.52748 -71.998586)
		(end 38.791134 -71.26224)
		(width 0.10668)
		(layer "In7.Cu")
		(net "RMII_RXER")
	)
	(segment
		(start 61.92774 -103.250746)
		(end 58.915554 -100.23856)
		(width 0.10668)
		(layer "In7.Cu")
		(net "RMII_RXER")
	)
	(segment
		(start 49.88814 -83.65871)
		(end 49.88814 -83.090004)
		(width 0.10668)
		(layer "In7.Cu")
		(net "RMII_RXER")
	)
	(segment
		(start 39.342568 -51.276504)
		(end 39.55288 -51.066192)
		(width 0.10668)
		(layer "In7.Cu")
		(net "RMII_RXER")
	)
	(segment
		(start 40.49522 -45.941234)
		(end 40.49522 -42.18178)
		(width 0.10668)
		(layer "In7.Cu")
		(net "RMII_RXER")
	)
	(segment
		(start 38.591236 -54.811676)
		(end 38.12286 -54.3433)
		(width 0.10668)
		(layer "In7.Cu")
		(net "RMII_RXER")
	)
	(segment
		(start 39.55288 -51.066192)
		(end 39.55288 -49.344834)
		(width 0.10668)
		(layer "In7.Cu")
		(net "RMII_RXER")
	)
	(segment
		(start 44.895008 -40.17137)
		(end 44.499784 -39.776146)
		(width 0.11684)
		(layer "F.Cu")
		(net "RMII_RXD1")
	)
	(segment
		(start 48.71212 -116.47932)
		(end 49.0982 -116.8654)
		(width 0.11684)
		(layer "F.Cu")
		(net "RMII_RXD1")
	)
	(segment
		(start 49.0982 -118.426738)
		(end 49.064926 -118.460012)
		(width 0.11684)
		(layer "F.Cu")
		(net "RMII_RXD1")
	)
	(segment
		(start 48.71212 -116.0018)
		(end 48.71212 -116.47932)
		(width 0.11684)
		(layer "F.Cu")
		(net "RMII_RXD1")
	)
	(segment
		(start 49.0982 -116.8654)
		(end 49.0982 -118.426738)
		(width 0.11684)
		(layer "F.Cu")
		(net "RMII_RXD1")
	)
	(via
		(at 44.499784 -39.776146)
		(size 0.4572)
		(drill 0.254)
		(layers "F.Cu" "B.Cu")
		(net "RMII_RXD1")
	)
	(via
		(at 48.71212 -116.0018)
		(size 0.508)
		(drill 0.254)
		(layers "F.Cu" "B.Cu")
		(net "RMII_RXD1")
	)
	(segment
		(start 37.16782 -60.9346)
		(end 36.1823 -61.92012)
		(width 0.10668)
		(layer "In7.Cu")
		(net "RMII_RXD1")
	)
	(segment
		(start 42.95648 -40.023034)
		(end 42.8498 -39.916354)
		(width 0.10668)
		(layer "In7.Cu")
		(net "RMII_RXD1")
	)
	(segment
		(start 41.0972 -72.836786)
		(end 42.46372 -74.203306)
		(width 0.10668)
		(layer "In7.Cu")
		(net "RMII_RXD1")
	)
	(segment
		(start 40.202358 -52.075588)
		(end 39.5478 -52.730146)
		(width 0.10668)
		(layer "In7.Cu")
		(net "RMII_RXD1")
	)
	(segment
		(start 50.33645 -117.094)
		(end 49.24425 -116.0018)
		(width 0.10668)
		(layer "In7.Cu")
		(net "RMII_RXD1")
	)
	(segment
		(start 41.413938 -41.73728)
		(end 41.413938 -44.975018)
		(width 0.10668)
		(layer "In7.Cu")
		(net "RMII_RXD1")
	)
	(segment
		(start 43.630088 -40.799512)
		(end 43.630088 -40.988234)
		(width 0.10668)
		(layer "In7.Cu")
		(net "RMII_RXD1")
	)
	(segment
		(start 44.37253 -39.9034)
		(end 44.37253 -40.05707)
		(width 0.10668)
		(layer "In7.Cu")
		(net "RMII_RXD1")
	)
	(segment
		(start 59.200034 -100.048822)
		(end 62.26302 -103.111808)
		(width 0.10668)
		(layer "In7.Cu")
		(net "RMII_RXD1")
	)
	(segment
		(start 41.413938 -45.357542)
		(end 41.413938 -46.35119)
		(width 0.10668)
		(layer "In7.Cu")
		(net "RMII_RXD1")
	)
	(segment
		(start 39.5478 -55.230522)
		(end 39.42969 -55.515764)
		(width 0.10668)
		(layer "In7.Cu")
		(net "RMII_RXD1")
	)
	(segment
		(start 36.1823 -63.597028)
		(end 37.35324 -64.767968)
		(width 0.10668)
		(layer "In7.Cu")
		(net "RMII_RXD1")
	)
	(segment
		(start 42.419524 -39.916354)
		(end 42.297096 -40.038782)
		(width 0.10668)
		(layer "In7.Cu")
		(net "RMII_RXD1")
	)
	(segment
		(start 37.35324 -64.767968)
		(end 37.35324 -65.44056)
		(width 0.10668)
		(layer "In7.Cu")
		(net "RMII_RXD1")
	)
	(segment
		(start 62.26302 -103.111808)
		(end 62.26302 -104.502712)
		(width 0.10668)
		(layer "In7.Cu")
		(net "RMII_RXD1")
	)
	(segment
		(start 40.729916 -46.62043)
		(end 40.01516 -47.335186)
		(width 0.10668)
		(layer "In7.Cu")
		(net "RMII_RXD1")
	)
	(segment
		(start 40.01516 -47.335186)
		(end 40.01516 -51.311302)
		(width 0.10668)
		(layer "In7.Cu")
		(net "RMII_RXD1")
	)
	(segment
		(start 39.86276 -72.567546)
		(end 40.132 -72.836786)
		(width 0.10668)
		(layer "In7.Cu")
		(net "RMII_RXD1")
	)
	(segment
		(start 44.499784 -39.776146)
		(end 44.37253 -39.9034)
		(width 0.10668)
		(layer "In7.Cu")
		(net "RMII_RXD1")
	)
	(segment
		(start 63.373 -115.6462)
		(end 61.9252 -117.094)
		(width 0.10668)
		(layer "In7.Cu")
		(net "RMII_RXD1")
	)
	(segment
		(start 36.1823 -61.92012)
		(end 36.1823 -63.597028)
		(width 0.10668)
		(layer "In7.Cu")
		(net "RMII_RXD1")
	)
	(segment
		(start 40.01516 -51.311302)
		(end 40.202358 -51.4985)
		(width 0.10668)
		(layer "In7.Cu")
		(net "RMII_RXD1")
	)
	(segment
		(start 42.297096 -40.038782)
		(end 42.297096 -40.854122)
		(width 0.10668)
		(layer "In7.Cu")
		(net "RMII_RXD1")
	)
	(segment
		(start 50.22342 -83.519772)
		(end 52.125372 -85.421724)
		(width 0.10668)
		(layer "In7.Cu")
		(net "RMII_RXD1")
	)
	(segment
		(start 41.4147 -44.97578)
		(end 41.4147 -45.35678)
		(width 0.10668)
		(layer "In7.Cu")
		(net "RMII_RXD1")
	)
	(segment
		(start 36.74872 -68.53428)
		(end 39.86276 -71.64832)
		(width 0.10668)
		(layer "In7.Cu")
		(net "RMII_RXD1")
	)
	(segment
		(start 53.901848 -87.640414)
		(end 54.5084 -89.105486)
		(width 0.10668)
		(layer "In7.Cu")
		(net "RMII_RXD1")
	)
	(segment
		(start 41.144698 -46.62043)
		(end 40.729916 -46.62043)
		(width 0.10668)
		(layer "In7.Cu")
		(net "RMII_RXD1")
	)
	(segment
		(start 37.35324 -65.44056)
		(end 36.74872 -66.04508)
		(width 0.10668)
		(layer "In7.Cu")
		(net "RMII_RXD1")
	)
	(segment
		(start 54.5084 -94.074488)
		(end 58.292492 -97.85858)
		(width 0.10668)
		(layer "In7.Cu")
		(net "RMII_RXD1")
	)
	(segment
		(start 39.86276 -71.64832)
		(end 39.86276 -72.567546)
		(width 0.10668)
		(layer "In7.Cu")
		(net "RMII_RXD1")
	)
	(segment
		(start 40.202358 -51.4985)
		(end 40.202358 -52.075588)
		(width 0.10668)
		(layer "In7.Cu")
		(net "RMII_RXD1")
	)
	(segment
		(start 39.032942 -55.912512)
		(end 39.032942 -58.333894)
		(width 0.10668)
		(layer "In7.Cu")
		(net "RMII_RXD1")
	)
	(segment
		(start 42.95648 -40.988234)
		(end 42.95648 -40.023034)
		(width 0.10668)
		(layer "In7.Cu")
		(net "RMII_RXD1")
	)
	(segment
		(start 64.008 -106.247692)
		(end 64.008 -113.3475)
		(width 0.10668)
		(layer "In7.Cu")
		(net "RMII_RXD1")
	)
	(segment
		(start 43.523408 -41.094914)
		(end 43.06316 -41.094914)
		(width 0.10668)
		(layer "In7.Cu")
		(net "RMII_RXD1")
	)
	(segment
		(start 61.9252 -117.094)
		(end 50.33645 -117.094)
		(width 0.10668)
		(layer "In7.Cu")
		(net "RMII_RXD1")
	)
	(segment
		(start 39.032942 -58.333894)
		(end 37.16782 -60.199016)
		(width 0.10668)
		(layer "In7.Cu")
		(net "RMII_RXD1")
	)
	(segment
		(start 41.413938 -46.35119)
		(end 41.144698 -46.62043)
		(width 0.10668)
		(layer "In7.Cu")
		(net "RMII_RXD1")
	)
	(segment
		(start 43.266614 -74.203306)
		(end 46.7106 -77.647292)
		(width 0.10668)
		(layer "In7.Cu")
		(net "RMII_RXD1")
	)
	(segment
		(start 62.26302 -104.502712)
		(end 64.008 -106.247692)
		(width 0.10668)
		(layer "In7.Cu")
		(net "RMII_RXD1")
	)
	(segment
		(start 54.5084 -89.105486)
		(end 54.5084 -94.074488)
		(width 0.10668)
		(layer "In7.Cu")
		(net "RMII_RXD1")
	)
	(segment
		(start 42.46372 -74.203306)
		(end 43.266614 -74.203306)
		(width 0.10668)
		(layer "In7.Cu")
		(net "RMII_RXD1")
	)
	(segment
		(start 63.373 -113.9825)
		(end 63.373 -115.6462)
		(width 0.10668)
		(layer "In7.Cu")
		(net "RMII_RXD1")
	)
	(segment
		(start 39.42969 -55.515764)
		(end 39.032942 -55.912512)
		(width 0.10668)
		(layer "In7.Cu")
		(net "RMII_RXD1")
	)
	(segment
		(start 49.24425 -116.0018)
		(end 48.71212 -116.0018)
		(width 0.10668)
		(layer "In7.Cu")
		(net "RMII_RXD1")
	)
	(segment
		(start 50.22342 -82.951066)
		(end 50.22342 -83.519772)
		(width 0.10668)
		(layer "In7.Cu")
		(net "RMII_RXD1")
	)
	(segment
		(start 41.4147 -45.35678)
		(end 41.413938 -45.357542)
		(width 0.10668)
		(layer "In7.Cu")
		(net "RMII_RXD1")
	)
	(segment
		(start 44.37253 -40.05707)
		(end 43.630088 -40.799512)
		(width 0.10668)
		(layer "In7.Cu")
		(net "RMII_RXD1")
	)
	(segment
		(start 52.125372 -85.421724)
		(end 52.439316 -86.177882)
		(width 0.10668)
		(layer "In7.Cu")
		(net "RMII_RXD1")
	)
	(segment
		(start 43.06316 -41.094914)
		(end 42.95648 -40.988234)
		(width 0.10668)
		(layer "In7.Cu")
		(net "RMII_RXD1")
	)
	(segment
		(start 64.008 -113.3475)
		(end 63.373 -113.9825)
		(width 0.10668)
		(layer "In7.Cu")
		(net "RMII_RXD1")
	)
	(segment
		(start 58.292492 -97.85858)
		(end 59.200034 -100.048822)
		(width 0.10668)
		(layer "In7.Cu")
		(net "RMII_RXD1")
	)
	(segment
		(start 40.132 -72.836786)
		(end 41.0972 -72.836786)
		(width 0.10668)
		(layer "In7.Cu")
		(net "RMII_RXD1")
	)
	(segment
		(start 42.8498 -39.916354)
		(end 42.419524 -39.916354)
		(width 0.10668)
		(layer "In7.Cu")
		(net "RMII_RXD1")
	)
	(segment
		(start 42.297096 -40.854122)
		(end 41.413938 -41.73728)
		(width 0.10668)
		(layer "In7.Cu")
		(net "RMII_RXD1")
	)
	(segment
		(start 36.74872 -66.04508)
		(end 36.74872 -68.53428)
		(width 0.10668)
		(layer "In7.Cu")
		(net "RMII_RXD1")
	)
	(segment
		(start 37.16782 -60.199016)
		(end 37.16782 -60.9346)
		(width 0.10668)
		(layer "In7.Cu")
		(net "RMII_RXD1")
	)
	(segment
		(start 41.413938 -44.975018)
		(end 41.4147 -44.97578)
		(width 0.10668)
		(layer "In7.Cu")
		(net "RMII_RXD1")
	)
	(segment
		(start 43.630088 -40.988234)
		(end 43.523408 -41.094914)
		(width 0.10668)
		(layer "In7.Cu")
		(net "RMII_RXD1")
	)
	(segment
		(start 46.7106 -77.647292)
		(end 46.7106 -79.438246)
		(width 0.10668)
		(layer "In7.Cu")
		(net "RMII_RXD1")
	)
	(segment
		(start 52.439316 -86.177882)
		(end 53.901848 -87.640414)
		(width 0.10668)
		(layer "In7.Cu")
		(net "RMII_RXD1")
	)
	(segment
		(start 39.5478 -52.730146)
		(end 39.5478 -55.230522)
		(width 0.10668)
		(layer "In7.Cu")
		(net "RMII_RXD1")
	)
	(segment
		(start 46.7106 -79.438246)
		(end 50.22342 -82.951066)
		(width 0.10668)
		(layer "In7.Cu")
		(net "RMII_RXD1")
	)
	(segment
		(start 48.71212 -115.1382)
		(end 48.7172 -115.1382)
		(width 0.11684)
		(layer "F.Cu")
		(net "RMII_RXD0")
	)
	(segment
		(start 49.21504 -116.278152)
		(end 49.6062 -116.669312)
		(width 0.11684)
		(layer "F.Cu")
		(net "RMII_RXD0")
	)
	(segment
		(start 46.494954 -40.971216)
		(end 46.09973 -40.575992)
		(width 0.11684)
		(layer "F.Cu")
		(net "RMII_RXD0")
	)
	(segment
		(start 49.665128 -117.229128)
		(end 49.665128 -118.25986)
		(width 0.11684)
		(layer "F.Cu")
		(net "RMII_RXD0")
	)
	(segment
		(start 49.6062 -116.669312)
		(end 49.6062 -117.1702)
		(width 0.11684)
		(layer "F.Cu")
		(net "RMII_RXD0")
	)
	(segment
		(start 49.21504 -115.63604)
		(end 49.21504 -116.278152)
		(width 0.11684)
		(layer "F.Cu")
		(net "RMII_RXD0")
	)
	(segment
		(start 49.6062 -117.1702)
		(end 49.665128 -117.229128)
		(width 0.11684)
		(layer "F.Cu")
		(net "RMII_RXD0")
	)
	(segment
		(start 48.7172 -115.1382)
		(end 49.21504 -115.63604)
		(width 0.11684)
		(layer "F.Cu")
		(net "RMII_RXD0")
	)
	(via
		(at 48.71212 -115.1382)
		(size 0.508)
		(drill 0.254)
		(layers "F.Cu" "B.Cu")
		(net "RMII_RXD0")
	)
	(via
		(at 66.4718 -111.6838)
		(size 0.508)
		(drill 0.254)
		(layers "F.Cu" "B.Cu")
		(net "RMII_RXD0")
	)
	(via
		(at 46.09973 -40.575992)
		(size 0.4572)
		(drill 0.254)
		(layers "F.Cu" "B.Cu")
		(net "RMII_RXD0")
	)
	(segment
		(start 62.357 -116.4336)
		(end 63.2206 -115.57)
		(width 0.08382)
		(layer "In2.Cu")
		(net "RMII_RXD0")
	)
	(segment
		(start 58.547 -115.443)
		(end 59.5376 -116.4336)
		(width 0.08382)
		(layer "In2.Cu")
		(net "RMII_RXD0")
	)
	(segment
		(start 63.2206 -113.364772)
		(end 64.901572 -111.6838)
		(width 0.08382)
		(layer "In2.Cu")
		(net "RMII_RXD0")
	)
	(segment
		(start 59.5376 -116.4336)
		(end 62.357 -116.4336)
		(width 0.08382)
		(layer "In2.Cu")
		(net "RMII_RXD0")
	)
	(segment
		(start 64.901572 -111.6838)
		(end 66.4718 -111.6838)
		(width 0.08382)
		(layer "In2.Cu")
		(net "RMII_RXD0")
	)
	(segment
		(start 63.2206 -115.57)
		(end 63.2206 -113.364772)
		(width 0.08382)
		(layer "In2.Cu")
		(net "RMII_RXD0")
	)
	(segment
		(start 51.7906 -116.2304)
		(end 52.578 -115.443)
		(width 0.08382)
		(layer "In2.Cu")
		(net "RMII_RXD0")
	)
	(segment
		(start 49.2506 -115.1382)
		(end 50.3428 -116.2304)
		(width 0.08382)
		(layer "In2.Cu")
		(net "RMII_RXD0")
	)
	(segment
		(start 48.71212 -115.1382)
		(end 49.2506 -115.1382)
		(width 0.08382)
		(layer "In2.Cu")
		(net "RMII_RXD0")
	)
	(segment
		(start 50.3428 -116.2304)
		(end 51.7906 -116.2304)
		(width 0.08382)
		(layer "In2.Cu")
		(net "RMII_RXD0")
	)
	(segment
		(start 52.578 -115.443)
		(end 58.547 -115.443)
		(width 0.08382)
		(layer "In2.Cu")
		(net "RMII_RXD0")
	)
	(segment
		(start 41.948608 -47.801276)
		(end 41.78808 -47.961804)
		(width 0.10668)
		(layer "In7.Cu")
		(net "RMII_RXD0")
	)
	(segment
		(start 55.55488 -89.0016)
		(end 55.55488 -93.198442)
		(width 0.10668)
		(layer "In7.Cu")
		(net "RMII_RXD0")
	)
	(segment
		(start 46.09973 -40.575992)
		(end 45.72 -40.955722)
		(width 0.10668)
		(layer "In7.Cu")
		(net "RMII_RXD0")
	)
	(segment
		(start 38.4048 -66.014854)
		(end 38.2524 -66.167254)
		(width 0.10668)
		(layer "In7.Cu")
		(net "RMII_RXD0")
	)
	(segment
		(start 39.1414 -68.317618)
		(end 39.1414 -69.424296)
		(width 0.10668)
		(layer "In7.Cu")
		(net "RMII_RXD0")
	)
	(segment
		(start 53.66512 -84.70773)
		(end 54.485032 -86.682326)
		(width 0.10668)
		(layer "In7.Cu")
		(net "RMII_RXD0")
	)
	(segment
		(start 62.36208 -98.81489)
		(end 62.36208 -101.313742)
		(width 0.10668)
		(layer "In7.Cu")
		(net "RMII_RXD0")
	)
	(segment
		(start 41.208198 -52.594256)
		(end 40.55364 -53.248814)
		(width 0.10668)
		(layer "In7.Cu")
		(net "RMII_RXD0")
	)
	(segment
		(start 38.2524 -66.167254)
		(end 38.2524 -67.428618)
		(width 0.10668)
		(layer "In7.Cu")
		(net "RMII_RXD0")
	)
	(segment
		(start 39.1414 -69.424296)
		(end 42.91457 -73.197466)
		(width 0.10668)
		(layer "In7.Cu")
		(net "RMII_RXD0")
	)
	(segment
		(start 48.3489 -77.560424)
		(end 48.3489 -79.381604)
		(width 0.10668)
		(layer "In7.Cu")
		(net "RMII_RXD0")
	)
	(segment
		(start 62.36208 -101.313742)
		(end 65.01384 -103.965502)
		(width 0.10668)
		(layer "In7.Cu")
		(net "RMII_RXD0")
	)
	(segment
		(start 40.038782 -56.329326)
		(end 40.038782 -58.871104)
		(width 0.10668)
		(layer "In7.Cu")
		(net "RMII_RXD0")
	)
	(segment
		(start 42.42054 -45.773594)
		(end 42.419778 -45.774356)
		(width 0.10668)
		(layer "In7.Cu")
		(net "RMII_RXD0")
	)
	(segment
		(start 40.43426 -62.467236)
		(end 38.4048 -64.496696)
		(width 0.10668)
		(layer "In7.Cu")
		(net "RMII_RXD0")
	)
	(segment
		(start 45.72 -40.955722)
		(end 45.72 -41.213278)
		(width 0.10668)
		(layer "In7.Cu")
		(net "RMII_RXD0")
	)
	(segment
		(start 45.71619 -41.217088)
		(end 45.71619 -41.535096)
		(width 0.10668)
		(layer "In7.Cu")
		(net "RMII_RXD0")
	)
	(segment
		(start 44.732702 -74.21118)
		(end 46.255686 -74.21118)
		(width 0.10668)
		(layer "In7.Cu")
		(net "RMII_RXD0")
	)
	(segment
		(start 57.860438 -95.504)
		(end 59.01436 -95.504)
		(width 0.10668)
		(layer "In7.Cu")
		(net "RMII_RXD0")
	)
	(segment
		(start 54.485032 -86.682326)
		(end 54.671468 -86.868762)
		(width 0.10668)
		(layer "In7.Cu")
		(net "RMII_RXD0")
	)
	(segment
		(start 41.78808 -47.961804)
		(end 41.78808 -48.729138)
		(width 0.10668)
		(layer "In7.Cu")
		(net "RMII_RXD0")
	)
	(segment
		(start 38.2524 -67.428618)
		(end 39.1414 -68.317618)
		(width 0.10668)
		(layer "In7.Cu")
		(net "RMII_RXD0")
	)
	(segment
		(start 46.78172 -74.737214)
		(end 46.78172 -76.220574)
		(width 0.10668)
		(layer "In7.Cu")
		(net "RMII_RXD0")
	)
	(segment
		(start 40.55364 -53.248814)
		(end 40.55364 -55.43169)
		(width 0.10668)
		(layer "In7.Cu")
		(net "RMII_RXD0")
	)
	(segment
		(start 45.72 -41.6306)
		(end 45.4914 -41.8592)
		(width 0.10668)
		(layer "In7.Cu")
		(net "RMII_RXD0")
	)
	(segment
		(start 65.01384 -103.965502)
		(end 65.01384 -108.16844)
		(width 0.10668)
		(layer "In7.Cu")
		(net "RMII_RXD0")
	)
	(segment
		(start 48.3489 -79.381604)
		(end 53.66512 -84.70773)
		(width 0.10668)
		(layer "In7.Cu")
		(net "RMII_RXD0")
	)
	(segment
		(start 47.686976 -76.8985)
		(end 48.3489 -77.560424)
		(width 0.10668)
		(layer "In7.Cu")
		(net "RMII_RXD0")
	)
	(segment
		(start 59.01436 -95.504)
		(end 59.1439 -95.37446)
		(width 0.10668)
		(layer "In7.Cu")
		(net "RMII_RXD0")
	)
	(segment
		(start 40.282876 -56.085232)
		(end 40.038782 -56.329326)
		(width 0.10668)
		(layer "In7.Cu")
		(net "RMII_RXD0")
	)
	(segment
		(start 66.4718 -109.6264)
		(end 66.4718 -111.6838)
		(width 0.10668)
		(layer "In7.Cu")
		(net "RMII_RXD0")
	)
	(segment
		(start 42.91457 -73.197466)
		(end 43.718988 -73.197466)
		(width 0.10668)
		(layer "In7.Cu")
		(net "RMII_RXD0")
	)
	(segment
		(start 41.78808 -48.729138)
		(end 41.208198 -49.30902)
		(width 0.10668)
		(layer "In7.Cu")
		(net "RMII_RXD0")
	)
	(segment
		(start 59.8678 -95.71736)
		(end 59.8678 -96.32061)
		(width 0.10668)
		(layer "In7.Cu")
		(net "RMII_RXD0")
	)
	(segment
		(start 45.71619 -41.535096)
		(end 45.72 -41.538906)
		(width 0.10668)
		(layer "In7.Cu")
		(net "RMII_RXD0")
	)
	(segment
		(start 59.8678 -96.32061)
		(end 62.36208 -98.81489)
		(width 0.10668)
		(layer "In7.Cu")
		(net "RMII_RXD0")
	)
	(segment
		(start 38.4048 -64.496696)
		(end 38.4048 -66.014854)
		(width 0.10668)
		(layer "In7.Cu")
		(net "RMII_RXD0")
	)
	(segment
		(start 55.55488 -93.198442)
		(end 57.860438 -95.504)
		(width 0.10668)
		(layer "In7.Cu")
		(net "RMII_RXD0")
	)
	(segment
		(start 47.459646 -76.8985)
		(end 47.686976 -76.8985)
		(width 0.10668)
		(layer "In7.Cu")
		(net "RMII_RXD0")
	)
	(segment
		(start 45.4914 -41.8592)
		(end 44.181776 -41.8592)
		(width 0.10668)
		(layer "In7.Cu")
		(net "RMII_RXD0")
	)
	(segment
		(start 40.43426 -59.266582)
		(end 40.43426 -62.467236)
		(width 0.10668)
		(layer "In7.Cu")
		(net "RMII_RXD0")
	)
	(segment
		(start 42.419778 -46.663864)
		(end 41.948608 -47.801276)
		(width 0.10668)
		(layer "In7.Cu")
		(net "RMII_RXD0")
	)
	(segment
		(start 46.78172 -76.220574)
		(end 47.459646 -76.8985)
		(width 0.10668)
		(layer "In7.Cu")
		(net "RMII_RXD0")
	)
	(segment
		(start 54.671468 -86.868762)
		(end 55.55488 -89.0016)
		(width 0.10668)
		(layer "In7.Cu")
		(net "RMII_RXD0")
	)
	(segment
		(start 40.038782 -58.871104)
		(end 40.43426 -59.266582)
		(width 0.10668)
		(layer "In7.Cu")
		(net "RMII_RXD0")
	)
	(segment
		(start 43.718988 -73.197466)
		(end 44.732702 -74.21118)
		(width 0.10668)
		(layer "In7.Cu")
		(net "RMII_RXD0")
	)
	(segment
		(start 45.72 -41.213278)
		(end 45.71619 -41.217088)
		(width 0.10668)
		(layer "In7.Cu")
		(net "RMII_RXD0")
	)
	(segment
		(start 65.01384 -108.16844)
		(end 66.4718 -109.6264)
		(width 0.10668)
		(layer "In7.Cu")
		(net "RMII_RXD0")
	)
	(segment
		(start 44.181776 -41.8592)
		(end 42.42054 -43.620436)
		(width 0.10668)
		(layer "In7.Cu")
		(net "RMII_RXD0")
	)
	(segment
		(start 46.255686 -74.21118)
		(end 46.78172 -74.737214)
		(width 0.10668)
		(layer "In7.Cu")
		(net "RMII_RXD0")
	)
	(segment
		(start 59.5249 -95.37446)
		(end 59.8678 -95.71736)
		(width 0.10668)
		(layer "In7.Cu")
		(net "RMII_RXD0")
	)
	(segment
		(start 59.1439 -95.37446)
		(end 59.5249 -95.37446)
		(width 0.10668)
		(layer "In7.Cu")
		(net "RMII_RXD0")
	)
	(segment
		(start 42.42054 -43.620436)
		(end 42.42054 -45.773594)
		(width 0.10668)
		(layer "In7.Cu")
		(net "RMII_RXD0")
	)
	(segment
		(start 40.55364 -55.43169)
		(end 40.282876 -56.085232)
		(width 0.10668)
		(layer "In7.Cu")
		(net "RMII_RXD0")
	)
	(segment
		(start 45.72 -41.538906)
		(end 45.72 -41.6306)
		(width 0.10668)
		(layer "In7.Cu")
		(net "RMII_RXD0")
	)
	(segment
		(start 41.208198 -49.30902)
		(end 41.208198 -52.594256)
		(width 0.10668)
		(layer "In7.Cu")
		(net "RMII_RXD0")
	)
	(segment
		(start 42.419778 -45.774356)
		(end 42.419778 -46.663864)
		(width 0.10668)
		(layer "In7.Cu")
		(net "RMII_RXD0")
	)
	(segment
		(start 51.6636 -110.213902)
		(end 51.438302 -110.4392)
		(width 0.11684)
		(layer "F.Cu")
		(net "RMII_CSRDV")
	)
	(segment
		(start 52.665122 -118.460012)
		(end 52.578 -118.37289)
		(width 0.11684)
		(layer "F.Cu")
		(net "RMII_CSRDV")
	)
	(segment
		(start 52.578 -117.1194)
		(end 52.324 -116.8654)
		(width 0.11684)
		(layer "F.Cu")
		(net "RMII_CSRDV")
	)
	(segment
		(start 52.0446 -111.045498)
		(end 51.438302 -110.4392)
		(width 0.11684)
		(layer "F.Cu")
		(net "RMII_CSRDV")
	)
	(segment
		(start 52.324 -114.699288)
		(end 51.62296 -113.998248)
		(width 0.11684)
		(layer "F.Cu")
		(net "RMII_CSRDV")
	)
	(segment
		(start 52.578 -118.37289)
		(end 52.578 -117.1194)
		(width 0.11684)
		(layer "F.Cu")
		(net "RMII_CSRDV")
	)
	(segment
		(start 51.6636 -109.79785)
		(end 51.6636 -110.213902)
		(width 0.11684)
		(layer "F.Cu")
		(net "RMII_CSRDV")
	)
	(segment
		(start 51.62296 -112.86744)
		(end 52.0446 -112.4458)
		(width 0.11684)
		(layer "F.Cu")
		(net "RMII_CSRDV")
	)
	(segment
		(start 52.0446 -112.4458)
		(end 52.0446 -111.045498)
		(width 0.11684)
		(layer "F.Cu")
		(net "RMII_CSRDV")
	)
	(segment
		(start 45.695108 -40.17137)
		(end 45.299884 -39.776146)
		(width 0.11684)
		(layer "F.Cu")
		(net "RMII_CSRDV")
	)
	(segment
		(start 51.62296 -113.998248)
		(end 51.62296 -112.86744)
		(width 0.11684)
		(layer "F.Cu")
		(net "RMII_CSRDV")
	)
	(segment
		(start 52.324 -116.8654)
		(end 52.324 -114.699288)
		(width 0.11684)
		(layer "F.Cu")
		(net "RMII_CSRDV")
	)
	(via
		(at 51.438302 -110.4392)
		(size 0.508)
		(drill 0.254)
		(layers "F.Cu" "B.Cu")
		(net "RMII_CSRDV")
	)
	(via
		(at 63.3476 -104.2162)
		(size 0.762)
		(drill 0.254)
		(layers "F.Cu" "B.Cu")
		(net "RMII_CSRDV")
	)
	(via
		(at 45.299884 -39.776146)
		(size 0.4572)
		(drill 0.254)
		(layers "F.Cu" "B.Cu")
		(net "RMII_CSRDV")
	)
	(segment
		(start 52.890166 -107.081828)
		(end 52.890166 -108.886752)
		(width 0.08382)
		(layer "In2.Cu")
		(net "RMII_CSRDV")
	)
	(segment
		(start 53.507386 -108.886752)
		(end 53.507386 -107.076748)
		(width 0.08382)
		(layer "In2.Cu")
		(net "RMII_CSRDV")
	)
	(segment
		(start 53.507386 -107.076748)
		(end 53.688234 -106.8959)
		(width 0.08382)
		(layer "In2.Cu")
		(net "RMII_CSRDV")
	)
	(segment
		(start 52.709318 -106.90098)
		(end 52.890166 -107.081828)
		(width 0.08382)
		(layer "In2.Cu")
		(net "RMII_CSRDV")
	)
	(segment
		(start 53.688234 -106.8959)
		(end 53.943758 -106.8959)
		(width 0.08382)
		(layer "In2.Cu")
		(net "RMII_CSRDV")
	)
	(segment
		(start 56.1594 -108.2294)
		(end 56.62422 -107.76458)
		(width 0.08382)
		(layer "In2.Cu")
		(net "RMII_CSRDV")
	)
	(segment
		(start 53.326538 -109.0676)
		(end 53.507386 -108.886752)
		(width 0.08382)
		(layer "In2.Cu")
		(net "RMII_CSRDV")
	)
	(segment
		(start 51.721766 -106.90098)
		(end 52.709318 -106.90098)
		(width 0.08382)
		(layer "In2.Cu")
		(net "RMII_CSRDV")
	)
	(segment
		(start 54.741826 -108.410248)
		(end 54.922674 -108.2294)
		(width 0.08382)
		(layer "In2.Cu")
		(net "RMII_CSRDV")
	)
	(segment
		(start 51.438302 -110.4392)
		(end 51.438302 -107.184444)
		(width 0.08382)
		(layer "In2.Cu")
		(net "RMII_CSRDV")
	)
	(segment
		(start 53.943758 -106.8959)
		(end 54.124606 -107.076748)
		(width 0.08382)
		(layer "In2.Cu")
		(net "RMII_CSRDV")
	)
	(segment
		(start 53.071014 -109.0676)
		(end 53.326538 -109.0676)
		(width 0.08382)
		(layer "In2.Cu")
		(net "RMII_CSRDV")
	)
	(segment
		(start 54.124606 -107.076748)
		(end 54.124606 -108.886752)
		(width 0.08382)
		(layer "In2.Cu")
		(net "RMII_CSRDV")
	)
	(segment
		(start 56.62422 -106.31678)
		(end 58.7248 -104.2162)
		(width 0.08382)
		(layer "In2.Cu")
		(net "RMII_CSRDV")
	)
	(segment
		(start 54.305454 -109.0676)
		(end 54.560978 -109.0676)
		(width 0.08382)
		(layer "In2.Cu")
		(net "RMII_CSRDV")
	)
	(segment
		(start 54.922674 -108.2294)
		(end 56.1594 -108.2294)
		(width 0.08382)
		(layer "In2.Cu")
		(net "RMII_CSRDV")
	)
	(segment
		(start 54.560978 -109.0676)
		(end 54.741826 -108.886752)
		(width 0.08382)
		(layer "In2.Cu")
		(net "RMII_CSRDV")
	)
	(segment
		(start 52.890166 -108.886752)
		(end 53.071014 -109.0676)
		(width 0.08382)
		(layer "In2.Cu")
		(net "RMII_CSRDV")
	)
	(segment
		(start 56.62422 -107.76458)
		(end 56.62422 -106.31678)
		(width 0.08382)
		(layer "In2.Cu")
		(net "RMII_CSRDV")
	)
	(segment
		(start 54.741826 -108.886752)
		(end 54.741826 -108.410248)
		(width 0.08382)
		(layer "In2.Cu")
		(net "RMII_CSRDV")
	)
	(segment
		(start 54.124606 -108.886752)
		(end 54.305454 -109.0676)
		(width 0.08382)
		(layer "In2.Cu")
		(net "RMII_CSRDV")
	)
	(segment
		(start 51.438302 -107.184444)
		(end 51.721766 -106.90098)
		(width 0.08382)
		(layer "In2.Cu")
		(net "RMII_CSRDV")
	)
	(segment
		(start 58.7248 -104.2162)
		(end 63.3476 -104.2162)
		(width 0.08382)
		(layer "In2.Cu")
		(net "RMII_CSRDV")
	)
	(segment
		(start 41.749218 -43.343322)
		(end 41.749218 -44.83608)
		(width 0.10668)
		(layer "In7.Cu")
		(net "RMII_CSRDV")
	)
	(segment
		(start 40.35044 -48.092106)
		(end 40.35044 -51.172364)
		(width 0.10668)
		(layer "In7.Cu")
		(net "RMII_CSRDV")
	)
	(segment
		(start 44.9072 -39.911274)
		(end 44.9072 -40.8178)
		(width 0.10668)
		(layer "In7.Cu")
		(net "RMII_CSRDV")
	)
	(segment
		(start 40.537638 -52.248562)
		(end 39.88308 -52.90312)
		(width 0.10668)
		(layer "In7.Cu")
		(net "RMII_CSRDV")
	)
	(segment
		(start 41.749218 -45.49648)
		(end 41.749218 -46.53026)
		(width 0.10668)
		(layer "In7.Cu")
		(net "RMII_CSRDV")
	)
	(segment
		(start 54.864 -89.087198)
		(end 54.864 -93.95587)
		(width 0.10668)
		(layer "In7.Cu")
		(net "RMII_CSRDV")
	)
	(segment
		(start 41.749218 -46.53026)
		(end 41.380156 -47.421292)
		(width 0.10668)
		(layer "In7.Cu")
		(net "RMII_CSRDV")
	)
	(segment
		(start 61.35624 -101.73081)
		(end 62.5983 -102.97287)
		(width 0.10668)
		(layer "In7.Cu")
		(net "RMII_CSRDV")
	)
	(segment
		(start 62.5983 -102.97287)
		(end 62.5983 -103.4669)
		(width 0.10668)
		(layer "In7.Cu")
		(net "RMII_CSRDV")
	)
	(segment
		(start 61.35624 -99.948238)
		(end 61.35624 -101.73081)
		(width 0.10668)
		(layer "In7.Cu")
		(net "RMII_CSRDV")
	)
	(segment
		(start 52.641754 -85.7885)
		(end 54.145688 -87.352632)
		(width 0.10668)
		(layer "In7.Cu")
		(net "RMII_CSRDV")
	)
	(segment
		(start 47.04588 -77.525626)
		(end 47.089314 -77.56906)
		(width 0.10668)
		(layer "In7.Cu")
		(net "RMII_CSRDV")
	)
	(segment
		(start 41.043098 -47.75835)
		(end 40.684196 -47.75835)
		(width 0.10668)
		(layer "In7.Cu")
		(net "RMII_CSRDV")
	)
	(segment
		(start 45.299884 -39.776146)
		(end 45.042328 -39.776146)
		(width 0.10668)
		(layer "In7.Cu")
		(net "RMII_CSRDV")
	)
	(segment
		(start 47.67834 -79.66456)
		(end 51.819048 -83.807808)
		(width 0.10668)
		(layer "In7.Cu")
		(net "RMII_CSRDV")
	)
	(segment
		(start 59.528202 -98.1202)
		(end 61.35624 -99.948238)
		(width 0.10668)
		(layer "In7.Cu")
		(net "RMII_CSRDV")
	)
	(segment
		(start 37.5031 -61.0743)
		(end 36.51758 -62.05982)
		(width 0.10668)
		(layer "In7.Cu")
		(net "RMII_CSRDV")
	)
	(segment
		(start 43.965368 -41.127172)
		(end 41.749218 -43.343322)
		(width 0.10668)
		(layer "In7.Cu")
		(net "RMII_CSRDV")
	)
	(segment
		(start 39.88308 -55.297578)
		(end 39.71417 -55.705502)
		(width 0.10668)
		(layer "In7.Cu")
		(net "RMII_CSRDV")
	)
	(segment
		(start 41.749218 -44.83608)
		(end 41.74998 -44.836842)
		(width 0.10668)
		(layer "In7.Cu")
		(net "RMII_CSRDV")
	)
	(segment
		(start 37.084 -66.184018)
		(end 37.084 -68.349114)
		(width 0.10668)
		(layer "In7.Cu")
		(net "RMII_CSRDV")
	)
	(segment
		(start 47.67834 -77.8383)
		(end 47.67834 -79.66456)
		(width 0.10668)
		(layer "In7.Cu")
		(net "RMII_CSRDV")
	)
	(segment
		(start 37.68852 -64.62903)
		(end 37.68852 -65.579498)
		(width 0.10668)
		(layer "In7.Cu")
		(net "RMII_CSRDV")
	)
	(segment
		(start 59.02833 -98.1202)
		(end 59.528202 -98.1202)
		(width 0.10668)
		(layer "In7.Cu")
		(net "RMII_CSRDV")
	)
	(segment
		(start 36.51758 -63.45809)
		(end 37.68852 -64.62903)
		(width 0.10668)
		(layer "In7.Cu")
		(net "RMII_CSRDV")
	)
	(segment
		(start 39.368222 -56.05145)
		(end 39.368222 -58.472832)
		(width 0.10668)
		(layer "In7.Cu")
		(net "RMII_CSRDV")
	)
	(segment
		(start 42.602912 -73.868026)
		(end 43.405552 -73.868026)
		(width 0.10668)
		(layer "In7.Cu")
		(net "RMII_CSRDV")
	)
	(segment
		(start 41.74998 -44.836842)
		(end 41.74998 -45.495718)
		(width 0.10668)
		(layer "In7.Cu")
		(net "RMII_CSRDV")
	)
	(segment
		(start 41.74998 -45.495718)
		(end 41.749218 -45.49648)
		(width 0.10668)
		(layer "In7.Cu")
		(net "RMII_CSRDV")
	)
	(segment
		(start 40.684196 -47.75835)
		(end 40.35044 -48.092106)
		(width 0.10668)
		(layer "In7.Cu")
		(net "RMII_CSRDV")
	)
	(segment
		(start 44.597828 -41.127172)
		(end 43.965368 -41.127172)
		(width 0.10668)
		(layer "In7.Cu")
		(net "RMII_CSRDV")
	)
	(segment
		(start 54.145688 -87.352632)
		(end 54.864 -89.087198)
		(width 0.10668)
		(layer "In7.Cu")
		(net "RMII_CSRDV")
	)
	(segment
		(start 37.68852 -65.579498)
		(end 37.084 -66.184018)
		(width 0.10668)
		(layer "In7.Cu")
		(net "RMII_CSRDV")
	)
	(segment
		(start 45.042328 -39.776146)
		(end 44.9072 -39.911274)
		(width 0.10668)
		(layer "In7.Cu")
		(net "RMII_CSRDV")
	)
	(segment
		(start 36.51758 -62.05982)
		(end 36.51758 -63.45809)
		(width 0.10668)
		(layer "In7.Cu")
		(net "RMII_CSRDV")
	)
	(segment
		(start 40.537638 -51.359562)
		(end 40.537638 -52.248562)
		(width 0.10668)
		(layer "In7.Cu")
		(net "RMII_CSRDV")
	)
	(segment
		(start 47.04588 -77.508354)
		(end 47.04588 -77.525626)
		(width 0.10668)
		(layer "In7.Cu")
		(net "RMII_CSRDV")
	)
	(segment
		(start 39.368222 -58.472832)
		(end 37.5031 -60.337954)
		(width 0.10668)
		(layer "In7.Cu")
		(net "RMII_CSRDV")
	)
	(segment
		(start 44.9072 -40.8178)
		(end 44.597828 -41.127172)
		(width 0.10668)
		(layer "In7.Cu")
		(net "RMII_CSRDV")
	)
	(segment
		(start 39.88308 -52.90312)
		(end 39.88308 -55.297578)
		(width 0.10668)
		(layer "In7.Cu")
		(net "RMII_CSRDV")
	)
	(segment
		(start 47.089314 -77.56906)
		(end 47.4091 -77.56906)
		(width 0.10668)
		(layer "In7.Cu")
		(net "RMII_CSRDV")
	)
	(segment
		(start 40.35044 -51.172364)
		(end 40.537638 -51.359562)
		(width 0.10668)
		(layer "In7.Cu")
		(net "RMII_CSRDV")
	)
	(segment
		(start 37.084 -68.349114)
		(end 42.602912 -73.868026)
		(width 0.10668)
		(layer "In7.Cu")
		(net "RMII_CSRDV")
	)
	(segment
		(start 39.71417 -55.705502)
		(end 39.368222 -56.05145)
		(width 0.10668)
		(layer "In7.Cu")
		(net "RMII_CSRDV")
	)
	(segment
		(start 41.380156 -47.421292)
		(end 41.043098 -47.75835)
		(width 0.10668)
		(layer "In7.Cu")
		(net "RMII_CSRDV")
	)
	(segment
		(start 43.405552 -73.868026)
		(end 47.04588 -77.508354)
		(width 0.10668)
		(layer "In7.Cu")
		(net "RMII_CSRDV")
	)
	(segment
		(start 54.864 -93.95587)
		(end 59.02833 -98.1202)
		(width 0.10668)
		(layer "In7.Cu")
		(net "RMII_CSRDV")
	)
	(segment
		(start 47.4091 -77.56906)
		(end 47.67834 -77.8383)
		(width 0.10668)
		(layer "In7.Cu")
		(net "RMII_CSRDV")
	)
	(segment
		(start 37.5031 -60.337954)
		(end 37.5031 -61.0743)
		(width 0.10668)
		(layer "In7.Cu")
		(net "RMII_CSRDV")
	)
	(segment
		(start 51.819048 -83.807808)
		(end 52.641754 -85.7885)
		(width 0.10668)
		(layer "In7.Cu")
		(net "RMII_CSRDV")
	)
	(segment
		(start 62.5983 -103.4669)
		(end 63.3476 -104.2162)
		(width 0.10668)
		(layer "In7.Cu")
		(net "RMII_CSRDV")
	)
	(segment
		(start 12.88034 -13.738606)
		(end 12.577572 -13.435838)
		(width 0.11684)
		(layer "F.Cu")
		(net "PWR_BTN_BMC_N")
	)
	(segment
		(start 38.08603 -68.00723)
		(end 38.2778 -67.81546)
		(width 0.11684)
		(layer "F.Cu")
		(net "PWR_BTN_BMC_N")
	)
	(segment
		(start 29.921454 -87.9856)
		(end 30.15615 -87.9856)
		(width 0.11684)
		(layer "F.Cu")
		(net "PWR_BTN_BMC_N")
	)
	(segment
		(start 38.866826 -67.81546)
		(end 40.132 -69.080634)
		(width 0.11684)
		(layer "F.Cu")
		(net "PWR_BTN_BMC_N")
	)
	(segment
		(start 40.132 -69.080634)
		(end 40.132 -69.522594)
		(width 0.11684)
		(layer "F.Cu")
		(net "PWR_BTN_BMC_N")
	)
	(segment
		(start 29.6926 -88.214454)
		(end 29.921454 -87.9856)
		(width 0.11684)
		(layer "F.Cu")
		(net "PWR_BTN_BMC_N")
	)
	(segment
		(start 29.6926 -88.646)
		(end 29.6926 -88.214454)
		(width 0.11684)
		(layer "F.Cu")
		(net "PWR_BTN_BMC_N")
	)
	(segment
		(start 12.88034 -13.899896)
		(end 12.88034 -13.738606)
		(width 0.11684)
		(layer "F.Cu")
		(net "PWR_BTN_BMC_N")
	)
	(segment
		(start 29.1338 -89.2048)
		(end 29.6926 -88.646)
		(width 0.11684)
		(layer "F.Cu")
		(net "PWR_BTN_BMC_N")
	)
	(segment
		(start 37.90061 -68.00723)
		(end 38.08603 -68.00723)
		(width 0.11684)
		(layer "F.Cu")
		(net "PWR_BTN_BMC_N")
	)
	(segment
		(start 12.577572 -13.435838)
		(end 12.201652 -13.435838)
		(width 0.11684)
		(layer "F.Cu")
		(net "PWR_BTN_BMC_N")
	)
	(segment
		(start 38.2778 -67.81546)
		(end 38.866826 -67.81546)
		(width 0.11684)
		(layer "F.Cu")
		(net "PWR_BTN_BMC_N")
	)
	(via
		(at 37.90061 -68.00723)
		(size 0.508)
		(drill 0.254)
		(layers "F.Cu" "B.Cu")
		(net "PWR_BTN_BMC_N")
	)
	(via
		(at 29.1338 -89.2048)
		(size 0.508)
		(drill 0.254)
		(layers "F.Cu" "B.Cu")
		(net "PWR_BTN_BMC_N")
	)
	(via
		(at 12.88034 -13.899896)
		(size 0.508)
		(drill 0.254)
		(layers "F.Cu" "B.Cu")
		(net "PWR_BTN_BMC_N")
	)
	(via
		(at 12.8778 -63.6016)
		(size 0.508)
		(drill 0.254)
		(layers "F.Cu" "B.Cu")
		(net "PWR_BTN_BMC_N")
	)
	(via
		(at 38.064948 -61.922152)
		(size 0.508)
		(drill 0.254)
		(layers "F.Cu" "B.Cu")
		(net "PWR_BTN_BMC_N")
	)
	(via
		(at 33.6804 -88.92286)
		(size 0.508)
		(drill 0.254)
		(layers "F.Cu" "B.Cu")
		(net "PWR_BTN_BMC_N")
	)
	(segment
		(start 38.586156 -62.44336)
		(end 38.064948 -61.922152)
		(width 0.11684)
		(layer "B.Cu")
		(net "PWR_BTN_BMC_N")
	)
	(segment
		(start 41.518078 -61.788802)
		(end 40.86352 -62.44336)
		(width 0.11684)
		(layer "B.Cu")
		(net "PWR_BTN_BMC_N")
	)
	(segment
		(start 41.518078 -60.573666)
		(end 41.518078 -61.788802)
		(width 0.11684)
		(layer "B.Cu")
		(net "PWR_BTN_BMC_N")
	)
	(segment
		(start 40.86352 -62.44336)
		(end 38.586156 -62.44336)
		(width 0.11684)
		(layer "B.Cu")
		(net "PWR_BTN_BMC_N")
	)
	(segment
		(start 16.0782 -65.0494)
		(end 15.7226 -65.405)
		(width 0.08382)
		(layer "In2.Cu")
		(net "PWR_BTN_BMC_N")
	)
	(segment
		(start 25.34412 -63.051436)
		(end 23.474426 -64.92113)
		(width 0.08382)
		(layer "In2.Cu")
		(net "PWR_BTN_BMC_N")
	)
	(segment
		(start 28.219654 -63.051436)
		(end 25.34412 -63.051436)
		(width 0.08382)
		(layer "In2.Cu")
		(net "PWR_BTN_BMC_N")
	)
	(segment
		(start 33.6804 -88.92286)
		(end 32.50946 -90.0938)
		(width 0.11684)
		(layer "In2.Cu")
		(net "PWR_BTN_BMC_N")
	)
	(segment
		(start 31.115 -90.0938)
		(end 30.226 -89.2048)
		(width 0.11684)
		(layer "In2.Cu")
		(net "PWR_BTN_BMC_N")
	)
	(segment
		(start 21.80209 -64.92113)
		(end 20.51431 -63.63335)
		(width 0.08382)
		(layer "In2.Cu")
		(net "PWR_BTN_BMC_N")
	)
	(segment
		(start 16.63065 -63.63335)
		(end 16.0782 -64.1858)
		(width 0.08382)
		(layer "In2.Cu")
		(net "PWR_BTN_BMC_N")
	)
	(segment
		(start 14.6812 -65.405)
		(end 12.8778 -63.6016)
		(width 0.08382)
		(layer "In2.Cu")
		(net "PWR_BTN_BMC_N")
	)
	(segment
		(start 37.314632 -60.962286)
		(end 35.018218 -60.962286)
		(width 0.08382)
		(layer "In2.Cu")
		(net "PWR_BTN_BMC_N")
	)
	(segment
		(start 35.018218 -60.962286)
		(end 32.593534 -63.38697)
		(width 0.08382)
		(layer "In2.Cu")
		(net "PWR_BTN_BMC_N")
	)
	(segment
		(start 15.7226 -65.405)
		(end 14.6812 -65.405)
		(width 0.08382)
		(layer "In2.Cu")
		(net "PWR_BTN_BMC_N")
	)
	(segment
		(start 29.232352 -63.30315)
		(end 28.471368 -63.30315)
		(width 0.08382)
		(layer "In2.Cu")
		(net "PWR_BTN_BMC_N")
	)
	(segment
		(start 30.226 -89.2048)
		(end 29.1338 -89.2048)
		(width 0.11684)
		(layer "In2.Cu")
		(net "PWR_BTN_BMC_N")
	)
	(segment
		(start 30.399228 -62.90564)
		(end 29.629862 -62.90564)
		(width 0.08382)
		(layer "In2.Cu")
		(net "PWR_BTN_BMC_N")
	)
	(segment
		(start 20.51431 -63.63335)
		(end 16.63065 -63.63335)
		(width 0.08382)
		(layer "In2.Cu")
		(net "PWR_BTN_BMC_N")
	)
	(segment
		(start 30.880558 -63.38697)
		(end 30.399228 -62.90564)
		(width 0.08382)
		(layer "In2.Cu")
		(net "PWR_BTN_BMC_N")
	)
	(segment
		(start 38.064948 -61.922152)
		(end 38.064948 -61.712602)
		(width 0.08382)
		(layer "In2.Cu")
		(net "PWR_BTN_BMC_N")
	)
	(segment
		(start 28.471368 -63.30315)
		(end 28.219654 -63.051436)
		(width 0.08382)
		(layer "In2.Cu")
		(net "PWR_BTN_BMC_N")
	)
	(segment
		(start 23.474426 -64.92113)
		(end 21.80209 -64.92113)
		(width 0.08382)
		(layer "In2.Cu")
		(net "PWR_BTN_BMC_N")
	)
	(segment
		(start 29.629862 -62.90564)
		(end 29.232352 -63.30315)
		(width 0.08382)
		(layer "In2.Cu")
		(net "PWR_BTN_BMC_N")
	)
	(segment
		(start 38.064948 -61.712602)
		(end 37.314632 -60.962286)
		(width 0.08382)
		(layer "In2.Cu")
		(net "PWR_BTN_BMC_N")
	)
	(segment
		(start 32.50946 -90.0938)
		(end 31.115 -90.0938)
		(width 0.11684)
		(layer "In2.Cu")
		(net "PWR_BTN_BMC_N")
	)
	(segment
		(start 32.593534 -63.38697)
		(end 30.880558 -63.38697)
		(width 0.08382)
		(layer "In2.Cu")
		(net "PWR_BTN_BMC_N")
	)
	(segment
		(start 16.0782 -64.1858)
		(end 16.0782 -65.0494)
		(width 0.08382)
		(layer "In2.Cu")
		(net "PWR_BTN_BMC_N")
	)
	(segment
		(start 37.91712 -68.02374)
		(end 38.30066 -68.02374)
		(width 0.10668)
		(layer "In4.Cu")
		(net "PWR_BTN_BMC_N")
	)
	(segment
		(start 38.5318 -63.246)
		(end 38.12032 -63.65748)
		(width 0.10668)
		(layer "In4.Cu")
		(net "PWR_BTN_BMC_N")
	)
	(segment
		(start 38.30066 -68.02374)
		(end 38.66642 -68.3895)
		(width 0.10668)
		(layer "In4.Cu")
		(net "PWR_BTN_BMC_N")
	)
	(segment
		(start 37.53104 -78.302866)
		(end 37.53104 -79.487014)
		(width 0.10668)
		(layer "In4.Cu")
		(net "PWR_BTN_BMC_N")
	)
	(segment
		(start 37.53104 -79.487014)
		(end 35.19932 -81.818734)
		(width 0.10668)
		(layer "In4.Cu")
		(net "PWR_BTN_BMC_N")
	)
	(segment
		(start 38.064948 -72.98436)
		(end 38.26002 -73.179432)
		(width 0.10668)
		(layer "In4.Cu")
		(net "PWR_BTN_BMC_N")
	)
	(segment
		(start 38.66642 -71.54926)
		(end 38.064948 -72.150732)
		(width 0.10668)
		(layer "In4.Cu")
		(net "PWR_BTN_BMC_N")
	)
	(segment
		(start 37.90061 -68.00723)
		(end 37.91712 -68.02374)
		(width 0.10668)
		(layer "In4.Cu")
		(net "PWR_BTN_BMC_N")
	)
	(segment
		(start 38.12032 -63.65748)
		(end 38.12032 -67.78752)
		(width 0.10668)
		(layer "In4.Cu")
		(net "PWR_BTN_BMC_N")
	)
	(segment
		(start 38.26002 -73.179432)
		(end 38.26002 -73.560432)
		(width 0.10668)
		(layer "In4.Cu")
		(net "PWR_BTN_BMC_N")
	)
	(segment
		(start 38.064948 -72.150732)
		(end 38.064948 -72.98436)
		(width 0.10668)
		(layer "In4.Cu")
		(net "PWR_BTN_BMC_N")
	)
	(segment
		(start 35.884358 -74.473562)
		(end 35.239198 -74.473562)
		(width 0.10668)
		(layer "In4.Cu")
		(net "PWR_BTN_BMC_N")
	)
	(segment
		(start 38.260274 -73.838054)
		(end 37.794438 -74.30389)
		(width 0.10668)
		(layer "In4.Cu")
		(net "PWR_BTN_BMC_N")
	)
	(segment
		(start 34.0614 -85.598)
		(end 33.6042 -86.0552)
		(width 0.10668)
		(layer "In4.Cu")
		(net "PWR_BTN_BMC_N")
	)
	(segment
		(start 38.5318 -62.389004)
		(end 38.5318 -63.246)
		(width 0.10668)
		(layer "In4.Cu")
		(net "PWR_BTN_BMC_N")
	)
	(segment
		(start 33.6042 -86.0552)
		(end 33.6042 -88.84666)
		(width 0.10668)
		(layer "In4.Cu")
		(net "PWR_BTN_BMC_N")
	)
	(segment
		(start 36.05403 -74.30389)
		(end 35.884358 -74.473562)
		(width 0.10668)
		(layer "In4.Cu")
		(net "PWR_BTN_BMC_N")
	)
	(segment
		(start 35.239198 -74.473562)
		(end 34.741612 -74.971148)
		(width 0.10668)
		(layer "In4.Cu")
		(net "PWR_BTN_BMC_N")
	)
	(segment
		(start 38.260274 -73.560686)
		(end 38.260274 -73.838054)
		(width 0.10668)
		(layer "In4.Cu")
		(net "PWR_BTN_BMC_N")
	)
	(segment
		(start 37.794438 -74.30389)
		(end 36.05403 -74.30389)
		(width 0.10668)
		(layer "In4.Cu")
		(net "PWR_BTN_BMC_N")
	)
	(segment
		(start 34.6964 -85.598)
		(end 34.0614 -85.598)
		(width 0.10668)
		(layer "In4.Cu")
		(net "PWR_BTN_BMC_N")
	)
	(segment
		(start 38.66642 -68.3895)
		(end 38.66642 -71.54926)
		(width 0.10668)
		(layer "In4.Cu")
		(net "PWR_BTN_BMC_N")
	)
	(segment
		(start 36.220146 -77.418946)
		(end 36.64712 -77.418946)
		(width 0.10668)
		(layer "In4.Cu")
		(net "PWR_BTN_BMC_N")
	)
	(segment
		(start 38.064948 -61.922152)
		(end 38.5318 -62.389004)
		(width 0.10668)
		(layer "In4.Cu")
		(net "PWR_BTN_BMC_N")
	)
	(segment
		(start 36.64712 -77.418946)
		(end 37.53104 -78.302866)
		(width 0.10668)
		(layer "In4.Cu")
		(net "PWR_BTN_BMC_N")
	)
	(segment
		(start 38.26002 -73.560432)
		(end 38.260274 -73.560686)
		(width 0.10668)
		(layer "In4.Cu")
		(net "PWR_BTN_BMC_N")
	)
	(segment
		(start 34.741612 -75.940412)
		(end 36.220146 -77.418946)
		(width 0.10668)
		(layer "In4.Cu")
		(net "PWR_BTN_BMC_N")
	)
	(segment
		(start 35.19932 -81.818734)
		(end 35.19932 -85.09508)
		(width 0.10668)
		(layer "In4.Cu")
		(net "PWR_BTN_BMC_N")
	)
	(segment
		(start 38.12032 -67.78752)
		(end 37.90061 -68.00723)
		(width 0.10668)
		(layer "In4.Cu")
		(net "PWR_BTN_BMC_N")
	)
	(segment
		(start 33.6042 -88.84666)
		(end 33.6804 -88.92286)
		(width 0.10668)
		(layer "In4.Cu")
		(net "PWR_BTN_BMC_N")
	)
	(segment
		(start 35.19932 -85.09508)
		(end 34.6964 -85.598)
		(width 0.10668)
		(layer "In4.Cu")
		(net "PWR_BTN_BMC_N")
	)
	(segment
		(start 34.741612 -74.971148)
		(end 34.741612 -75.940412)
		(width 0.10668)
		(layer "In4.Cu")
		(net "PWR_BTN_BMC_N")
	)
	(segment
		(start 16.802354 -38.874954)
		(end 17.25422 -39.32682)
		(width 0.08382)
		(layer "In9.Cu")
		(net "PWR_BTN_BMC_N")
	)
	(segment
		(start 15.389352 -56.996076)
		(end 14.74597 -57.639458)
		(width 0.08382)
		(layer "In9.Cu")
		(net "PWR_BTN_BMC_N")
	)
	(segment
		(start 17.443196 -41.57599)
		(end 16.136874 -42.882312)
		(width 0.08382)
		(layer "In9.Cu")
		(net "PWR_BTN_BMC_N")
	)
	(segment
		(start 16.45158 -33.40862)
		(end 16.802354 -33.759394)
		(width 0.08382)
		(layer "In9.Cu")
		(net "PWR_BTN_BMC_N")
	)
	(segment
		(start 14.71549 -49.74463)
		(end 14.71549 -51.545744)
		(width 0.08382)
		(layer "In9.Cu")
		(net "PWR_BTN_BMC_N")
	)
	(segment
		(start 12.5476 -20.701)
		(end 12.947142 -21.100542)
		(width 0.08382)
		(layer "In9.Cu")
		(net "PWR_BTN_BMC_N")
	)
	(segment
		(start 13.286994 -16.431006)
		(end 12.5476 -17.1704)
		(width 0.08382)
		(layer "In9.Cu")
		(net "PWR_BTN_BMC_N")
	)
	(segment
		(start 15.389352 -52.219606)
		(end 15.389352 -56.996076)
		(width 0.08382)
		(layer "In9.Cu")
		(net "PWR_BTN_BMC_N")
	)
	(segment
		(start 15.1765 -27.6225)
		(end 16.45158 -28.89758)
		(width 0.08382)
		(layer "In9.Cu")
		(net "PWR_BTN_BMC_N")
	)
	(segment
		(start 15.200884 -48.57242)
		(end 14.71549 -49.74463)
		(width 0.08382)
		(layer "In9.Cu")
		(net "PWR_BTN_BMC_N")
	)
	(segment
		(start 16.136874 -42.882312)
		(end 16.136874 -46.18101)
		(width 0.08382)
		(layer "In9.Cu")
		(net "PWR_BTN_BMC_N")
	)
	(segment
		(start 12.947142 -21.100542)
		(end 14.992604 -21.100542)
		(width 0.08382)
		(layer "In9.Cu")
		(net "PWR_BTN_BMC_N")
	)
	(segment
		(start 12.88034 -13.899896)
		(end 13.286994 -14.30655)
		(width 0.08382)
		(layer "In9.Cu")
		(net "PWR_BTN_BMC_N")
	)
	(segment
		(start 14.74597 -57.639458)
		(end 14.74597 -61.73343)
		(width 0.08382)
		(layer "In9.Cu")
		(net "PWR_BTN_BMC_N")
	)
	(segment
		(start 16.136874 -46.18101)
		(end 15.200884 -47.117)
		(width 0.08382)
		(layer "In9.Cu")
		(net "PWR_BTN_BMC_N")
	)
	(segment
		(start 17.907 -39.37)
		(end 18.8722 -40.3352)
		(width 0.08382)
		(layer "In9.Cu")
		(net "PWR_BTN_BMC_N")
	)
	(segment
		(start 15.1765 -21.284438)
		(end 15.1765 -27.6225)
		(width 0.08382)
		(layer "In9.Cu")
		(net "PWR_BTN_BMC_N")
	)
	(segment
		(start 18.266156 -41.57599)
		(end 17.443196 -41.57599)
		(width 0.08382)
		(layer "In9.Cu")
		(net "PWR_BTN_BMC_N")
	)
	(segment
		(start 18.8722 -40.3352)
		(end 18.8722 -40.969946)
		(width 0.08382)
		(layer "In9.Cu")
		(net "PWR_BTN_BMC_N")
	)
	(segment
		(start 16.45158 -28.89758)
		(end 16.45158 -33.40862)
		(width 0.08382)
		(layer "In9.Cu")
		(net "PWR_BTN_BMC_N")
	)
	(segment
		(start 13.286994 -14.30655)
		(end 13.286994 -16.431006)
		(width 0.08382)
		(layer "In9.Cu")
		(net "PWR_BTN_BMC_N")
	)
	(segment
		(start 14.71549 -51.545744)
		(end 15.389352 -52.219606)
		(width 0.08382)
		(layer "In9.Cu")
		(net "PWR_BTN_BMC_N")
	)
	(segment
		(start 14.74597 -61.73343)
		(end 12.8778 -63.6016)
		(width 0.08382)
		(layer "In9.Cu")
		(net "PWR_BTN_BMC_N")
	)
	(segment
		(start 18.8722 -40.969946)
		(end 18.266156 -41.57599)
		(width 0.08382)
		(layer "In9.Cu")
		(net "PWR_BTN_BMC_N")
	)
	(segment
		(start 17.25422 -39.32682)
		(end 17.358614 -39.37)
		(width 0.08382)
		(layer "In9.Cu")
		(net "PWR_BTN_BMC_N")
	)
	(segment
		(start 12.5476 -17.1704)
		(end 12.5476 -20.701)
		(width 0.08382)
		(layer "In9.Cu")
		(net "PWR_BTN_BMC_N")
	)
	(segment
		(start 14.992604 -21.100542)
		(end 15.1765 -21.284438)
		(width 0.08382)
		(layer "In9.Cu")
		(net "PWR_BTN_BMC_N")
	)
	(segment
		(start 17.358614 -39.37)
		(end 17.907 -39.37)
		(width 0.08382)
		(layer "In9.Cu")
		(net "PWR_BTN_BMC_N")
	)
	(segment
		(start 15.200884 -47.117)
		(end 15.200884 -48.57242)
		(width 0.08382)
		(layer "In9.Cu")
		(net "PWR_BTN_BMC_N")
	)
	(segment
		(start 16.802354 -33.759394)
		(end 16.802354 -38.874954)
		(width 0.08382)
		(layer "In9.Cu")
		(net "PWR_BTN_BMC_N")
	)
	(segment
		(start 15.813786 -54.06136)
		(end 15.638272 -54.236874)
		(width 0.11684)
		(layer "F.Cu")
		(net "PWRGD_P5V_AUX")
	)
	(segment
		(start 31.210504 -62.808104)
		(end 31.210504 -62.3062)
		(width 0.11684)
		(layer "F.Cu")
		(net "PWRGD_P5V_AUX")
	)
	(segment
		(start 16.397986 -37.741606)
		(end 16.397986 -38.186614)
		(width 0.11684)
		(layer "F.Cu")
		(net "PWRGD_P5V_AUX")
	)
	(segment
		(start 15.638272 -54.236874)
		(end 14.941042 -54.236874)
		(width 0.11684)
		(layer "F.Cu")
		(net "PWRGD_P5V_AUX")
	)
	(segment
		(start 15.813786 -52.067206)
		(end 15.813786 -53.6194)
		(width 0.11684)
		(layer "F.Cu")
		(net "PWRGD_P5V_AUX")
	)
	(segment
		(start 16.397986 -38.186614)
		(end 16.246094 -38.338506)
		(width 0.11684)
		(layer "F.Cu")
		(net "PWRGD_P5V_AUX")
	)
	(segment
		(start 12.13104 -57.423304)
		(end 12.13104 -55.403242)
		(width 0.11684)
		(layer "F.Cu")
		(net "PWRGD_P5V_AUX")
	)
	(segment
		(start 16.246094 -40.038528)
		(end 16.566642 -40.359076)
		(width 0.11684)
		(layer "F.Cu")
		(net "PWRGD_P5V_AUX")
	)
	(segment
		(start 16.246094 -38.338506)
		(end 16.246094 -40.038528)
		(width 0.11684)
		(layer "F.Cu")
		(net "PWRGD_P5V_AUX")
	)
	(segment
		(start 16.566642 -40.359076)
		(end 17.346676 -40.359076)
		(width 0.11684)
		(layer "F.Cu")
		(net "PWRGD_P5V_AUX")
	)
	(segment
		(start 17.4244 -40.4368)
		(end 17.4244 -40.42664)
		(width 0.11684)
		(layer "F.Cu")
		(net "PWRGD_P5V_AUX")
	)
	(segment
		(start 12.13104 -55.403242)
		(end 12.197842 -55.33644)
		(width 0.11684)
		(layer "F.Cu")
		(net "PWRGD_P5V_AUX")
	)
	(segment
		(start 32.099504 -62.92596)
		(end 31.32836 -62.92596)
		(width 0.11684)
		(layer "F.Cu")
		(net "PWRGD_P5V_AUX")
	)
	(segment
		(start 17.346676 -40.359076)
		(end 17.4244 -40.4368)
		(width 0.11684)
		(layer "F.Cu")
		(net "PWRGD_P5V_AUX")
	)
	(segment
		(start 31.32836 -62.92596)
		(end 31.210504 -62.808104)
		(width 0.11684)
		(layer "F.Cu")
		(net "PWRGD_P5V_AUX")
	)
	(segment
		(start 15.813786 -53.6194)
		(end 15.813786 -54.06136)
		(width 0.11684)
		(layer "F.Cu")
		(net "PWRGD_P5V_AUX")
	)
	(via
		(at 33.782 -15.2146)
		(size 0.508)
		(drill 0.254)
		(layers "F.Cu" "B.Cu")
		(net "PWRGD_P5V_AUX")
	)
	(via
		(at 15.813786 -53.6194)
		(size 0.762)
		(drill 0.381)
		(layers "F.Cu" "B.Cu")
		(net "PWRGD_P5V_AUX")
	)
	(via
		(at 17.4244 -40.42664)
		(size 0.508)
		(drill 0.254)
		(layers "F.Cu" "B.Cu")
		(net "PWRGD_P5V_AUX")
	)
	(via
		(at 81.7372 -15.25397)
		(size 0.508)
		(drill 0.254)
		(layers "F.Cu" "B.Cu")
		(net "PWRGD_P5V_AUX")
	)
	(via
		(at 11.30935 -99.4791)
		(size 0.508)
		(drill 0.254)
		(layers "F.Cu" "B.Cu")
		(net "PWRGD_P5V_AUX")
	)
	(via
		(at 12.197842 -55.33644)
		(size 0.508)
		(drill 0.254)
		(layers "F.Cu" "B.Cu")
		(net "PWRGD_P5V_AUX")
	)
	(via
		(at 31.210504 -62.3062)
		(size 0.508)
		(drill 0.254)
		(layers "F.Cu" "B.Cu")
		(net "PWRGD_P5V_AUX")
	)
	(via
		(at 14.941042 -54.236874)
		(size 0.508)
		(drill 0.254)
		(layers "F.Cu" "B.Cu")
		(net "PWRGD_P5V_AUX")
	)
	(segment
		(start 13.835126 -54.236874)
		(end 14.941042 -54.236874)
		(width 0.11684)
		(layer "B.Cu")
		(net "PWRGD_P5V_AUX")
	)
	(segment
		(start 10.9601 -99.4791)
		(end 11.30935 -99.4791)
		(width 0.11684)
		(layer "B.Cu")
		(net "PWRGD_P5V_AUX")
	)
	(segment
		(start 12.197842 -55.33644)
		(end 12.73556 -55.33644)
		(width 0.11684)
		(layer "B.Cu")
		(net "PWRGD_P5V_AUX")
	)
	(segment
		(start 11.461496 -102.672896)
		(end 10.953496 -102.672896)
		(width 0.11684)
		(layer "B.Cu")
		(net "PWRGD_P5V_AUX")
	)
	(segment
		(start 84.9122 -15.9004)
		(end 85.6996 -16.6878)
		(width 0.11684)
		(layer "B.Cu")
		(net "PWRGD_P5V_AUX")
	)
	(segment
		(start 81.153 -70.6628)
		(end 79.5274 -70.6628)
		(width 0.11684)
		(layer "B.Cu")
		(net "PWRGD_P5V_AUX")
	)
	(segment
		(start 12.72667 -56.00192)
		(end 12.72667 -55.77967)
		(width 0.11684)
		(layer "B.Cu")
		(net "PWRGD_P5V_AUX")
	)
	(segment
		(start 86.80196 -18.80616)
		(end 86.80196 -20.789138)
		(width 0.11684)
		(layer "B.Cu")
		(net "PWRGD_P5V_AUX")
	)
	(segment
		(start 10.7442 -99.695)
		(end 10.9601 -99.4791)
		(width 0.11684)
		(layer "B.Cu")
		(net "PWRGD_P5V_AUX")
	)
	(segment
		(start 85.6996 -16.6878)
		(end 85.6996 -17.7038)
		(width 0.11684)
		(layer "B.Cu")
		(net "PWRGD_P5V_AUX")
	)
	(segment
		(start 12.199112 -55.33771)
		(end 12.197842 -55.33644)
		(width 0.11684)
		(layer "B.Cu")
		(net "PWRGD_P5V_AUX")
	)
	(segment
		(start 86.80196 -20.789138)
		(end 88.23706 -22.224238)
		(width 0.11684)
		(layer "B.Cu")
		(net "PWRGD_P5V_AUX")
	)
	(segment
		(start 12.319 -103.053896)
		(end 11.842496 -103.053896)
		(width 0.11684)
		(layer "B.Cu")
		(net "PWRGD_P5V_AUX")
	)
	(segment
		(start 10.953496 -102.672896)
		(end 10.7442 -102.4636)
		(width 0.11684)
		(layer "B.Cu")
		(net "PWRGD_P5V_AUX")
	)
	(segment
		(start 88.23706 -68.53174)
		(end 86.5632 -70.2056)
		(width 0.11684)
		(layer "B.Cu")
		(net "PWRGD_P5V_AUX")
	)
	(segment
		(start 79.131414 -70.266814)
		(end 79.131414 -69.618606)
		(width 0.11684)
		(layer "B.Cu")
		(net "PWRGD_P5V_AUX")
	)
	(segment
		(start 12.73556 -55.33644)
		(end 13.835126 -54.236874)
		(width 0.11684)
		(layer "B.Cu")
		(net "PWRGD_P5V_AUX")
	)
	(segment
		(start 11.842496 -103.053896)
		(end 11.461496 -102.672896)
		(width 0.11684)
		(layer "B.Cu")
		(net "PWRGD_P5V_AUX")
	)
	(segment
		(start 85.6996 -17.7038)
		(end 86.80196 -18.80616)
		(width 0.11684)
		(layer "B.Cu")
		(net "PWRGD_P5V_AUX")
	)
	(segment
		(start 86.5632 -70.2056)
		(end 81.6102 -70.2056)
		(width 0.11684)
		(layer "B.Cu")
		(net "PWRGD_P5V_AUX")
	)
	(segment
		(start 79.5274 -70.6628)
		(end 79.131414 -70.266814)
		(width 0.11684)
		(layer "B.Cu")
		(net "PWRGD_P5V_AUX")
	)
	(segment
		(start 12.28471 -55.33771)
		(end 12.199112 -55.33771)
		(width 0.11684)
		(layer "B.Cu")
		(net "PWRGD_P5V_AUX")
	)
	(segment
		(start 88.23706 -22.224238)
		(end 88.23706 -68.53174)
		(width 0.11684)
		(layer "B.Cu")
		(net "PWRGD_P5V_AUX")
	)
	(segment
		(start 81.7372 -15.25397)
		(end 82.38363 -15.9004)
		(width 0.11684)
		(layer "B.Cu")
		(net "PWRGD_P5V_AUX")
	)
	(segment
		(start 10.7442 -102.4636)
		(end 10.7442 -99.695)
		(width 0.11684)
		(layer "B.Cu")
		(net "PWRGD_P5V_AUX")
	)
	(segment
		(start 12.72667 -55.77967)
		(end 12.28471 -55.33771)
		(width 0.11684)
		(layer "B.Cu")
		(net "PWRGD_P5V_AUX")
	)
	(segment
		(start 82.38363 -15.9004)
		(end 84.9122 -15.9004)
		(width 0.11684)
		(layer "B.Cu")
		(net "PWRGD_P5V_AUX")
	)
	(segment
		(start 81.6102 -70.2056)
		(end 81.153 -70.6628)
		(width 0.11684)
		(layer "B.Cu")
		(net "PWRGD_P5V_AUX")
	)
	(segment
		(start 27.716226 -58.72226)
		(end 25.585928 -58.72226)
		(width 0.08382)
		(layer "In2.Cu")
		(net "PWRGD_P5V_AUX")
	)
	(segment
		(start 29.737812 -57.653936)
		(end 28.828746 -58.261504)
		(width 0.08382)
		(layer "In2.Cu")
		(net "PWRGD_P5V_AUX")
	)
	(segment
		(start 32.639 -56.931052)
		(end 32.154368 -56.44642)
		(width 0.08382)
		(layer "In2.Cu")
		(net "PWRGD_P5V_AUX")
	)
	(segment
		(start 49.475898 -14.187424)
		(end 47.209964 -11.92149)
		(width 0.08382)
		(layer "In2.Cu")
		(net "PWRGD_P5V_AUX")
	)
	(segment
		(start 32.154368 -56.44642)
		(end 30.945328 -56.44642)
		(width 0.08382)
		(layer "In2.Cu")
		(net "PWRGD_P5V_AUX")
	)
	(segment
		(start 23.724616 -57.6834)
		(end 22.572218 -57.6834)
		(width 0.08382)
		(layer "In2.Cu")
		(net "PWRGD_P5V_AUX")
	)
	(segment
		(start 37.325808 -13.313918)
		(end 37.325808 -15.13078)
		(width 0.08382)
		(layer "In2.Cu")
		(net "PWRGD_P5V_AUX")
	)
	(segment
		(start 31.94558 -59.052206)
		(end 32.639 -58.358786)
		(width 0.08382)
		(layer "In2.Cu")
		(net "PWRGD_P5V_AUX")
	)
	(segment
		(start 32.639 -58.358786)
		(end 32.639 -56.931052)
		(width 0.08382)
		(layer "In2.Cu")
		(net "PWRGD_P5V_AUX")
	)
	(segment
		(start 38.718236 -11.92149)
		(end 37.325808 -13.313918)
		(width 0.08382)
		(layer "In2.Cu")
		(net "PWRGD_P5V_AUX")
	)
	(segment
		(start 22.572218 -57.6834)
		(end 21.988018 -57.0992)
		(width 0.08382)
		(layer "In2.Cu")
		(net "PWRGD_P5V_AUX")
	)
	(segment
		(start 14.941042 -54.412642)
		(end 14.941042 -54.236874)
		(width 0.08382)
		(layer "In2.Cu")
		(net "PWRGD_P5V_AUX")
	)
	(segment
		(start 61.976 -13.52169)
		(end 54.767988 -13.52169)
		(width 0.08382)
		(layer "In2.Cu")
		(net "PWRGD_P5V_AUX")
	)
	(segment
		(start 47.209964 -11.92149)
		(end 38.718236 -11.92149)
		(width 0.08382)
		(layer "In2.Cu")
		(net "PWRGD_P5V_AUX")
	)
	(segment
		(start 28.828746 -58.261504)
		(end 27.716226 -58.72226)
		(width 0.08382)
		(layer "In2.Cu")
		(net "PWRGD_P5V_AUX")
	)
	(segment
		(start 73.74001 -13.65631)
		(end 65.72631 -13.65631)
		(width 0.08382)
		(layer "In2.Cu")
		(net "PWRGD_P5V_AUX")
	)
	(segment
		(start 37.241988 -15.2146)
		(end 33.782 -15.2146)
		(width 0.08382)
		(layer "In2.Cu")
		(net "PWRGD_P5V_AUX")
	)
	(segment
		(start 81.7372 -15.25397)
		(end 81.7372 -15.58798)
		(width 0.08382)
		(layer "In2.Cu")
		(net "PWRGD_P5V_AUX")
	)
	(segment
		(start 62.79769 -12.7)
		(end 61.976 -13.52169)
		(width 0.08382)
		(layer "In2.Cu")
		(net "PWRGD_P5V_AUX")
	)
	(segment
		(start 31.94558 -61.571124)
		(end 31.94558 -59.052206)
		(width 0.08382)
		(layer "In2.Cu")
		(net "PWRGD_P5V_AUX")
	)
	(segment
		(start 25.585928 -58.72226)
		(end 24.18207 -58.140854)
		(width 0.08382)
		(layer "In2.Cu")
		(net "PWRGD_P5V_AUX")
	)
	(segment
		(start 37.325808 -15.13078)
		(end 37.241988 -15.2146)
		(width 0.08382)
		(layer "In2.Cu")
		(net "PWRGD_P5V_AUX")
	)
	(segment
		(start 54.767988 -13.52169)
		(end 54.102254 -14.187424)
		(width 0.08382)
		(layer "In2.Cu")
		(net "PWRGD_P5V_AUX")
	)
	(segment
		(start 30.945328 -56.44642)
		(end 29.737812 -57.653936)
		(width 0.08382)
		(layer "In2.Cu")
		(net "PWRGD_P5V_AUX")
	)
	(segment
		(start 17.6276 -57.0992)
		(end 14.941042 -54.412642)
		(width 0.08382)
		(layer "In2.Cu")
		(net "PWRGD_P5V_AUX")
	)
	(segment
		(start 76.33208 -16.24838)
		(end 73.74001 -13.65631)
		(width 0.08382)
		(layer "In2.Cu")
		(net "PWRGD_P5V_AUX")
	)
	(segment
		(start 81.7372 -15.58798)
		(end 81.0768 -16.24838)
		(width 0.08382)
		(layer "In2.Cu")
		(net "PWRGD_P5V_AUX")
	)
	(segment
		(start 31.210504 -62.3062)
		(end 31.94558 -61.571124)
		(width 0.08382)
		(layer "In2.Cu")
		(net "PWRGD_P5V_AUX")
	)
	(segment
		(start 81.0768 -16.24838)
		(end 76.33208 -16.24838)
		(width 0.08382)
		(layer "In2.Cu")
		(net "PWRGD_P5V_AUX")
	)
	(segment
		(start 64.77 -12.7)
		(end 62.79769 -12.7)
		(width 0.08382)
		(layer "In2.Cu")
		(net "PWRGD_P5V_AUX")
	)
	(segment
		(start 65.72631 -13.65631)
		(end 64.77 -12.7)
		(width 0.08382)
		(layer "In2.Cu")
		(net "PWRGD_P5V_AUX")
	)
	(segment
		(start 54.102254 -14.187424)
		(end 49.475898 -14.187424)
		(width 0.08382)
		(layer "In2.Cu")
		(net "PWRGD_P5V_AUX")
	)
	(segment
		(start 24.18207 -58.140854)
		(end 23.724616 -57.6834)
		(width 0.08382)
		(layer "In2.Cu")
		(net "PWRGD_P5V_AUX")
	)
	(segment
		(start 21.988018 -57.0992)
		(end 17.6276 -57.0992)
		(width 0.08382)
		(layer "In2.Cu")
		(net "PWRGD_P5V_AUX")
	)
	(segment
		(start 12.497054 -59.77509)
		(end 13.268198 -59.77509)
		(width 0.08382)
		(layer "In9.Cu")
		(net "PWRGD_P5V_AUX")
	)
	(segment
		(start 15.368524 -34.2773)
		(end 14.77772 -33.686496)
		(width 0.08382)
		(layer "In9.Cu")
		(net "PWRGD_P5V_AUX")
	)
	(segment
		(start 11.650472 -60.621672)
		(end 12.497054 -59.77509)
		(width 0.08382)
		(layer "In9.Cu")
		(net "PWRGD_P5V_AUX")
	)
	(segment
		(start 11.75385 -16.786098)
		(end 11.94435 -16.595598)
		(width 0.08382)
		(layer "In9.Cu")
		(net "PWRGD_P5V_AUX")
	)
	(segment
		(start 13.268198 -59.77509)
		(end 13.65631 -59.386978)
		(width 0.08382)
		(layer "In9.Cu")
		(net "PWRGD_P5V_AUX")
	)
	(segment
		(start 15.047214 -45.729398)
		(end 14.082522 -46.69409)
		(width 0.08382)
		(layer "In9.Cu")
		(net "PWRGD_P5V_AUX")
	)
	(segment
		(start 10.34542 -99.822)
		(end 9.321546 -99.822)
		(width 0.08382)
		(layer "In9.Cu")
		(net "PWRGD_P5V_AUX")
	)
	(segment
		(start 11.94435 -13.45565)
		(end 13.589 -11.811)
		(width 0.08382)
		(layer "In9.Cu")
		(net "PWRGD_P5V_AUX")
	)
	(segment
		(start 11.75385 -21.26869)
		(end 11.75385 -16.786098)
		(width 0.08382)
		(layer "In9.Cu")
		(net "PWRGD_P5V_AUX")
	)
	(segment
		(start 9.34593 -83.939634)
		(end 9.34593 -82.909664)
		(width 0.08382)
		(layer "In9.Cu")
		(net "PWRGD_P5V_AUX")
	)
	(segment
		(start 15.047214 -42.4307)
		(end 15.047214 -45.729398)
		(width 0.08382)
		(layer "In9.Cu")
		(net "PWRGD_P5V_AUX")
	)
	(segment
		(start 10.70102 -99.4664)
		(end 10.34542 -99.822)
		(width 0.08382)
		(layer "In9.Cu")
		(net "PWRGD_P5V_AUX")
	)
	(segment
		(start 13.589 -11.811)
		(end 13.97 -11.811)
		(width 0.08382)
		(layer "In9.Cu")
		(net "PWRGD_P5V_AUX")
	)
	(segment
		(start 16.060166 -9.669272)
		(end 18.034 -9.669272)
		(width 0.08382)
		(layer "In9.Cu")
		(net "PWRGD_P5V_AUX")
	)
	(segment
		(start 11.650472 -67.546474)
		(end 11.650472 -60.621672)
		(width 0.08382)
		(layer "In9.Cu")
		(net "PWRGD_P5V_AUX")
	)
	(segment
		(start 16.025114 -39.1541)
		(end 16.025114 -34.470594)
		(width 0.08382)
		(layer "In9.Cu")
		(net "PWRGD_P5V_AUX")
	)
	(segment
		(start 18.6944 -11.8618)
		(end 29.21 -11.8618)
		(width 0.08382)
		(layer "In9.Cu")
		(net "PWRGD_P5V_AUX")
	)
	(segment
		(start 17.051274 -40.42664)
		(end 15.047214 -42.4307)
		(width 0.08382)
		(layer "In9.Cu")
		(net "PWRGD_P5V_AUX")
	)
	(segment
		(start 14.082522 -46.69409)
		(end 14.082522 -48.424592)
		(width 0.08382)
		(layer "In9.Cu")
		(net "PWRGD_P5V_AUX")
	)
	(segment
		(start 10.00125 -86.6902)
		(end 10.00125 -84.594954)
		(width 0.08382)
		(layer "In9.Cu")
		(net "PWRGD_P5V_AUX")
	)
	(segment
		(start 17.4244 -40.42664)
		(end 17.15516 -40.1574)
		(width 0.08382)
		(layer "In9.Cu")
		(net "PWRGD_P5V_AUX")
	)
	(segment
		(start 14.08684 -23.60168)
		(end 11.75385 -21.26869)
		(width 0.08382)
		(layer "In9.Cu")
		(net "PWRGD_P5V_AUX")
	)
	(segment
		(start 11.25855 -99.4791)
		(end 11.24585 -99.4664)
		(width 0.08382)
		(layer "In9.Cu")
		(net "PWRGD_P5V_AUX")
	)
	(segment
		(start 13.65631 -56.794908)
		(end 12.197842 -55.33644)
		(width 0.08382)
		(layer "In9.Cu")
		(net "PWRGD_P5V_AUX")
	)
	(segment
		(start 9.321546 -99.822)
		(end 7.1628 -97.663254)
		(width 0.08382)
		(layer "In9.Cu")
		(net "PWRGD_P5V_AUX")
	)
	(segment
		(start 11.30935 -99.4791)
		(end 11.25855 -99.4791)
		(width 0.08382)
		(layer "In9.Cu")
		(net "PWRGD_P5V_AUX")
	)
	(segment
		(start 29.9466 -14.2748)
		(end 30.8864 -15.2146)
		(width 0.08382)
		(layer "In9.Cu")
		(net "PWRGD_P5V_AUX")
	)
	(segment
		(start 29.21 -11.8618)
		(end 29.9466 -12.5984)
		(width 0.08382)
		(layer "In9.Cu")
		(net "PWRGD_P5V_AUX")
	)
	(segment
		(start 14.082522 -48.424592)
		(end 11.671046 -50.836068)
		(width 0.08382)
		(layer "In9.Cu")
		(net "PWRGD_P5V_AUX")
	)
	(segment
		(start 14.224 -11.557)
		(end 14.224 -10.78103)
		(width 0.08382)
		(layer "In9.Cu")
		(net "PWRGD_P5V_AUX")
	)
	(segment
		(start 14.605 -10.40003)
		(end 15.329408 -10.40003)
		(width 0.08382)
		(layer "In9.Cu")
		(net "PWRGD_P5V_AUX")
	)
	(segment
		(start 7.1628 -97.663254)
		(end 7.1628 -89.52865)
		(width 0.08382)
		(layer "In9.Cu")
		(net "PWRGD_P5V_AUX")
	)
	(segment
		(start 30.8864 -15.2146)
		(end 33.782 -15.2146)
		(width 0.08382)
		(layer "In9.Cu")
		(net "PWRGD_P5V_AUX")
	)
	(segment
		(start 13.65631 -59.386978)
		(end 13.65631 -56.794908)
		(width 0.08382)
		(layer "In9.Cu")
		(net "PWRGD_P5V_AUX")
	)
	(segment
		(start 18.161 -11.3284)
		(end 18.6944 -11.8618)
		(width 0.08382)
		(layer "In9.Cu")
		(net "PWRGD_P5V_AUX")
	)
	(segment
		(start 10.00125 -84.594954)
		(end 9.34593 -83.939634)
		(width 0.08382)
		(layer "In9.Cu")
		(net "PWRGD_P5V_AUX")
	)
	(segment
		(start 15.83182 -34.2773)
		(end 15.368524 -34.2773)
		(width 0.08382)
		(layer "In9.Cu")
		(net "PWRGD_P5V_AUX")
	)
	(segment
		(start 14.224 -10.78103)
		(end 14.605 -10.40003)
		(width 0.08382)
		(layer "In9.Cu")
		(net "PWRGD_P5V_AUX")
	)
	(segment
		(start 14.77772 -33.686496)
		(end 14.77772 -29.225494)
		(width 0.08382)
		(layer "In9.Cu")
		(net "PWRGD_P5V_AUX")
	)
	(segment
		(start 12.54633 -79.411576)
		(end 12.54633 -68.442332)
		(width 0.08382)
		(layer "In9.Cu")
		(net "PWRGD_P5V_AUX")
	)
	(segment
		(start 16.025114 -34.470594)
		(end 15.83182 -34.2773)
		(width 0.08382)
		(layer "In9.Cu")
		(net "PWRGD_P5V_AUX")
	)
	(segment
		(start 11.94435 -16.595598)
		(end 11.94435 -13.45565)
		(width 0.08382)
		(layer "In9.Cu")
		(net "PWRGD_P5V_AUX")
	)
	(segment
		(start 11.49731 -80.758284)
		(end 11.49731 -80.460596)
		(width 0.08382)
		(layer "In9.Cu")
		(net "PWRGD_P5V_AUX")
	)
	(segment
		(start 18.034 -9.669272)
		(end 18.161 -9.796272)
		(width 0.08382)
		(layer "In9.Cu")
		(net "PWRGD_P5V_AUX")
	)
	(segment
		(start 11.671046 -54.809644)
		(end 12.197842 -55.33644)
		(width 0.08382)
		(layer "In9.Cu")
		(net "PWRGD_P5V_AUX")
	)
	(segment
		(start 17.15516 -40.1574)
		(end 17.002506 -40.1574)
		(width 0.08382)
		(layer "In9.Cu")
		(net "PWRGD_P5V_AUX")
	)
	(segment
		(start 18.161 -9.796272)
		(end 18.161 -11.3284)
		(width 0.08382)
		(layer "In9.Cu")
		(net "PWRGD_P5V_AUX")
	)
	(segment
		(start 14.77772 -29.225494)
		(end 14.08684 -28.534614)
		(width 0.08382)
		(layer "In9.Cu")
		(net "PWRGD_P5V_AUX")
	)
	(segment
		(start 29.9466 -12.5984)
		(end 29.9466 -14.2748)
		(width 0.08382)
		(layer "In9.Cu")
		(net "PWRGD_P5V_AUX")
	)
	(segment
		(start 16.578072 -39.981632)
		(end 16.025114 -39.1541)
		(width 0.08382)
		(layer "In9.Cu")
		(net "PWRGD_P5V_AUX")
	)
	(segment
		(start 13.97 -11.811)
		(end 14.224 -11.557)
		(width 0.08382)
		(layer "In9.Cu")
		(net "PWRGD_P5V_AUX")
	)
	(segment
		(start 14.08684 -28.534614)
		(end 14.08684 -23.60168)
		(width 0.08382)
		(layer "In9.Cu")
		(net "PWRGD_P5V_AUX")
	)
	(segment
		(start 11.49731 -80.460596)
		(end 12.54633 -79.411576)
		(width 0.08382)
		(layer "In9.Cu")
		(net "PWRGD_P5V_AUX")
	)
	(segment
		(start 17.002506 -40.1574)
		(end 16.578072 -39.981632)
		(width 0.08382)
		(layer "In9.Cu")
		(net "PWRGD_P5V_AUX")
	)
	(segment
		(start 12.54633 -68.442332)
		(end 11.650472 -67.546474)
		(width 0.08382)
		(layer "In9.Cu")
		(net "PWRGD_P5V_AUX")
	)
	(segment
		(start 7.1628 -89.52865)
		(end 10.00125 -86.6902)
		(width 0.08382)
		(layer "In9.Cu")
		(net "PWRGD_P5V_AUX")
	)
	(segment
		(start 11.671046 -50.836068)
		(end 11.671046 -54.809644)
		(width 0.08382)
		(layer "In9.Cu")
		(net "PWRGD_P5V_AUX")
	)
	(segment
		(start 9.34593 -82.909664)
		(end 11.49731 -80.758284)
		(width 0.08382)
		(layer "In9.Cu")
		(net "PWRGD_P5V_AUX")
	)
	(segment
		(start 17.4244 -40.42664)
		(end 17.051274 -40.42664)
		(width 0.08382)
		(layer "In9.Cu")
		(net "PWRGD_P5V_AUX")
	)
	(segment
		(start 11.24585 -99.4664)
		(end 10.70102 -99.4664)
		(width 0.08382)
		(layer "In9.Cu")
		(net "PWRGD_P5V_AUX")
	)
	(segment
		(start 15.329408 -10.40003)
		(end 16.060166 -9.669272)
		(width 0.08382)
		(layer "In9.Cu")
		(net "PWRGD_P5V_AUX")
	)
	(segment
		(start 12.40028 -69.74078)
		(end 12.40028 -68.471034)
		(width 0.11684)
		(layer "F.Cu")
		(net "PWRGD_P3V3_AUX")
	)
	(segment
		(start 11.73988 -70.40118)
		(end 12.40028 -69.74078)
		(width 0.11684)
		(layer "F.Cu")
		(net "PWRGD_P3V3_AUX")
	)
	(segment
		(start 12.02055 -100.1649)
		(end 11.96975 -100.1141)
		(width 0.11684)
		(layer "F.Cu")
		(net "PWRGD_P3V3_AUX")
	)
	(segment
		(start 12.40028 -68.471034)
		(end 13.17625 -67.695064)
		(width 0.11684)
		(layer "F.Cu")
		(net "PWRGD_P3V3_AUX")
	)
	(segment
		(start 11.96975 -100.1141)
		(end 11.30935 -100.1141)
		(width 0.11684)
		(layer "F.Cu")
		(net "PWRGD_P3V3_AUX")
	)
	(segment
		(start 13.17625 -67.695064)
		(end 13.17625 -67.2084)
		(width 0.11684)
		(layer "F.Cu")
		(net "PWRGD_P3V3_AUX")
	)
	(via
		(at 81.47431 -29.103828)
		(size 0.508)
		(drill 0.254)
		(layers "F.Cu" "B.Cu")
		(net "PWRGD_P3V3_AUX")
	)
	(via
		(at 56.896 -18.86585)
		(size 0.508)
		(drill 0.254)
		(layers "F.Cu" "B.Cu")
		(net "PWRGD_P3V3_AUX")
	)
	(via
		(at 11.30935 -100.1141)
		(size 0.508)
		(drill 0.254)
		(layers "F.Cu" "B.Cu")
		(net "PWRGD_P3V3_AUX")
	)
	(via
		(at 11.73988 -70.40118)
		(size 0.508)
		(drill 0.254)
		(layers "F.Cu" "B.Cu")
		(net "PWRGD_P3V3_AUX")
	)
	(segment
		(start 75.692 -21.943314)
		(end 76.761086 -23.0124)
		(width 0.08382)
		(layer "In2.Cu")
		(net "PWRGD_P3V3_AUX")
	)
	(segment
		(start 74.684128 -20.30349)
		(end 75.692 -21.311362)
		(width 0.08382)
		(layer "In2.Cu")
		(net "PWRGD_P3V3_AUX")
	)
	(segment
		(start 68.81749 -20.30349)
		(end 74.684128 -20.30349)
		(width 0.08382)
		(layer "In2.Cu")
		(net "PWRGD_P3V3_AUX")
	)
	(segment
		(start 75.692 -21.311362)
		(end 75.692 -21.943314)
		(width 0.08382)
		(layer "In2.Cu")
		(net "PWRGD_P3V3_AUX")
	)
	(segment
		(start 61.781182 -16.759682)
		(end 62.3697 -17.3482)
		(width 0.08382)
		(layer "In2.Cu")
		(net "PWRGD_P3V3_AUX")
	)
	(segment
		(start 62.3697 -17.3482)
		(end 65.8622 -17.3482)
		(width 0.08382)
		(layer "In2.Cu")
		(net "PWRGD_P3V3_AUX")
	)
	(segment
		(start 76.761086 -23.0124)
		(end 79.273146 -23.0124)
		(width 0.08382)
		(layer "In2.Cu")
		(net "PWRGD_P3V3_AUX")
	)
	(segment
		(start 61.5188 -15.920212)
		(end 61.781182 -16.182594)
		(width 0.08382)
		(layer "In2.Cu")
		(net "PWRGD_P3V3_AUX")
	)
	(segment
		(start 65.8622 -17.3482)
		(end 68.81749 -20.30349)
		(width 0.08382)
		(layer "In2.Cu")
		(net "PWRGD_P3V3_AUX")
	)
	(segment
		(start 56.896 -18.86585)
		(end 56.896 -18.8722)
		(width 0.08382)
		(layer "In2.Cu")
		(net "PWRGD_P3V3_AUX")
	)
	(segment
		(start 79.273146 -23.0124)
		(end 80.2767 -24.015954)
		(width 0.08382)
		(layer "In2.Cu")
		(net "PWRGD_P3V3_AUX")
	)
	(segment
		(start 80.2767 -26.897076)
		(end 80.729074 -27.34945)
		(width 0.08382)
		(layer "In2.Cu")
		(net "PWRGD_P3V3_AUX")
	)
	(segment
		(start 61.781182 -16.182594)
		(end 61.781182 -16.759682)
		(width 0.08382)
		(layer "In2.Cu")
		(net "PWRGD_P3V3_AUX")
	)
	(segment
		(start 59.847988 -15.920212)
		(end 61.5188 -15.920212)
		(width 0.08382)
		(layer "In2.Cu")
		(net "PWRGD_P3V3_AUX")
	)
	(segment
		(start 80.2767 -24.015954)
		(end 80.2767 -26.897076)
		(width 0.08382)
		(layer "In2.Cu")
		(net "PWRGD_P3V3_AUX")
	)
	(segment
		(start 80.729074 -27.34945)
		(end 80.729074 -28.358592)
		(width 0.08382)
		(layer "In2.Cu")
		(net "PWRGD_P3V3_AUX")
	)
	(segment
		(start 56.896 -18.8722)
		(end 59.847988 -15.920212)
		(width 0.08382)
		(layer "In2.Cu")
		(net "PWRGD_P3V3_AUX")
	)
	(segment
		(start 80.729074 -28.358592)
		(end 81.47431 -29.103828)
		(width 0.08382)
		(layer "In2.Cu")
		(net "PWRGD_P3V3_AUX")
	)
	(segment
		(start 14.290802 -34.971482)
		(end 14.5288 -35.54603)
		(width 0.10668)
		(layer "In7.Cu")
		(net "PWRGD_P3V3_AUX")
	)
	(segment
		(start 14.5288 -45.304202)
		(end 12.8524 -46.980602)
		(width 0.10668)
		(layer "In7.Cu")
		(net "PWRGD_P3V3_AUX")
	)
	(segment
		(start 14.06652 -28.071826)
		(end 13.75664 -28.381706)
		(width 0.10668)
		(layer "In7.Cu")
		(net "PWRGD_P3V3_AUX")
	)
	(segment
		(start 11.6586 -53.26888)
		(end 11.6586 -55.447438)
		(width 0.10668)
		(layer "In7.Cu")
		(net "PWRGD_P3V3_AUX")
	)
	(segment
		(start 13.75664 -28.381706)
		(end 13.75664 -33.361122)
		(width 0.10668)
		(layer "In7.Cu")
		(net "PWRGD_P3V3_AUX")
	)
	(segment
		(start 55.747666 -17.0434)
		(end 53.6194 -17.0434)
		(width 0.10668)
		(layer "In7.Cu")
		(net "PWRGD_P3V3_AUX")
	)
	(segment
		(start 28.388564 -12.937236)
		(end 27.345386 -13.980414)
		(width 0.10668)
		(layer "In7.Cu")
		(net "PWRGD_P3V3_AUX")
	)
	(segment
		(start 36.71316 -14.20876)
		(end 35.078924 -14.20876)
		(width 0.10668)
		(layer "In7.Cu")
		(net "PWRGD_P3V3_AUX")
	)
	(segment
		(start 24.641048 -14.605)
		(end 18.3134 -14.605)
		(width 0.10668)
		(layer "In7.Cu")
		(net "PWRGD_P3V3_AUX")
	)
	(segment
		(start 12.54252 -58.062622)
		(end 11.673586 -58.931556)
		(width 0.10668)
		(layer "In7.Cu")
		(net "PWRGD_P3V3_AUX")
	)
	(segment
		(start 12.54252 -56.331358)
		(end 12.54252 -58.062622)
		(width 0.10668)
		(layer "In7.Cu")
		(net "PWRGD_P3V3_AUX")
	)
	(segment
		(start 11.673586 -58.931556)
		(end 11.673586 -66.994786)
		(width 0.10668)
		(layer "In7.Cu")
		(net "PWRGD_P3V3_AUX")
	)
	(segment
		(start 35.078924 -14.20876)
		(end 33.8074 -12.937236)
		(width 0.10668)
		(layer "In7.Cu")
		(net "PWRGD_P3V3_AUX")
	)
	(segment
		(start 18.3134 -14.605)
		(end 16.9164 -16.002)
		(width 0.10668)
		(layer "In7.Cu")
		(net "PWRGD_P3V3_AUX")
	)
	(segment
		(start 49.293526 -15.84198)
		(end 38.34638 -15.84198)
		(width 0.10668)
		(layer "In7.Cu")
		(net "PWRGD_P3V3_AUX")
	)
	(segment
		(start 33.8074 -12.937236)
		(end 28.388564 -12.937236)
		(width 0.10668)
		(layer "In7.Cu")
		(net "PWRGD_P3V3_AUX")
	)
	(segment
		(start 16.9164 -17.273016)
		(end 15.713964 -18.475452)
		(width 0.10668)
		(layer "In7.Cu")
		(net "PWRGD_P3V3_AUX")
	)
	(segment
		(start 14.5288 -35.54603)
		(end 14.5288 -45.304202)
		(width 0.10668)
		(layer "In7.Cu")
		(net "PWRGD_P3V3_AUX")
	)
	(segment
		(start 51.079146 -17.6276)
		(end 49.293526 -15.84198)
		(width 0.10668)
		(layer "In7.Cu")
		(net "PWRGD_P3V3_AUX")
	)
	(segment
		(start 12.8524 -46.980602)
		(end 12.8524 -48.95469)
		(width 0.10668)
		(layer "In7.Cu")
		(net "PWRGD_P3V3_AUX")
	)
	(segment
		(start 53.0352 -17.6276)
		(end 51.079146 -17.6276)
		(width 0.10668)
		(layer "In7.Cu")
		(net "PWRGD_P3V3_AUX")
	)
	(segment
		(start 13.75664 -33.361122)
		(end 14.290294 -34.651442)
		(width 0.10668)
		(layer "In7.Cu")
		(net "PWRGD_P3V3_AUX")
	)
	(segment
		(start 11.4808 -53.09108)
		(end 11.6586 -53.26888)
		(width 0.10668)
		(layer "In7.Cu")
		(net "PWRGD_P3V3_AUX")
	)
	(segment
		(start 15.713964 -19.41576)
		(end 14.06652 -21.063204)
		(width 0.10668)
		(layer "In7.Cu")
		(net "PWRGD_P3V3_AUX")
	)
	(segment
		(start 27.345386 -13.980414)
		(end 25.265634 -13.980414)
		(width 0.10668)
		(layer "In7.Cu")
		(net "PWRGD_P3V3_AUX")
	)
	(segment
		(start 14.06652 -21.063204)
		(end 14.06652 -28.071826)
		(width 0.10668)
		(layer "In7.Cu")
		(net "PWRGD_P3V3_AUX")
	)
	(segment
		(start 16.9164 -16.002)
		(end 16.9164 -17.273016)
		(width 0.10668)
		(layer "In7.Cu")
		(net "PWRGD_P3V3_AUX")
	)
	(segment
		(start 53.6194 -17.0434)
		(end 53.0352 -17.6276)
		(width 0.10668)
		(layer "In7.Cu")
		(net "PWRGD_P3V3_AUX")
	)
	(segment
		(start 11.673586 -66.994786)
		(end 11.73988 -67.06108)
		(width 0.10668)
		(layer "In7.Cu")
		(net "PWRGD_P3V3_AUX")
	)
	(segment
		(start 25.265634 -13.980414)
		(end 24.641048 -14.605)
		(width 0.10668)
		(layer "In7.Cu")
		(net "PWRGD_P3V3_AUX")
	)
	(segment
		(start 11.4808 -50.32629)
		(end 11.4808 -53.09108)
		(width 0.10668)
		(layer "In7.Cu")
		(net "PWRGD_P3V3_AUX")
	)
	(segment
		(start 14.290294 -34.651442)
		(end 14.290802 -34.971482)
		(width 0.10668)
		(layer "In7.Cu")
		(net "PWRGD_P3V3_AUX")
	)
	(segment
		(start 38.34638 -15.84198)
		(end 36.71316 -14.20876)
		(width 0.10668)
		(layer "In7.Cu")
		(net "PWRGD_P3V3_AUX")
	)
	(segment
		(start 12.8524 -48.95469)
		(end 11.4808 -50.32629)
		(width 0.10668)
		(layer "In7.Cu")
		(net "PWRGD_P3V3_AUX")
	)
	(segment
		(start 56.896 -18.191734)
		(end 55.747666 -17.0434)
		(width 0.10668)
		(layer "In7.Cu")
		(net "PWRGD_P3V3_AUX")
	)
	(segment
		(start 56.896 -18.86585)
		(end 56.896 -18.191734)
		(width 0.10668)
		(layer "In7.Cu")
		(net "PWRGD_P3V3_AUX")
	)
	(segment
		(start 11.73988 -67.06108)
		(end 11.73988 -70.40118)
		(width 0.10668)
		(layer "In7.Cu")
		(net "PWRGD_P3V3_AUX")
	)
	(segment
		(start 15.713964 -18.475452)
		(end 15.713964 -19.41576)
		(width 0.10668)
		(layer "In7.Cu")
		(net "PWRGD_P3V3_AUX")
	)
	(segment
		(start 11.6586 -55.447438)
		(end 12.54252 -56.331358)
		(width 0.10668)
		(layer "In7.Cu")
		(net "PWRGD_P3V3_AUX")
	)
	(segment
		(start 11.72464 -75.626722)
		(end 11.72464 -70.41642)
		(width 0.08382)
		(layer "In9.Cu")
		(net "PWRGD_P3V3_AUX")
	)
	(segment
		(start 9.017 -81.229454)
		(end 9.559798 -80.686656)
		(width 0.08382)
		(layer "In9.Cu")
		(net "PWRGD_P3V3_AUX")
	)
	(segment
		(start 8.247126 -88.00211)
		(end 9.68883 -86.560406)
		(width 0.08382)
		(layer "In9.Cu")
		(net "PWRGD_P3V3_AUX")
	)
	(segment
		(start 11.138408 -79.361538)
		(end 11.26998 -79.229966)
		(width 0.08382)
		(layer "In9.Cu")
		(net "PWRGD_P3V3_AUX")
	)
	(segment
		(start 5.01142 -102.09022)
		(end 5.01142 -88.19134)
		(width 0.08382)
		(layer "In9.Cu")
		(net "PWRGD_P3V3_AUX")
	)
	(segment
		(start 7.365492 -88.00211)
		(end 8.247126 -88.00211)
		(width 0.08382)
		(layer "In9.Cu")
		(net "PWRGD_P3V3_AUX")
	)
	(segment
		(start 11.30935 -100.1141)
		(end 11.25855 -100.1649)
		(width 0.08382)
		(layer "In9.Cu")
		(net "PWRGD_P3V3_AUX")
	)
	(segment
		(start 9.017 -84.052664)
		(end 9.017 -81.229454)
		(width 0.08382)
		(layer "In9.Cu")
		(net "PWRGD_P3V3_AUX")
	)
	(segment
		(start 11.26998 -76.081382)
		(end 11.72464 -75.626722)
		(width 0.08382)
		(layer "In9.Cu")
		(net "PWRGD_P3V3_AUX")
	)
	(segment
		(start 11.061954 -100.1649)
		(end 8.737854 -102.489)
		(width 0.08382)
		(layer "In9.Cu")
		(net "PWRGD_P3V3_AUX")
	)
	(segment
		(start 11.26998 -79.229966)
		(end 11.26998 -76.081382)
		(width 0.08382)
		(layer "In9.Cu")
		(net "PWRGD_P3V3_AUX")
	)
	(segment
		(start 5.71754 -87.48522)
		(end 6.848602 -87.48522)
		(width 0.08382)
		(layer "In9.Cu")
		(net "PWRGD_P3V3_AUX")
	)
	(segment
		(start 9.68883 -84.724494)
		(end 9.017 -84.052664)
		(width 0.08382)
		(layer "In9.Cu")
		(net "PWRGD_P3V3_AUX")
	)
	(segment
		(start 6.848602 -87.48522)
		(end 7.365492 -88.00211)
		(width 0.08382)
		(layer "In9.Cu")
		(net "PWRGD_P3V3_AUX")
	)
	(segment
		(start 11.72464 -70.41642)
		(end 11.73988 -70.40118)
		(width 0.08382)
		(layer "In9.Cu")
		(net "PWRGD_P3V3_AUX")
	)
	(segment
		(start 9.68883 -86.560406)
		(end 9.68883 -84.724494)
		(width 0.08382)
		(layer "In9.Cu")
		(net "PWRGD_P3V3_AUX")
	)
	(segment
		(start 5.4102 -102.489)
		(end 5.01142 -102.09022)
		(width 0.08382)
		(layer "In9.Cu")
		(net "PWRGD_P3V3_AUX")
	)
	(segment
		(start 11.25855 -100.1649)
		(end 11.061954 -100.1649)
		(width 0.08382)
		(layer "In9.Cu")
		(net "PWRGD_P3V3_AUX")
	)
	(segment
		(start 5.01142 -88.19134)
		(end 5.71754 -87.48522)
		(width 0.08382)
		(layer "In9.Cu")
		(net "PWRGD_P3V3_AUX")
	)
	(segment
		(start 11.128248 -79.372206)
		(end 11.138408 -79.361538)
		(width 0.08382)
		(layer "In9.Cu")
		(net "PWRGD_P3V3_AUX")
	)
	(segment
		(start 9.81329 -80.686656)
		(end 11.128248 -79.372206)
		(width 0.08382)
		(layer "In9.Cu")
		(net "PWRGD_P3V3_AUX")
	)
	(segment
		(start 8.737854 -102.489)
		(end 5.4102 -102.489)
		(width 0.08382)
		(layer "In9.Cu")
		(net "PWRGD_P3V3_AUX")
	)
	(segment
		(start 9.559798 -80.686656)
		(end 9.81329 -80.686656)
		(width 0.08382)
		(layer "In9.Cu")
		(net "PWRGD_P3V3_AUX")
	)
	(via
		(at 65.151 -25.019)
		(size 0.6604)
		(drill 0.3302)
		(layers "F.Cu" "B.Cu")
		(net "PWRGD_P2V5_AUX")
	)
	(via
		(at 57.629298 -29.793438)
		(size 0.508)
		(drill 0.254)
		(layers "F.Cu" "B.Cu")
		(net "PWRGD_P2V5_AUX")
	)
	(via
		(at 13.40231 -99.1108)
		(size 0.508)
		(drill 0.254)
		(layers "F.Cu" "B.Cu")
		(net "PWRGD_P2V5_AUX")
	)
	(via
		(at 34.126932 -58.437526)
		(size 0.508)
		(drill 0.254)
		(layers "F.Cu" "B.Cu")
		(net "PWRGD_P2V5_AUX")
	)
	(segment
		(start 60.927234 -25.781)
		(end 62.6618 -25.781)
		(width 0.11684)
		(layer "B.Cu")
		(net "PWRGD_P2V5_AUX")
	)
	(segment
		(start 59.52617 -28.75407)
		(end 59.52617 -27.52217)
		(width 0.11684)
		(layer "B.Cu")
		(net "PWRGD_P2V5_AUX")
	)
	(segment
		(start 63.5508 -24.892)
		(end 64.6684 -24.892)
		(width 0.11684)
		(layer "B.Cu")
		(net "PWRGD_P2V5_AUX")
	)
	(segment
		(start 73.9394 -28.3464)
		(end 73.025 -29.2608)
		(width 0.11684)
		(layer "B.Cu")
		(net "PWRGD_P2V5_AUX")
	)
	(segment
		(start 13.40231 -99.1108)
		(end 13.32611 -99.0346)
		(width 0.11684)
		(layer "B.Cu")
		(net "PWRGD_P2V5_AUX")
	)
	(segment
		(start 72.4662 -32.4104)
		(end 72.4662 -33.6042)
		(width 0.11684)
		(layer "B.Cu")
		(net "PWRGD_P2V5_AUX")
	)
	(segment
		(start 60.58662 -25.359614)
		(end 60.58662 -25.440386)
		(width 0.11684)
		(layer "B.Cu")
		(net "PWRGD_P2V5_AUX")
	)
	(segment
		(start 72.818498 -33.956498)
		(end 78.698852 -33.956498)
		(width 0.11684)
		(layer "B.Cu")
		(net "PWRGD_P2V5_AUX")
	)
	(segment
		(start 11.91895 -98.9076)
		(end 11.91895 -98.552)
		(width 0.11684)
		(layer "B.Cu")
		(net "PWRGD_P2V5_AUX")
	)
	(segment
		(start 73.545954 -25.5778)
		(end 73.9394 -25.971246)
		(width 0.11684)
		(layer "B.Cu")
		(net "PWRGD_P2V5_AUX")
	)
	(segment
		(start 58.94324 -29.337)
		(end 59.52617 -28.75407)
		(width 0.11684)
		(layer "B.Cu")
		(net "PWRGD_P2V5_AUX")
	)
	(segment
		(start 65.60058 -24.56942)
		(end 66.58864 -24.56942)
		(width 0.11684)
		(layer "B.Cu")
		(net "PWRGD_P2V5_AUX")
	)
	(segment
		(start 57.629298 -29.793438)
		(end 57.837324 -29.585412)
		(width 0.11684)
		(layer "B.Cu")
		(net "PWRGD_P2V5_AUX")
	)
	(segment
		(start 73.025 -29.9212)
		(end 72.63384 -30.31236)
		(width 0.11684)
		(layer "B.Cu")
		(net "PWRGD_P2V5_AUX")
	)
	(segment
		(start 67.222878 -26.342848)
		(end 67.551046 -26.342848)
		(width 0.11684)
		(layer "B.Cu")
		(net "PWRGD_P2V5_AUX")
	)
	(segment
		(start 60.58662 -25.440386)
		(end 60.927234 -25.781)
		(width 0.11684)
		(layer "B.Cu")
		(net "PWRGD_P2V5_AUX")
	)
	(segment
		(start 59.1566 -26.223976)
		(end 59.47537 -25.905206)
		(width 0.11684)
		(layer "B.Cu")
		(net "PWRGD_P2V5_AUX")
	)
	(segment
		(start 66.931286 -26.14803)
		(end 67.222878 -26.342848)
		(width 0.11684)
		(layer "B.Cu")
		(net "PWRGD_P2V5_AUX")
	)
	(segment
		(start 58.437018 -29.337)
		(end 58.94324 -29.337)
		(width 0.11684)
		(layer "B.Cu")
		(net "PWRGD_P2V5_AUX")
	)
	(segment
		(start 72.56272 -25.5778)
		(end 73.545954 -25.5778)
		(width 0.11684)
		(layer "B.Cu")
		(net "PWRGD_P2V5_AUX")
	)
	(segment
		(start 72.4662 -33.6042)
		(end 72.818498 -33.956498)
		(width 0.11684)
		(layer "B.Cu")
		(net "PWRGD_P2V5_AUX")
	)
	(segment
		(start 62.6618 -25.781)
		(end 63.5508 -24.892)
		(width 0.11684)
		(layer "B.Cu")
		(net "PWRGD_P2V5_AUX")
	)
	(segment
		(start 72.009762 -25.024842)
		(end 72.56272 -25.5778)
		(width 0.11684)
		(layer "B.Cu")
		(net "PWRGD_P2V5_AUX")
	)
	(segment
		(start 66.79946 -25.82926)
		(end 66.931286 -26.14803)
		(width 0.11684)
		(layer "B.Cu")
		(net "PWRGD_P2V5_AUX")
	)
	(segment
		(start 73.025 -29.2608)
		(end 73.025 -29.9212)
		(width 0.11684)
		(layer "B.Cu")
		(net "PWRGD_P2V5_AUX")
	)
	(segment
		(start 64.7954 -25.019)
		(end 65.151 -25.019)
		(width 0.11684)
		(layer "B.Cu")
		(net "PWRGD_P2V5_AUX")
	)
	(segment
		(start 59.47537 -25.45969)
		(end 59.863736 -25.071324)
		(width 0.11684)
		(layer "B.Cu")
		(net "PWRGD_P2V5_AUX")
	)
	(segment
		(start 78.698852 -33.956498)
		(end 78.7908 -33.86455)
		(width 0.11684)
		(layer "B.Cu")
		(net "PWRGD_P2V5_AUX")
	)
	(segment
		(start 67.551046 -26.342848)
		(end 68.869052 -25.024842)
		(width 0.11684)
		(layer "B.Cu")
		(net "PWRGD_P2V5_AUX")
	)
	(segment
		(start 79.176118 -33.504632)
		(end 79.315818 -33.504632)
		(width 0.11684)
		(layer "B.Cu")
		(net "PWRGD_P2V5_AUX")
	)
	(segment
		(start 66.79946 -24.78024)
		(end 66.79946 -25.82926)
		(width 0.11684)
		(layer "B.Cu")
		(net "PWRGD_P2V5_AUX")
	)
	(segment
		(start 64.6684 -24.892)
		(end 64.7954 -25.019)
		(width 0.11684)
		(layer "B.Cu")
		(net "PWRGD_P2V5_AUX")
	)
	(segment
		(start 66.58864 -24.56942)
		(end 66.79946 -24.78024)
		(width 0.11684)
		(layer "B.Cu")
		(net "PWRGD_P2V5_AUX")
	)
	(segment
		(start 65.151 -25.019)
		(end 65.60058 -24.56942)
		(width 0.11684)
		(layer "B.Cu")
		(net "PWRGD_P2V5_AUX")
	)
	(segment
		(start 59.52617 -27.52217)
		(end 59.1566 -27.1526)
		(width 0.11684)
		(layer "B.Cu")
		(net "PWRGD_P2V5_AUX")
	)
	(segment
		(start 68.869052 -25.024842)
		(end 72.009762 -25.024842)
		(width 0.11684)
		(layer "B.Cu")
		(net "PWRGD_P2V5_AUX")
	)
	(segment
		(start 79.315818 -33.504632)
		(end 79.756 -33.06445)
		(width 0.11684)
		(layer "B.Cu")
		(net "PWRGD_P2V5_AUX")
	)
	(segment
		(start 59.1566 -27.1526)
		(end 59.1566 -26.223976)
		(width 0.11684)
		(layer "B.Cu")
		(net "PWRGD_P2V5_AUX")
	)
	(segment
		(start 73.9394 -25.971246)
		(end 73.9394 -28.3464)
		(width 0.11684)
		(layer "B.Cu")
		(net "PWRGD_P2V5_AUX")
	)
	(segment
		(start 78.7908 -33.86455)
		(end 78.8162 -33.86455)
		(width 0.11684)
		(layer "B.Cu")
		(net "PWRGD_P2V5_AUX")
	)
	(segment
		(start 78.8162 -33.86455)
		(end 79.176118 -33.504632)
		(width 0.11684)
		(layer "B.Cu")
		(net "PWRGD_P2V5_AUX")
	)
	(segment
		(start 12.04595 -99.0346)
		(end 11.91895 -98.9076)
		(width 0.11684)
		(layer "B.Cu")
		(net "PWRGD_P2V5_AUX")
	)
	(segment
		(start 72.63384 -32.24276)
		(end 72.4662 -32.4104)
		(width 0.11684)
		(layer "B.Cu")
		(net "PWRGD_P2V5_AUX")
	)
	(segment
		(start 13.32611 -99.0346)
		(end 12.04595 -99.0346)
		(width 0.11684)
		(layer "B.Cu")
		(net "PWRGD_P2V5_AUX")
	)
	(segment
		(start 59.47537 -25.905206)
		(end 59.47537 -25.45969)
		(width 0.11684)
		(layer "B.Cu")
		(net "PWRGD_P2V5_AUX")
	)
	(segment
		(start 57.837324 -29.585412)
		(end 58.437018 -29.337)
		(width 0.11684)
		(layer "B.Cu")
		(net "PWRGD_P2V5_AUX")
	)
	(segment
		(start 59.863736 -25.071324)
		(end 60.29833 -25.071324)
		(width 0.11684)
		(layer "B.Cu")
		(net "PWRGD_P2V5_AUX")
	)
	(segment
		(start 60.29833 -25.071324)
		(end 60.58662 -25.359614)
		(width 0.11684)
		(layer "B.Cu")
		(net "PWRGD_P2V5_AUX")
	)
	(segment
		(start 72.63384 -30.31236)
		(end 72.63384 -32.24276)
		(width 0.11684)
		(layer "B.Cu")
		(net "PWRGD_P2V5_AUX")
	)
	(segment
		(start 53.93055 -36.99129)
		(end 45.103034 -36.99129)
		(width 0.10668)
		(layer "In4.Cu")
		(net "PWRGD_P2V5_AUX")
	)
	(segment
		(start 58.04662 -34.47288)
		(end 55.17642 -34.47288)
		(width 0.10668)
		(layer "In4.Cu")
		(net "PWRGD_P2V5_AUX")
	)
	(segment
		(start 54.27472 -35.37458)
		(end 54.27472 -36.64712)
		(width 0.10668)
		(layer "In4.Cu")
		(net "PWRGD_P2V5_AUX")
	)
	(segment
		(start 42.7736 -38.914324)
		(end 42.7736 -40.284654)
		(width 0.10668)
		(layer "In4.Cu")
		(net "PWRGD_P2V5_AUX")
	)
	(segment
		(start 45.103034 -36.99129)
		(end 44.136564 -37.507926)
		(width 0.10668)
		(layer "In4.Cu")
		(net "PWRGD_P2V5_AUX")
	)
	(segment
		(start 33.21431 -57.801764)
		(end 33.850072 -58.437526)
		(width 0.10668)
		(layer "In4.Cu")
		(net "PWRGD_P2V5_AUX")
	)
	(segment
		(start 33.0708 -56.369712)
		(end 33.0708 -57.014364)
		(width 0.10668)
		(layer "In4.Cu")
		(net "PWRGD_P2V5_AUX")
	)
	(segment
		(start 55.17642 -34.47288)
		(end 54.27472 -35.37458)
		(width 0.10668)
		(layer "In4.Cu")
		(net "PWRGD_P2V5_AUX")
	)
	(segment
		(start 44.136564 -37.507926)
		(end 44.048934 -37.63899)
		(width 0.10668)
		(layer "In4.Cu")
		(net "PWRGD_P2V5_AUX")
	)
	(segment
		(start 35.7632 -45.821854)
		(end 35.211004 -46.37405)
		(width 0.10668)
		(layer "In4.Cu")
		(net "PWRGD_P2V5_AUX")
	)
	(segment
		(start 37.305488 -43.8658)
		(end 35.7632 -45.408088)
		(width 0.10668)
		(layer "In4.Cu")
		(net "PWRGD_P2V5_AUX")
	)
	(segment
		(start 35.211004 -46.37405)
		(end 35.211004 -47.037498)
		(width 0.10668)
		(layer "In4.Cu")
		(net "PWRGD_P2V5_AUX")
	)
	(segment
		(start 57.84088 -30.00502)
		(end 57.84088 -30.518862)
		(width 0.10668)
		(layer "In4.Cu")
		(net "PWRGD_P2V5_AUX")
	)
	(segment
		(start 44.048934 -37.63899)
		(end 42.7736 -38.914324)
		(width 0.10668)
		(layer "In4.Cu")
		(net "PWRGD_P2V5_AUX")
	)
	(segment
		(start 33.21431 -57.157874)
		(end 33.21431 -57.801764)
		(width 0.10668)
		(layer "In4.Cu")
		(net "PWRGD_P2V5_AUX")
	)
	(segment
		(start 33.0708 -57.014364)
		(end 33.21431 -57.157874)
		(width 0.10668)
		(layer "In4.Cu")
		(net "PWRGD_P2V5_AUX")
	)
	(segment
		(start 38.831774 -44.22648)
		(end 38.481508 -44.22648)
		(width 0.10668)
		(layer "In4.Cu")
		(net "PWRGD_P2V5_AUX")
	)
	(segment
		(start 33.782 -50.487834)
		(end 33.782 -54.653434)
		(width 0.10668)
		(layer "In4.Cu")
		(net "PWRGD_P2V5_AUX")
	)
	(segment
		(start 58.105548 -30.78353)
		(end 58.105548 -32.0294)
		(width 0.10668)
		(layer "In4.Cu")
		(net "PWRGD_P2V5_AUX")
	)
	(segment
		(start 57.84088 -30.518862)
		(end 58.105548 -30.78353)
		(width 0.10668)
		(layer "In4.Cu")
		(net "PWRGD_P2V5_AUX")
	)
	(segment
		(start 35.211004 -47.037498)
		(end 33.782 -50.487834)
		(width 0.10668)
		(layer "In4.Cu")
		(net "PWRGD_P2V5_AUX")
	)
	(segment
		(start 42.7736 -40.284654)
		(end 38.831774 -44.22648)
		(width 0.10668)
		(layer "In4.Cu")
		(net "PWRGD_P2V5_AUX")
	)
	(segment
		(start 58.726324 -32.650176)
		(end 58.726324 -33.793176)
		(width 0.10668)
		(layer "In4.Cu")
		(net "PWRGD_P2V5_AUX")
	)
	(segment
		(start 58.726324 -33.793176)
		(end 58.04662 -34.47288)
		(width 0.10668)
		(layer "In4.Cu")
		(net "PWRGD_P2V5_AUX")
	)
	(segment
		(start 35.7632 -45.408088)
		(end 35.7632 -45.821854)
		(width 0.10668)
		(layer "In4.Cu")
		(net "PWRGD_P2V5_AUX")
	)
	(segment
		(start 57.629298 -29.793438)
		(end 57.84088 -30.00502)
		(width 0.10668)
		(layer "In4.Cu")
		(net "PWRGD_P2V5_AUX")
	)
	(segment
		(start 33.782 -54.653434)
		(end 33.0708 -56.369712)
		(width 0.10668)
		(layer "In4.Cu")
		(net "PWRGD_P2V5_AUX")
	)
	(segment
		(start 58.105548 -32.0294)
		(end 58.726324 -32.650176)
		(width 0.10668)
		(layer "In4.Cu")
		(net "PWRGD_P2V5_AUX")
	)
	(segment
		(start 33.850072 -58.437526)
		(end 34.126932 -58.437526)
		(width 0.10668)
		(layer "In4.Cu")
		(net "PWRGD_P2V5_AUX")
	)
	(segment
		(start 54.27472 -36.64712)
		(end 53.93055 -36.99129)
		(width 0.10668)
		(layer "In4.Cu")
		(net "PWRGD_P2V5_AUX")
	)
	(segment
		(start 38.481508 -44.22648)
		(end 38.120828 -43.8658)
		(width 0.10668)
		(layer "In4.Cu")
		(net "PWRGD_P2V5_AUX")
	)
	(segment
		(start 38.120828 -43.8658)
		(end 37.305488 -43.8658)
		(width 0.10668)
		(layer "In4.Cu")
		(net "PWRGD_P2V5_AUX")
	)
	(segment
		(start 12.5476 -90.6018)
		(end 12.5476 -89.189306)
		(width 0.08382)
		(layer "In9.Cu")
		(net "PWRGD_P2V5_AUX")
	)
	(segment
		(start 12.70254 -90.75674)
		(end 12.5476 -90.6018)
		(width 0.08382)
		(layer "In9.Cu")
		(net "PWRGD_P2V5_AUX")
	)
	(segment
		(start 13.40231 -99.1108)
		(end 13.40231 -98.08591)
		(width 0.08382)
		(layer "In9.Cu")
		(net "PWRGD_P2V5_AUX")
	)
	(segment
		(start 32.916368 -61.321188)
		(end 34.2138 -59.379866)
		(width 0.08382)
		(layer "In9.Cu")
		(net "PWRGD_P2V5_AUX")
	)
	(segment
		(start 28.662884 -75.858116)
		(end 28.911296 -75.258422)
		(width 0.08382)
		(layer "In9.Cu")
		(net "PWRGD_P2V5_AUX")
	)
	(segment
		(start 32.386778 -68.446904)
		(end 33.15335 -67.680332)
		(width 0.08382)
		(layer "In9.Cu")
		(net "PWRGD_P2V5_AUX")
	)
	(segment
		(start 13.40231 -98.08591)
		(end 12.70254 -97.38614)
		(width 0.08382)
		(layer "In9.Cu")
		(net "PWRGD_P2V5_AUX")
	)
	(segment
		(start 28.911296 -73.531222)
		(end 31.25851 -71.184008)
		(width 0.08382)
		(layer "In9.Cu")
		(net "PWRGD_P2V5_AUX")
	)
	(segment
		(start 15.7988 -83.9978)
		(end 21.16455 -83.9978)
		(width 0.08382)
		(layer "In9.Cu")
		(net "PWRGD_P2V5_AUX")
	)
	(segment
		(start 31.25851 -69.290184)
		(end 32.10179 -68.446904)
		(width 0.08382)
		(layer "In9.Cu")
		(net "PWRGD_P2V5_AUX")
	)
	(segment
		(start 26.61031 -82.813144)
		(end 26.61031 -80.221836)
		(width 0.08382)
		(layer "In9.Cu")
		(net "PWRGD_P2V5_AUX")
	)
	(segment
		(start 31.25851 -71.184008)
		(end 31.25851 -69.290184)
		(width 0.08382)
		(layer "In9.Cu")
		(net "PWRGD_P2V5_AUX")
	)
	(segment
		(start 33.15335 -67.680332)
		(end 33.15335 -67.308476)
		(width 0.08382)
		(layer "In9.Cu")
		(net "PWRGD_P2V5_AUX")
	)
	(segment
		(start 27.32278 -77.208634)
		(end 27.32278 -77.19822)
		(width 0.08382)
		(layer "In9.Cu")
		(net "PWRGD_P2V5_AUX")
	)
	(segment
		(start 28.911296 -75.258422)
		(end 28.911296 -73.531222)
		(width 0.08382)
		(layer "In9.Cu")
		(net "PWRGD_P2V5_AUX")
	)
	(segment
		(start 33.15335 -67.308476)
		(end 32.890968 -67.046094)
		(width 0.08382)
		(layer "In9.Cu")
		(net "PWRGD_P2V5_AUX")
	)
	(segment
		(start 32.890968 -66.991992)
		(end 33.207706 -66.675254)
		(width 0.08382)
		(layer "In9.Cu")
		(net "PWRGD_P2V5_AUX")
	)
	(segment
		(start 33.207706 -64.83096)
		(end 32.916368 -64.539622)
		(width 0.08382)
		(layer "In9.Cu")
		(net "PWRGD_P2V5_AUX")
	)
	(segment
		(start 27.2034 -77.328014)
		(end 27.32278 -77.208634)
		(width 0.08382)
		(layer "In9.Cu")
		(net "PWRGD_P2V5_AUX")
	)
	(segment
		(start 12.70254 -97.38614)
		(end 12.70254 -90.75674)
		(width 0.08382)
		(layer "In9.Cu")
		(net "PWRGD_P2V5_AUX")
	)
	(segment
		(start 32.916368 -64.539622)
		(end 32.916368 -61.321188)
		(width 0.08382)
		(layer "In9.Cu")
		(net "PWRGD_P2V5_AUX")
	)
	(segment
		(start 27.32278 -77.19822)
		(end 28.662884 -75.858116)
		(width 0.08382)
		(layer "In9.Cu")
		(net "PWRGD_P2V5_AUX")
	)
	(segment
		(start 34.2138 -58.524394)
		(end 34.126932 -58.437526)
		(width 0.08382)
		(layer "In9.Cu")
		(net "PWRGD_P2V5_AUX")
	)
	(segment
		(start 26.61031 -80.221836)
		(end 27.2034 -79.628746)
		(width 0.08382)
		(layer "In9.Cu")
		(net "PWRGD_P2V5_AUX")
	)
	(segment
		(start 21.16455 -83.9978)
		(end 21.76907 -84.60232)
		(width 0.08382)
		(layer "In9.Cu")
		(net "PWRGD_P2V5_AUX")
	)
	(segment
		(start 25.50414 -84.60232)
		(end 26.10104 -84.00542)
		(width 0.08382)
		(layer "In9.Cu")
		(net "PWRGD_P2V5_AUX")
	)
	(segment
		(start 21.76907 -84.60232)
		(end 25.50414 -84.60232)
		(width 0.08382)
		(layer "In9.Cu")
		(net "PWRGD_P2V5_AUX")
	)
	(segment
		(start 34.2138 -59.379866)
		(end 34.2138 -58.524394)
		(width 0.08382)
		(layer "In9.Cu")
		(net "PWRGD_P2V5_AUX")
	)
	(segment
		(start 32.10179 -68.446904)
		(end 32.386778 -68.446904)
		(width 0.08382)
		(layer "In9.Cu")
		(net "PWRGD_P2V5_AUX")
	)
	(segment
		(start 13.11402 -88.622886)
		(end 13.11402 -86.68258)
		(width 0.08382)
		(layer "In9.Cu")
		(net "PWRGD_P2V5_AUX")
	)
	(segment
		(start 26.10104 -84.00542)
		(end 26.10104 -83.322414)
		(width 0.08382)
		(layer "In9.Cu")
		(net "PWRGD_P2V5_AUX")
	)
	(segment
		(start 27.2034 -79.628746)
		(end 27.2034 -77.328014)
		(width 0.08382)
		(layer "In9.Cu")
		(net "PWRGD_P2V5_AUX")
	)
	(segment
		(start 32.890968 -67.046094)
		(end 32.890968 -66.991992)
		(width 0.08382)
		(layer "In9.Cu")
		(net "PWRGD_P2V5_AUX")
	)
	(segment
		(start 13.11402 -86.68258)
		(end 15.7988 -83.9978)
		(width 0.08382)
		(layer "In9.Cu")
		(net "PWRGD_P2V5_AUX")
	)
	(segment
		(start 12.5476 -89.189306)
		(end 13.11402 -88.622886)
		(width 0.08382)
		(layer "In9.Cu")
		(net "PWRGD_P2V5_AUX")
	)
	(segment
		(start 33.207706 -66.675254)
		(end 33.207706 -64.83096)
		(width 0.08382)
		(layer "In9.Cu")
		(net "PWRGD_P2V5_AUX")
	)
	(segment
		(start 26.10104 -83.322414)
		(end 26.61031 -82.813144)
		(width 0.08382)
		(layer "In9.Cu")
		(net "PWRGD_P2V5_AUX")
	)
	(segment
		(start 13.73759 -56.60644)
		(end 14.48816 -56.60644)
		(width 0.11684)
		(layer "F.Cu")
		(net "PWRGD_P1V8_AUX")
	)
	(segment
		(start 14.605 -58.40476)
		(end 13.95984 -59.04992)
		(width 0.11684)
		(layer "F.Cu")
		(net "PWRGD_P1V8_AUX")
	)
	(segment
		(start 77.192632 -72.413368)
		(end 76.9112 -72.6948)
		(width 0.254)
		(layer "F.Cu")
		(net "PWRGD_P1V8_AUX")
	)
	(segment
		(start 13.16355 -56.0324)
		(end 13.081 -56.11495)
		(width 0.11684)
		(layer "F.Cu")
		(net "PWRGD_P1V8_AUX")
	)
	(segment
		(start 38.735 -59.4868)
		(end 38.8874 -59.6392)
		(width 0.11684)
		(layer "F.Cu")
		(net "PWRGD_P1V8_AUX")
	)
	(segment
		(start 13.081 -56.11495)
		(end 13.081 -57.423304)
		(width 0.11684)
		(layer "F.Cu")
		(net "PWRGD_P1V8_AUX")
	)
	(segment
		(start 77.547724 -72.413368)
		(end 77.192632 -72.413368)
		(width 0.254)
		(layer "F.Cu")
		(net "PWRGD_P1V8_AUX")
	)
	(segment
		(start 13.6398 -59.04992)
		(end 13.486384 -59.203336)
		(width 0.11684)
		(layer "F.Cu")
		(net "PWRGD_P1V8_AUX")
	)
	(segment
		(start 13.16355 -56.0324)
		(end 13.73759 -56.60644)
		(width 0.11684)
		(layer "F.Cu")
		(net "PWRGD_P1V8_AUX")
	)
	(segment
		(start 13.486384 -59.203336)
		(end 13.486384 -60.884816)
		(width 0.11684)
		(layer "F.Cu")
		(net "PWRGD_P1V8_AUX")
	)
	(segment
		(start 14.605 -56.72328)
		(end 14.605 -58.40476)
		(width 0.11684)
		(layer "F.Cu")
		(net "PWRGD_P1V8_AUX")
	)
	(segment
		(start 13.95984 -59.04992)
		(end 13.6398 -59.04992)
		(width 0.11684)
		(layer "F.Cu")
		(net "PWRGD_P1V8_AUX")
	)
	(segment
		(start 38.989 -58.94705)
		(end 38.735 -59.20105)
		(width 0.11684)
		(layer "F.Cu")
		(net "PWRGD_P1V8_AUX")
	)
	(segment
		(start 13.486384 -60.884816)
		(end 13.1064 -61.2648)
		(width 0.11684)
		(layer "F.Cu")
		(net "PWRGD_P1V8_AUX")
	)
	(segment
		(start 14.48816 -56.60644)
		(end 14.605 -56.72328)
		(width 0.11684)
		(layer "F.Cu")
		(net "PWRGD_P1V8_AUX")
	)
	(segment
		(start 38.735 -59.20105)
		(end 38.735 -59.4868)
		(width 0.11684)
		(layer "F.Cu")
		(net "PWRGD_P1V8_AUX")
	)
	(via
		(at 38.8874 -59.6392)
		(size 0.508)
		(drill 0.254)
		(layers "F.Cu" "B.Cu")
		(net "PWRGD_P1V8_AUX")
	)
	(via
		(at 69.43217 -83.820254)
		(size 0.508)
		(drill 0.254)
		(layers "F.Cu" "B.Cu")
		(net "PWRGD_P1V8_AUX")
	)
	(via
		(at 75.9714 -72.771)
		(size 0.6604)
		(drill 0.3302)
		(layers "F.Cu" "B.Cu")
		(net "PWRGD_P1V8_AUX")
	)
	(via
		(at 36.1442 -85.5218)
		(size 0.508)
		(drill 0.254)
		(layers "F.Cu" "B.Cu")
		(net "PWRGD_P1V8_AUX")
	)
	(via
		(at 13.1064 -61.2648)
		(size 0.508)
		(drill 0.254)
		(layers "F.Cu" "B.Cu")
		(net "PWRGD_P1V8_AUX")
	)
	(via
		(at 19.77644 -103.804212)
		(size 0.508)
		(drill 0.254)
		(layers "F.Cu" "B.Cu")
		(net "PWRGD_P1V8_AUX")
	)
	(via
		(at 34.3662 -101.5746)
		(size 0.508)
		(drill 0.254)
		(layers "F.Cu" "B.Cu")
		(net "PWRGD_P1V8_AUX")
	)
	(via
		(at 76.9112 -72.6948)
		(size 0.508)
		(drill 0.254)
		(layers "F.Cu" "B.Cu")
		(net "PWRGD_P1V8_AUX")
	)
	(via
		(at 29.93136 -61.5188)
		(size 0.508)
		(drill 0.254)
		(layers "F.Cu" "B.Cu")
		(net "PWRGD_P1V8_AUX")
	)
	(segment
		(start 33.37814 -61.20638)
		(end 31.99638 -61.20638)
		(width 0.11684)
		(layer "B.Cu")
		(net "PWRGD_P1V8_AUX")
	)
	(segment
		(start 31.99638 -61.20638)
		(end 31.84652 -61.05652)
		(width 0.11684)
		(layer "B.Cu")
		(net "PWRGD_P1V8_AUX")
	)
	(segment
		(start 30.39364 -61.05652)
		(end 29.93136 -61.5188)
		(width 0.11684)
		(layer "B.Cu")
		(net "PWRGD_P1V8_AUX")
	)
	(segment
		(start 34.00933 -60.57519)
		(end 33.37814 -61.20638)
		(width 0.11684)
		(layer "B.Cu")
		(net "PWRGD_P1V8_AUX")
	)
	(segment
		(start 76.9112 -72.6948)
		(end 76.0476 -72.6948)
		(width 0.11684)
		(layer "B.Cu")
		(net "PWRGD_P1V8_AUX")
	)
	(segment
		(start 38.735 -59.4868)
		(end 36.79952 -59.4868)
		(width 0.11684)
		(layer "B.Cu")
		(net "PWRGD_P1V8_AUX")
	)
	(segment
		(start 19.77644 -102.85095)
		(end 19.77644 -103.804212)
		(width 0.11684)
		(layer "B.Cu")
		(net "PWRGD_P1V8_AUX")
	)
	(segment
		(start 76.0476 -72.6948)
		(end 75.9714 -72.771)
		(width 0.11684)
		(layer "B.Cu")
		(net "PWRGD_P1V8_AUX")
	)
	(segment
		(start 36.79952 -59.4868)
		(end 35.71113 -60.57519)
		(width 0.11684)
		(layer "B.Cu")
		(net "PWRGD_P1V8_AUX")
	)
	(segment
		(start 35.71113 -60.57519)
		(end 34.00933 -60.57519)
		(width 0.11684)
		(layer "B.Cu")
		(net "PWRGD_P1V8_AUX")
	)
	(segment
		(start 19.939 -102.38105)
		(end 19.939 -102.68839)
		(width 0.11684)
		(layer "B.Cu")
		(net "PWRGD_P1V8_AUX")
	)
	(segment
		(start 31.84652 -61.05652)
		(end 30.39364 -61.05652)
		(width 0.11684)
		(layer "B.Cu")
		(net "PWRGD_P1V8_AUX")
	)
	(segment
		(start 38.8874 -59.6392)
		(end 38.735 -59.4868)
		(width 0.11684)
		(layer "B.Cu")
		(net "PWRGD_P1V8_AUX")
	)
	(segment
		(start 19.939 -102.68839)
		(end 19.77644 -102.85095)
		(width 0.11684)
		(layer "B.Cu")
		(net "PWRGD_P1V8_AUX")
	)
	(segment
		(start 61.3791 -84.83346)
		(end 62.141354 -84.83346)
		(width 0.08382)
		(layer "In2.Cu")
		(net "PWRGD_P1V8_AUX")
	)
	(segment
		(start 21.4884 -105.74782)
		(end 25.31618 -105.74782)
		(width 0.08382)
		(layer "In2.Cu")
		(net "PWRGD_P1V8_AUX")
	)
	(segment
		(start 54.862222 -83.65617)
		(end 54.919372 -83.71332)
		(width 0.08382)
		(layer "In2.Cu")
		(net "PWRGD_P1V8_AUX")
	)
	(segment
		(start 35.6616 -84.587334)
		(end 36.166044 -84.08289)
		(width 0.08382)
		(layer "In2.Cu")
		(net "PWRGD_P1V8_AUX")
	)
	(segment
		(start 25.97531 -103.946198)
		(end 26.899108 -103.0224)
		(width 0.08382)
		(layer "In2.Cu")
		(net "PWRGD_P1V8_AUX")
	)
	(segment
		(start 32.749236 -102.429818)
		(end 33.510474 -101.66858)
		(width 0.08382)
		(layer "In2.Cu")
		(net "PWRGD_P1V8_AUX")
	)
	(segment
		(start 62.141354 -84.83346)
		(end 63.891414 -83.0834)
		(width 0.08382)
		(layer "In2.Cu")
		(net "PWRGD_P1V8_AUX")
	)
	(segment
		(start 56.567578 -83.655154)
		(end 57.914794 -83.655154)
		(width 0.08382)
		(layer "In2.Cu")
		(net "PWRGD_P1V8_AUX")
	)
	(segment
		(start 58.279538 -83.29041)
		(end 59.488578 -83.29041)
		(width 0.08382)
		(layer "In2.Cu")
		(net "PWRGD_P1V8_AUX")
	)
	(segment
		(start 19.77644 -103.804212)
		(end 19.77644 -104.03586)
		(width 0.08382)
		(layer "In2.Cu")
		(net "PWRGD_P1V8_AUX")
	)
	(segment
		(start 69.4436 -83.820254)
		(end 69.43217 -83.820254)
		(width 0.08382)
		(layer "In2.Cu")
		(net "PWRGD_P1V8_AUX")
	)
	(segment
		(start 13.1064 -61.2648)
		(end 13.6398 -61.7982)
		(width 0.08382)
		(layer "In2.Cu")
		(net "PWRGD_P1V8_AUX")
	)
	(segment
		(start 35.6616 -85.0392)
		(end 35.6616 -84.587334)
		(width 0.08382)
		(layer "In2.Cu")
		(net "PWRGD_P1V8_AUX")
	)
	(segment
		(start 26.899108 -103.0224)
		(end 29.788612 -103.0224)
		(width 0.08382)
		(layer "In2.Cu")
		(net "PWRGD_P1V8_AUX")
	)
	(segment
		(start 26.786078 -61.877956)
		(end 28.14447 -61.3156)
		(width 0.08382)
		(layer "In2.Cu")
		(net "PWRGD_P1V8_AUX")
	)
	(segment
		(start 51.722274 -83.65617)
		(end 54.862222 -83.65617)
		(width 0.08382)
		(layer "In2.Cu")
		(net "PWRGD_P1V8_AUX")
	)
	(segment
		(start 60.032646 -83.487006)
		(end 61.3791 -84.83346)
		(width 0.08382)
		(layer "In2.Cu")
		(net "PWRGD_P1V8_AUX")
	)
	(segment
		(start 63.891414 -83.0834)
		(end 68.3006 -83.0834)
		(width 0.08382)
		(layer "In2.Cu")
		(net "PWRGD_P1V8_AUX")
	)
	(segment
		(start 59.685174 -83.487006)
		(end 60.032646 -83.487006)
		(width 0.08382)
		(layer "In2.Cu")
		(net "PWRGD_P1V8_AUX")
	)
	(segment
		(start 21.23948 -60.87364)
		(end 22.243796 -61.877956)
		(width 0.08382)
		(layer "In2.Cu")
		(net "PWRGD_P1V8_AUX")
	)
	(segment
		(start 57.914794 -83.655154)
		(end 58.279538 -83.29041)
		(width 0.08382)
		(layer "In2.Cu")
		(net "PWRGD_P1V8_AUX")
	)
	(segment
		(start 51.388264 -83.99018)
		(end 51.722274 -83.65617)
		(width 0.08382)
		(layer "In2.Cu")
		(net "PWRGD_P1V8_AUX")
	)
	(segment
		(start 36.1442 -85.5218)
		(end 35.6616 -85.0392)
		(width 0.08382)
		(layer "In2.Cu")
		(net "PWRGD_P1V8_AUX")
	)
	(segment
		(start 49.609756 -83.99018)
		(end 51.388264 -83.99018)
		(width 0.08382)
		(layer "In2.Cu")
		(net "PWRGD_P1V8_AUX")
	)
	(segment
		(start 33.510474 -101.66858)
		(end 34.27222 -101.66858)
		(width 0.08382)
		(layer "In2.Cu")
		(net "PWRGD_P1V8_AUX")
	)
	(segment
		(start 34.27222 -101.66858)
		(end 34.3662 -101.5746)
		(width 0.08382)
		(layer "In2.Cu")
		(net "PWRGD_P1V8_AUX")
	)
	(segment
		(start 30.381194 -102.429818)
		(end 32.749236 -102.429818)
		(width 0.08382)
		(layer "In2.Cu")
		(net "PWRGD_P1V8_AUX")
	)
	(segment
		(start 69.4436 -83.82)
		(end 69.4436 -83.820254)
		(width 0.08382)
		(layer "In2.Cu")
		(net "PWRGD_P1V8_AUX")
	)
	(segment
		(start 13.6398 -61.7982)
		(end 18.562574 -61.7982)
		(width 0.08382)
		(layer "In2.Cu")
		(net "PWRGD_P1V8_AUX")
	)
	(segment
		(start 18.562574 -61.7982)
		(end 19.487134 -60.87364)
		(width 0.08382)
		(layer "In2.Cu")
		(net "PWRGD_P1V8_AUX")
	)
	(segment
		(start 22.243796 -61.877956)
		(end 26.786078 -61.877956)
		(width 0.08382)
		(layer "In2.Cu")
		(net "PWRGD_P1V8_AUX")
	)
	(segment
		(start 42.946574 -84.08289)
		(end 43.309032 -83.720432)
		(width 0.08382)
		(layer "In2.Cu")
		(net "PWRGD_P1V8_AUX")
	)
	(segment
		(start 56.509412 -83.71332)
		(end 56.567578 -83.655154)
		(width 0.08382)
		(layer "In2.Cu")
		(net "PWRGD_P1V8_AUX")
	)
	(segment
		(start 19.77644 -104.03586)
		(end 21.4884 -105.74782)
		(width 0.08382)
		(layer "In2.Cu")
		(net "PWRGD_P1V8_AUX")
	)
	(segment
		(start 25.97531 -105.08869)
		(end 25.97531 -103.946198)
		(width 0.08382)
		(layer "In2.Cu")
		(net "PWRGD_P1V8_AUX")
	)
	(segment
		(start 49.340008 -83.720432)
		(end 49.609756 -83.99018)
		(width 0.08382)
		(layer "In2.Cu")
		(net "PWRGD_P1V8_AUX")
	)
	(segment
		(start 68.3006 -83.0834)
		(end 69.0372 -83.82)
		(width 0.08382)
		(layer "In2.Cu")
		(net "PWRGD_P1V8_AUX")
	)
	(segment
		(start 54.919372 -83.71332)
		(end 56.509412 -83.71332)
		(width 0.08382)
		(layer "In2.Cu")
		(net "PWRGD_P1V8_AUX")
	)
	(segment
		(start 25.31618 -105.74782)
		(end 25.97531 -105.08869)
		(width 0.08382)
		(layer "In2.Cu")
		(net "PWRGD_P1V8_AUX")
	)
	(segment
		(start 28.14447 -61.3156)
		(end 29.72816 -61.3156)
		(width 0.08382)
		(layer "In2.Cu")
		(net "PWRGD_P1V8_AUX")
	)
	(segment
		(start 19.487134 -60.87364)
		(end 21.23948 -60.87364)
		(width 0.08382)
		(layer "In2.Cu")
		(net "PWRGD_P1V8_AUX")
	)
	(segment
		(start 29.72816 -61.3156)
		(end 29.93136 -61.5188)
		(width 0.08382)
		(layer "In2.Cu")
		(net "PWRGD_P1V8_AUX")
	)
	(segment
		(start 43.309032 -83.720432)
		(end 49.340008 -83.720432)
		(width 0.08382)
		(layer "In2.Cu")
		(net "PWRGD_P1V8_AUX")
	)
	(segment
		(start 69.0372 -83.82)
		(end 69.4436 -83.82)
		(width 0.08382)
		(layer "In2.Cu")
		(net "PWRGD_P1V8_AUX")
	)
	(segment
		(start 59.488578 -83.29041)
		(end 59.685174 -83.487006)
		(width 0.08382)
		(layer "In2.Cu")
		(net "PWRGD_P1V8_AUX")
	)
	(segment
		(start 29.788612 -103.0224)
		(end 30.381194 -102.429818)
		(width 0.08382)
		(layer "In2.Cu")
		(net "PWRGD_P1V8_AUX")
	)
	(segment
		(start 36.166044 -84.08289)
		(end 42.946574 -84.08289)
		(width 0.08382)
		(layer "In2.Cu")
		(net "PWRGD_P1V8_AUX")
	)
	(segment
		(start 34.24428 -101.45268)
		(end 34.3662 -101.5746)
		(width 0.10668)
		(layer "In4.Cu")
		(net "PWRGD_P1V8_AUX")
	)
	(segment
		(start 37.592 -76.6699)
		(end 37.592 -77.889608)
		(width 0.10668)
		(layer "In4.Cu")
		(net "PWRGD_P1V8_AUX")
	)
	(segment
		(start 39.0017 -71.030846)
		(end 39.2176 -71.246746)
		(width 0.10668)
		(layer "In4.Cu")
		(net "PWRGD_P1V8_AUX")
	)
	(segment
		(start 37.592 -77.889608)
		(end 37.86632 -78.163928)
		(width 0.10668)
		(layer "In4.Cu")
		(net "PWRGD_P1V8_AUX")
	)
	(segment
		(start 38.5191 -74.06386)
		(end 38.1762 -74.40676)
		(width 0.10668)
		(layer "In4.Cu")
		(net "PWRGD_P1V8_AUX")
	)
	(segment
		(start 33.77692 -96.293432)
		(end 33.77692 -98.26752)
		(width 0.10668)
		(layer "In4.Cu")
		(net "PWRGD_P1V8_AUX")
	)
	(segment
		(start 34.463228 -100.390452)
		(end 34.24428 -100.6094)
		(width 0.10668)
		(layer "In4.Cu")
		(net "PWRGD_P1V8_AUX")
	)
	(segment
		(start 39.2176 -73.68159)
		(end 38.83533 -74.06386)
		(width 0.10668)
		(layer "In4.Cu")
		(net "PWRGD_P1V8_AUX")
	)
	(segment
		(start 33.99282 -96.077532)
		(end 33.77692 -96.293432)
		(width 0.10668)
		(layer "In4.Cu")
		(net "PWRGD_P1V8_AUX")
	)
	(segment
		(start 33.77692 -98.26752)
		(end 34.463228 -98.953828)
		(width 0.10668)
		(layer "In4.Cu")
		(net "PWRGD_P1V8_AUX")
	)
	(segment
		(start 38.481 -67.550792)
		(end 39.0017 -68.071492)
		(width 0.10668)
		(layer "In4.Cu")
		(net "PWRGD_P1V8_AUX")
	)
	(segment
		(start 35.3314 -86.92896)
		(end 34.60242 -87.65794)
		(width 0.10668)
		(layer "In4.Cu")
		(net "PWRGD_P1V8_AUX")
	)
	(segment
		(start 33.99282 -92.770452)
		(end 33.99282 -96.077532)
		(width 0.10668)
		(layer "In4.Cu")
		(net "PWRGD_P1V8_AUX")
	)
	(segment
		(start 38.1762 -76.0857)
		(end 37.592 -76.6699)
		(width 0.10668)
		(layer "In4.Cu")
		(net "PWRGD_P1V8_AUX")
	)
	(segment
		(start 34.463228 -98.953828)
		(end 34.463228 -100.390452)
		(width 0.10668)
		(layer "In4.Cu")
		(net "PWRGD_P1V8_AUX")
	)
	(segment
		(start 38.481 -63.9572)
		(end 38.481 -67.550792)
		(width 0.10668)
		(layer "In4.Cu")
		(net "PWRGD_P1V8_AUX")
	)
	(segment
		(start 34.60242 -92.160852)
		(end 33.99282 -92.770452)
		(width 0.10668)
		(layer "In4.Cu")
		(net "PWRGD_P1V8_AUX")
	)
	(segment
		(start 38.8874 -59.6392)
		(end 38.8874 -63.5508)
		(width 0.10668)
		(layer "In4.Cu")
		(net "PWRGD_P1V8_AUX")
	)
	(segment
		(start 34.24428 -100.6094)
		(end 34.24428 -101.45268)
		(width 0.10668)
		(layer "In4.Cu")
		(net "PWRGD_P1V8_AUX")
	)
	(segment
		(start 35.3314 -86.3346)
		(end 35.3314 -86.92896)
		(width 0.10668)
		(layer "In4.Cu")
		(net "PWRGD_P1V8_AUX")
	)
	(segment
		(start 38.83533 -74.06386)
		(end 38.5191 -74.06386)
		(width 0.10668)
		(layer "In4.Cu")
		(net "PWRGD_P1V8_AUX")
	)
	(segment
		(start 38.8874 -63.5508)
		(end 38.481 -63.9572)
		(width 0.10668)
		(layer "In4.Cu")
		(net "PWRGD_P1V8_AUX")
	)
	(segment
		(start 39.2176 -71.246746)
		(end 39.2176 -73.68159)
		(width 0.10668)
		(layer "In4.Cu")
		(net "PWRGD_P1V8_AUX")
	)
	(segment
		(start 36.1442 -85.5218)
		(end 35.3314 -86.3346)
		(width 0.10668)
		(layer "In4.Cu")
		(net "PWRGD_P1V8_AUX")
	)
	(segment
		(start 37.86632 -79.625952)
		(end 35.5346 -81.957672)
		(width 0.10668)
		(layer "In4.Cu")
		(net "PWRGD_P1V8_AUX")
	)
	(segment
		(start 39.0017 -68.071492)
		(end 39.0017 -71.030846)
		(width 0.10668)
		(layer "In4.Cu")
		(net "PWRGD_P1V8_AUX")
	)
	(segment
		(start 35.5346 -84.9122)
		(end 36.1442 -85.5218)
		(width 0.10668)
		(layer "In4.Cu")
		(net "PWRGD_P1V8_AUX")
	)
	(segment
		(start 35.5346 -81.957672)
		(end 35.5346 -84.9122)
		(width 0.10668)
		(layer "In4.Cu")
		(net "PWRGD_P1V8_AUX")
	)
	(segment
		(start 38.1762 -74.40676)
		(end 38.1762 -76.0857)
		(width 0.10668)
		(layer "In4.Cu")
		(net "PWRGD_P1V8_AUX")
	)
	(segment
		(start 34.60242 -87.65794)
		(end 34.60242 -92.160852)
		(width 0.10668)
		(layer "In4.Cu")
		(net "PWRGD_P1V8_AUX")
	)
	(segment
		(start 37.86632 -78.163928)
		(end 37.86632 -79.625952)
		(width 0.10668)
		(layer "In4.Cu")
		(net "PWRGD_P1V8_AUX")
	)
	(segment
		(start 69.342 -83.730084)
		(end 69.43217 -83.820254)
		(width 0.10668)
		(layer "In7.Cu")
		(net "PWRGD_P1V8_AUX")
	)
	(segment
		(start 76.9112 -72.6948)
		(end 76.2254 -72.6948)
		(width 0.10668)
		(layer "In7.Cu")
		(net "PWRGD_P1V8_AUX")
	)
	(segment
		(start 69.342 -83.04276)
		(end 69.342 -83.730084)
		(width 0.10668)
		(layer "In7.Cu")
		(net "PWRGD_P1V8_AUX")
	)
	(segment
		(start 70.60692 -79.928466)
		(end 70.81012 -80.131666)
		(width 0.10668)
		(layer "In7.Cu")
		(net "PWRGD_P1V8_AUX")
	)
	(segment
		(start 70.60692 -72.927972)
		(end 70.60692 -79.928466)
		(width 0.10668)
		(layer "In7.Cu")
		(net "PWRGD_P1V8_AUX")
	)
	(segment
		(start 70.81012 -81.57464)
		(end 69.342 -83.04276)
		(width 0.10668)
		(layer "In7.Cu")
		(net "PWRGD_P1V8_AUX")
	)
	(segment
		(start 71.591424 -71.943468)
		(end 70.60692 -72.927972)
		(width 0.10668)
		(layer "In7.Cu")
		(net "PWRGD_P1V8_AUX")
	)
	(segment
		(start 72.98055 -71.943468)
		(end 71.591424 -71.943468)
		(width 0.10668)
		(layer "In7.Cu")
		(net "PWRGD_P1V8_AUX")
	)
	(segment
		(start 73.681082 -71.242936)
		(end 72.98055 -71.943468)
		(width 0.10668)
		(layer "In7.Cu")
		(net "PWRGD_P1V8_AUX")
	)
	(segment
		(start 76.2254 -72.6948)
		(end 74.773536 -71.242936)
		(width 0.10668)
		(layer "In7.Cu")
		(net "PWRGD_P1V8_AUX")
	)
	(segment
		(start 70.81012 -80.131666)
		(end 70.81012 -81.57464)
		(width 0.10668)
		(layer "In7.Cu")
		(net "PWRGD_P1V8_AUX")
	)
	(segment
		(start 74.773536 -71.242936)
		(end 73.681082 -71.242936)
		(width 0.10668)
		(layer "In7.Cu")
		(net "PWRGD_P1V8_AUX")
	)
	(segment
		(start 15.8496 -42.291)
		(end 16.0528 -42.4942)
		(width 0.11684)
		(layer "F.Cu")
		(net "PWRGD_P1V2_AUX")
	)
	(segment
		(start 19.31162 -104.2924)
		(end 19.17192 -104.4321)
		(width 0.11684)
		(layer "F.Cu")
		(net "PWRGD_P1V2_AUX")
	)
	(segment
		(start 20.066 -103.14305)
		(end 19.779234 -103.14305)
		(width 0.11684)
		(layer "F.Cu")
		(net "PWRGD_P1V2_AUX")
	)
	(segment
		(start 79.3242 -86.5378)
		(end 84.2518 -86.5378)
		(width 0.11684)
		(layer "F.Cu")
		(net "PWRGD_P1V2_AUX")
	)
	(segment
		(start 19.31162 -103.610664)
		(end 19.31162 -104.2924)
		(width 0.11684)
		(layer "F.Cu")
		(net "PWRGD_P1V2_AUX")
	)
	(segment
		(start 15.748 -37.741606)
		(end 15.8496 -37.843206)
		(width 0.11684)
		(layer "F.Cu")
		(net "PWRGD_P1V2_AUX")
	)
	(segment
		(start 15.8496 -37.843206)
		(end 15.8496 -42.291)
		(width 0.11684)
		(layer "F.Cu")
		(net "PWRGD_P1V2_AUX")
	)
	(segment
		(start 17.66316 -43.87088)
		(end 17.51584 -44.0182)
		(width 0.11684)
		(layer "F.Cu")
		(net "PWRGD_P1V2_AUX")
	)
	(segment
		(start 17.272 -42.4942)
		(end 17.66316 -42.88536)
		(width 0.11684)
		(layer "F.Cu")
		(net "PWRGD_P1V2_AUX")
	)
	(segment
		(start 19.17192 -104.4321)
		(end 13.90904 -104.4321)
		(width 0.11684)
		(layer "F.Cu")
		(net "PWRGD_P1V2_AUX")
	)
	(segment
		(start 13.38834 -103.9114)
		(end 10.04062 -103.9114)
		(width 0.11684)
		(layer "F.Cu")
		(net "PWRGD_P1V2_AUX")
	)
	(segment
		(start 85.4964 -85.2932)
		(end 85.4964 -79.400146)
		(width 0.11684)
		(layer "F.Cu")
		(net "PWRGD_P1V2_AUX")
	)
	(segment
		(start 13.90904 -104.4321)
		(end 13.38834 -103.9114)
		(width 0.11684)
		(layer "F.Cu")
		(net "PWRGD_P1V2_AUX")
	)
	(segment
		(start 19.779234 -103.14305)
		(end 19.31162 -103.610664)
		(width 0.11684)
		(layer "F.Cu")
		(net "PWRGD_P1V2_AUX")
	)
	(segment
		(start 84.455 -78.358746)
		(end 84.455 -77.05725)
		(width 0.11684)
		(layer "F.Cu")
		(net "PWRGD_P1V2_AUX")
	)
	(segment
		(start 85.4964 -79.400146)
		(end 84.455 -78.358746)
		(width 0.11684)
		(layer "F.Cu")
		(net "PWRGD_P1V2_AUX")
	)
	(segment
		(start 16.0528 -42.4942)
		(end 17.272 -42.4942)
		(width 0.11684)
		(layer "F.Cu")
		(net "PWRGD_P1V2_AUX")
	)
	(segment
		(start 17.66316 -42.88536)
		(end 17.66316 -43.87088)
		(width 0.11684)
		(layer "F.Cu")
		(net "PWRGD_P1V2_AUX")
	)
	(segment
		(start 84.2518 -86.5378)
		(end 85.4964 -85.2932)
		(width 0.11684)
		(layer "F.Cu")
		(net "PWRGD_P1V2_AUX")
	)
	(via
		(at 9.017 -86.487)
		(size 0.508)
		(drill 0.254)
		(layers "F.Cu" "B.Cu")
		(net "PWRGD_P1V2_AUX")
	)
	(via
		(at 19.9644 -72.12838)
		(size 0.508)
		(drill 0.254)
		(layers "F.Cu" "B.Cu")
		(net "PWRGD_P1V2_AUX")
	)
	(via
		(at 79.3242 -86.5378)
		(size 0.762)
		(drill 0.254)
		(layers "F.Cu" "B.Cu")
		(net "PWRGD_P1V2_AUX")
	)
	(via
		(at 10.04062 -103.9114)
		(size 0.508)
		(drill 0.254)
		(layers "F.Cu" "B.Cu")
		(net "PWRGD_P1V2_AUX")
	)
	(via
		(at 17.51584 -44.0182)
		(size 0.508)
		(drill 0.254)
		(layers "F.Cu" "B.Cu")
		(net "PWRGD_P1V2_AUX")
	)
	(segment
		(start 15.1384 -77.395832)
		(end 14.33195 -79.34325)
		(width 0.08382)
		(layer "In2.Cu")
		(net "PWRGD_P1V2_AUX")
	)
	(segment
		(start 50.774854 -78.2066)
		(end 50.477674 -78.50378)
		(width 0.08382)
		(layer "In2.Cu")
		(net "PWRGD_P1V2_AUX")
	)
	(segment
		(start 35.870388 -79.3496)
		(end 35.090608 -78.56982)
		(width 0.08382)
		(layer "In2.Cu")
		(net "PWRGD_P1V2_AUX")
	)
	(segment
		(start 39.860474 -79.19593)
		(end 39.381684 -78.71714)
		(width 0.08382)
		(layer "In2.Cu")
		(net "PWRGD_P1V2_AUX")
	)
	(segment
		(start 35.090608 -78.56982)
		(end 32.26562 -78.56982)
		(width 0.08382)
		(layer "In2.Cu")
		(net "PWRGD_P1V2_AUX")
	)
	(segment
		(start 14.069568 -79.60995)
		(end 14.06525 -79.60995)
		(width 0.08382)
		(layer "In2.Cu")
		(net "PWRGD_P1V2_AUX")
	)
	(segment
		(start 50.477674 -78.50378)
		(end 49.334674 -78.50378)
		(width 0.08382)
		(layer "In2.Cu")
		(net "PWRGD_P1V2_AUX")
	)
	(segment
		(start 53.948838 -77.663548)
		(end 53.405786 -78.2066)
		(width 0.08382)
		(layer "In2.Cu")
		(net "PWRGD_P1V2_AUX")
	)
	(segment
		(start 44.186094 -77.798168)
		(end 42.788332 -79.19593)
		(width 0.08382)
		(layer "In2.Cu")
		(net "PWRGD_P1V2_AUX")
	)
	(segment
		(start 24.571706 -74.853546)
		(end 23.37054 -73.65238)
		(width 0.08382)
		(layer "In2.Cu")
		(net "PWRGD_P1V2_AUX")
	)
	(segment
		(start 27.701494 -78.24978)
		(end 24.57196 -75.120246)
		(width 0.08382)
		(layer "In2.Cu")
		(net "PWRGD_P1V2_AUX")
	)
	(segment
		(start 9.871202 -81.111598)
		(end 8.7122 -82.2706)
		(width 0.08382)
		(layer "In2.Cu")
		(net "PWRGD_P1V2_AUX")
	)
	(segment
		(start 20.774914 -72.12838)
		(end 19.9644 -72.12838)
		(width 0.08382)
		(layer "In2.Cu")
		(net "PWRGD_P1V2_AUX")
	)
	(segment
		(start 61.860684 -79.9592)
		(end 61.85916 -79.9592)
		(width 0.08382)
		(layer "In2.Cu")
		(net "PWRGD_P1V2_AUX")
	)
	(segment
		(start 9.652 -84.327746)
		(end 9.652 -85.852)
		(width 0.08382)
		(layer "In2.Cu")
		(net "PWRGD_P1V2_AUX")
	)
	(segment
		(start 57.57418 -80.22082)
		(end 55.016908 -77.663548)
		(width 0.08382)
		(layer "In2.Cu")
		(net "PWRGD_P1V2_AUX")
	)
	(segment
		(start 75.819 -87.2236)
		(end 74.549 -85.9536)
		(width 0.08382)
		(layer "In2.Cu")
		(net "PWRGD_P1V2_AUX")
	)
	(segment
		(start 49.334674 -78.50378)
		(end 48.844454 -78.994)
		(width 0.08382)
		(layer "In2.Cu")
		(net "PWRGD_P1V2_AUX")
	)
	(segment
		(start 60.014358 -80.22082)
		(end 57.57418 -80.22082)
		(width 0.08382)
		(layer "In2.Cu")
		(net "PWRGD_P1V2_AUX")
	)
	(segment
		(start 32.26562 -78.56982)
		(end 31.94558 -78.24978)
		(width 0.08382)
		(layer "In2.Cu")
		(net "PWRGD_P1V2_AUX")
	)
	(segment
		(start 61.85916 -79.9592)
		(end 61.85662 -79.96174)
		(width 0.08382)
		(layer "In2.Cu")
		(net "PWRGD_P1V2_AUX")
	)
	(segment
		(start 74.193654 -79.7052)
		(end 65.92443 -79.7052)
		(width 0.08382)
		(layer "In2.Cu")
		(net "PWRGD_P1V2_AUX")
	)
	(segment
		(start 11.853418 -80.37322)
		(end 11.11504 -81.111598)
		(width 0.08382)
		(layer "In2.Cu")
		(net "PWRGD_P1V2_AUX")
	)
	(segment
		(start 74.549 -85.9536)
		(end 74.549 -80.060546)
		(width 0.08382)
		(layer "In2.Cu")
		(net "PWRGD_P1V2_AUX")
	)
	(segment
		(start 19.060922 -72.73036)
		(end 17.32788 -72.73036)
		(width 0.08382)
		(layer "In2.Cu")
		(net "PWRGD_P1V2_AUX")
	)
	(segment
		(start 24.57196 -74.854308)
		(end 24.571706 -74.853546)
		(width 0.08382)
		(layer "In2.Cu")
		(net "PWRGD_P1V2_AUX")
	)
	(segment
		(start 15.1384 -74.91984)
		(end 15.1384 -77.395832)
		(width 0.08382)
		(layer "In2.Cu")
		(net "PWRGD_P1V2_AUX")
	)
	(segment
		(start 12.09294 -80.37322)
		(end 11.853418 -80.37322)
		(width 0.08382)
		(layer "In2.Cu")
		(net "PWRGD_P1V2_AUX")
	)
	(segment
		(start 55.016908 -77.663548)
		(end 53.948838 -77.663548)
		(width 0.08382)
		(layer "In2.Cu")
		(net "PWRGD_P1V2_AUX")
	)
	(segment
		(start 48.844454 -78.994)
		(end 46.606206 -78.994)
		(width 0.08382)
		(layer "In2.Cu")
		(net "PWRGD_P1V2_AUX")
	)
	(segment
		(start 62.527434 -79.29245)
		(end 61.860684 -79.9592)
		(width 0.08382)
		(layer "In2.Cu")
		(net "PWRGD_P1V2_AUX")
	)
	(segment
		(start 36.819586 -79.3496)
		(end 35.870388 -79.3496)
		(width 0.08382)
		(layer "In2.Cu")
		(net "PWRGD_P1V2_AUX")
	)
	(segment
		(start 65.92443 -79.7052)
		(end 65.75552 -79.87411)
		(width 0.08382)
		(layer "In2.Cu")
		(net "PWRGD_P1V2_AUX")
	)
	(segment
		(start 19.9644 -72.160892)
		(end 19.631152 -72.49414)
		(width 0.08382)
		(layer "In2.Cu")
		(net "PWRGD_P1V2_AUX")
	)
	(segment
		(start 24.57196 -75.120246)
		(end 24.57196 -74.854308)
		(width 0.08382)
		(layer "In2.Cu")
		(net "PWRGD_P1V2_AUX")
	)
	(segment
		(start 45.642022 -78.029816)
		(end 45.082968 -77.798168)
		(width 0.08382)
		(layer "In2.Cu")
		(net "PWRGD_P1V2_AUX")
	)
	(segment
		(start 22.298914 -73.65238)
		(end 20.774914 -72.12838)
		(width 0.08382)
		(layer "In2.Cu")
		(net "PWRGD_P1V2_AUX")
	)
	(segment
		(start 74.549 -80.060546)
		(end 74.193654 -79.7052)
		(width 0.08382)
		(layer "In2.Cu")
		(net "PWRGD_P1V2_AUX")
	)
	(segment
		(start 46.606206 -78.994)
		(end 45.642022 -78.029816)
		(width 0.08382)
		(layer "In2.Cu")
		(net "PWRGD_P1V2_AUX")
	)
	(segment
		(start 45.082968 -77.798168)
		(end 44.186094 -77.798168)
		(width 0.08382)
		(layer "In2.Cu")
		(net "PWRGD_P1V2_AUX")
	)
	(segment
		(start 37.452046 -78.71714)
		(end 36.819586 -79.3496)
		(width 0.08382)
		(layer "In2.Cu")
		(net "PWRGD_P1V2_AUX")
	)
	(segment
		(start 65.75552 -79.87411)
		(end 64.40043 -79.87411)
		(width 0.08382)
		(layer "In2.Cu")
		(net "PWRGD_P1V2_AUX")
	)
	(segment
		(start 13.7668 -79.9084)
		(end 12.55776 -79.9084)
		(width 0.08382)
		(layer "In2.Cu")
		(net "PWRGD_P1V2_AUX")
	)
	(segment
		(start 14.06525 -79.60995)
		(end 13.7668 -79.9084)
		(width 0.08382)
		(layer "In2.Cu")
		(net "PWRGD_P1V2_AUX")
	)
	(segment
		(start 53.405786 -78.2066)
		(end 50.774854 -78.2066)
		(width 0.08382)
		(layer "In2.Cu")
		(net "PWRGD_P1V2_AUX")
	)
	(segment
		(start 42.788332 -79.19593)
		(end 39.860474 -79.19593)
		(width 0.08382)
		(layer "In2.Cu")
		(net "PWRGD_P1V2_AUX")
	)
	(segment
		(start 78.6384 -87.2236)
		(end 75.819 -87.2236)
		(width 0.08382)
		(layer "In2.Cu")
		(net "PWRGD_P1V2_AUX")
	)
	(segment
		(start 17.32788 -72.73036)
		(end 15.1384 -74.91984)
		(width 0.08382)
		(layer "In2.Cu")
		(net "PWRGD_P1V2_AUX")
	)
	(segment
		(start 8.7122 -83.387946)
		(end 9.652 -84.327746)
		(width 0.08382)
		(layer "In2.Cu")
		(net "PWRGD_P1V2_AUX")
	)
	(segment
		(start 14.33195 -79.347568)
		(end 14.069568 -79.60995)
		(width 0.08382)
		(layer "In2.Cu")
		(net "PWRGD_P1V2_AUX")
	)
	(segment
		(start 23.37054 -73.65238)
		(end 22.298914 -73.65238)
		(width 0.08382)
		(layer "In2.Cu")
		(net "PWRGD_P1V2_AUX")
	)
	(segment
		(start 60.273438 -79.96174)
		(end 60.014358 -80.22082)
		(width 0.08382)
		(layer "In2.Cu")
		(net "PWRGD_P1V2_AUX")
	)
	(segment
		(start 39.381684 -78.71714)
		(end 37.452046 -78.71714)
		(width 0.08382)
		(layer "In2.Cu")
		(net "PWRGD_P1V2_AUX")
	)
	(segment
		(start 19.9644 -72.12838)
		(end 19.9644 -72.160892)
		(width 0.08382)
		(layer "In2.Cu")
		(net "PWRGD_P1V2_AUX")
	)
	(segment
		(start 8.7122 -82.2706)
		(end 8.7122 -83.387946)
		(width 0.08382)
		(layer "In2.Cu")
		(net "PWRGD_P1V2_AUX")
	)
	(segment
		(start 14.33195 -79.34325)
		(end 14.33195 -79.347568)
		(width 0.08382)
		(layer "In2.Cu")
		(net "PWRGD_P1V2_AUX")
	)
	(segment
		(start 19.631152 -72.49414)
		(end 19.060922 -72.73036)
		(width 0.08382)
		(layer "In2.Cu")
		(net "PWRGD_P1V2_AUX")
	)
	(segment
		(start 31.94558 -78.24978)
		(end 27.701494 -78.24978)
		(width 0.08382)
		(layer "In2.Cu")
		(net "PWRGD_P1V2_AUX")
	)
	(segment
		(start 61.85662 -79.96174)
		(end 60.273438 -79.96174)
		(width 0.08382)
		(layer "In2.Cu")
		(net "PWRGD_P1V2_AUX")
	)
	(segment
		(start 63.81877 -79.29245)
		(end 62.527434 -79.29245)
		(width 0.08382)
		(layer "In2.Cu")
		(net "PWRGD_P1V2_AUX")
	)
	(segment
		(start 11.11504 -81.111598)
		(end 9.871202 -81.111598)
		(width 0.08382)
		(layer "In2.Cu")
		(net "PWRGD_P1V2_AUX")
	)
	(segment
		(start 64.40043 -79.87411)
		(end 63.81877 -79.29245)
		(width 0.08382)
		(layer "In2.Cu")
		(net "PWRGD_P1V2_AUX")
	)
	(segment
		(start 79.3242 -86.5378)
		(end 78.6384 -87.2236)
		(width 0.08382)
		(layer "In2.Cu")
		(net "PWRGD_P1V2_AUX")
	)
	(segment
		(start 9.652 -85.852)
		(end 9.017 -86.487)
		(width 0.08382)
		(layer "In2.Cu")
		(net "PWRGD_P1V2_AUX")
	)
	(segment
		(start 12.55776 -79.9084)
		(end 12.09294 -80.37322)
		(width 0.08382)
		(layer "In2.Cu")
		(net "PWRGD_P1V2_AUX")
	)
	(segment
		(start 16.87576 -46.277022)
		(end 15.791434 -47.361348)
		(width 0.10668)
		(layer "In7.Cu")
		(net "PWRGD_P1V2_AUX")
	)
	(segment
		(start 18.868136 -70.4215)
		(end 19.22399 -70.4215)
		(width 0.10668)
		(layer "In7.Cu")
		(net "PWRGD_P1V2_AUX")
	)
	(segment
		(start 16.88846 -52.488084)
		(end 17.077182 -52.676806)
		(width 0.10668)
		(layer "In7.Cu")
		(net "PWRGD_P1V2_AUX")
	)
	(segment
		(start 16.87576 -44.65828)
		(end 16.87576 -46.277022)
		(width 0.10668)
		(layer "In7.Cu")
		(net "PWRGD_P1V2_AUX")
	)
	(segment
		(start 17.077182 -57.395618)
		(end 16.7132 -57.7596)
		(width 0.10668)
		(layer "In7.Cu")
		(net "PWRGD_P1V2_AUX")
	)
	(segment
		(start 15.791434 -47.361348)
		(end 15.791434 -48.551592)
		(width 0.10668)
		(layer "In7.Cu")
		(net "PWRGD_P1V2_AUX")
	)
	(segment
		(start 17.423892 -67.767962)
		(end 17.423892 -68.977256)
		(width 0.10668)
		(layer "In7.Cu")
		(net "PWRGD_P1V2_AUX")
	)
	(segment
		(start 16.49984 -50.140616)
		(end 17.14246 -50.783236)
		(width 0.10668)
		(layer "In7.Cu")
		(net "PWRGD_P1V2_AUX")
	)
	(segment
		(start 15.791434 -48.551592)
		(end 16.49984 -49.259998)
		(width 0.10668)
		(layer "In7.Cu")
		(net "PWRGD_P1V2_AUX")
	)
	(segment
		(start 17.3736 -59.4868)
		(end 17.3736 -62.163706)
		(width 0.10668)
		(layer "In7.Cu")
		(net "PWRGD_P1V2_AUX")
	)
	(segment
		(start 17.077182 -52.676806)
		(end 17.077182 -57.395618)
		(width 0.10668)
		(layer "In7.Cu")
		(net "PWRGD_P1V2_AUX")
	)
	(segment
		(start 17.14246 -50.783236)
		(end 17.14246 -51.46548)
		(width 0.10668)
		(layer "In7.Cu")
		(net "PWRGD_P1V2_AUX")
	)
	(segment
		(start 18.13052 -67.623944)
		(end 17.853152 -67.623944)
		(width 0.10668)
		(layer "In7.Cu")
		(net "PWRGD_P1V2_AUX")
	)
	(segment
		(start 16.7132 -58.8264)
		(end 17.3736 -59.4868)
		(width 0.10668)
		(layer "In7.Cu")
		(net "PWRGD_P1V2_AUX")
	)
	(segment
		(start 17.14246 -51.46548)
		(end 16.88846 -51.71948)
		(width 0.10668)
		(layer "In7.Cu")
		(net "PWRGD_P1V2_AUX")
	)
	(segment
		(start 17.423892 -68.977256)
		(end 18.868136 -70.4215)
		(width 0.10668)
		(layer "In7.Cu")
		(net "PWRGD_P1V2_AUX")
	)
	(segment
		(start 17.568164 -67.62369)
		(end 17.423892 -67.767962)
		(width 0.10668)
		(layer "In7.Cu")
		(net "PWRGD_P1V2_AUX")
	)
	(segment
		(start 17.852898 -67.62369)
		(end 17.568164 -67.62369)
		(width 0.10668)
		(layer "In7.Cu")
		(net "PWRGD_P1V2_AUX")
	)
	(segment
		(start 19.22399 -70.4215)
		(end 19.9644 -71.16191)
		(width 0.10668)
		(layer "In7.Cu")
		(net "PWRGD_P1V2_AUX")
	)
	(segment
		(start 17.853152 -67.623944)
		(end 17.852898 -67.62369)
		(width 0.10668)
		(layer "In7.Cu")
		(net "PWRGD_P1V2_AUX")
	)
	(segment
		(start 16.88846 -51.71948)
		(end 16.88846 -52.488084)
		(width 0.10668)
		(layer "In7.Cu")
		(net "PWRGD_P1V2_AUX")
	)
	(segment
		(start 19.9644 -71.16191)
		(end 19.9644 -72.12838)
		(width 0.10668)
		(layer "In7.Cu")
		(net "PWRGD_P1V2_AUX")
	)
	(segment
		(start 18.98904 -66.765424)
		(end 18.13052 -67.623944)
		(width 0.10668)
		(layer "In7.Cu")
		(net "PWRGD_P1V2_AUX")
	)
	(segment
		(start 16.7132 -57.7596)
		(end 16.7132 -58.8264)
		(width 0.10668)
		(layer "In7.Cu")
		(net "PWRGD_P1V2_AUX")
	)
	(segment
		(start 17.3736 -62.163706)
		(end 18.98904 -63.779146)
		(width 0.10668)
		(layer "In7.Cu")
		(net "PWRGD_P1V2_AUX")
	)
	(segment
		(start 17.51584 -44.0182)
		(end 16.87576 -44.65828)
		(width 0.10668)
		(layer "In7.Cu")
		(net "PWRGD_P1V2_AUX")
	)
	(segment
		(start 18.98904 -63.779146)
		(end 18.98904 -66.765424)
		(width 0.10668)
		(layer "In7.Cu")
		(net "PWRGD_P1V2_AUX")
	)
	(segment
		(start 16.49984 -49.259998)
		(end 16.49984 -50.140616)
		(width 0.10668)
		(layer "In7.Cu")
		(net "PWRGD_P1V2_AUX")
	)
	(segment
		(start 8.95604 -104.99598)
		(end 10.04062 -103.9114)
		(width 0.08382)
		(layer "In9.Cu")
		(net "PWRGD_P1V2_AUX")
	)
	(segment
		(start 5.30098 -104.99598)
		(end 8.95604 -104.99598)
		(width 0.08382)
		(layer "In9.Cu")
		(net "PWRGD_P1V2_AUX")
	)
	(segment
		(start 4.699 -88.0618)
		(end 4.699 -104.394)
		(width 0.08382)
		(layer "In9.Cu")
		(net "PWRGD_P1V2_AUX")
	)
	(segment
		(start 5.588 -87.1728)
		(end 4.699 -88.0618)
		(width 0.08382)
		(layer "In9.Cu")
		(net "PWRGD_P1V2_AUX")
	)
	(segment
		(start 9.017 -86.487)
		(end 7.9502 -87.5538)
		(width 0.08382)
		(layer "In9.Cu")
		(net "PWRGD_P1V2_AUX")
	)
	(segment
		(start 7.1628 -87.1728)
		(end 5.588 -87.1728)
		(width 0.08382)
		(layer "In9.Cu")
		(net "PWRGD_P1V2_AUX")
	)
	(segment
		(start 7.9502 -87.5538)
		(end 7.5438 -87.5538)
		(width 0.08382)
		(layer "In9.Cu")
		(net "PWRGD_P1V2_AUX")
	)
	(segment
		(start 4.699 -104.394)
		(end 5.30098 -104.99598)
		(width 0.08382)
		(layer "In9.Cu")
		(net "PWRGD_P1V2_AUX")
	)
	(segment
		(start 7.5438 -87.5538)
		(end 7.1628 -87.1728)
		(width 0.08382)
		(layer "In9.Cu")
		(net "PWRGD_P1V2_AUX")
	)
	(segment
		(start 25.776174 -35.224974)
		(end 25.5016 -34.9504)
		(width 0.11684)
		(layer "F.Cu")
		(net "PWRGD_P1V0_AUX")
	)
	(segment
		(start 34.93135 -34.04235)
		(end 34.69132 -33.80232)
		(width 0.11684)
		(layer "F.Cu")
		(net "PWRGD_P1V0_AUX")
	)
	(segment
		(start 32.59328 -33.80232)
		(end 30.7086 -35.687)
		(width 0.11684)
		(layer "F.Cu")
		(net "PWRGD_P1V0_AUX")
	)
	(segment
		(start 26.161746 -33.476946)
		(end 26.161746 -33.782254)
		(width 0.11684)
		(layer "F.Cu")
		(net "PWRGD_P1V0_AUX")
	)
	(segment
		(start 25.5016 -34.9504)
		(end 25.5016 -34.30905)
		(width 0.11684)
		(layer "F.Cu")
		(net "PWRGD_P1V0_AUX")
	)
	(segment
		(start 34.93135 -35.751008)
		(end 34.93135 -34.04235)
		(width 0.11684)
		(layer "F.Cu")
		(net "PWRGD_P1V0_AUX")
	)
	(segment
		(start 25.63495 -34.30905)
		(end 25.5016 -34.30905)
		(width 0.11684)
		(layer "F.Cu")
		(net "PWRGD_P1V0_AUX")
	)
	(segment
		(start 30.7086 -35.687)
		(end 26.891742 -35.687)
		(width 0.11684)
		(layer "F.Cu")
		(net "PWRGD_P1V0_AUX")
	)
	(segment
		(start 26.161746 -33.782254)
		(end 25.63495 -34.30905)
		(width 0.11684)
		(layer "F.Cu")
		(net "PWRGD_P1V0_AUX")
	)
	(segment
		(start 26.891742 -35.687)
		(end 25.776174 -35.224974)
		(width 0.11684)
		(layer "F.Cu")
		(net "PWRGD_P1V0_AUX")
	)
	(segment
		(start 34.69132 -33.80232)
		(end 32.59328 -33.80232)
		(width 0.11684)
		(layer "F.Cu")
		(net "PWRGD_P1V0_AUX")
	)
	(via
		(at 9.58469 -99.3648)
		(size 0.508)
		(drill 0.254)
		(layers "F.Cu" "B.Cu")
		(net "PWRGD_P1V0_AUX")
	)
	(via
		(at 26.161746 -33.476946)
		(size 0.508)
		(drill 0.254)
		(layers "F.Cu" "B.Cu")
		(net "PWRGD_P1V0_AUX")
	)
	(via
		(at 18.3642 -40.4876)
		(size 0.508)
		(drill 0.254)
		(layers "F.Cu" "B.Cu")
		(net "PWRGD_P1V0_AUX")
	)
	(via
		(at 14.732 -55.2958)
		(size 0.508)
		(drill 0.254)
		(layers "F.Cu" "B.Cu")
		(net "PWRGD_P1V0_AUX")
	)
	(via
		(at 17.2466 -101.73335)
		(size 0.508)
		(drill 0.254)
		(layers "F.Cu" "B.Cu")
		(net "PWRGD_P1V0_AUX")
	)
	(segment
		(start 17.57045 -102.38105)
		(end 17.2466 -102.0572)
		(width 0.11684)
		(layer "B.Cu")
		(net "PWRGD_P1V0_AUX")
	)
	(segment
		(start 17.2466 -102.0572)
		(end 17.2466 -101.73335)
		(width 0.11684)
		(layer "B.Cu")
		(net "PWRGD_P1V0_AUX")
	)
	(segment
		(start 17.907 -102.38105)
		(end 17.57045 -102.38105)
		(width 0.11684)
		(layer "B.Cu")
		(net "PWRGD_P1V0_AUX")
	)
	(segment
		(start 18.67535 -41.88841)
		(end 18.3642 -41.57726)
		(width 0.08382)
		(layer "In2.Cu")
		(net "PWRGD_P1V0_AUX")
	)
	(segment
		(start 22.63013 -40.546782)
		(end 20.936712 -42.2402)
		(width 0.08382)
		(layer "In2.Cu")
		(net "PWRGD_P1V0_AUX")
	)
	(segment
		(start 18.3642 -41.57726)
		(end 18.3642 -40.4876)
		(width 0.08382)
		(layer "In2.Cu")
		(net "PWRGD_P1V0_AUX")
	)
	(segment
		(start 19.896328 -42.2402)
		(end 19.544538 -41.88841)
		(width 0.08382)
		(layer "In2.Cu")
		(net "PWRGD_P1V0_AUX")
	)
	(segment
		(start 22.63013 -36.604448)
		(end 22.63013 -40.546782)
		(width 0.08382)
		(layer "In2.Cu")
		(net "PWRGD_P1V0_AUX")
	)
	(segment
		(start 20.936712 -42.2402)
		(end 19.896328 -42.2402)
		(width 0.08382)
		(layer "In2.Cu")
		(net "PWRGD_P1V0_AUX")
	)
	(segment
		(start 26.161746 -33.476946)
		(end 25.329642 -34.30905)
		(width 0.08382)
		(layer "In2.Cu")
		(net "PWRGD_P1V0_AUX")
	)
	(segment
		(start 23.9522 -34.747454)
		(end 23.9522 -35.282378)
		(width 0.08382)
		(layer "In2.Cu")
		(net "PWRGD_P1V0_AUX")
	)
	(segment
		(start 25.329642 -34.30905)
		(end 24.390604 -34.30905)
		(width 0.08382)
		(layer "In2.Cu")
		(net "PWRGD_P1V0_AUX")
	)
	(segment
		(start 23.9522 -35.282378)
		(end 22.63013 -36.604448)
		(width 0.08382)
		(layer "In2.Cu")
		(net "PWRGD_P1V0_AUX")
	)
	(segment
		(start 19.544538 -41.88841)
		(end 18.67535 -41.88841)
		(width 0.08382)
		(layer "In2.Cu")
		(net "PWRGD_P1V0_AUX")
	)
	(segment
		(start 24.390604 -34.30905)
		(end 23.9522 -34.747454)
		(width 0.08382)
		(layer "In2.Cu")
		(net "PWRGD_P1V0_AUX")
	)
	(segment
		(start 11.02868 -102.53726)
		(end 16.44269 -102.53726)
		(width 0.10668)
		(layer "In4.Cu")
		(net "PWRGD_P1V0_AUX")
	)
	(segment
		(start 16.44269 -102.53726)
		(end 17.2466 -101.73335)
		(width 0.10668)
		(layer "In4.Cu")
		(net "PWRGD_P1V0_AUX")
	)
	(segment
		(start 10.422128 -101.930708)
		(end 11.02868 -102.53726)
		(width 0.10668)
		(layer "In4.Cu")
		(net "PWRGD_P1V0_AUX")
	)
	(segment
		(start 10.422128 -100.202238)
		(end 10.422128 -101.930708)
		(width 0.10668)
		(layer "In4.Cu")
		(net "PWRGD_P1V0_AUX")
	)
	(segment
		(start 9.58469 -99.3648)
		(end 10.422128 -100.202238)
		(width 0.10668)
		(layer "In4.Cu")
		(net "PWRGD_P1V0_AUX")
	)
	(segment
		(start 13.32357 -68.12026)
		(end 13.32357 -79.733648)
		(width 0.08382)
		(layer "In9.Cu")
		(net "PWRGD_P1V0_AUX")
	)
	(segment
		(start 8.001 -89.789762)
		(end 8.001 -95.173292)
		(width 0.08382)
		(layer "In9.Cu")
		(net "PWRGD_P1V0_AUX")
	)
	(segment
		(start 15.076932 -52.349146)
		(end 14.40307 -51.675284)
		(width 0.08382)
		(layer "In9.Cu")
		(net "PWRGD_P1V0_AUX")
	)
	(segment
		(start 11.8364 -81.518506)
		(end 11.8364 -82.403188)
		(width 0.08382)
		(layer "In9.Cu")
		(net "PWRGD_P1V0_AUX")
	)
	(segment
		(start 14.732 -55.2958)
		(end 14.492732 -55.056532)
		(width 0.08382)
		(layer "In9.Cu")
		(net "PWRGD_P1V0_AUX")
	)
	(segment
		(start 9.9568 -98.99269)
		(end 9.58469 -99.3648)
		(width 0.08382)
		(layer "In9.Cu")
		(net "PWRGD_P1V0_AUX")
	)
	(segment
		(start 18.136616 -41.26357)
		(end 18.3642 -41.035986)
		(width 0.08382)
		(layer "In9.Cu")
		(net "PWRGD_P1V0_AUX")
	)
	(segment
		(start 15.076932 -53.376068)
		(end 15.076932 -52.349146)
		(width 0.08382)
		(layer "In9.Cu")
		(net "PWRGD_P1V0_AUX")
	)
	(segment
		(start 15.824454 -46.05147)
		(end 15.824454 -42.752772)
		(width 0.08382)
		(layer "In9.Cu")
		(net "PWRGD_P1V0_AUX")
	)
	(segment
		(start 14.492732 -55.056532)
		(end 14.492732 -53.960268)
		(width 0.08382)
		(layer "In9.Cu")
		(net "PWRGD_P1V0_AUX")
	)
	(segment
		(start 13.32357 -79.733648)
		(end 12.27455 -80.782668)
		(width 0.08382)
		(layer "In9.Cu")
		(net "PWRGD_P1V0_AUX")
	)
	(segment
		(start 11.23569 -82.74431)
		(end 10.77849 -83.20151)
		(width 0.08382)
		(layer "In9.Cu")
		(net "PWRGD_P1V0_AUX")
	)
	(segment
		(start 18.3642 -41.035986)
		(end 18.3642 -40.4876)
		(width 0.08382)
		(layer "In9.Cu")
		(net "PWRGD_P1V0_AUX")
	)
	(segment
		(start 9.9568 -97.129092)
		(end 9.9568 -98.99269)
		(width 0.08382)
		(layer "In9.Cu")
		(net "PWRGD_P1V0_AUX")
	)
	(segment
		(start 14.732 -57.211468)
		(end 14.43355 -57.509918)
		(width 0.08382)
		(layer "In9.Cu")
		(net "PWRGD_P1V0_AUX")
	)
	(segment
		(start 8.001 -95.173292)
		(end 9.9568 -97.129092)
		(width 0.08382)
		(layer "In9.Cu")
		(net "PWRGD_P1V0_AUX")
	)
	(segment
		(start 12.427712 -67.224402)
		(end 13.32357 -68.12026)
		(width 0.08382)
		(layer "In9.Cu")
		(net "PWRGD_P1V0_AUX")
	)
	(segment
		(start 14.40307 -51.675284)
		(end 14.40307 -49.681892)
		(width 0.08382)
		(layer "In9.Cu")
		(net "PWRGD_P1V0_AUX")
	)
	(segment
		(start 14.43355 -57.509918)
		(end 14.43355 -61.411612)
		(width 0.08382)
		(layer "In9.Cu")
		(net "PWRGD_P1V0_AUX")
	)
	(segment
		(start 17.313656 -41.26357)
		(end 18.136616 -41.26357)
		(width 0.08382)
		(layer "In9.Cu")
		(net "PWRGD_P1V0_AUX")
	)
	(segment
		(start 10.77849 -83.20151)
		(end 10.77849 -87.012272)
		(width 0.08382)
		(layer "In9.Cu")
		(net "PWRGD_P1V0_AUX")
	)
	(segment
		(start 14.881352 -48.527462)
		(end 14.881352 -46.994572)
		(width 0.08382)
		(layer "In9.Cu")
		(net "PWRGD_P1V0_AUX")
	)
	(segment
		(start 14.40307 -49.681892)
		(end 14.881352 -48.527462)
		(width 0.08382)
		(layer "In9.Cu")
		(net "PWRGD_P1V0_AUX")
	)
	(segment
		(start 12.27455 -80.782668)
		(end 12.27455 -81.080356)
		(width 0.08382)
		(layer "In9.Cu")
		(net "PWRGD_P1V0_AUX")
	)
	(segment
		(start 15.824454 -42.752772)
		(end 17.313656 -41.26357)
		(width 0.08382)
		(layer "In9.Cu")
		(net "PWRGD_P1V0_AUX")
	)
	(segment
		(start 14.43355 -61.411612)
		(end 12.427712 -63.41745)
		(width 0.08382)
		(layer "In9.Cu")
		(net "PWRGD_P1V0_AUX")
	)
	(segment
		(start 12.427712 -63.41745)
		(end 12.427712 -67.224402)
		(width 0.08382)
		(layer "In9.Cu")
		(net "PWRGD_P1V0_AUX")
	)
	(segment
		(start 11.495278 -82.74431)
		(end 11.23569 -82.74431)
		(width 0.08382)
		(layer "In9.Cu")
		(net "PWRGD_P1V0_AUX")
	)
	(segment
		(start 10.77849 -87.012272)
		(end 8.001 -89.789762)
		(width 0.08382)
		(layer "In9.Cu")
		(net "PWRGD_P1V0_AUX")
	)
	(segment
		(start 12.27455 -81.080356)
		(end 11.8364 -81.518506)
		(width 0.08382)
		(layer "In9.Cu")
		(net "PWRGD_P1V0_AUX")
	)
	(segment
		(start 14.732 -55.2958)
		(end 14.732 -57.211468)
		(width 0.08382)
		(layer "In9.Cu")
		(net "PWRGD_P1V0_AUX")
	)
	(segment
		(start 11.8364 -82.403188)
		(end 11.495278 -82.74431)
		(width 0.08382)
		(layer "In9.Cu")
		(net "PWRGD_P1V0_AUX")
	)
	(segment
		(start 14.492732 -53.960268)
		(end 15.076932 -53.376068)
		(width 0.08382)
		(layer "In9.Cu")
		(net "PWRGD_P1V0_AUX")
	)
	(segment
		(start 14.881352 -46.994572)
		(end 15.824454 -46.05147)
		(width 0.08382)
		(layer "In9.Cu")
		(net "PWRGD_P1V0_AUX")
	)
	(segment
		(start 46.99 -115.951)
		(end 46.99 -117.018054)
		(width 0.11684)
		(layer "F.Cu")
		(net "PVCCIO_PECI_BMC")
	)
	(segment
		(start 51.295046 -55.371238)
		(end 50.899822 -55.766462)
		(width 0.3556)
		(layer "F.Cu")
		(net "PVCCIO_PECI_BMC")
	)
	(segment
		(start 47.265082 -117.293136)
		(end 47.265082 -118.460012)
		(width 0.11684)
		(layer "F.Cu")
		(net "PVCCIO_PECI_BMC")
	)
	(segment
		(start 46.99 -117.018054)
		(end 47.265082 -117.293136)
		(width 0.11684)
		(layer "F.Cu")
		(net "PVCCIO_PECI_BMC")
	)
	(via
		(at 46.99 -115.951)
		(size 0.508)
		(drill 0.254)
		(layers "F.Cu" "B.Cu")
		(net "PVCCIO_PECI_BMC")
	)
	(via
		(at 50.899822 -55.766462)
		(size 0.4572)
		(drill 0.254)
		(layers "F.Cu" "B.Cu")
		(net "PVCCIO_PECI_BMC")
	)
	(via
		(at 38.7096 -57.4802)
		(size 0.6604)
		(drill 0.3302)
		(layers "F.Cu" "B.Cu")
		(net "PVCCIO_PECI_BMC")
	)
	(via
		(at 41.1988 -56.229504)
		(size 0.508)
		(drill 0.254)
		(layers "F.Cu" "B.Cu")
		(net "PVCCIO_PECI_BMC")
	)
	(segment
		(start 50.506884 -56.1594)
		(end 47.3964 -56.1594)
		(width 0.08382)
		(layer "In2.Cu")
		(net "PVCCIO_PECI_BMC")
	)
	(segment
		(start 41.7576 -58.674)
		(end 41.3258 -58.674)
		(width 0.08382)
		(layer "In2.Cu")
		(net "PVCCIO_PECI_BMC")
	)
	(segment
		(start 41.0718 -58.42)
		(end 41.0718 -56.356504)
		(width 0.08382)
		(layer "In2.Cu")
		(net "PVCCIO_PECI_BMC")
	)
	(segment
		(start 47.2948 -56.7944)
		(end 47.1424 -56.9468)
		(width 0.08382)
		(layer "In2.Cu")
		(net "PVCCIO_PECI_BMC")
	)
	(segment
		(start 50.899822 -55.766462)
		(end 50.506884 -56.1594)
		(width 0.08382)
		(layer "In2.Cu")
		(net "PVCCIO_PECI_BMC")
	)
	(segment
		(start 41.0718 -56.356504)
		(end 41.1988 -56.229504)
		(width 0.08382)
		(layer "In2.Cu")
		(net "PVCCIO_PECI_BMC")
	)
	(segment
		(start 44.3738 -57.7342)
		(end 42.6974 -57.7342)
		(width 0.08382)
		(layer "In2.Cu")
		(net "PVCCIO_PECI_BMC")
	)
	(segment
		(start 42.6974 -57.7342)
		(end 41.7576 -58.674)
		(width 0.08382)
		(layer "In2.Cu")
		(net "PVCCIO_PECI_BMC")
	)
	(segment
		(start 41.3258 -58.674)
		(end 41.0718 -58.42)
		(width 0.08382)
		(layer "In2.Cu")
		(net "PVCCIO_PECI_BMC")
	)
	(segment
		(start 47.3964 -56.1594)
		(end 47.2948 -56.261)
		(width 0.08382)
		(layer "In2.Cu")
		(net "PVCCIO_PECI_BMC")
	)
	(segment
		(start 45.1612 -56.9468)
		(end 44.3738 -57.7342)
		(width 0.08382)
		(layer "In2.Cu")
		(net "PVCCIO_PECI_BMC")
	)
	(segment
		(start 47.1424 -56.9468)
		(end 45.1612 -56.9468)
		(width 0.08382)
		(layer "In2.Cu")
		(net "PVCCIO_PECI_BMC")
	)
	(segment
		(start 47.2948 -56.261)
		(end 47.2948 -56.7944)
		(width 0.08382)
		(layer "In2.Cu")
		(net "PVCCIO_PECI_BMC")
	)
	(segment
		(start 49.1998 -106.0196)
		(end 49.1998 -104.7242)
		(width 0.10668)
		(layer "In4.Cu")
		(net "PVCCIO_PECI_BMC")
	)
	(segment
		(start 53.790088 -58.561478)
		(end 53.683408 -58.454798)
		(width 0.10668)
		(layer "In4.Cu")
		(net "PVCCIO_PECI_BMC")
	)
	(segment
		(start 49.67986 -93.1799)
		(end 49.9491 -92.91066)
		(width 0.10668)
		(layer "In4.Cu")
		(net "PVCCIO_PECI_BMC")
	)
	(segment
		(start 54.58714 -60.27674)
		(end 54.58714 -58.871866)
		(width 0.10668)
		(layer "In4.Cu")
		(net "PVCCIO_PECI_BMC")
	)
	(segment
		(start 50.88636 -76.15174)
		(end 53.335428 -73.702672)
		(width 0.10668)
		(layer "In4.Cu")
		(net "PVCCIO_PECI_BMC")
	)
	(segment
		(start 53.683408 -56.400954)
		(end 53.441854 -56.1594)
		(width 0.10668)
		(layer "In4.Cu")
		(net "PVCCIO_PECI_BMC")
	)
	(segment
		(start 51.29276 -56.1594)
		(end 50.899822 -55.766462)
		(width 0.10668)
		(layer "In4.Cu")
		(net "PVCCIO_PECI_BMC")
	)
	(segment
		(start 54.26837 -63.574422)
		(end 53.87848 -63.184532)
		(width 0.10668)
		(layer "In4.Cu")
		(net "PVCCIO_PECI_BMC")
	)
	(segment
		(start 49.57826 -99.66706)
		(end 49.57826 -98.515424)
		(width 0.10668)
		(layer "In4.Cu")
		(net "PVCCIO_PECI_BMC")
	)
	(segment
		(start 54.58714 -58.871866)
		(end 54.276752 -58.561478)
		(width 0.10668)
		(layer "In4.Cu")
		(net "PVCCIO_PECI_BMC")
	)
	(segment
		(start 53.87848 -63.184532)
		(end 53.87848 -60.9854)
		(width 0.10668)
		(layer "In4.Cu")
		(net "PVCCIO_PECI_BMC")
	)
	(segment
		(start 50.193448 -103.730552)
		(end 50.193448 -100.282248)
		(width 0.10668)
		(layer "In4.Cu")
		(net "PVCCIO_PECI_BMC")
	)
	(segment
		(start 54.44617 -68.187824)
		(end 54.44617 -67.17665)
		(width 0.10668)
		(layer "In4.Cu")
		(net "PVCCIO_PECI_BMC")
	)
	(segment
		(start 53.335428 -69.298566)
		(end 54.44617 -68.187824)
		(width 0.10668)
		(layer "In4.Cu")
		(net "PVCCIO_PECI_BMC")
	)
	(segment
		(start 54.44617 -67.17665)
		(end 53.78577 -66.51625)
		(width 0.10668)
		(layer "In4.Cu")
		(net "PVCCIO_PECI_BMC")
	)
	(segment
		(start 53.441854 -56.1594)
		(end 51.29276 -56.1594)
		(width 0.10668)
		(layer "In4.Cu")
		(net "PVCCIO_PECI_BMC")
	)
	(segment
		(start 50.193448 -100.282248)
		(end 49.57826 -99.66706)
		(width 0.10668)
		(layer "In4.Cu")
		(net "PVCCIO_PECI_BMC")
	)
	(segment
		(start 53.335428 -73.702672)
		(end 53.335428 -69.298566)
		(width 0.10668)
		(layer "In4.Cu")
		(net "PVCCIO_PECI_BMC")
	)
	(segment
		(start 53.87848 -60.9854)
		(end 54.58714 -60.27674)
		(width 0.10668)
		(layer "In4.Cu")
		(net "PVCCIO_PECI_BMC")
	)
	(segment
		(start 47.1805 -115.77574)
		(end 47.44974 -115.5065)
		(width 0.10668)
		(layer "In4.Cu")
		(net "PVCCIO_PECI_BMC")
	)
	(segment
		(start 47.44974 -115.21186)
		(end 48.6918 -113.9698)
		(width 0.10668)
		(layer "In4.Cu")
		(net "PVCCIO_PECI_BMC")
	)
	(segment
		(start 49.9491 -92.91066)
		(end 50.523394 -92.91066)
		(width 0.10668)
		(layer "In4.Cu")
		(net "PVCCIO_PECI_BMC")
	)
	(segment
		(start 48.6918 -113.9698)
		(end 48.6918 -108.9152)
		(width 0.10668)
		(layer "In4.Cu")
		(net "PVCCIO_PECI_BMC")
	)
	(segment
		(start 49.98974 -107.61726)
		(end 49.98974 -106.80954)
		(width 0.10668)
		(layer "In4.Cu")
		(net "PVCCIO_PECI_BMC")
	)
	(segment
		(start 53.78577 -65.545462)
		(end 54.26837 -65.062862)
		(width 0.10668)
		(layer "In4.Cu")
		(net "PVCCIO_PECI_BMC")
	)
	(segment
		(start 50.523394 -92.91066)
		(end 51.66106 -91.772994)
		(width 0.10668)
		(layer "In4.Cu")
		(net "PVCCIO_PECI_BMC")
	)
	(segment
		(start 54.276752 -58.561478)
		(end 53.790088 -58.561478)
		(width 0.10668)
		(layer "In4.Cu")
		(net "PVCCIO_PECI_BMC")
	)
	(segment
		(start 49.57826 -98.515424)
		(end 49.03724 -97.974404)
		(width 0.10668)
		(layer "In4.Cu")
		(net "PVCCIO_PECI_BMC")
	)
	(segment
		(start 49.03724 -97.974404)
		(end 49.03724 -94.396814)
		(width 0.10668)
		(layer "In4.Cu")
		(net "PVCCIO_PECI_BMC")
	)
	(segment
		(start 49.67986 -93.754194)
		(end 49.67986 -93.1799)
		(width 0.10668)
		(layer "In4.Cu")
		(net "PVCCIO_PECI_BMC")
	)
	(segment
		(start 53.683408 -58.454798)
		(end 53.683408 -56.400954)
		(width 0.10668)
		(layer "In4.Cu")
		(net "PVCCIO_PECI_BMC")
	)
	(segment
		(start 50.88636 -78.38313)
		(end 50.88636 -76.15174)
		(width 0.10668)
		(layer "In4.Cu")
		(net "PVCCIO_PECI_BMC")
	)
	(segment
		(start 47.44974 -115.5065)
		(end 47.44974 -115.21186)
		(width 0.10668)
		(layer "In4.Cu")
		(net "PVCCIO_PECI_BMC")
	)
	(segment
		(start 48.6918 -108.9152)
		(end 49.98974 -107.61726)
		(width 0.10668)
		(layer "In4.Cu")
		(net "PVCCIO_PECI_BMC")
	)
	(segment
		(start 51.66106 -91.772994)
		(end 51.66106 -79.15783)
		(width 0.10668)
		(layer "In4.Cu")
		(net "PVCCIO_PECI_BMC")
	)
	(segment
		(start 54.26837 -65.062862)
		(end 54.26837 -63.574422)
		(width 0.10668)
		(layer "In4.Cu")
		(net "PVCCIO_PECI_BMC")
	)
	(segment
		(start 46.99 -115.951)
		(end 47.16526 -115.77574)
		(width 0.10668)
		(layer "In4.Cu")
		(net "PVCCIO_PECI_BMC")
	)
	(segment
		(start 47.16526 -115.77574)
		(end 47.1805 -115.77574)
		(width 0.10668)
		(layer "In4.Cu")
		(net "PVCCIO_PECI_BMC")
	)
	(segment
		(start 49.98974 -106.80954)
		(end 49.1998 -106.0196)
		(width 0.10668)
		(layer "In4.Cu")
		(net "PVCCIO_PECI_BMC")
	)
	(segment
		(start 53.78577 -66.51625)
		(end 53.78577 -65.545462)
		(width 0.10668)
		(layer "In4.Cu")
		(net "PVCCIO_PECI_BMC")
	)
	(segment
		(start 49.1998 -104.7242)
		(end 50.193448 -103.730552)
		(width 0.10668)
		(layer "In4.Cu")
		(net "PVCCIO_PECI_BMC")
	)
	(segment
		(start 51.66106 -79.15783)
		(end 50.88636 -78.38313)
		(width 0.10668)
		(layer "In4.Cu")
		(net "PVCCIO_PECI_BMC")
	)
	(segment
		(start 49.03724 -94.396814)
		(end 49.67986 -93.754194)
		(width 0.10668)
		(layer "In4.Cu")
		(net "PVCCIO_PECI_BMC")
	)
	(segment
		(start 19.864324 -95.182182)
		(end 20.259548 -94.786958)
		(width 0.381)
		(layer "F.Cu")
		(net "PVCCA_AUX_PLD")
	)
	(segment
		(start 23.054564 -91.991942)
		(end 22.65934 -92.387166)
		(width 0.381)
		(layer "F.Cu")
		(net "PVCCA_AUX_PLD")
	)
	(segment
		(start 15.864332 -87.99195)
		(end 15.459456 -87.587074)
		(width 0.381)
		(layer "F.Cu")
		(net "PVCCA_AUX_PLD")
	)
	(segment
		(start 15.11046 -99.951286)
		(end 15.113 -100.076)
		(width 0.4064)
		(layer "F.Cu")
		(net "PVCCA_AUX_PLD")
	)
	(segment
		(start 27.459432 -99.58705)
		(end 27.459432 -100.3554)
		(width 0.3556)
		(layer "F.Cu")
		(net "PVCCA_AUX_PLD")
	)
	(segment
		(start 19.864324 -91.991942)
		(end 20.259548 -92.387166)
		(width 0.381)
		(layer "F.Cu")
		(net "PVCCA_AUX_PLD")
	)
	(segment
		(start 23.054564 -95.182182)
		(end 22.65934 -94.786958)
		(width 0.381)
		(layer "F.Cu")
		(net "PVCCA_AUX_PLD")
	)
	(segment
		(start 15.459456 -99.58705)
		(end 15.11046 -99.951286)
		(width 0.4064)
		(layer "F.Cu")
		(net "PVCCA_AUX_PLD")
	)
	(segment
		(start 27.459432 -87.593424)
		(end 27.459432 -87.587074)
		(width 0.381)
		(layer "F.Cu")
		(net "PVCCA_AUX_PLD")
	)
	(segment
		(start 27.067256 -87.9856)
		(end 27.459432 -87.593424)
		(width 0.381)
		(layer "F.Cu")
		(net "PVCCA_AUX_PLD")
	)
	(via
		(at 14.097 -100.4824)
		(size 0.6604)
		(drill 0.3302)
		(layers "F.Cu" "B.Cu")
		(net "PVCCA_AUX_PLD")
	)
	(via
		(at 15.113 -100.076)
		(size 0.508)
		(drill 0.254)
		(layers "F.Cu" "B.Cu")
		(net "PVCCA_AUX_PLD")
	)
	(via
		(at 27.067256 -87.9856)
		(size 0.4572)
		(drill 0.254)
		(layers "F.Cu" "B.Cu")
		(net "PVCCA_AUX_PLD")
	)
	(via
		(at 15.19428 -86.62162)
		(size 0.6604)
		(drill 0.3302)
		(layers "F.Cu" "B.Cu")
		(net "PVCCA_AUX_PLD")
	)
	(via
		(at 15.864332 -87.99195)
		(size 0.4572)
		(drill 0.254)
		(layers "F.Cu" "B.Cu")
		(net "PVCCA_AUX_PLD")
	)
	(via
		(at 27.459432 -100.3554)
		(size 0.508)
		(drill 0.254)
		(layers "F.Cu" "B.Cu")
		(net "PVCCA_AUX_PLD")
	)
	(via
		(at 19.864324 -91.991942)
		(size 0.4572)
		(drill 0.254)
		(layers "F.Cu" "B.Cu")
		(net "PVCCA_AUX_PLD")
	)
	(via
		(at 23.054564 -95.182182)
		(size 0.4572)
		(drill 0.254)
		(layers "F.Cu" "B.Cu")
		(net "PVCCA_AUX_PLD")
	)
	(via
		(at 19.864324 -95.182182)
		(size 0.4572)
		(drill 0.254)
		(layers "F.Cu" "B.Cu")
		(net "PVCCA_AUX_PLD")
	)
	(via
		(at 23.054564 -91.991942)
		(size 0.4572)
		(drill 0.254)
		(layers "F.Cu" "B.Cu")
		(net "PVCCA_AUX_PLD")
	)
	(segment
		(start 19.864324 -91.993466)
		(end 20.282408 -92.41155)
		(width 0.254)
		(layer "B.Cu")
		(net "PVCCA_AUX_PLD")
	)
	(segment
		(start 19.864324 -91.991942)
		(end 19.864324 -91.993466)
		(width 0.254)
		(layer "B.Cu")
		(net "PVCCA_AUX_PLD")
	)
	(segment
		(start 26.665682 -88.387174)
		(end 26.659332 -88.387174)
		(width 0.254)
		(layer "B.Cu")
		(net "PVCCA_AUX_PLD")
	)
	(segment
		(start 19.472656 -95.57385)
		(end 19.472656 -95.61195)
		(width 0.254)
		(layer "B.Cu")
		(net "PVCCA_AUX_PLD")
	)
	(segment
		(start 27.067256 -87.9856)
		(end 26.665682 -88.387174)
		(width 0.254)
		(layer "B.Cu")
		(net "PVCCA_AUX_PLD")
	)
	(segment
		(start 23.054564 -95.182182)
		(end 23.106634 -95.130112)
		(width 0.254)
		(layer "B.Cu")
		(net "PVCCA_AUX_PLD")
	)
	(segment
		(start 23.106634 -95.130112)
		(end 23.802594 -95.130112)
		(width 0.254)
		(layer "B.Cu")
		(net "PVCCA_AUX_PLD")
	)
	(segment
		(start 19.864324 -95.182182)
		(end 19.472656 -95.57385)
		(width 0.254)
		(layer "B.Cu")
		(net "PVCCA_AUX_PLD")
	)
	(segment
		(start 73.181464 -30.557724)
		(end 72.46493 -30.557724)
		(width 0.254)
		(layer "F.Cu")
		(net "LED_POSTCODE_7_R")
	)
	(segment
		(start 74.01052 -30.557724)
		(end 73.181464 -30.557724)
		(width 0.254)
		(layer "F.Cu")
		(net "LED_POSTCODE_7_R")
	)
	(via
		(at 73.181464 -30.557724)
		(size 0.508)
		(drill 0.254)
		(layers "F.Cu" "B.Cu")
		(net "LED_POSTCODE_7_R")
	)
	(segment
		(start 73.140316 -33.4518)
		(end 73.100184 -33.411668)
		(width 0.254)
		(layer "F.Cu")
		(net "LED_POSTCODE_6_R")
	)
	(segment
		(start 75.646534 -32.515048)
		(end 75.646534 -33.039812)
		(width 0.254)
		(layer "F.Cu")
		(net "LED_POSTCODE_6_R")
	)
	(segment
		(start 75.646534 -33.039812)
		(end 75.234546 -33.4518)
		(width 0.254)
		(layer "F.Cu")
		(net "LED_POSTCODE_6_R")
	)
	(segment
		(start 72.46493 -33.411668)
		(end 73.100184 -33.411668)
		(width 0.254)
		(layer "F.Cu")
		(net "LED_POSTCODE_6_R")
	)
	(segment
		(start 75.234546 -33.4518)
		(end 73.140316 -33.4518)
		(width 0.254)
		(layer "F.Cu")
		(net "LED_POSTCODE_6_R")
	)
	(via
		(at 73.100184 -33.411668)
		(size 0.508)
		(drill 0.254)
		(layers "F.Cu" "B.Cu")
		(net "LED_POSTCODE_6_R")
	)
	(segment
		(start 77.281786 -30.557724)
		(end 77.868018 -29.971492)
		(width 0.254)
		(layer "F.Cu")
		(net "LED_POSTCODE_5_R")
	)
	(segment
		(start 79.91475 -30.43555)
		(end 80.4418 -30.43555)
		(width 0.254)
		(layer "F.Cu")
		(net "LED_POSTCODE_5_R")
	)
	(segment
		(start 77.868018 -29.971492)
		(end 77.87259 -29.971492)
		(width 0.254)
		(layer "F.Cu")
		(net "LED_POSTCODE_5_R")
	)
	(segment
		(start 79.2988 -29.8196)
		(end 79.91475 -30.43555)
		(width 0.254)
		(layer "F.Cu")
		(net "LED_POSTCODE_5_R")
	)
	(segment
		(start 78.024482 -29.8196)
		(end 79.2988 -29.8196)
		(width 0.254)
		(layer "F.Cu")
		(net "LED_POSTCODE_5_R")
	)
	(segment
		(start 77.87259 -29.971492)
		(end 78.024482 -29.8196)
		(width 0.254)
		(layer "F.Cu")
		(net "LED_POSTCODE_5_R")
	)
	(segment
		(start 78.907894 -32.515048)
		(end 79.08925 -32.696404)
		(width 0.254)
		(layer "F.Cu")
		(net "LED_POSTCODE_4_R")
	)
	(segment
		(start 79.08925 -32.696404)
		(end 79.08925 -34.1122)
		(width 0.254)
		(layer "F.Cu")
		(net "LED_POSTCODE_4_R")
	)
	(segment
		(start 74.01052 -26.98877)
		(end 72.942958 -26.98877)
		(width 0.3556)
		(layer "F.Cu")
		(net "LED_POSTCODE_3_R")
	)
	(segment
		(start 72.192388 -26.2382)
		(end 72.649588 -25.781)
		(width 0.3556)
		(layer "F.Cu")
		(net "LED_POSTCODE_3_R")
	)
	(segment
		(start 72.649588 -25.781)
		(end 73.10755 -25.781)
		(width 0.3556)
		(layer "F.Cu")
		(net "LED_POSTCODE_3_R")
	)
	(segment
		(start 72.942958 -26.98877)
		(end 72.192388 -26.2382)
		(width 0.3556)
		(layer "F.Cu")
		(net "LED_POSTCODE_3_R")
	)
	(segment
		(start 73.10755 -25.781)
		(end 73.38695 -25.5016)
		(width 0.3556)
		(layer "F.Cu")
		(net "LED_POSTCODE_3_R")
	)
	(via
		(at 72.192388 -26.2382)
		(size 0.762)
		(drill 0.381)
		(layers "F.Cu" "B.Cu")
		(net "LED_POSTCODE_3_R")
	)
	(segment
		(start 73.211436 -29.6926)
		(end 72.46493 -28.946094)
		(width 0.254)
		(layer "F.Cu")
		(net "LED_POSTCODE_2_R")
	)
	(segment
		(start 74.900028 -29.6926)
		(end 73.211436 -29.6926)
		(width 0.254)
		(layer "F.Cu")
		(net "LED_POSTCODE_2_R")
	)
	(segment
		(start 75.646534 -28.946094)
		(end 74.900028 -29.6926)
		(width 0.254)
		(layer "F.Cu")
		(net "LED_POSTCODE_2_R")
	)
	(segment
		(start 78.359508 -25.911048)
		(end 78.935072 -25.911048)
		(width 0.254)
		(layer "F.Cu")
		(net "LED_POSTCODE_1_R")
	)
	(segment
		(start 80.280764 -26.096722)
		(end 80.09509 -25.911048)
		(width 0.254)
		(layer "F.Cu")
		(net "LED_POSTCODE_1_R")
	)
	(segment
		(start 80.09509 -25.911048)
		(end 78.935072 -25.911048)
		(width 0.254)
		(layer "F.Cu")
		(net "LED_POSTCODE_1_R")
	)
	(segment
		(start 77.281786 -26.98877)
		(end 78.359508 -25.911048)
		(width 0.254)
		(layer "F.Cu")
		(net "LED_POSTCODE_1_R")
	)
	(via
		(at 78.935072 -25.911048)
		(size 0.762)
		(drill 0.381)
		(layers "F.Cu" "B.Cu")
		(net "LED_POSTCODE_1_R")
	)
	(segment
		(start 79.568294 -28.946094)
		(end 79.568548 -28.94584)
		(width 0.254)
		(layer "F.Cu")
		(net "LED_POSTCODE_0_R")
	)
	(segment
		(start 79.568548 -28.94584)
		(end 80.280764 -28.94584)
		(width 0.254)
		(layer "F.Cu")
		(net "LED_POSTCODE_0_R")
	)
	(segment
		(start 78.907894 -28.946094)
		(end 79.568294 -28.946094)
		(width 0.254)
		(layer "F.Cu")
		(net "LED_POSTCODE_0_R")
	)
	(segment
		(start 54.851046 -27.626818)
		(end 54.55539 -27.626818)
		(width 0.11684)
		(layer "F.Cu")
		(net "PU_25M_BMC_CLK_EN")
	)
	(segment
		(start 55.810912 -27.0256)
		(end 56.023256 -27.237944)
		(width 0.11684)
		(layer "F.Cu")
		(net "PU_25M_BMC_CLK_EN")
	)
	(segment
		(start 54.9656 -27.512264)
		(end 54.851046 -27.626818)
		(width 0.11684)
		(layer "F.Cu")
		(net "PU_25M_BMC_CLK_EN")
	)
	(segment
		(start 54.9656 -27.0256)
		(end 54.9656 -27.512264)
		(width 0.11684)
		(layer "F.Cu")
		(net "PU_25M_BMC_CLK_EN")
	)
	(segment
		(start 54.9656 -27.0256)
		(end 55.810912 -27.0256)
		(width 0.11684)
		(layer "F.Cu")
		(net "PU_25M_BMC_CLK_EN")
	)
	(via
		(at 54.9656 -27.0256)
		(size 0.508)
		(drill 0.254)
		(layers "F.Cu" "B.Cu")
		(net "PU_25M_BMC_CLK_EN")
	)
	(segment
		(start 52.3748 -59.891422)
		(end 52.894992 -59.37123)
		(width 0.11684)
		(layer "F.Cu")
		(net "PECI_BMC_R")
	)
	(segment
		(start 50.75174 -63.553594)
		(end 51.054 -63.251334)
		(width 0.11684)
		(layer "F.Cu")
		(net "PECI_BMC_R")
	)
	(segment
		(start 50.8508 -61.98616)
		(end 52.3748 -60.46216)
		(width 0.11684)
		(layer "F.Cu")
		(net "PECI_BMC_R")
	)
	(segment
		(start 50.8508 -62.585346)
		(end 50.8508 -61.98616)
		(width 0.11684)
		(layer "F.Cu")
		(net "PECI_BMC_R")
	)
	(segment
		(start 51.054 -63.251334)
		(end 51.054 -62.788546)
		(width 0.11684)
		(layer "F.Cu")
		(net "PECI_BMC_R")
	)
	(segment
		(start 52.3748 -60.46216)
		(end 52.3748 -59.891422)
		(width 0.11684)
		(layer "F.Cu")
		(net "PECI_BMC_R")
	)
	(segment
		(start 51.054 -62.788546)
		(end 50.8508 -62.585346)
		(width 0.11684)
		(layer "F.Cu")
		(net "PECI_BMC_R")
	)
	(segment
		(start 50.4952 -66.82359)
		(end 50.05705 -67.26174)
		(width 0.11684)
		(layer "F.Cu")
		(net "PECI_BMC")
	)
	(segment
		(start 47.866554 -117.335808)
		(end 47.866554 -118.258336)
		(width 0.11684)
		(layer "F.Cu")
		(net "PECI_BMC")
	)
	(segment
		(start 50.4952 -65.024)
		(end 50.4952 -66.82359)
		(width 0.11684)
		(layer "F.Cu")
		(net "PECI_BMC")
	)
	(segment
		(start 46.99 -115.316)
		(end 47.4218 -115.316)
		(width 0.11684)
		(layer "F.Cu")
		(net "PECI_BMC")
	)
	(segment
		(start 50.75174 -64.76746)
		(end 50.4952 -65.024)
		(width 0.11684)
		(layer "F.Cu")
		(net "PECI_BMC")
	)
	(segment
		(start 50.13579 -67.34048)
		(end 51.0794 -67.34048)
		(width 0.11684)
		(layer "F.Cu")
		(net "PECI_BMC")
	)
	(segment
		(start 47.866554 -118.258336)
		(end 47.86503 -118.25986)
		(width 0.11684)
		(layer "F.Cu")
		(net "PECI_BMC")
	)
	(segment
		(start 47.6758 -115.57)
		(end 47.6758 -117.145054)
		(width 0.11684)
		(layer "F.Cu")
		(net "PECI_BMC")
	)
	(segment
		(start 50.05705 -67.26174)
		(end 50.13579 -67.34048)
		(width 0.11684)
		(layer "F.Cu")
		(net "PECI_BMC")
	)
	(segment
		(start 47.6758 -117.145054)
		(end 47.866554 -117.335808)
		(width 0.11684)
		(layer "F.Cu")
		(net "PECI_BMC")
	)
	(segment
		(start 50.75174 -64.353694)
		(end 50.75174 -64.76746)
		(width 0.11684)
		(layer "F.Cu")
		(net "PECI_BMC")
	)
	(segment
		(start 47.4218 -115.316)
		(end 47.6758 -115.57)
		(width 0.11684)
		(layer "F.Cu")
		(net "PECI_BMC")
	)
	(via
		(at 51.0794 -67.34048)
		(size 0.508)
		(drill 0.254)
		(layers "F.Cu" "B.Cu")
		(net "PECI_BMC")
	)
	(via
		(at 74.3458 -102.5398)
		(size 0.508)
		(drill 0.254)
		(layers "F.Cu" "B.Cu")
		(net "PECI_BMC")
	)
	(via
		(at 46.99 -115.316)
		(size 0.508)
		(drill 0.254)
		(layers "F.Cu" "B.Cu")
		(net "PECI_BMC")
	)
	(segment
		(start 62.62116 -116.6114)
		(end 62.6872 -116.6114)
		(width 0.08382)
		(layer "In2.Cu")
		(net "PECI_BMC")
	)
	(segment
		(start 53.4416 -116.7384)
		(end 54.4195 -115.7605)
		(width 0.08382)
		(layer "In2.Cu")
		(net "PECI_BMC")
	)
	(segment
		(start 62.6872 -116.6114)
		(end 63.542164 -115.756436)
		(width 0.08382)
		(layer "In2.Cu")
		(net "PECI_BMC")
	)
	(segment
		(start 66.64071 -112.13211)
		(end 67.52717 -113.01857)
		(width 0.08382)
		(layer "In2.Cu")
		(net "PECI_BMC")
	)
	(segment
		(start 48.768 -116.7384)
		(end 53.4416 -116.7384)
		(width 0.08382)
		(layer "In2.Cu")
		(net "PECI_BMC")
	)
	(segment
		(start 67.52717 -113.01857)
		(end 70.344284 -113.01857)
		(width 0.08382)
		(layer "In2.Cu")
		(net "PECI_BMC")
	)
	(segment
		(start 47.3456 -115.316)
		(end 48.768 -116.7384)
		(width 0.08382)
		(layer "In2.Cu")
		(net "PECI_BMC")
	)
	(segment
		(start 63.542164 -115.756436)
		(end 63.542164 -113.543334)
		(width 0.08382)
		(layer "In2.Cu")
		(net "PECI_BMC")
	)
	(segment
		(start 46.99 -115.316)
		(end 47.3456 -115.316)
		(width 0.08382)
		(layer "In2.Cu")
		(net "PECI_BMC")
	)
	(segment
		(start 70.344284 -113.01857)
		(end 72.5424 -110.820454)
		(width 0.08382)
		(layer "In2.Cu")
		(net "PECI_BMC")
	)
	(segment
		(start 63.542164 -113.543334)
		(end 64.953388 -112.13211)
		(width 0.08382)
		(layer "In2.Cu")
		(net "PECI_BMC")
	)
	(segment
		(start 64.953388 -112.13211)
		(end 66.64071 -112.13211)
		(width 0.08382)
		(layer "In2.Cu")
		(net "PECI_BMC")
	)
	(segment
		(start 59.40806 -116.74602)
		(end 62.48654 -116.74602)
		(width 0.08382)
		(layer "In2.Cu")
		(net "PECI_BMC")
	)
	(segment
		(start 62.48654 -116.74602)
		(end 62.62116 -116.6114)
		(width 0.08382)
		(layer "In2.Cu")
		(net "PECI_BMC")
	)
	(segment
		(start 72.5424 -104.3432)
		(end 74.3458 -102.5398)
		(width 0.08382)
		(layer "In2.Cu")
		(net "PECI_BMC")
	)
	(segment
		(start 58.42254 -115.7605)
		(end 59.40806 -116.74602)
		(width 0.08382)
		(layer "In2.Cu")
		(net "PECI_BMC")
	)
	(segment
		(start 54.4195 -115.7605)
		(end 58.42254 -115.7605)
		(width 0.08382)
		(layer "In2.Cu")
		(net "PECI_BMC")
	)
	(segment
		(start 72.5424 -110.820454)
		(end 72.5424 -104.3432)
		(width 0.08382)
		(layer "In2.Cu")
		(net "PECI_BMC")
	)
	(segment
		(start 64.54394 -77.16774)
		(end 63.95974 -76.58354)
		(width 0.10668)
		(layer "In7.Cu")
		(net "PECI_BMC")
	)
	(segment
		(start 59.07659 -71.675752)
		(end 58.551318 -71.15048)
		(width 0.10668)
		(layer "In7.Cu")
		(net "PECI_BMC")
	)
	(segment
		(start 60.452 -74.96302)
		(end 60.452 -73.947782)
		(width 0.10668)
		(layer "In7.Cu")
		(net "PECI_BMC")
	)
	(segment
		(start 68.77558 -97.103184)
		(end 68.77558 -93.21419)
		(width 0.10668)
		(layer "In7.Cu")
		(net "PECI_BMC")
	)
	(segment
		(start 58.551318 -71.15048)
		(end 57.959752 -71.15048)
		(width 0.10668)
		(layer "In7.Cu")
		(net "PECI_BMC")
	)
	(segment
		(start 57.959752 -71.15048)
		(end 56.946546 -70.137274)
		(width 0.10668)
		(layer "In7.Cu")
		(net "PECI_BMC")
	)
	(segment
		(start 70.40753 -98.735134)
		(end 68.77558 -97.103184)
		(width 0.10668)
		(layer "In7.Cu")
		(net "PECI_BMC")
	)
	(segment
		(start 51.409854 -68.8594)
		(end 51.0794 -68.528946)
		(width 0.10668)
		(layer "In7.Cu")
		(net "PECI_BMC")
	)
	(segment
		(start 51.0794 -68.528946)
		(end 51.0794 -67.34048)
		(width 0.10668)
		(layer "In7.Cu")
		(net "PECI_BMC")
	)
	(segment
		(start 70.65518 -99.332796)
		(end 70.40753 -98.735134)
		(width 0.10668)
		(layer "In7.Cu")
		(net "PECI_BMC")
	)
	(segment
		(start 62.07252 -76.58354)
		(end 60.452 -74.96302)
		(width 0.10668)
		(layer "In7.Cu")
		(net "PECI_BMC")
	)
	(segment
		(start 64.54394 -81.125314)
		(end 64.54394 -77.16774)
		(width 0.10668)
		(layer "In7.Cu")
		(net "PECI_BMC")
	)
	(segment
		(start 63.849758 -81.819496)
		(end 64.54394 -81.125314)
		(width 0.10668)
		(layer "In7.Cu")
		(net "PECI_BMC")
	)
	(segment
		(start 74.3458 -102.5398)
		(end 72.817482 -102.5398)
		(width 0.10668)
		(layer "In7.Cu")
		(net "PECI_BMC")
	)
	(segment
		(start 63.95974 -76.58354)
		(end 62.07252 -76.58354)
		(width 0.10668)
		(layer "In7.Cu")
		(net "PECI_BMC")
	)
	(segment
		(start 72.817482 -102.5398)
		(end 70.65518 -100.377498)
		(width 0.10668)
		(layer "In7.Cu")
		(net "PECI_BMC")
	)
	(segment
		(start 52.954428 -68.8594)
		(end 51.409854 -68.8594)
		(width 0.10668)
		(layer "In7.Cu")
		(net "PECI_BMC")
	)
	(segment
		(start 63.78194 -81.892394)
		(end 63.849758 -81.824576)
		(width 0.10668)
		(layer "In7.Cu")
		(net "PECI_BMC")
	)
	(segment
		(start 56.946546 -70.137274)
		(end 54.232302 -70.137274)
		(width 0.10668)
		(layer "In7.Cu")
		(net "PECI_BMC")
	)
	(segment
		(start 63.849758 -82.42554)
		(end 63.78194 -82.261964)
		(width 0.10668)
		(layer "In7.Cu")
		(net "PECI_BMC")
	)
	(segment
		(start 63.849758 -81.824576)
		(end 63.849758 -81.819496)
		(width 0.10668)
		(layer "In7.Cu")
		(net "PECI_BMC")
	)
	(segment
		(start 54.232302 -70.137274)
		(end 52.954428 -68.8594)
		(width 0.10668)
		(layer "In7.Cu")
		(net "PECI_BMC")
	)
	(segment
		(start 60.452 -73.947782)
		(end 59.07659 -72.572372)
		(width 0.10668)
		(layer "In7.Cu")
		(net "PECI_BMC")
	)
	(segment
		(start 64.595756 -83.171538)
		(end 63.849758 -82.42554)
		(width 0.10668)
		(layer "In7.Cu")
		(net "PECI_BMC")
	)
	(segment
		(start 70.65518 -100.377498)
		(end 70.65518 -99.332796)
		(width 0.10668)
		(layer "In7.Cu")
		(net "PECI_BMC")
	)
	(segment
		(start 63.78194 -82.261964)
		(end 63.78194 -81.892394)
		(width 0.10668)
		(layer "In7.Cu")
		(net "PECI_BMC")
	)
	(segment
		(start 68.77558 -93.21419)
		(end 64.595756 -89.034366)
		(width 0.10668)
		(layer "In7.Cu")
		(net "PECI_BMC")
	)
	(segment
		(start 64.595756 -89.034366)
		(end 64.595756 -83.171538)
		(width 0.10668)
		(layer "In7.Cu")
		(net "PECI_BMC")
	)
	(segment
		(start 59.07659 -72.572372)
		(end 59.07659 -71.675752)
		(width 0.10668)
		(layer "In7.Cu")
		(net "PECI_BMC")
	)
	(segment
		(start 57.695084 -40.971216)
		(end 58.090308 -40.575992)
		(width 0.11684)
		(layer "F.Cu")
		(net "PD_SP_ENTEST")
	)
	(via
		(at 62.876684 -36.210748)
		(size 0.6604)
		(drill 0.3302)
		(layers "F.Cu" "B.Cu")
		(net "PD_SP_ENTEST")
	)
	(via
		(at 58.090308 -40.575992)
		(size 0.4572)
		(drill 0.254)
		(layers "F.Cu" "B.Cu")
		(net "PD_SP_ENTEST")
	)
	(segment
		(start 59.037982 -40.178228)
		(end 59.286394 -39.929816)
		(width 0.11684)
		(layer "B.Cu")
		(net "PD_SP_ENTEST")
	)
	(segment
		(start 59.493404 -39.376604)
		(end 59.894724 -39.376604)
		(width 0.11684)
		(layer "B.Cu")
		(net "PD_SP_ENTEST")
	)
	(segment
		(start 60.22594 -38.631876)
		(end 60.521342 -38.336474)
		(width 0.11684)
		(layer "B.Cu")
		(net "PD_SP_ENTEST")
	)
	(segment
		(start 62.868048 -36.202112)
		(end 62.876684 -36.210748)
		(width 0.11684)
		(layer "B.Cu")
		(net "PD_SP_ENTEST")
	)
	(segment
		(start 62.768734 -36.441634)
		(end 62.868048 -36.202112)
		(width 0.11684)
		(layer "B.Cu")
		(net "PD_SP_ENTEST")
	)
	(segment
		(start 59.286394 -39.583614)
		(end 59.493404 -39.376604)
		(width 0.11684)
		(layer "B.Cu")
		(net "PD_SP_ENTEST")
	)
	(segment
		(start 59.894724 -39.376604)
		(end 60.22594 -39.045388)
		(width 0.11684)
		(layer "B.Cu")
		(net "PD_SP_ENTEST")
	)
	(segment
		(start 62.868048 -36.078668)
		(end 62.868048 -36.202112)
		(width 0.11684)
		(layer "B.Cu")
		(net "PD_SP_ENTEST")
	)
	(segment
		(start 58.090308 -40.575992)
		(end 58.488072 -40.178228)
		(width 0.11684)
		(layer "B.Cu")
		(net "PD_SP_ENTEST")
	)
	(segment
		(start 60.521342 -38.336474)
		(end 60.873894 -38.336474)
		(width 0.11684)
		(layer "B.Cu")
		(net "PD_SP_ENTEST")
	)
	(segment
		(start 59.286394 -39.929816)
		(end 59.286394 -39.583614)
		(width 0.11684)
		(layer "B.Cu")
		(net "PD_SP_ENTEST")
	)
	(segment
		(start 60.873894 -38.336474)
		(end 62.768734 -36.441634)
		(width 0.11684)
		(layer "B.Cu")
		(net "PD_SP_ENTEST")
	)
	(segment
		(start 64.102996 -35.037776)
		(end 63.742824 -35.037776)
		(width 0.11684)
		(layer "B.Cu")
		(net "PD_SP_ENTEST")
	)
	(segment
		(start 58.488072 -40.178228)
		(end 59.037982 -40.178228)
		(width 0.11684)
		(layer "B.Cu")
		(net "PD_SP_ENTEST")
	)
	(segment
		(start 63.201804 -35.578796)
		(end 62.868048 -36.078668)
		(width 0.11684)
		(layer "B.Cu")
		(net "PD_SP_ENTEST")
	)
	(segment
		(start 60.22594 -39.045388)
		(end 60.22594 -38.631876)
		(width 0.11684)
		(layer "B.Cu")
		(net "PD_SP_ENTEST")
	)
	(segment
		(start 63.742824 -35.037776)
		(end 63.201804 -35.578796)
		(width 0.11684)
		(layer "B.Cu")
		(net "PD_SP_ENTEST")
	)
	(segment
		(start 79.452216 -49.907444)
		(end 79.833978 -50.289206)
		(width 0.11684)
		(layer "F.Cu")
		(net "PD_M_BMC_DDR4_ZQ")
	)
	(via
		(at 79.833978 -50.289206)
		(size 0.4572)
		(drill 0.254)
		(layers "F.Cu" "B.Cu")
		(net "PD_M_BMC_DDR4_ZQ")
	)
	(segment
		(start 80.186022 -50.64125)
		(end 79.833978 -50.289206)
		(width 0.11684)
		(layer "B.Cu")
		(net "PD_M_BMC_DDR4_ZQ")
	)
	(segment
		(start 80.547464 -50.64125)
		(end 80.186022 -50.64125)
		(width 0.11684)
		(layer "B.Cu")
		(net "PD_M_BMC_DDR4_ZQ")
	)
	(segment
		(start 79.452216 -44.307506)
		(end 79.99222 -44.307506)
		(width 0.11684)
		(layer "F.Cu")
		(net "PD_M_BMC_DDR4_TEN")
	)
	(via
		(at 79.99222 -44.307506)
		(size 0.4572)
		(drill 0.254)
		(layers "F.Cu" "B.Cu")
		(net "PD_M_BMC_DDR4_TEN")
	)
	(segment
		(start 80.729836 -44.038012)
		(end 80.261714 -44.038012)
		(width 0.11684)
		(layer "B.Cu")
		(net "PD_M_BMC_DDR4_TEN")
	)
	(segment
		(start 80.261714 -44.038012)
		(end 79.99222 -44.307506)
		(width 0.11684)
		(layer "B.Cu")
		(net "PD_M_BMC_DDR4_TEN")
	)
	(segment
		(start 74.23404 -41.525698)
		(end 74.589894 -41.881552)
		(width 0.11684)
		(layer "F.Cu")
		(net "PD_M_BMC_DDR4_PAR")
	)
	(segment
		(start 74.589894 -41.881552)
		(end 74.652378 -41.90746)
		(width 0.11684)
		(layer "F.Cu")
		(net "PD_M_BMC_DDR4_PAR")
	)
	(via
		(at 74.23404 -41.525698)
		(size 0.4572)
		(drill 0.254)
		(layers "F.Cu" "B.Cu")
		(net "PD_M_BMC_DDR4_PAR")
	)
	(via
		(at 73.128632 -43.26128)
		(size 0.6604)
		(drill 0.3302)
		(layers "F.Cu" "B.Cu")
		(net "PD_M_BMC_DDR4_PAR")
	)
	(segment
		(start 73.128632 -42.294302)
		(end 73.128632 -43.26128)
		(width 0.11684)
		(layer "B.Cu")
		(net "PD_M_BMC_DDR4_PAR")
	)
	(segment
		(start 73.474326 -41.948608)
		(end 73.309226 -42.113708)
		(width 0.11684)
		(layer "B.Cu")
		(net "PD_M_BMC_DDR4_PAR")
	)
	(segment
		(start 73.309226 -42.113708)
		(end 73.128632 -42.294302)
		(width 0.11684)
		(layer "B.Cu")
		(net "PD_M_BMC_DDR4_PAR")
	)
	(segment
		(start 73.91273 -41.618408)
		(end 73.664826 -41.866312)
		(width 0.11684)
		(layer "B.Cu")
		(net "PD_M_BMC_DDR4_PAR")
	)
	(arc
		(start 73.572624 -41.90619)
		(mid 73.519419 -41.917981)
		(end 73.474326 -41.948608)
		(width 0.11684)
		(layer "B.Cu")
		(net "PD_M_BMC_DDR4_PAR")
	)
	(arc
		(start 73.664826 -41.866312)
		(mid 73.622544 -41.895084)
		(end 73.572624 -41.90619)
		(width 0.11684)
		(layer "B.Cu")
		(net "PD_M_BMC_DDR4_PAR")
	)
	(arc
		(start 74.23404 -41.525698)
		(mid 74.066829 -41.549335)
		(end 73.91273 -41.618408)
		(width 0.11684)
		(layer "B.Cu")
		(net "PD_M_BMC_DDR4_PAR")
	)
	(segment
		(start 56.894984 -43.371262)
		(end 57.290208 -42.976038)
		(width 0.11684)
		(layer "F.Cu")
		(net "JTAG_SCM_NTRST")
	)
	(via
		(at 65.659 -37.1856)
		(size 0.508)
		(drill 0.254)
		(layers "F.Cu" "B.Cu")
		(net "JTAG_SCM_NTRST")
	)
	(via
		(at 57.290208 -42.976038)
		(size 0.4572)
		(drill 0.254)
		(layers "F.Cu" "B.Cu")
		(net "JTAG_SCM_NTRST")
	)
	(segment
		(start 66.205862 -36.638738)
		(end 66.513202 -36.638738)
		(width 0.11684)
		(layer "B.Cu")
		(net "JTAG_SCM_NTRST")
	)
	(segment
		(start 65.659 -37.1856)
		(end 66.205862 -36.638738)
		(width 0.11684)
		(layer "B.Cu")
		(net "JTAG_SCM_NTRST")
	)
	(segment
		(start 60.10656 -42.817034)
		(end 60.10656 -43.246294)
		(width 0.10668)
		(layer "In7.Cu")
		(net "JTAG_SCM_NTRST")
	)
	(segment
		(start 60.10656 -43.246294)
		(end 59.969654 -43.3832)
		(width 0.10668)
		(layer "In7.Cu")
		(net "JTAG_SCM_NTRST")
	)
	(segment
		(start 60.719462 -42.592498)
		(end 60.331096 -42.592498)
		(width 0.10668)
		(layer "In7.Cu")
		(net "JTAG_SCM_NTRST")
	)
	(segment
		(start 65.659 -38.934136)
		(end 64.994536 -39.5986)
		(width 0.10668)
		(layer "In7.Cu")
		(net "JTAG_SCM_NTRST")
	)
	(segment
		(start 63.71336 -39.5986)
		(end 60.719462 -42.592498)
		(width 0.10668)
		(layer "In7.Cu")
		(net "JTAG_SCM_NTRST")
	)
	(segment
		(start 59.969654 -43.3832)
		(end 57.69737 -43.3832)
		(width 0.10668)
		(layer "In7.Cu")
		(net "JTAG_SCM_NTRST")
	)
	(segment
		(start 60.331096 -42.592498)
		(end 60.10656 -42.817034)
		(width 0.10668)
		(layer "In7.Cu")
		(net "JTAG_SCM_NTRST")
	)
	(segment
		(start 57.69737 -43.3832)
		(end 57.290208 -42.976038)
		(width 0.10668)
		(layer "In7.Cu")
		(net "JTAG_SCM_NTRST")
	)
	(segment
		(start 65.659 -37.1856)
		(end 65.659 -38.934136)
		(width 0.10668)
		(layer "In7.Cu")
		(net "JTAG_SCM_NTRST")
	)
	(segment
		(start 64.994536 -39.5986)
		(end 63.71336 -39.5986)
		(width 0.10668)
		(layer "In7.Cu")
		(net "JTAG_SCM_NTRST")
	)
	(via
		(at 70.712076 -28.20289)
		(size 0.6604)
		(drill 0.3302)
		(layers "F.Cu" "B.Cu")
		(net "PD_FRU_WC_N")
	)
	(segment
		(start 69.637402 -29.277564)
		(end 69.637402 -29.637736)
		(width 0.11684)
		(layer "B.Cu")
		(net "PD_FRU_WC_N")
	)
	(segment
		(start 70.712076 -28.20289)
		(end 71.42988 -27.485086)
		(width 0.11684)
		(layer "B.Cu")
		(net "PD_FRU_WC_N")
	)
	(segment
		(start 69.637402 -29.637736)
		(end 69.464174 -29.810964)
		(width 0.11684)
		(layer "B.Cu")
		(net "PD_FRU_WC_N")
	)
	(segment
		(start 69.464174 -29.810964)
		(end 68.98259 -29.810964)
		(width 0.11684)
		(layer "B.Cu")
		(net "PD_FRU_WC_N")
	)
	(segment
		(start 70.712076 -28.20289)
		(end 69.637402 -29.277564)
		(width 0.11684)
		(layer "B.Cu")
		(net "PD_FRU_WC_N")
	)
	(segment
		(start 71.42988 -27.485086)
		(end 72.783446 -27.485086)
		(width 0.11684)
		(layer "B.Cu")
		(net "PD_FRU_WC_N")
	)
	(segment
		(start 30.75813 -17.503394)
		(end 31.542736 -18.288)
		(width 0.4572)
		(layer "F.Cu")
		(net "P5V_USB_REAR")
	)
	(segment
		(start 38.8366 -17.8308)
		(end 38.8366 -19.177)
		(width 0.4572)
		(layer "F.Cu")
		(net "P5V_USB_REAR")
	)
	(segment
		(start 38.8366 -19.177)
		(end 38.8112 -19.2024)
		(width 0.4572)
		(layer "F.Cu")
		(net "P5V_USB_REAR")
	)
	(segment
		(start 34.713926 -17.762474)
		(end 35.699446 -17.354296)
		(width 0.4572)
		(layer "F.Cu")
		(net "P5V_USB_REAR")
	)
	(segment
		(start 34.1884 -18.288)
		(end 34.713926 -17.762474)
		(width 0.4572)
		(layer "F.Cu")
		(net "P5V_USB_REAR")
	)
	(segment
		(start 35.699446 -17.354296)
		(end 38.360096 -17.354296)
		(width 0.4572)
		(layer "F.Cu")
		(net "P5V_USB_REAR")
	)
	(segment
		(start 38.360096 -17.354296)
		(end 38.8366 -17.8308)
		(width 0.4572)
		(layer "F.Cu")
		(net "P5V_USB_REAR")
	)
	(segment
		(start 31.542736 -18.288)
		(end 34.1884 -18.288)
		(width 0.4572)
		(layer "F.Cu")
		(net "P5V_USB_REAR")
	)
	(via
		(at 38.811454 -17.868646)
		(size 0.6604)
		(drill 0.3302)
		(layers "F.Cu" "B.Cu")
		(net "P5V_USB_REAR")
	)
	(via
		(at 49.0474 -17.5514)
		(size 0.508)
		(drill 0.254)
		(layers "F.Cu" "B.Cu")
		(net "P5V_USB_REAR")
	)
	(via
		(at 38.8112 -19.2024)
		(size 0.508)
		(drill 0.254)
		(layers "F.Cu" "B.Cu")
		(net "P5V_USB_REAR")
	)
	(via
		(at 48.1076 -17.6784)
		(size 0.508)
		(drill 0.254)
		(layers "F.Cu" "B.Cu")
		(net "P5V_USB_REAR")
	)
	(segment
		(start 38.8112 -17.8689)
		(end 38.811454 -17.868646)
		(width 0.4572)
		(layer "B.Cu")
		(net "P5V_USB_REAR")
	)
	(segment
		(start 39.42207 -13.379958)
		(end 38.664388 -13.379958)
		(width 0.4572)
		(layer "B.Cu")
		(net "P5V_USB_REAR")
	)
	(segment
		(start 37.846 -16.903192)
		(end 38.811454 -17.868646)
		(width 0.4572)
		(layer "B.Cu")
		(net "P5V_USB_REAR")
	)
	(segment
		(start 38.664388 -13.379958)
		(end 37.846 -14.198346)
		(width 0.4572)
		(layer "B.Cu")
		(net "P5V_USB_REAR")
	)
	(segment
		(start 37.846 -14.198346)
		(end 37.846 -16.903192)
		(width 0.4572)
		(layer "B.Cu")
		(net "P5V_USB_REAR")
	)
	(segment
		(start 38.8112 -19.2024)
		(end 38.8112 -17.8689)
		(width 0.4572)
		(layer "B.Cu")
		(net "P5V_USB_REAR")
	)
	(segment
		(start 11.571986 -54.538372)
		(end 11.621008 -54.587394)
		(width 0.381)
		(layer "F.Cu")
		(net "P5V_AUX_VCC")
	)
	(segment
		(start 11.621008 -54.587394)
		(end 12.185142 -54.587394)
		(width 0.381)
		(layer "F.Cu")
		(net "P5V_AUX_VCC")
	)
	(segment
		(start 12.185142 -54.587394)
		(end 12.206986 -54.56555)
		(width 0.381)
		(layer "F.Cu")
		(net "P5V_AUX_VCC")
	)
	(via
		(at 12.206986 -54.56555)
		(size 0.508)
		(drill 0.254)
		(layers "F.Cu" "B.Cu")
		(net "P5V_AUX_VCC")
	)
	(via
		(at 4.8514 -47.60468)
		(size 0.508)
		(drill 0.254)
		(layers "F.Cu" "B.Cu")
		(net "P5V_AUX_VCC")
	)
	(via
		(at 10.3124 -51.562)
		(size 0.6604)
		(drill 0.3302)
		(layers "F.Cu" "B.Cu")
		(net "P5V_AUX_VCC")
	)
	(segment
		(start 12.345162 -54.56555)
		(end 12.726162 -54.18455)
		(width 0.381)
		(layer "B.Cu")
		(net "P5V_AUX_VCC")
	)
	(segment
		(start 5.64769 -47.60468)
		(end 4.8514 -47.60468)
		(width 0.381)
		(layer "B.Cu")
		(net "P5V_AUX_VCC")
	)
	(segment
		(start 9.60501 -51.562)
		(end 5.64769 -47.60468)
		(width 0.381)
		(layer "B.Cu")
		(net "P5V_AUX_VCC")
	)
	(segment
		(start 12.726162 -54.18455)
		(end 12.726162 -53.645562)
		(width 0.381)
		(layer "B.Cu")
		(net "P5V_AUX_VCC")
	)
	(segment
		(start 12.726162 -53.645562)
		(end 10.6426 -51.562)
		(width 0.381)
		(layer "B.Cu")
		(net "P5V_AUX_VCC")
	)
	(segment
		(start 10.3124 -51.562)
		(end 9.60501 -51.562)
		(width 0.381)
		(layer "B.Cu")
		(net "P5V_AUX_VCC")
	)
	(segment
		(start 12.206986 -54.56555)
		(end 12.345162 -54.56555)
		(width 0.381)
		(layer "B.Cu")
		(net "P5V_AUX_VCC")
	)
	(segment
		(start 10.6426 -51.562)
		(end 10.3124 -51.562)
		(width 0.381)
		(layer "B.Cu")
		(net "P5V_AUX_VCC")
	)
	(segment
		(start 9.999218 -49.75606)
		(end 10.25271 -49.144174)
		(width 0.254)
		(layer "F.Cu")
		(net "P5V_AUX_REF")
	)
	(segment
		(start 9.771634 -49.884584)
		(end 10.007346 -49.787048)
		(width 0.1778)
		(layer "F.Cu")
		(net "P5V_AUX_REF")
	)
	(segment
		(start 8.459724 -49.979834)
		(end 9.30656 -49.979834)
		(width 0.1778)
		(layer "F.Cu")
		(net "P5V_AUX_REF")
	)
	(segment
		(start 9.40181 -49.884584)
		(end 9.771634 -49.884584)
		(width 0.1778)
		(layer "F.Cu")
		(net "P5V_AUX_REF")
	)
	(segment
		(start 10.25271 -49.144174)
		(end 10.746994 -48.64989)
		(width 0.254)
		(layer "F.Cu")
		(net "P5V_AUX_REF")
	)
	(segment
		(start 10.007346 -49.787048)
		(end 10.009632 -49.78146)
		(width 0.1778)
		(layer "F.Cu")
		(net "P5V_AUX_REF")
	)
	(segment
		(start 9.30656 -49.979834)
		(end 9.40181 -49.884584)
		(width 0.1778)
		(layer "F.Cu")
		(net "P5V_AUX_REF")
	)
	(segment
		(start 10.009632 -49.78146)
		(end 9.999218 -49.75606)
		(width 0.254)
		(layer "F.Cu")
		(net "P5V_AUX_REF")
	)
	(via
		(at 10.009632 -49.78146)
		(size 0.508)
		(drill 0.254)
		(layers "F.Cu" "B.Cu")
		(net "P5V_AUX_REF")
	)
	(segment
		(start 11.783568 -50.510948)
		(end 10.767568 -50.510948)
		(width 0.254)
		(layer "F.Cu")
		(net "P5V_AUX_FB")
	)
	(segment
		(start 8.86079 -50.779934)
		(end 9.071356 -50.9905)
		(width 0.1778)
		(layer "F.Cu")
		(net "P5V_AUX_FB")
	)
	(segment
		(start 10.288016 -50.9905)
		(end 10.767568 -50.510948)
		(width 0.1778)
		(layer "F.Cu")
		(net "P5V_AUX_FB")
	)
	(segment
		(start 8.459724 -50.779934)
		(end 8.86079 -50.779934)
		(width 0.1778)
		(layer "F.Cu")
		(net "P5V_AUX_FB")
	)
	(segment
		(start 9.071356 -50.9905)
		(end 10.288016 -50.9905)
		(width 0.1778)
		(layer "F.Cu")
		(net "P5V_AUX_FB")
	)
	(segment
		(start 12.799568 -50.510948)
		(end 11.783568 -50.510948)
		(width 0.254)
		(layer "F.Cu")
		(net "P5V_AUX_FB")
	)
	(segment
		(start 12.181332 -51.5366)
		(end 12.76858 -51.5366)
		(width 0.11684)
		(layer "F.Cu")
		(net "EN_P5V_AUX")
	)
	(segment
		(start 8.825484 -51.17973)
		(end 9.009634 -51.36388)
		(width 0.11684)
		(layer "F.Cu")
		(net "EN_P5V_AUX")
	)
	(segment
		(start 12.840462 -51.608482)
		(end 13.169646 -51.608482)
		(width 0.11684)
		(layer "F.Cu")
		(net "EN_P5V_AUX")
	)
	(segment
		(start 10.456164 -51.608482)
		(end 10.739374 -51.608482)
		(width 0.11684)
		(layer "F.Cu")
		(net "EN_P5V_AUX")
	)
	(segment
		(start 12.76858 -51.5366)
		(end 12.840462 -51.608482)
		(width 0.11684)
		(layer "F.Cu")
		(net "EN_P5V_AUX")
	)
	(segment
		(start 12.10945 -51.608482)
		(end 12.181332 -51.5366)
		(width 0.11684)
		(layer "F.Cu")
		(net "EN_P5V_AUX")
	)
	(segment
		(start 8.459724 -51.17973)
		(end 8.825484 -51.17973)
		(width 0.11684)
		(layer "F.Cu")
		(net "EN_P5V_AUX")
	)
	(segment
		(start 9.009634 -51.36388)
		(end 10.211562 -51.36388)
		(width 0.11684)
		(layer "F.Cu")
		(net "EN_P5V_AUX")
	)
	(segment
		(start 11.761978 -51.608482)
		(end 12.10945 -51.608482)
		(width 0.11684)
		(layer "F.Cu")
		(net "EN_P5V_AUX")
	)
	(segment
		(start 10.739374 -51.608482)
		(end 11.761978 -51.608482)
		(width 0.11684)
		(layer "F.Cu")
		(net "EN_P5V_AUX")
	)
	(segment
		(start 10.211562 -51.36388)
		(end 10.456164 -51.608482)
		(width 0.11684)
		(layer "F.Cu")
		(net "EN_P5V_AUX")
	)
	(segment
		(start 8.897874 -49.179734)
		(end 9.601708 -48.4759)
		(width 0.1778)
		(layer "F.Cu")
		(net "P5V_AUX_CS")
	)
	(segment
		(start 10.042652 -48.390302)
		(end 10.477754 -47.9552)
		(width 0.254)
		(layer "F.Cu")
		(net "P5V_AUX_CS")
	)
	(segment
		(start 9.601708 -48.4759)
		(end 9.80821 -48.390302)
		(width 0.1778)
		(layer "F.Cu")
		(net "P5V_AUX_CS")
	)
	(segment
		(start 10.888726 -47.9552)
		(end 11.212576 -47.63135)
		(width 0.254)
		(layer "F.Cu")
		(net "P5V_AUX_CS")
	)
	(segment
		(start 9.80821 -48.390302)
		(end 10.042652 -48.390302)
		(width 0.254)
		(layer "F.Cu")
		(net "P5V_AUX_CS")
	)
	(segment
		(start 8.459724 -49.179734)
		(end 8.897874 -49.179734)
		(width 0.1778)
		(layer "F.Cu")
		(net "P5V_AUX_CS")
	)
	(segment
		(start 10.477754 -47.9552)
		(end 10.888726 -47.9552)
		(width 0.254)
		(layer "F.Cu")
		(net "P5V_AUX_CS")
	)
	(segment
		(start 25.3238 -30.23235)
		(end 25.3238 -29.75864)
		(width 0.4572)
		(layer "F.Cu")
		(net "P5V_AUX")
	)
	(segment
		(start 25.3238 -29.75864)
		(end 25.49144 -29.591)
		(width 0.4572)
		(layer "F.Cu")
		(net "P5V_AUX")
	)
	(segment
		(start 62.3062 -14.097)
		(end 60.198 -11.9888)
		(width 0.4572)
		(layer "F.Cu")
		(net "P5V_AUX")
	)
	(segment
		(start 85.7504 -70.85965)
		(end 85.751162 -70.858888)
		(width 0.381)
		(layer "F.Cu")
		(net "P5V_AUX")
	)
	(segment
		(start 55.8292 -23.9522)
		(end 55.8546 -23.9776)
		(width 0.4572)
		(layer "F.Cu")
		(net "P5V_AUX")
	)
	(segment
		(start 85.751162 -70.858888)
		(end 86.515448 -70.858888)
		(width 0.381)
		(layer "F.Cu")
		(net "P5V_AUX")
	)
	(segment
		(start 55.8546 -23.9776)
		(end 55.8546 -25.7302)
		(width 0.4572)
		(layer "F.Cu")
		(net "P5V_AUX")
	)
	(segment
		(start 56.909208 -23.913592)
		(end 60.03036 -20.79244)
		(width 0.4572)
		(layer "F.Cu")
		(net "P5V_AUX")
	)
	(segment
		(start 60.198 -11.32205)
		(end 60.198 -11.9888)
		(width 0.4572)
		(layer "F.Cu")
		(net "P5V_AUX")
	)
	(segment
		(start 55.24373 -25.911556)
		(end 55.425086 -25.7302)
		(width 0.4572)
		(layer "F.Cu")
		(net "P5V_AUX")
	)
	(segment
		(start 12.799568 -49.710848)
		(end 11.783568 -49.710848)
		(width 0.4572)
		(layer "F.Cu")
		(net "P5V_AUX")
	)
	(segment
		(start 55.425086 -25.7302)
		(end 55.8546 -25.7302)
		(width 0.4572)
		(layer "F.Cu")
		(net "P5V_AUX")
	)
	(segment
		(start 13.430504 -49.710848)
		(end 12.799568 -49.710848)
		(width 0.4572)
		(layer "F.Cu")
		(net "P5V_AUX")
	)
	(segment
		(start 29.591 -10.68705)
		(end 29.21 -11.06805)
		(width 0.4572)
		(layer "F.Cu")
		(net "P5V_AUX")
	)
	(segment
		(start 56.552592 -23.913592)
		(end 56.909208 -23.913592)
		(width 0.4572)
		(layer "F.Cu")
		(net "P5V_AUX")
	)
	(segment
		(start 62.3062 -17.2339)
		(end 62.3062 -14.097)
		(width 0.4572)
		(layer "F.Cu")
		(net "P5V_AUX")
	)
	(segment
		(start 60.03036 -20.79244)
		(end 60.03036 -19.50974)
		(width 0.4572)
		(layer "F.Cu")
		(net "P5V_AUX")
	)
	(segment
		(start 60.03036 -19.50974)
		(end 62.3062 -17.2339)
		(width 0.4572)
		(layer "F.Cu")
		(net "P5V_AUX")
	)
	(segment
		(start 29.21 -11.06805)
		(end 29.21 -11.303)
		(width 0.4572)
		(layer "F.Cu")
		(net "P5V_AUX")
	)
	(via
		(at 8.187944 -33.212532)
		(size 0.508)
		(drill 0.254)
		(layers "F.Cu" "B.Cu")
		(net "P5V_AUX")
	)
	(via
		(at 6.028944 -32.450532)
		(size 0.508)
		(drill 0.254)
		(layers "F.Cu" "B.Cu")
		(net "P5V_AUX")
	)
	(via
		(at 30.099 -19.177)
		(size 0.508)
		(drill 0.254)
		(layers "F.Cu" "B.Cu")
		(net "P5V_AUX")
	)
	(via
		(at 25.49144 -29.591)
		(size 0.508)
		(drill 0.254)
		(layers "F.Cu" "B.Cu")
		(net "P5V_AUX")
	)
	(via
		(at 6.028944 -33.212532)
		(size 0.508)
		(drill 0.254)
		(layers "F.Cu" "B.Cu")
		(net "P5V_AUX")
	)
	(via
		(at 55.8546 -25.7302)
		(size 0.508)
		(drill 0.254)
		(layers "F.Cu" "B.Cu")
		(net "P5V_AUX")
	)
	(via
		(at 22.352 -16.891)
		(size 0.508)
		(drill 0.254)
		(layers "F.Cu" "B.Cu")
		(net "P5V_AUX")
	)
	(via
		(at 9.271 -32.893)
		(size 0.6604)
		(drill 0.3302)
		(layers "F.Cu" "B.Cu")
		(net "P5V_AUX")
	)
	(via
		(at 11.43 -32.893)
		(size 0.6604)
		(drill 0.3302)
		(layers "F.Cu" "B.Cu")
		(net "P5V_AUX")
	)
	(via
		(at 29.21 -11.303)
		(size 0.508)
		(drill 0.254)
		(layers "F.Cu" "B.Cu")
		(net "P5V_AUX")
	)
	(via
		(at 6.096 -35.179)
		(size 0.6604)
		(drill 0.3302)
		(layers "F.Cu" "B.Cu")
		(net "P5V_AUX")
	)
	(via
		(at 35.0774 -54.2544)
		(size 0.508)
		(drill 0.254)
		(layers "F.Cu" "B.Cu")
		(net "P5V_AUX")
	)
	(via
		(at 84.262214 -31.952184)
		(size 0.508)
		(drill 0.254)
		(layers "F.Cu" "B.Cu")
		(net "P5V_AUX")
	)
	(via
		(at 10.346944 -32.450532)
		(size 0.508)
		(drill 0.254)
		(layers "F.Cu" "B.Cu")
		(net "P5V_AUX")
	)
	(via
		(at 79.84236 -94.817184)
		(size 0.508)
		(drill 0.254)
		(layers "F.Cu" "B.Cu")
		(net "P5V_AUX")
	)
	(via
		(at 7.366 -32.893)
		(size 0.6604)
		(drill 0.3302)
		(layers "F.Cu" "B.Cu")
		(net "P5V_AUX")
	)
	(via
		(at 31.027624 -40.092376)
		(size 0.508)
		(drill 0.254)
		(layers "F.Cu" "B.Cu")
		(net "P5V_AUX")
	)
	(via
		(at 12.505944 -33.212532)
		(size 0.508)
		(drill 0.254)
		(layers "F.Cu" "B.Cu")
		(net "P5V_AUX")
	)
	(via
		(at 60.198 -11.9888)
		(size 0.508)
		(drill 0.254)
		(layers "F.Cu" "B.Cu")
		(net "P5V_AUX")
	)
	(via
		(at 56.2102 -23.3934)
		(size 0.508)
		(drill 0.254)
		(layers "F.Cu" "B.Cu")
		(net "P5V_AUX")
	)
	(via
		(at 10.346944 -33.212532)
		(size 0.508)
		(drill 0.254)
		(layers "F.Cu" "B.Cu")
		(net "P5V_AUX")
	)
	(via
		(at 13.268198 -32.898588)
		(size 0.508)
		(drill 0.254)
		(layers "F.Cu" "B.Cu")
		(net "P5V_AUX")
	)
	(via
		(at 13.97 -19.304)
		(size 0.508)
		(drill 0.254)
		(layers "F.Cu" "B.Cu")
		(net "P5V_AUX")
	)
	(via
		(at 55.5244 -23.3934)
		(size 0.508)
		(drill 0.254)
		(layers "F.Cu" "B.Cu")
		(net "P5V_AUX")
	)
	(via
		(at 32.131 -40.132)
		(size 0.508)
		(drill 0.254)
		(layers "F.Cu" "B.Cu")
		(net "P5V_AUX")
	)
	(via
		(at 29.591 -18.796)
		(size 0.508)
		(drill 0.254)
		(layers "F.Cu" "B.Cu")
		(net "P5V_AUX")
	)
	(via
		(at 56.806084 -74.66584)
		(size 0.508)
		(drill 0.254)
		(layers "F.Cu" "B.Cu")
		(net "P5V_AUX")
	)
	(via
		(at 8.187944 -32.450532)
		(size 0.508)
		(drill 0.254)
		(layers "F.Cu" "B.Cu")
		(net "P5V_AUX")
	)
	(via
		(at 13.430504 -49.710848)
		(size 0.508)
		(drill 0.254)
		(layers "F.Cu" "B.Cu")
		(net "P5V_AUX")
	)
	(via
		(at 44.9326 -3.71475)
		(size 0.508)
		(drill 0.254)
		(layers "F.Cu" "B.Cu")
		(net "P5V_AUX")
	)
	(via
		(at 4.826 -32.893)
		(size 0.6604)
		(drill 0.3302)
		(layers "F.Cu" "B.Cu")
		(net "P5V_AUX")
	)
	(via
		(at 86.515448 -70.858888)
		(size 0.508)
		(drill 0.254)
		(layers "F.Cu" "B.Cu")
		(net "P5V_AUX")
	)
	(via
		(at 28.702 -40.132)
		(size 0.508)
		(drill 0.254)
		(layers "F.Cu" "B.Cu")
		(net "P5V_AUX")
	)
	(via
		(at 12.505944 -32.450532)
		(size 0.508)
		(drill 0.254)
		(layers "F.Cu" "B.Cu")
		(net "P5V_AUX")
	)
	(segment
		(start 57.506616 -74.66584)
		(end 56.806084 -74.66584)
		(width 0.381)
		(layer "B.Cu")
		(net "P5V_AUX")
	)
	(segment
		(start 12.573 -35.306)
		(end 14.5034 -37.2364)
		(width 0.4572)
		(layer "B.Cu")
		(net "P5V_AUX")
	)
	(segment
		(start 14.097 -20.04695)
		(end 14.097 -19.812254)
		(width 0.4572)
		(layer "B.Cu")
		(net "P5V_AUX")
	)
	(segment
		(start 45.5676 -3.71475)
		(end 44.9326 -3.71475)
		(width 0.4572)
		(layer "B.Cu")
		(net "P5V_AUX")
	)
	(segment
		(start 14.5034 -48.637952)
		(end 13.430504 -49.710848)
		(width 0.4572)
		(layer "B.Cu")
		(net "P5V_AUX")
	)
	(segment
		(start 79.767176 -94.742)
		(end 79.84236 -94.817184)
		(width 0.4572)
		(layer "B.Cu")
		(net "P5V_AUX")
	)
	(segment
		(start 14.097 -18.68805)
		(end 13.97 -18.81505)
		(width 0.4572)
		(layer "B.Cu")
		(net "P5V_AUX")
	)
	(segment
		(start 79.14005 -94.742)
		(end 79.767176 -94.742)
		(width 0.4572)
		(layer "B.Cu")
		(net "P5V_AUX")
	)
	(segment
		(start 22.352 -17.12595)
		(end 22.352 -16.891)
		(width 0.4572)
		(layer "B.Cu")
		(net "P5V_AUX")
	)
	(segment
		(start 13.97 -18.81505)
		(end 13.97 -19.304)
		(width 0.4572)
		(layer "B.Cu")
		(net "P5V_AUX")
	)
	(segment
		(start 21.971 -17.50695)
		(end 22.352 -17.12595)
		(width 0.4572)
		(layer "B.Cu")
		(net "P5V_AUX")
	)
	(segment
		(start 13.97 -19.685254)
		(end 13.97 -19.304)
		(width 0.4572)
		(layer "B.Cu")
		(net "P5V_AUX")
	)
	(segment
		(start 14.097 -18.56105)
		(end 14.097 -18.68805)
		(width 0.4572)
		(layer "B.Cu")
		(net "P5V_AUX")
	)
	(segment
		(start 14.097 -19.812254)
		(end 13.97 -19.685254)
		(width 0.4572)
		(layer "B.Cu")
		(net "P5V_AUX")
	)
	(segment
		(start 14.5034 -37.2364)
		(end 14.5034 -48.637952)
		(width 0.4572)
		(layer "B.Cu")
		(net "P5V_AUX")
	)
	(segment
		(start 29.1592 -4.7244)
		(end 43.79595 -4.7244)
		(width 0.4572)
		(layer "In2.Cu")
		(net "P5V_AUX")
	)
	(segment
		(start 29.21 -9.017)
		(end 28.2956 -8.1026)
		(width 0.4572)
		(layer "In2.Cu")
		(net "P5V_AUX")
	)
	(segment
		(start 57.277 -9.0678)
		(end 53.6194 -9.0678)
		(width 0.4572)
		(layer "In2.Cu")
		(net "P5V_AUX")
	)
	(segment
		(start 29.21 -11.303)
		(end 29.21 -9.017)
		(width 0.4572)
		(layer "In2.Cu")
		(net "P5V_AUX")
	)
	(segment
		(start 53.6194 -9.0678)
		(end 48.26635 -3.71475)
		(width 0.4572)
		(layer "In2.Cu")
		(net "P5V_AUX")
	)
	(segment
		(start 21.971 -17.526)
		(end 22.352 -17.145)
		(width 0.4572)
		(layer "In2.Cu")
		(net "P5V_AUX")
	)
	(segment
		(start 28.2956 -8.1026)
		(end 28.2956 -5.588)
		(width 0.4572)
		(layer "In2.Cu")
		(net "P5V_AUX")
	)
	(segment
		(start 48.26635 -3.71475)
		(end 44.9326 -3.71475)
		(width 0.4572)
		(layer "In2.Cu")
		(net "P5V_AUX")
	)
	(segment
		(start 43.79595 -4.7244)
		(end 44.8056 -3.71475)
		(width 0.4572)
		(layer "In2.Cu")
		(net "P5V_AUX")
	)
	(segment
		(start 22.352 -17.145)
		(end 22.352 -16.891)
		(width 0.4572)
		(layer "In2.Cu")
		(net "P5V_AUX")
	)
	(segment
		(start 28.2956 -5.588)
		(end 29.1592 -4.7244)
		(width 0.4572)
		(layer "In2.Cu")
		(net "P5V_AUX")
	)
	(segment
		(start 13.97 -18.617438)
		(end 14.807438 -17.78)
		(width 0.4572)
		(layer "In2.Cu")
		(net "P5V_AUX")
	)
	(segment
		(start 19.685 -17.78)
		(end 19.939 -17.526)
		(width 0.4572)
		(layer "In2.Cu")
		(net "P5V_AUX")
	)
	(segment
		(start 60.198 -11.9888)
		(end 57.277 -9.0678)
		(width 0.4572)
		(layer "In2.Cu")
		(net "P5V_AUX")
	)
	(segment
		(start 14.807438 -17.78)
		(end 19.685 -17.78)
		(width 0.4572)
		(layer "In2.Cu")
		(net "P5V_AUX")
	)
	(segment
		(start 19.939 -17.526)
		(end 21.971 -17.526)
		(width 0.4572)
		(layer "In2.Cu")
		(net "P5V_AUX")
	)
	(segment
		(start 13.97 -19.304)
		(end 13.97 -18.617438)
		(width 0.4572)
		(layer "In2.Cu")
		(net "P5V_AUX")
	)
	(segment
		(start 44.8056 -3.71475)
		(end 44.9326 -3.71475)
		(width 0.4572)
		(layer "In2.Cu")
		(net "P5V_AUX")
	)
	(segment
		(start 54.494938 -44.971208)
		(end 54.494938 -44.412408)
		(width 0.3556)
		(layer "F.Cu")
		(net "P3V3_STBY_PLLAHVDD")
	)
	(via
		(at 36.87699 -34.090356)
		(size 0.508)
		(drill 0.254)
		(layers "F.Cu" "B.Cu")
		(net "P3V3_STBY_PLLAHVDD")
	)
	(via
		(at 35.687 -34.163)
		(size 0.6604)
		(drill 0.3302)
		(layers "F.Cu" "B.Cu")
		(net "P3V3_STBY_PLLAHVDD")
	)
	(via
		(at 36.294568 -34.70783)
		(size 0.508)
		(drill 0.254)
		(layers "F.Cu" "B.Cu")
		(net "P3V3_STBY_PLLAHVDD")
	)
	(via
		(at 54.494938 -44.412408)
		(size 0.4572)
		(drill 0.254)
		(layers "F.Cu" "B.Cu")
		(net "P3V3_STBY_PLLAHVDD")
	)
	(segment
		(start 49.076864 -53.589428)
		(end 49.076864 -53.153056)
		(width 0.3556)
		(layer "F.Cu")
		(net "P3V3_STBY_DACAV33")
	)
	(segment
		(start 48.895 -53.771292)
		(end 49.076864 -53.589428)
		(width 0.3556)
		(layer "F.Cu")
		(net "P3V3_STBY_DACAV33")
	)
	(segment
		(start 49.076864 -53.153056)
		(end 48.895 -52.971192)
		(width 0.3556)
		(layer "F.Cu")
		(net "P3V3_STBY_DACAV33")
	)
	(segment
		(start 48.499776 -54.166516)
		(end 48.895 -53.771292)
		(width 0.3556)
		(layer "F.Cu")
		(net "P3V3_STBY_DACAV33")
	)
	(via
		(at 43.3324 -51.8922)
		(size 0.6604)
		(drill 0.3302)
		(layers "F.Cu" "B.Cu")
		(net "P3V3_STBY_DACAV33")
	)
	(via
		(at 48.499776 -54.166516)
		(size 0.4572)
		(drill 0.254)
		(layers "F.Cu" "B.Cu")
		(net "P3V3_STBY_DACAV33")
	)
	(via
		(at 43.845734 -52.9082)
		(size 0.508)
		(drill 0.254)
		(layers "F.Cu" "B.Cu")
		(net "P3V3_STBY_DACAV33")
	)
	(segment
		(start 47.295054 -52.971192)
		(end 46.89983 -53.366416)
		(width 0.3556)
		(layer "F.Cu")
		(net "P3V3_RTC_AUX")
	)
	(via
		(at 44.254928 -77.300582)
		(size 0.508)
		(drill 0.254)
		(layers "F.Cu" "B.Cu")
		(net "P3V3_RTC_AUX")
	)
	(via
		(at 47.5742 -97.6122)
		(size 0.508)
		(drill 0.254)
		(layers "F.Cu" "B.Cu")
		(net "P3V3_RTC_AUX")
	)
	(via
		(at 49.537874 -78.024228)
		(size 0.508)
		(drill 0.254)
		(layers "F.Cu" "B.Cu")
		(net "P3V3_RTC_AUX")
	)
	(via
		(at 46.89983 -53.366416)
		(size 0.4572)
		(drill 0.254)
		(layers "F.Cu" "B.Cu")
		(net "P3V3_RTC_AUX")
	)
	(via
		(at 47.05223 -106.045)
		(size 0.508)
		(drill 0.254)
		(layers "F.Cu" "B.Cu")
		(net "P3V3_RTC_AUX")
	)
	(segment
		(start 46.25975 -106.299)
		(end 44.967398 -106.299)
		(width 0.381)
		(layer "B.Cu")
		(net "P3V3_RTC_AUX")
	)
	(segment
		(start 47.05223 -106.045)
		(end 46.51375 -106.045)
		(width 0.381)
		(layer "B.Cu")
		(net "P3V3_RTC_AUX")
	)
	(segment
		(start 46.3804 -106.17835)
		(end 46.25975 -106.299)
		(width 0.381)
		(layer "B.Cu")
		(net "P3V3_RTC_AUX")
	)
	(segment
		(start 46.51375 -106.045)
		(end 46.3804 -106.17835)
		(width 0.381)
		(layer "B.Cu")
		(net "P3V3_RTC_AUX")
	)
	(segment
		(start 46.887638 -53.354224)
		(end 46.111414 -53.354224)
		(width 0.381)
		(layer "B.Cu")
		(net "P3V3_RTC_AUX")
	)
	(segment
		(start 46.89983 -53.366416)
		(end 46.887638 -53.354224)
		(width 0.381)
		(layer "B.Cu")
		(net "P3V3_RTC_AUX")
	)
	(segment
		(start 49.537874 -77.902054)
		(end 49.537874 -78.024228)
		(width 0.4572)
		(layer "In2.Cu")
		(net "P3V3_RTC_AUX")
	)
	(segment
		(start 44.254928 -77.300582)
		(end 44.36491 -77.1906)
		(width 0.4572)
		(layer "In2.Cu")
		(net "P3V3_RTC_AUX")
	)
	(segment
		(start 45.042836 -77.1906)
		(end 45.607224 -77.42428)
		(width 0.4572)
		(layer "In2.Cu")
		(net "P3V3_RTC_AUX")
	)
	(segment
		(start 44.36491 -77.1906)
		(end 45.042836 -77.1906)
		(width 0.4572)
		(layer "In2.Cu")
		(net "P3V3_RTC_AUX")
	)
	(segment
		(start 49.28362 -77.6478)
		(end 49.537874 -77.902054)
		(width 0.4572)
		(layer "In2.Cu")
		(net "P3V3_RTC_AUX")
	)
	(segment
		(start 47.52848 -77.42428)
		(end 47.752 -77.6478)
		(width 0.4572)
		(layer "In2.Cu")
		(net "P3V3_RTC_AUX")
	)
	(segment
		(start 45.607224 -77.42428)
		(end 47.52848 -77.42428)
		(width 0.4572)
		(layer "In2.Cu")
		(net "P3V3_RTC_AUX")
	)
	(segment
		(start 47.752 -77.6478)
		(end 49.28362 -77.6478)
		(width 0.4572)
		(layer "In2.Cu")
		(net "P3V3_RTC_AUX")
	)
	(segment
		(start 44.042584 -58.698384)
		(end 44.81068 -59.46648)
		(width 0.254)
		(layer "In4.Cu")
		(net "P3V3_RTC_AUX")
	)
	(segment
		(start 44.865036 -62.05347)
		(end 44.865036 -65.891156)
		(width 0.254)
		(layer "In4.Cu")
		(net "P3V3_RTC_AUX")
	)
	(segment
		(start 44.81068 -59.92114)
		(end 43.9928 -60.73902)
		(width 0.254)
		(layer "In4.Cu")
		(net "P3V3_RTC_AUX")
	)
	(segment
		(start 44.3992 -69.088)
		(end 44.987718 -69.676518)
		(width 0.254)
		(layer "In4.Cu")
		(net "P3V3_RTC_AUX")
	)
	(segment
		(start 44.3992 -68.30822)
		(end 44.3992 -69.088)
		(width 0.254)
		(layer "In4.Cu")
		(net "P3V3_RTC_AUX")
	)
	(segment
		(start 44.208192 -57.786016)
		(end 44.042584 -57.951624)
		(width 0.254)
		(layer "In4.Cu")
		(net "P3V3_RTC_AUX")
	)
	(segment
		(start 44.987718 -69.676518)
		(end 44.987718 -76.567792)
		(width 0.254)
		(layer "In4.Cu")
		(net "P3V3_RTC_AUX")
	)
	(segment
		(start 44.81068 -59.46648)
		(end 44.81068 -59.92114)
		(width 0.254)
		(layer "In4.Cu")
		(net "P3V3_RTC_AUX")
	)
	(segment
		(start 45.64253 -54.776878)
		(end 45.64253 -56.13527)
		(width 0.254)
		(layer "In4.Cu")
		(net "P3V3_RTC_AUX")
	)
	(segment
		(start 45.64253 -56.13527)
		(end 44.7548 -57.023)
		(width 0.254)
		(layer "In4.Cu")
		(net "P3V3_RTC_AUX")
	)
	(segment
		(start 44.597828 -57.624472)
		(end 44.208192 -57.786016)
		(width 0.254)
		(layer "In4.Cu")
		(net "P3V3_RTC_AUX")
	)
	(segment
		(start 46.44263 -53.823616)
		(end 46.44263 -53.976778)
		(width 0.254)
		(layer "In4.Cu")
		(net "P3V3_RTC_AUX")
	)
	(segment
		(start 45.36186 -67.34556)
		(end 44.3992 -68.30822)
		(width 0.254)
		(layer "In4.Cu")
		(net "P3V3_RTC_AUX")
	)
	(segment
		(start 44.7548 -57.4675)
		(end 44.597828 -57.624472)
		(width 0.254)
		(layer "In4.Cu")
		(net "P3V3_RTC_AUX")
	)
	(segment
		(start 46.89983 -53.366416)
		(end 46.44263 -53.823616)
		(width 0.254)
		(layer "In4.Cu")
		(net "P3V3_RTC_AUX")
	)
	(segment
		(start 43.9928 -61.181234)
		(end 44.865036 -62.05347)
		(width 0.254)
		(layer "In4.Cu")
		(net "P3V3_RTC_AUX")
	)
	(segment
		(start 44.042584 -57.951624)
		(end 44.042584 -58.698384)
		(width 0.254)
		(layer "In4.Cu")
		(net "P3V3_RTC_AUX")
	)
	(segment
		(start 46.44263 -53.976778)
		(end 45.64253 -54.776878)
		(width 0.254)
		(layer "In4.Cu")
		(net "P3V3_RTC_AUX")
	)
	(segment
		(start 43.9928 -60.73902)
		(end 43.9928 -61.181234)
		(width 0.254)
		(layer "In4.Cu")
		(net "P3V3_RTC_AUX")
	)
	(segment
		(start 45.36186 -66.38798)
		(end 45.36186 -67.34556)
		(width 0.254)
		(layer "In4.Cu")
		(net "P3V3_RTC_AUX")
	)
	(segment
		(start 44.865036 -65.891156)
		(end 45.36186 -66.38798)
		(width 0.254)
		(layer "In4.Cu")
		(net "P3V3_RTC_AUX")
	)
	(segment
		(start 44.7548 -57.023)
		(end 44.7548 -57.4675)
		(width 0.254)
		(layer "In4.Cu")
		(net "P3V3_RTC_AUX")
	)
	(segment
		(start 44.987718 -76.567792)
		(end 44.254928 -77.300582)
		(width 0.254)
		(layer "In4.Cu")
		(net "P3V3_RTC_AUX")
	)
	(segment
		(start 47.8536 -97.6122)
		(end 48.641 -96.8248)
		(width 0.381)
		(layer "In9.Cu")
		(net "P3V3_RTC_AUX")
	)
	(segment
		(start 46.939454 -106.045)
		(end 47.05223 -106.045)
		(width 0.381)
		(layer "In9.Cu")
		(net "P3V3_RTC_AUX")
	)
	(segment
		(start 51.6636 -95.6564)
		(end 51.6636 -91.0336)
		(width 0.381)
		(layer "In9.Cu")
		(net "P3V3_RTC_AUX")
	)
	(segment
		(start 51.28006 -77.3938)
		(end 50.0126 -77.3938)
		(width 0.381)
		(layer "In9.Cu")
		(net "P3V3_RTC_AUX")
	)
	(segment
		(start 47.5742 -97.6122)
		(end 47.8536 -97.6122)
		(width 0.381)
		(layer "In9.Cu")
		(net "P3V3_RTC_AUX")
	)
	(segment
		(start 46.5582 -105.663746)
		(end 46.939454 -106.045)
		(width 0.381)
		(layer "In9.Cu")
		(net "P3V3_RTC_AUX")
	)
	(segment
		(start 46.5582 -101.5238)
		(end 46.5582 -105.663746)
		(width 0.381)
		(layer "In9.Cu")
		(net "P3V3_RTC_AUX")
	)
	(segment
		(start 49.5554 -88.9254)
		(end 49.5554 -87.79256)
		(width 0.381)
		(layer "In9.Cu")
		(net "P3V3_RTC_AUX")
	)
	(segment
		(start 51.6636 -91.0336)
		(end 49.5554 -88.9254)
		(width 0.381)
		(layer "In9.Cu")
		(net "P3V3_RTC_AUX")
	)
	(segment
		(start 48.641 -96.8248)
		(end 50.4952 -96.8248)
		(width 0.381)
		(layer "In9.Cu")
		(net "P3V3_RTC_AUX")
	)
	(segment
		(start 49.537874 -77.868526)
		(end 49.537874 -78.024228)
		(width 0.381)
		(layer "In9.Cu")
		(net "P3V3_RTC_AUX")
	)
	(segment
		(start 50.43424 -87.41156)
		(end 51.7144 -86.1314)
		(width 0.381)
		(layer "In9.Cu")
		(net "P3V3_RTC_AUX")
	)
	(segment
		(start 51.7144 -86.1314)
		(end 51.7144 -77.82814)
		(width 0.381)
		(layer "In9.Cu")
		(net "P3V3_RTC_AUX")
	)
	(segment
		(start 51.7144 -77.82814)
		(end 51.28006 -77.3938)
		(width 0.381)
		(layer "In9.Cu")
		(net "P3V3_RTC_AUX")
	)
	(segment
		(start 47.5742 -97.6122)
		(end 47.5742 -100.5078)
		(width 0.381)
		(layer "In9.Cu")
		(net "P3V3_RTC_AUX")
	)
	(segment
		(start 49.5554 -87.79256)
		(end 49.9364 -87.41156)
		(width 0.381)
		(layer "In9.Cu")
		(net "P3V3_RTC_AUX")
	)
	(segment
		(start 49.9364 -87.41156)
		(end 50.43424 -87.41156)
		(width 0.381)
		(layer "In9.Cu")
		(net "P3V3_RTC_AUX")
	)
	(segment
		(start 47.5742 -100.5078)
		(end 46.5582 -101.5238)
		(width 0.381)
		(layer "In9.Cu")
		(net "P3V3_RTC_AUX")
	)
	(segment
		(start 50.4952 -96.8248)
		(end 51.6636 -95.6564)
		(width 0.381)
		(layer "In9.Cu")
		(net "P3V3_RTC_AUX")
	)
	(segment
		(start 50.0126 -77.3938)
		(end 49.537874 -77.868526)
		(width 0.381)
		(layer "In9.Cu")
		(net "P3V3_RTC_AUX")
	)
	(segment
		(start 36.86302 -65.28054)
		(end 36.86302 -71.33082)
		(width 0.381)
		(layer "F.Cu")
		(net "P3V3_RGM")
	)
	(segment
		(start 36.86302 -71.33082)
		(end 37.8714 -72.3392)
		(width 0.381)
		(layer "F.Cu")
		(net "P3V3_RGM")
	)
	(segment
		(start 31.98495 -20.9042)
		(end 31.42234 -20.9042)
		(width 0.381)
		(layer "F.Cu")
		(net "P3V3_RGM")
	)
	(segment
		(start 49.53 -95.29445)
		(end 49.53 -94.9706)
		(width 0.381)
		(layer "F.Cu")
		(net "P3V3_RGM")
	)
	(segment
		(start 49.2125 -97.89795)
		(end 50.19548 -97.89795)
		(width 0.381)
		(layer "F.Cu")
		(net "P3V3_RGM")
	)
	(segment
		(start 26.52395 -20.32)
		(end 26.52395 -20.955)
		(width 0.381)
		(layer "F.Cu")
		(net "P3V3_RGM")
	)
	(segment
		(start 62.7888 -29.8196)
		(end 62.484 -30.1244)
		(width 0.381)
		(layer "F.Cu")
		(net "P3V3_RGM")
	)
	(segment
		(start 49.2125 -95.61195)
		(end 49.53 -95.29445)
		(width 0.381)
		(layer "F.Cu")
		(net "P3V3_RGM")
	)
	(segment
		(start 32.0548 -20.97405)
		(end 31.98495 -20.9042)
		(width 0.381)
		(layer "F.Cu")
		(net "P3V3_RGM")
	)
	(segment
		(start 49.2125 -94.6531)
		(end 49.2125 -94.31655)
		(width 0.381)
		(layer "F.Cu")
		(net "P3V3_RGM")
	)
	(segment
		(start 37.8714 -72.3392)
		(end 38.608 -72.3392)
		(width 0.381)
		(layer "F.Cu")
		(net "P3V3_RGM")
	)
	(segment
		(start 35.87496 -66.2686)
		(end 33.97885 -66.2686)
		(width 0.381)
		(layer "F.Cu")
		(net "P3V3_RGM")
	)
	(segment
		(start 59.837066 -34.237676)
		(end 59.860434 -34.261044)
		(width 0.254)
		(layer "F.Cu")
		(net "P3V3_RGM")
	)
	(segment
		(start 38.608 -72.3392)
		(end 38.7096 -72.2376)
		(width 0.381)
		(layer "F.Cu")
		(net "P3V3_RGM")
	)
	(segment
		(start 56.094884 -46.571154)
		(end 56.894984 -46.571154)
		(width 0.3556)
		(layer "F.Cu")
		(net "P3V3_RGM")
	)
	(segment
		(start 59.362594 -34.237676)
		(end 59.837066 -34.237676)
		(width 0.254)
		(layer "F.Cu")
		(net "P3V3_RGM")
	)
	(segment
		(start 59.860434 -34.261044)
		(end 60.341002 -34.261044)
		(width 0.254)
		(layer "F.Cu")
		(net "P3V3_RGM")
	)
	(segment
		(start 56.894984 -46.571154)
		(end 57.290208 -46.17593)
		(width 0.3556)
		(layer "F.Cu")
		(net "P3V3_RGM")
	)
	(segment
		(start 33.97885 -66.2686)
		(end 33.72485 -66.5226)
		(width 0.381)
		(layer "F.Cu")
		(net "P3V3_RGM")
	)
	(segment
		(start 49.53 -94.9706)
		(end 49.2125 -94.6531)
		(width 0.381)
		(layer "F.Cu")
		(net "P3V3_RGM")
	)
	(segment
		(start 59.311794 -33.678876)
		(end 59.311794 -34.288476)
		(width 0.254)
		(layer "F.Cu")
		(net "P3V3_RGM")
	)
	(segment
		(start 62.484 -30.1244)
		(end 62.484 -30.46095)
		(width 0.381)
		(layer "F.Cu")
		(net "P3V3_RGM")
	)
	(segment
		(start 59.311794 -34.288476)
		(end 59.362594 -34.237676)
		(width 0.254)
		(layer "F.Cu")
		(net "P3V3_RGM")
	)
	(segment
		(start 36.8935 -65.25006)
		(end 36.86302 -65.28054)
		(width 0.381)
		(layer "F.Cu")
		(net "P3V3_RGM")
	)
	(segment
		(start 60.341002 -34.261044)
		(end 60.36437 -34.237676)
		(width 0.254)
		(layer "F.Cu")
		(net "P3V3_RGM")
	)
	(segment
		(start 36.86302 -65.28054)
		(end 35.87496 -66.2686)
		(width 0.381)
		(layer "F.Cu")
		(net "P3V3_RGM")
	)
	(via
		(at 70.09384 -32.00654)
		(size 0.508)
		(drill 0.254)
		(layers "F.Cu" "B.Cu")
		(net "P3V3_RGM")
	)
	(via
		(at 57.290208 -46.17593)
		(size 0.4572)
		(drill 0.254)
		(layers "F.Cu" "B.Cu")
		(net "P3V3_RGM")
	)
	(via
		(at 26.52395 -20.955)
		(size 0.508)
		(drill 0.254)
		(layers "F.Cu" "B.Cu")
		(net "P3V3_RGM")
	)
	(via
		(at 37.5412 -51.000406)
		(size 0.508)
		(drill 0.254)
		(layers "F.Cu" "B.Cu")
		(net "P3V3_RGM")
	)
	(via
		(at 59.311794 -33.678876)
		(size 0.508)
		(drill 0.254)
		(layers "F.Cu" "B.Cu")
		(net "P3V3_RGM")
	)
	(via
		(at 67.83324 -31.6865)
		(size 0.6604)
		(drill 0.3302)
		(layers "F.Cu" "B.Cu")
		(net "P3V3_RGM")
	)
	(via
		(at 31.42234 -20.9042)
		(size 0.508)
		(drill 0.254)
		(layers "F.Cu" "B.Cu")
		(net "P3V3_RGM")
	)
	(via
		(at 38.7096 -72.2376)
		(size 0.508)
		(drill 0.254)
		(layers "F.Cu" "B.Cu")
		(net "P3V3_RGM")
	)
	(via
		(at 36.8935 -65.25006)
		(size 0.508)
		(drill 0.254)
		(layers "F.Cu" "B.Cu")
		(net "P3V3_RGM")
	)
	(via
		(at 58.469784 -67.939158)
		(size 0.508)
		(drill 0.254)
		(layers "F.Cu" "B.Cu")
		(net "P3V3_RGM")
	)
	(via
		(at 50.19548 -97.89795)
		(size 0.508)
		(drill 0.254)
		(layers "F.Cu" "B.Cu")
		(net "P3V3_RGM")
	)
	(via
		(at 43.458892 -86.670896)
		(size 0.508)
		(drill 0.254)
		(layers "F.Cu" "B.Cu")
		(net "P3V3_RGM")
	)
	(via
		(at 48.4124 -85.8266)
		(size 0.508)
		(drill 0.254)
		(layers "F.Cu" "B.Cu")
		(net "P3V3_RGM")
	)
	(via
		(at 69.4563 -31.7627)
		(size 0.508)
		(drill 0.254)
		(layers "F.Cu" "B.Cu")
		(net "P3V3_RGM")
	)
	(via
		(at 52.8828 -28.38704)
		(size 0.508)
		(drill 0.254)
		(layers "F.Cu" "B.Cu")
		(net "P3V3_RGM")
	)
	(via
		(at 51.95824 -76.48702)
		(size 0.508)
		(drill 0.254)
		(layers "F.Cu" "B.Cu")
		(net "P3V3_RGM")
	)
	(via
		(at 49.53 -94.9706)
		(size 0.508)
		(drill 0.254)
		(layers "F.Cu" "B.Cu")
		(net "P3V3_RGM")
	)
	(via
		(at 73.66 -20.828)
		(size 0.508)
		(drill 0.254)
		(layers "F.Cu" "B.Cu")
		(net "P3V3_RGM")
	)
	(via
		(at 62.7888 -29.8196)
		(size 0.508)
		(drill 0.254)
		(layers "F.Cu" "B.Cu")
		(net "P3V3_RGM")
	)
	(segment
		(start 68.8848 -31.7627)
		(end 69.4563 -31.7627)
		(width 0.381)
		(layer "B.Cu")
		(net "P3V3_RGM")
	)
	(segment
		(start 65.108582 -30.467554)
		(end 65.108582 -28.805632)
		(width 0.381)
		(layer "B.Cu")
		(net "P3V3_RGM")
	)
	(segment
		(start 62.865 -30.96895)
		(end 62.7888 -30.89275)
		(width 0.4572)
		(layer "B.Cu")
		(net "P3V3_RGM")
	)
	(segment
		(start 45.212 -86.8426)
		(end 45.18152 -86.87308)
		(width 0.381)
		(layer "B.Cu")
		(net "P3V3_RGM")
	)
	(segment
		(start 62.7888 -30.89275)
		(end 62.7888 -29.8196)
		(width 0.4572)
		(layer "B.Cu")
		(net "P3V3_RGM")
	)
	(segment
		(start 68.8086 -31.6865)
		(end 68.8848 -31.7627)
		(width 0.381)
		(layer "B.Cu")
		(net "P3V3_RGM")
	)
	(segment
		(start 67.83324 -31.38424)
		(end 67.83324 -31.6865)
		(width 0.381)
		(layer "B.Cu")
		(net "P3V3_RGM")
	)
	(segment
		(start 48.559212 -86.735666)
		(end 48.559212 -86.024212)
		(width 0.381)
		(layer "B.Cu")
		(net "P3V3_RGM")
	)
	(segment
		(start 48.9966 -87.173054)
		(end 48.559212 -86.735666)
		(width 0.381)
		(layer "B.Cu")
		(net "P3V3_RGM")
	)
	(segment
		(start 65.5447 -30.467554)
		(end 65.6717 -30.340554)
		(width 0.381)
		(layer "B.Cu")
		(net "P3V3_RGM")
	)
	(segment
		(start 43.661076 -86.87308)
		(end 43.458892 -86.670896)
		(width 0.381)
		(layer "B.Cu")
		(net "P3V3_RGM")
	)
	(segment
		(start 65.6717 -30.340554)
		(end 66.127884 -30.340554)
		(width 0.381)
		(layer "B.Cu")
		(net "P3V3_RGM")
	)
	(segment
		(start 48.4124 -85.8774)
		(end 48.4124 -85.8266)
		(width 0.381)
		(layer "B.Cu")
		(net "P3V3_RGM")
	)
	(segment
		(start 65.108582 -28.805632)
		(end 65.0494 -28.74645)
		(width 0.381)
		(layer "B.Cu")
		(net "P3V3_RGM")
	)
	(segment
		(start 48.559212 -86.024212)
		(end 48.4124 -85.8774)
		(width 0.381)
		(layer "B.Cu")
		(net "P3V3_RGM")
	)
	(segment
		(start 66.127884 -30.340554)
		(end 66.789554 -30.340554)
		(width 0.381)
		(layer "B.Cu")
		(net "P3V3_RGM")
	)
	(segment
		(start 49.2252 -87.71255)
		(end 48.9966 -87.48395)
		(width 0.381)
		(layer "B.Cu")
		(net "P3V3_RGM")
	)
	(segment
		(start 26.133044 -20.564094)
		(end 26.52395 -20.955)
		(width 0.4572)
		(layer "B.Cu")
		(net "P3V3_RGM")
	)
	(segment
		(start 48.9966 -87.48395)
		(end 48.9966 -87.173054)
		(width 0.381)
		(layer "B.Cu")
		(net "P3V3_RGM")
	)
	(segment
		(start 65.108582 -30.467554)
		(end 65.5447 -30.467554)
		(width 0.381)
		(layer "B.Cu")
		(net "P3V3_RGM")
	)
	(segment
		(start 67.83324 -31.6865)
		(end 68.8086 -31.6865)
		(width 0.381)
		(layer "B.Cu")
		(net "P3V3_RGM")
	)
	(segment
		(start 26.133044 -19.955764)
		(end 26.133044 -20.564094)
		(width 0.4572)
		(layer "B.Cu")
		(net "P3V3_RGM")
	)
	(segment
		(start 45.18152 -86.87308)
		(end 43.661076 -86.87308)
		(width 0.381)
		(layer "B.Cu")
		(net "P3V3_RGM")
	)
	(segment
		(start 66.789554 -30.340554)
		(end 67.83324 -31.38424)
		(width 0.381)
		(layer "B.Cu")
		(net "P3V3_RGM")
	)
	(segment
		(start 31.0134 -20.9042)
		(end 31.42234 -20.9042)
		(width 0.381)
		(layer "In2.Cu")
		(net "P3V3_RGM")
	)
	(segment
		(start 40.811196 -74.669396)
		(end 38.7096 -72.5678)
		(width 0.381)
		(layer "In2.Cu")
		(net "P3V3_RGM")
	)
	(segment
		(start 50.204624 -73.4568)
		(end 42.627296 -73.4568)
		(width 0.381)
		(layer "In2.Cu")
		(net "P3V3_RGM")
	)
	(segment
		(start 38.7096 -72.5678)
		(end 38.7096 -72.2376)
		(width 0.381)
		(layer "In2.Cu")
		(net "P3V3_RGM")
	)
	(segment
		(start 71.110856 -31.2166)
		(end 73.7108 -31.2166)
		(width 0.4572)
		(layer "In2.Cu")
		(net "P3V3_RGM")
	)
	(segment
		(start 73.7108 -31.2166)
		(end 74.1426 -30.7848)
		(width 0.4572)
		(layer "In2.Cu")
		(net "P3V3_RGM")
	)
	(segment
		(start 27.127454 -20.955)
		(end 27.889454 -20.193)
		(width 0.381)
		(layer "In2.Cu")
		(net "P3V3_RGM")
	)
	(segment
		(start 30.475936 -20.366736)
		(end 31.0134 -20.9042)
		(width 0.381)
		(layer "In2.Cu")
		(net "P3V3_RGM")
	)
	(segment
		(start 70.861428 -31.466028)
		(end 71.110856 -31.2166)
		(width 0.4572)
		(layer "In2.Cu")
		(net "P3V3_RGM")
	)
	(segment
		(start 27.889454 -20.193)
		(end 28.526994 -20.193)
		(width 0.381)
		(layer "In2.Cu")
		(net "P3V3_RGM")
	)
	(segment
		(start 28.70073 -20.366736)
		(end 30.475936 -20.366736)
		(width 0.381)
		(layer "In2.Cu")
		(net "P3V3_RGM")
	)
	(segment
		(start 51.7779 -76.30668)
		(end 51.7779 -75.030076)
		(width 0.381)
		(layer "In2.Cu")
		(net "P3V3_RGM")
	)
	(segment
		(start 51.95824 -76.48702)
		(end 51.7779 -76.30668)
		(width 0.381)
		(layer "In2.Cu")
		(net "P3V3_RGM")
	)
	(segment
		(start 26.52395 -20.955)
		(end 27.127454 -20.955)
		(width 0.381)
		(layer "In2.Cu")
		(net "P3V3_RGM")
	)
	(segment
		(start 41.4147 -74.669396)
		(end 40.811196 -74.669396)
		(width 0.381)
		(layer "In2.Cu")
		(net "P3V3_RGM")
	)
	(segment
		(start 74.1426 -21.3106)
		(end 73.66 -20.828)
		(width 0.4572)
		(layer "In2.Cu")
		(net "P3V3_RGM")
	)
	(segment
		(start 51.7779 -75.030076)
		(end 50.204624 -73.4568)
		(width 0.381)
		(layer "In2.Cu")
		(net "P3V3_RGM")
	)
	(segment
		(start 42.627296 -73.4568)
		(end 41.4147 -74.669396)
		(width 0.381)
		(layer "In2.Cu")
		(net "P3V3_RGM")
	)
	(segment
		(start 28.526994 -20.193)
		(end 28.70073 -20.366736)
		(width 0.381)
		(layer "In2.Cu")
		(net "P3V3_RGM")
	)
	(segment
		(start 74.1426 -30.7848)
		(end 74.1426 -21.3106)
		(width 0.4572)
		(layer "In2.Cu")
		(net "P3V3_RGM")
	)
	(segment
		(start 36.8935 -64.900048)
		(end 36.8935 -65.25006)
		(width 0.381)
		(layer "In4.Cu")
		(net "P3V3_RGM")
	)
	(segment
		(start 35.2552 -55.3212)
		(end 35.5346 -55.6006)
		(width 0.381)
		(layer "In4.Cu")
		(net "P3V3_RGM")
	)
	(segment
		(start 51.99888 -76.52766)
		(end 51.99888 -76.762864)
		(width 0.4572)
		(layer "In4.Cu")
		(net "P3V3_RGM")
	)
	(segment
		(start 35.2552 -54.9402)
		(end 35.2552 -55.3212)
		(width 0.381)
		(layer "In4.Cu")
		(net "P3V3_RGM")
	)
	(segment
		(start 35.5346 -55.6006)
		(end 35.5346 -56.6674)
		(width 0.381)
		(layer "In4.Cu")
		(net "P3V3_RGM")
	)
	(segment
		(start 35.7632 -53.467)
		(end 35.7632 -54.4322)
		(width 0.381)
		(layer "In4.Cu")
		(net "P3V3_RGM")
	)
	(segment
		(start 37.5412 -51.000406)
		(end 37.5412 -51.689)
		(width 0.381)
		(layer "In4.Cu")
		(net "P3V3_RGM")
	)
	(segment
		(start 49.53 -94.9706)
		(end 49.53 -97.23247)
		(width 0.381)
		(layer "In4.Cu")
		(net "P3V3_RGM")
	)
	(segment
		(start 35.7632 -54.4322)
		(end 35.2552 -54.9402)
		(width 0.381)
		(layer "In4.Cu")
		(net "P3V3_RGM")
	)
	(segment
		(start 37.5412 -51.689)
		(end 35.7632 -53.467)
		(width 0.381)
		(layer "In4.Cu")
		(net "P3V3_RGM")
	)
	(segment
		(start 51.905408 -97.372424)
		(end 51.379882 -97.89795)
		(width 0.4572)
		(layer "In4.Cu")
		(net "P3V3_RGM")
	)
	(segment
		(start 36.03752 -59.68492)
		(end 36.03752 -64.044068)
		(width 0.381)
		(layer "In4.Cu")
		(net "P3V3_RGM")
	)
	(segment
		(start 35.3822 -56.8198)
		(end 35.3822 -59.0296)
		(width 0.381)
		(layer "In4.Cu")
		(net "P3V3_RGM")
	)
	(segment
		(start 51.379882 -97.89795)
		(end 50.19548 -97.89795)
		(width 0.4572)
		(layer "In4.Cu")
		(net "P3V3_RGM")
	)
	(segment
		(start 52.0954 -95.398082)
		(end 52.23256 -95.729298)
		(width 0.4572)
		(layer "In4.Cu")
		(net "P3V3_RGM")
	)
	(segment
		(start 36.03752 -64.044068)
		(end 36.8935 -64.900048)
		(width 0.381)
		(layer "In4.Cu")
		(net "P3V3_RGM")
	)
	(segment
		(start 35.3822 -59.0296)
		(end 36.03752 -59.68492)
		(width 0.381)
		(layer "In4.Cu")
		(net "P3V3_RGM")
	)
	(segment
		(start 52.23256 -95.729298)
		(end 51.905408 -97.372424)
		(width 0.4572)
		(layer "In4.Cu")
		(net "P3V3_RGM")
	)
	(segment
		(start 52.0954 -76.859384)
		(end 52.0954 -95.398082)
		(width 0.4572)
		(layer "In4.Cu")
		(net "P3V3_RGM")
	)
	(segment
		(start 51.95824 -76.48702)
		(end 51.99888 -76.52766)
		(width 0.4572)
		(layer "In4.Cu")
		(net "P3V3_RGM")
	)
	(segment
		(start 35.5346 -56.6674)
		(end 35.3822 -56.8198)
		(width 0.381)
		(layer "In4.Cu")
		(net "P3V3_RGM")
	)
	(segment
		(start 49.53 -97.23247)
		(end 50.19548 -97.89795)
		(width 0.381)
		(layer "In4.Cu")
		(net "P3V3_RGM")
	)
	(segment
		(start 51.99888 -76.762864)
		(end 52.0954 -76.859384)
		(width 0.4572)
		(layer "In4.Cu")
		(net "P3V3_RGM")
	)
	(segment
		(start 36.204144 -21.4376)
		(end 36.102544 -21.336)
		(width 0.4572)
		(layer "In7.Cu")
		(net "P3V3_RGM")
	)
	(segment
		(start 32.81934 -22.3012)
		(end 31.42234 -20.9042)
		(width 0.4572)
		(layer "In7.Cu")
		(net "P3V3_RGM")
	)
	(segment
		(start 52.8828 -28.38704)
		(end 52.8828 -27.440636)
		(width 0.4572)
		(layer "In7.Cu")
		(net "P3V3_RGM")
	)
	(segment
		(start 52.660296 -25.609296)
		(end 49.8348 -22.7838)
		(width 0.4572)
		(layer "In7.Cu")
		(net "P3V3_RGM")
	)
	(segment
		(start 34.0106 -22.3012)
		(end 32.81934 -22.3012)
		(width 0.4572)
		(layer "In7.Cu")
		(net "P3V3_RGM")
	)
	(segment
		(start 34.9758 -21.336)
		(end 34.0106 -22.3012)
		(width 0.4572)
		(layer "In7.Cu")
		(net "P3V3_RGM")
	)
	(segment
		(start 52.660296 -27.218132)
		(end 52.660296 -25.609296)
		(width 0.4572)
		(layer "In7.Cu")
		(net "P3V3_RGM")
	)
	(segment
		(start 36.102544 -21.336)
		(end 34.9758 -21.336)
		(width 0.4572)
		(layer "In7.Cu")
		(net "P3V3_RGM")
	)
	(segment
		(start 44.958 -21.4376)
		(end 36.204144 -21.4376)
		(width 0.4572)
		(layer "In7.Cu")
		(net "P3V3_RGM")
	)
	(segment
		(start 49.8348 -22.7838)
		(end 46.3042 -22.7838)
		(width 0.4572)
		(layer "In7.Cu")
		(net "P3V3_RGM")
	)
	(segment
		(start 46.3042 -22.7838)
		(end 44.958 -21.4376)
		(width 0.4572)
		(layer "In7.Cu")
		(net "P3V3_RGM")
	)
	(segment
		(start 52.8828 -27.440636)
		(end 52.660296 -27.218132)
		(width 0.4572)
		(layer "In7.Cu")
		(net "P3V3_RGM")
	)
	(segment
		(start 47.4218 -88.2904)
		(end 47.4218 -86.973156)
		(width 0.381)
		(layer "In9.Cu")
		(net "P3V3_RGM")
	)
	(segment
		(start 43.458892 -86.854792)
		(end 43.458892 -86.670896)
		(width 0.381)
		(layer "In9.Cu")
		(net "P3V3_RGM")
	)
	(segment
		(start 49.53 -94.9706)
		(end 46.5074 -91.948)
		(width 0.4572)
		(layer "In9.Cu")
		(net "P3V3_RGM")
	)
	(segment
		(start 46.5074 -91.948)
		(end 46.5074 -89.9033)
		(width 0.4572)
		(layer "In9.Cu")
		(net "P3V3_RGM")
	)
	(segment
		(start 46.425358 -89.286842)
		(end 47.4218 -88.2904)
		(width 0.381)
		(layer "In9.Cu")
		(net "P3V3_RGM")
	)
	(segment
		(start 47.4218 -86.973156)
		(end 48.4124 -85.982556)
		(width 0.381)
		(layer "In9.Cu")
		(net "P3V3_RGM")
	)
	(segment
		(start 48.4124 -85.982556)
		(end 48.4124 -85.8266)
		(width 0.381)
		(layer "In9.Cu")
		(net "P3V3_RGM")
	)
	(segment
		(start 46.5074 -89.9033)
		(end 45.890942 -89.286842)
		(width 0.4572)
		(layer "In9.Cu")
		(net "P3V3_RGM")
	)
	(segment
		(start 45.890942 -89.286842)
		(end 43.458892 -86.854792)
		(width 0.381)
		(layer "In9.Cu")
		(net "P3V3_RGM")
	)
	(segment
		(start 45.890942 -89.286842)
		(end 46.425358 -89.286842)
		(width 0.381)
		(layer "In9.Cu")
		(net "P3V3_RGM")
	)
	(segment
		(start 48.0949 -47.371254)
		(end 47.699676 -46.97603)
		(width 0.381)
		(layer "F.Cu")
		(net "P3V3_P2V5_P1V8_RVDD")
	)
	(segment
		(start 48.895 -46.571154)
		(end 48.499776 -46.17593)
		(width 0.381)
		(layer "F.Cu")
		(net "P3V3_P2V5_P1V8_RVDD")
	)
	(segment
		(start 48.895 -45.771308)
		(end 48.499776 -45.376084)
		(width 0.381)
		(layer "F.Cu")
		(net "P3V3_P2V5_P1V8_RVDD")
	)
	(segment
		(start 47.965106 -48.04156)
		(end 47.965106 -47.501048)
		(width 0.3556)
		(layer "F.Cu")
		(net "P3V3_P2V5_P1V8_RVDD")
	)
	(segment
		(start 47.965106 -47.501048)
		(end 48.0949 -47.371254)
		(width 0.3556)
		(layer "F.Cu")
		(net "P3V3_P2V5_P1V8_RVDD")
	)
	(segment
		(start 48.0949 -48.171354)
		(end 47.965106 -48.04156)
		(width 0.3556)
		(layer "F.Cu")
		(net "P3V3_P2V5_P1V8_RVDD")
	)
	(via
		(at 47.699676 -46.97603)
		(size 0.4572)
		(drill 0.254)
		(layers "F.Cu" "B.Cu")
		(net "P3V3_P2V5_P1V8_RVDD")
	)
	(via
		(at 37.700966 -37.511228)
		(size 0.508)
		(drill 0.254)
		(layers "F.Cu" "B.Cu")
		(net "P3V3_P2V5_P1V8_RVDD")
	)
	(via
		(at 38.749224 -37.511482)
		(size 0.508)
		(drill 0.254)
		(layers "F.Cu" "B.Cu")
		(net "P3V3_P2V5_P1V8_RVDD")
	)
	(via
		(at 48.499776 -45.376084)
		(size 0.4572)
		(drill 0.254)
		(layers "F.Cu" "B.Cu")
		(net "P3V3_P2V5_P1V8_RVDD")
	)
	(via
		(at 48.499776 -46.17593)
		(size 0.4572)
		(drill 0.254)
		(layers "F.Cu" "B.Cu")
		(net "P3V3_P2V5_P1V8_RVDD")
	)
	(segment
		(start 50.494946 -44.971208)
		(end 50.099722 -44.575984)
		(width 0.381)
		(layer "F.Cu")
		(net "P3V3_P1V8_SD2VDD")
	)
	(segment
		(start 51.295046 -44.971208)
		(end 50.899822 -44.575984)
		(width 0.381)
		(layer "F.Cu")
		(net "P3V3_P1V8_SD2VDD")
	)
	(via
		(at 39.727124 -32.817562)
		(size 0.508)
		(drill 0.254)
		(layers "F.Cu" "B.Cu")
		(net "P3V3_P1V8_SD2VDD")
	)
	(via
		(at 39.696644 -31.725362)
		(size 0.508)
		(drill 0.254)
		(layers "F.Cu" "B.Cu")
		(net "P3V3_P1V8_SD2VDD")
	)
	(via
		(at 50.099722 -44.575984)
		(size 0.4572)
		(drill 0.254)
		(layers "F.Cu" "B.Cu")
		(net "P3V3_P1V8_SD2VDD")
	)
	(via
		(at 50.899822 -44.575984)
		(size 0.4572)
		(drill 0.254)
		(layers "F.Cu" "B.Cu")
		(net "P3V3_P1V8_SD2VDD")
	)
	(segment
		(start 48.895 -44.971208)
		(end 48.499776 -44.575984)
		(width 0.381)
		(layer "F.Cu")
		(net "P3V3_P1V8_SD1VDD")
	)
	(segment
		(start 48.895 -44.171362)
		(end 48.499776 -43.776138)
		(width 0.381)
		(layer "F.Cu")
		(net "P3V3_P1V8_SD1VDD")
	)
	(via
		(at 48.499776 -43.776138)
		(size 0.4572)
		(drill 0.254)
		(layers "F.Cu" "B.Cu")
		(net "P3V3_P1V8_SD1VDD")
	)
	(via
		(at 39.104316 -36.851844)
		(size 0.508)
		(drill 0.254)
		(layers "F.Cu" "B.Cu")
		(net "P3V3_P1V8_SD1VDD")
	)
	(via
		(at 38.13937 -36.851844)
		(size 0.508)
		(drill 0.254)
		(layers "F.Cu" "B.Cu")
		(net "P3V3_P1V8_SD1VDD")
	)
	(via
		(at 48.499776 -44.575984)
		(size 0.4572)
		(drill 0.254)
		(layers "F.Cu" "B.Cu")
		(net "P3V3_P1V8_SD1VDD")
	)
	(via
		(at 36.7792 -35.9918)
		(size 0.6604)
		(drill 0.3302)
		(layers "F.Cu" "B.Cu")
		(net "P3V3_P1V8_SD1VDD")
	)
	(segment
		(start 50.494946 -43.371262)
		(end 49.6951 -43.371262)
		(width 0.3556)
		(layer "F.Cu")
		(net "P3V3_P1V8_I2C_I3C")
	)
	(segment
		(start 49.6951 -43.371262)
		(end 49.299876 -42.976038)
		(width 0.3556)
		(layer "F.Cu")
		(net "P3V3_P1V8_I2C_I3C")
	)
	(via
		(at 49.299876 -42.976038)
		(size 0.4572)
		(drill 0.254)
		(layers "F.Cu" "B.Cu")
		(net "P3V3_P1V8_I2C_I3C")
	)
	(via
		(at 38.0492 -34.3154)
		(size 0.508)
		(drill 0.254)
		(layers "F.Cu" "B.Cu")
		(net "P3V3_P1V8_I2C_I3C")
	)
	(via
		(at 38.0492 -35.0774)
		(size 0.508)
		(drill 0.254)
		(layers "F.Cu" "B.Cu")
		(net "P3V3_P1V8_I2C_I3C")
	)
	(segment
		(start 49.372012 -42.903902)
		(end 49.299876 -42.976038)
		(width 0.3556)
		(layer "B.Cu")
		(net "P3V3_P1V8_I2C_I3C")
	)
	(segment
		(start 50.155602 -42.903902)
		(end 49.372012 -42.903902)
		(width 0.3556)
		(layer "B.Cu")
		(net "P3V3_P1V8_I2C_I3C")
	)
	(segment
		(start 57.695084 -45.771308)
		(end 58.090308 -45.376084)
		(width 0.3556)
		(layer "F.Cu")
		(net "P3V3_BMC_USB2AV33")
	)
	(via
		(at 69.1134 -34.8996)
		(size 0.6604)
		(drill 0.3302)
		(layers "F.Cu" "B.Cu")
		(net "P3V3_BMC_USB2AV33")
	)
	(via
		(at 58.090308 -45.376084)
		(size 0.4572)
		(drill 0.254)
		(layers "F.Cu" "B.Cu")
		(net "P3V3_BMC_USB2AV33")
	)
	(via
		(at 68.451222 -35.205416)
		(size 0.508)
		(drill 0.254)
		(layers "F.Cu" "B.Cu")
		(net "P3V3_BMC_USB2AV33")
	)
	(segment
		(start 58.642504 -45.939964)
		(end 58.642504 -45.92828)
		(width 0.381)
		(layer "B.Cu")
		(net "P3V3_BMC_USB2AV33")
	)
	(segment
		(start 58.642504 -45.92828)
		(end 58.090308 -45.376084)
		(width 0.381)
		(layer "B.Cu")
		(net "P3V3_BMC_USB2AV33")
	)
	(segment
		(start 5.13207 -64.950848)
		(end 4.33451 -64.950848)
		(width 0.3048)
		(layer "F.Cu")
		(net "P3V3_AUX_VCC")
	)
	(via
		(at 4.33451 -64.950848)
		(size 0.508)
		(drill 0.254)
		(layers "F.Cu" "B.Cu")
		(net "P3V3_AUX_VCC")
	)
	(segment
		(start 9.702292 -64.537082)
		(end 9.249156 -64.537082)
		(width 0.254)
		(layer "F.Cu")
		(net "P3V3_AUX_FB_RC")
	)
	(segment
		(start 12.30376 -64.14389)
		(end 13.31976 -64.14389)
		(width 0.254)
		(layer "F.Cu")
		(net "P3V3_AUX_FB_RC")
	)
	(segment
		(start 11.27125 -64.14389)
		(end 12.30376 -64.14389)
		(width 0.254)
		(layer "F.Cu")
		(net "P3V3_AUX_FB_RC")
	)
	(segment
		(start 11.27125 -64.14389)
		(end 10.095484 -64.14389)
		(width 0.254)
		(layer "F.Cu")
		(net "P3V3_AUX_FB_RC")
	)
	(segment
		(start 10.095484 -64.14389)
		(end 9.702292 -64.537082)
		(width 0.254)
		(layer "F.Cu")
		(net "P3V3_AUX_FB_RC")
	)
	(segment
		(start 47.66945 -75.545442)
		(end 47.656242 -75.55865)
		(width 0.4572)
		(layer "F.Cu")
		(net "P3V3_AUX")
	)
	(segment
		(start 58.039 -84.30895)
		(end 57.01665 -84.30895)
		(width 0.4572)
		(layer "F.Cu")
		(net "P3V3_AUX")
	)
	(segment
		(start 52.094892 -44.971208)
		(end 51.699668 -44.575984)
		(width 0.3556)
		(layer "F.Cu")
		(net "P3V3_AUX")
	)
	(segment
		(start 36.8808 -109.86135)
		(end 36.9189 -109.86135)
		(width 0.381)
		(layer "F.Cu")
		(net "P3V3_AUX")
	)
	(segment
		(start 23.0632 -65.58915)
		(end 22.098 -65.58915)
		(width 0.381)
		(layer "F.Cu")
		(net "P3V3_AUX")
	)
	(segment
		(start 48.0949 -51.361594)
		(end 47.699676 -50.96637)
		(width 0.3556)
		(layer "F.Cu")
		(net "P3V3_AUX")
	)
	(segment
		(start 10.90168 -14.268704)
		(end 10.90168 -13.435838)
		(width 0.4572)
		(layer "F.Cu")
		(net "P3V3_AUX")
	)
	(segment
		(start 46.9392 -25.069546)
		(end 46.9392 -25.4762)
		(width 0.4572)
		(layer "F.Cu")
		(net "P3V3_AUX")
	)
	(segment
		(start 61.068966 -81.10474)
		(end 61.068966 -80.428084)
		(width 0.4572)
		(layer "F.Cu")
		(net "P3V3_AUX")
	)
	(segment
		(start 30.564074 -61.74105)
		(end 30.633924 -61.6712)
		(width 0.4572)
		(layer "F.Cu")
		(net "P3V3_AUX")
	)
	(segment
		(start 10.287 -95.99295)
		(end 9.62025 -95.99295)
		(width 0.4572)
		(layer "F.Cu")
		(net "P3V3_AUX")
	)
	(segment
		(start 46.58995 -76.01585)
		(end 47.04715 -75.55865)
		(width 0.4572)
		(layer "F.Cu")
		(net "P3V3_AUX")
	)
	(segment
		(start 33.738312 -35.624262)
		(end 33.738312 -35.1536)
		(width 0.4572)
		(layer "F.Cu")
		(net "P3V3_AUX")
	)
	(segment
		(start 14.506702 -9.906)
		(end 15.86611 -9.906)
		(width 0.4572)
		(layer "F.Cu")
		(net "P3V3_AUX")
	)
	(segment
		(start 48.77816 -75.32751)
		(end 48.25365 -74.803)
		(width 0.4572)
		(layer "F.Cu")
		(net "P3V3_AUX")
	)
	(segment
		(start 22.84095 -64.897)
		(end 22.84095 -65.3669)
		(width 0.4572)
		(layer "F.Cu")
		(net "P3V3_AUX")
	)
	(segment
		(start 36.61918 -90.010234)
		(end 36.56203 -89.953084)
		(width 0.4572)
		(layer "F.Cu")
		(net "P3V3_AUX")
	)
	(segment
		(start 26.758646 -83.34375)
		(end 26.86177 -83.240626)
		(width 0.381)
		(layer "F.Cu")
		(net "P3V3_AUX")
	)
	(segment
		(start 34.60242 -107.67949)
		(end 34.565082 -107.716828)
		(width 0.381)
		(layer "F.Cu")
		(net "P3V3_AUX")
	)
	(segment
		(start 77.94498 -21.336)
		(end 78.63078 -21.336)
		(width 0.4572)
		(layer "F.Cu")
		(net "P3V3_AUX")
	)
	(segment
		(start 35.97275 -43.608752)
		(end 36.46805 -44.104052)
		(width 0.4572)
		(layer "F.Cu")
		(net "P3V3_AUX")
	)
	(segment
		(start 16.826992 -43.824652)
		(end 16.826992 -43.268646)
		(width 0.381)
		(layer "F.Cu")
		(net "P3V3_AUX")
	)
	(segment
		(start 53.388006 -30.467554)
		(end 53.388006 -30.017974)
		(width 0.381)
		(layer "F.Cu")
		(net "P3V3_AUX")
	)
	(segment
		(start 7.18185 -80.4926)
		(end 7.53745 -80.137)
		(width 0.381)
		(layer "F.Cu")
		(net "P3V3_AUX")
	)
	(segment
		(start 24.178768 -65.256918)
		(end 24.178768 -65.358518)
		(width 0.254)
		(layer "F.Cu")
		(net "P3V3_AUX")
	)
	(segment
		(start 17.474946 -65.278)
		(end 17.52346 -65.278)
		(width 0.381)
		(layer "F.Cu")
		(net "P3V3_AUX")
	)
	(segment
		(start 36.51885 -44.45)
		(end 36.46805 -44.5008)
		(width 0.4572)
		(layer "F.Cu")
		(net "P3V3_AUX")
	)
	(segment
		(start 37.6936 -42.58945)
		(end 37.53993 -42.43578)
		(width 0.4572)
		(layer "F.Cu")
		(net "P3V3_AUX")
	)
	(segment
		(start 56.78551 -94.5896)
		(end 56.78551 -94.18955)
		(width 0.381)
		(layer "F.Cu")
		(net "P3V3_AUX")
	)
	(segment
		(start 38.03015 -110.0836)
		(end 38.23335 -109.8804)
		(width 0.381)
		(layer "F.Cu")
		(net "P3V3_AUX")
	)
	(segment
		(start 12.71905 -91.44)
		(end 12.71905 -90.44305)
		(width 0.4572)
		(layer "F.Cu")
		(net "P3V3_AUX")
	)
	(segment
		(start 17.672812 -65.427352)
		(end 17.52346 -65.278)
		(width 0.4572)
		(layer "F.Cu")
		(net "P3V3_AUX")
	)
	(segment
		(start 23.770336 -65.76695)
		(end 23.749 -65.76695)
		(width 0.254)
		(layer "F.Cu")
		(net "P3V3_AUX")
	)
	(segment
		(start 68.986908 -30.8356)
		(end 68.850764 -30.699456)
		(width 0.381)
		(layer "F.Cu")
		(net "P3V3_AUX")
	)
	(segment
		(start 76.292964 -14.492986)
		(end 76.30795 -14.478)
		(width 0.381)
		(layer "F.Cu")
		(net "P3V3_AUX")
	)
	(segment
		(start 48.83785 -79.0194)
		(end 48.91405 -78.9432)
		(width 0.4572)
		(layer "F.Cu")
		(net "P3V3_AUX")
	)
	(segment
		(start 52.894992 -44.971208)
		(end 52.499768 -44.575984)
		(width 0.3556)
		(layer "F.Cu")
		(net "P3V3_AUX")
	)
	(segment
		(start 21.971 -65.71615)
		(end 21.971 -65.17005)
		(width 0.381)
		(layer "F.Cu")
		(net "P3V3_AUX")
	)
	(segment
		(start 46.58995 -76.2254)
		(end 46.58995 -76.01585)
		(width 0.4572)
		(layer "F.Cu")
		(net "P3V3_AUX")
	)
	(segment
		(start 39.482014 -71.447406)
		(end 39.482014 -73.401936)
		(width 0.4572)
		(layer "F.Cu")
		(net "P3V3_AUX")
	)
	(segment
		(start 76.30795 -14.478)
		(end 76.30795 -13.847064)
		(width 0.4572)
		(layer "F.Cu")
		(net "P3V3_AUX")
	)
	(segment
		(start 36.56203 -89.337642)
		(end 36.56203 -89.953084)
		(width 0.381)
		(layer "F.Cu")
		(net "P3V3_AUX")
	)
	(segment
		(start 74.168 -74.69505)
		(end 75.819 -74.69505)
		(width 0.4572)
		(layer "F.Cu")
		(net "P3V3_AUX")
	)
	(segment
		(start 24.178768 -65.358518)
		(end 23.770336 -65.76695)
		(width 0.254)
		(layer "F.Cu")
		(net "P3V3_AUX")
	)
	(segment
		(start 32.5374 -34.6964)
		(end 33.281112 -34.6964)
		(width 0.4572)
		(layer "F.Cu")
		(net "P3V3_AUX")
	)
	(segment
		(start 69.36105 -101.82225)
		(end 69.36105 -101.473)
		(width 0.381)
		(layer "F.Cu")
		(net "P3V3_AUX")
	)
	(segment
		(start 29.591 -103.16845)
		(end 30.2768 -103.16845)
		(width 0.4572)
		(layer "F.Cu")
		(net "P3V3_AUX")
	)
	(segment
		(start 45.593 -29.6672)
		(end 45.593 -29.7688)
		(width 0.381)
		(layer "F.Cu")
		(net "P3V3_AUX")
	)
	(segment
		(start 68.850764 -30.699456)
		(end 68.850764 -29.991558)
		(width 0.381)
		(layer "F.Cu")
		(net "P3V3_AUX")
	)
	(segment
		(start 11.30935 -98.5012)
		(end 11.33475 -98.4758)
		(width 0.381)
		(layer "F.Cu")
		(net "P3V3_AUX")
	)
	(segment
		(start 50.494946 -53.771292)
		(end 50.504598 -53.771292)
		(width 0.3556)
		(layer "F.Cu")
		(net "P3V3_AUX")
	)
	(segment
		(start 30.24505 -105.41)
		(end 30.24505 -104.906318)
		(width 0.381)
		(layer "F.Cu")
		(net "P3V3_AUX")
	)
	(segment
		(start 16.826992 -43.268646)
		(end 17.10182 -42.993818)
		(width 0.381)
		(layer "F.Cu")
		(net "P3V3_AUX")
	)
	(segment
		(start 42.813478 -87.160608)
		(end 42.813478 -86.670134)
		(width 0.381)
		(layer "F.Cu")
		(net "P3V3_AUX")
	)
	(segment
		(start 46.56455 -76.2508)
		(end 46.58995 -76.2254)
		(width 0.4572)
		(layer "F.Cu")
		(net "P3V3_AUX")
	)
	(segment
		(start 22.098 -65.58915)
		(end 21.971 -65.71615)
		(width 0.381)
		(layer "F.Cu")
		(net "P3V3_AUX")
	)
	(segment
		(start 38.3032 -84.8614)
		(end 37.7444 -85.4202)
		(width 0.381)
		(layer "F.Cu")
		(net "P3V3_AUX")
	)
	(segment
		(start 36.390326 -38.215824)
		(end 37.110162 -38.93566)
		(width 0.381)
		(layer "F.Cu")
		(net "P3V3_AUX")
	)
	(segment
		(start 30.232604 -68.104004)
		(end 30.41904 -68.104004)
		(width 0.254)
		(layer "F.Cu")
		(net "P3V3_AUX")
	)
	(segment
		(start 32.70504 -68.104004)
		(end 32.70504 -67.494404)
		(width 0.254)
		(layer "F.Cu")
		(net "P3V3_AUX")
	)
	(segment
		(start 11.91895 -84.328)
		(end 11.2268 -84.328)
		(width 0.381)
		(layer "F.Cu")
		(net "P3V3_AUX")
	)
	(segment
		(start 16.827754 -43.825414)
		(end 16.826992 -43.824652)
		(width 0.381)
		(layer "F.Cu")
		(net "P3V3_AUX")
	)
	(segment
		(start 86.106 -17.78)
		(end 86.3346 -17.5514)
		(width 0.381)
		(layer "F.Cu")
		(net "P3V3_AUX")
	)
	(segment
		(start 48.83785 -79.0194)
		(end 48.83785 -78.355698)
		(width 0.4572)
		(layer "F.Cu")
		(net "P3V3_AUX")
	)
	(segment
		(start 58.70575 -66.3448)
		(end 59.0042 -66.3448)
		(width 0.381)
		(layer "F.Cu")
		(net "P3V3_AUX")
	)
	(segment
		(start 16.799306 -106.988356)
		(end 16.8275 -107.01655)
		(width 0.381)
		(layer "F.Cu")
		(net "P3V3_AUX")
	)
	(segment
		(start 30.607 -10.68705)
		(end 30.226 -11.06805)
		(width 0.4572)
		(layer "F.Cu")
		(net "P3V3_AUX")
	)
	(segment
		(start 39.482014 -73.401936)
		(end 39.37 -73.51395)
		(width 0.4572)
		(layer "F.Cu")
		(net "P3V3_AUX")
	)
	(segment
		(start 73.365868 -93.0148)
		(end 73.091294 -93.0148)
		(width 0.381)
		(layer "F.Cu")
		(net "P3V3_AUX")
	)
	(segment
		(start 48.0949 -48.9712)
		(end 48.0949 -49.7713)
		(width 0.381)
		(layer "F.Cu")
		(net "P3V3_AUX")
	)
	(segment
		(start 56.40197 -97.7646)
		(end 56.78297 -97.3836)
		(width 0.381)
		(layer "F.Cu")
		(net "P3V3_AUX")
	)
	(segment
		(start 77.092048 -92.85605)
		(end 76.66863 -92.85605)
		(width 0.381)
		(layer "F.Cu")
		(net "P3V3_AUX")
	)
	(segment
		(start 86.2838 -74.422)
		(end 85.804756 -74.422)
		(width 0.381)
		(layer "F.Cu")
		(net "P3V3_AUX")
	)
	(segment
		(start 50.4444 -108.806488)
		(end 50.64887 -109.010958)
		(width 0.381)
		(layer "F.Cu")
		(net "P3V3_AUX")
	)
	(segment
		(start 50.462688 -80.81645)
		(end 51.307238 -81.661)
		(width 0.4572)
		(layer "F.Cu")
		(net "P3V3_AUX")
	)
	(segment
		(start 48.6156 -30.467554)
		(end 49.80051 -30.467554)
		(width 0.4572)
		(layer "F.Cu")
		(net "P3V3_AUX")
	)
	(segment
		(start 60.549028 -30.467554)
		(end 60.230258 -30.148784)
		(width 0.381)
		(layer "F.Cu")
		(net "P3V3_AUX")
	)
	(segment
		(start 23.749 -65.76695)
		(end 23.241 -65.76695)
		(width 0.4572)
		(layer "F.Cu")
		(net "P3V3_AUX")
	)
	(segment
		(start 12.71905 -92.456)
		(end 12.71905 -91.44)
		(width 0.4572)
		(layer "F.Cu")
		(net "P3V3_AUX")
	)
	(segment
		(start 49.91735 -68.2498)
		(end 49.91735 -68.709032)
		(width 0.381)
		(layer "F.Cu")
		(net "P3V3_AUX")
	)
	(segment
		(start 26.289 -68.228464)
		(end 26.0604 -67.999864)
		(width 0.381)
		(layer "F.Cu")
		(net "P3V3_AUX")
	)
	(segment
		(start 30.9372 -36.2966)
		(end 32.5374 -34.6964)
		(width 0.4572)
		(layer "F.Cu")
		(net "P3V3_AUX")
	)
	(segment
		(start 12.319 -28.589986)
		(end 12.319 -28.702)
		(width 0.4572)
		(layer "F.Cu")
		(net "P3V3_AUX")
	)
	(segment
		(start 23.594314 -29.5148)
		(end 24.311864 -30.23235)
		(width 0.4572)
		(layer "F.Cu")
		(net "P3V3_AUX")
	)
	(segment
		(start 75.946 -76.2)
		(end 75.946 -74.82205)
		(width 0.4572)
		(layer "F.Cu")
		(net "P3V3_AUX")
	)
	(segment
		(start 7.53745 -80.137)
		(end 7.7978 -80.137)
		(width 0.381)
		(layer "F.Cu")
		(net "P3V3_AUX")
	)
	(segment
		(start 41.0083 -110.197646)
		(end 40.557704 -110.648242)
		(width 0.381)
		(layer "F.Cu")
		(net "P3V3_AUX")
	)
	(segment
		(start 51.30038 -78.6892)
		(end 51.615594 -79.004414)
		(width 0.4572)
		(layer "F.Cu")
		(net "P3V3_AUX")
	)
	(segment
		(start 19.41195 -65.8368)
		(end 19.100546 -65.8368)
		(width 0.4572)
		(layer "F.Cu")
		(net "P3V3_AUX")
	)
	(segment
		(start 16.827754 -45.167296)
		(end 16.827754 -43.825414)
		(width 0.381)
		(layer "F.Cu")
		(net "P3V3_AUX")
	)
	(segment
		(start 55.28945 -83.28025)
		(end 56.0324 -83.28025)
		(width 0.4572)
		(layer "F.Cu")
		(net "P3V3_AUX")
	)
	(segment
		(start 35.503104 -88.417654)
		(end 35.503104 -88.111584)
		(width 0.381)
		(layer "F.Cu")
		(net "P3V3_AUX")
	)
	(segment
		(start 36.53409 -47.96409)
		(end 36.905184 -47.96409)
		(width 0.4572)
		(layer "F.Cu")
		(net "P3V3_AUX")
	)
	(segment
		(start 31.983172 -85.089492)
		(end 31.98114 -85.091524)
		(width 0.381)
		(layer "F.Cu")
		(net "P3V3_AUX")
	)
	(segment
		(start 36.855908 -50.717196)
		(end 37.360352 -50.212752)
		(width 0.4572)
		(layer "F.Cu")
		(net "P3V3_AUX")
	)
	(segment
		(start 26.0604 -67.999864)
		(end 26.0604 -67.818)
		(width 0.381)
		(layer "F.Cu")
		(net "P3V3_AUX")
	)
	(segment
		(start 43.504104 -108.399834)
		(end 43.504104 -108.766864)
		(width 0.381)
		(layer "F.Cu")
		(net "P3V3_AUX")
	)
	(segment
		(start 39.03853 -84.217002)
		(end 38.394132 -84.8614)
		(width 0.381)
		(layer "F.Cu")
		(net "P3V3_AUX")
	)
	(segment
		(start 28.6512 -64.053466)
		(end 28.6512 -63.38316)
		(width 0.381)
		(layer "F.Cu")
		(net "P3V3_AUX")
	)
	(segment
		(start 10.4648 -108.9914)
		(end 10.4648 -108.45165)
		(width 0.4572)
		(layer "F.Cu")
		(net "P3V3_AUX")
	)
	(segment
		(start 54.473856 -30.467554)
		(end 53.388006 -30.467554)
		(width 0.381)
		(layer "F.Cu")
		(net "P3V3_AUX")
	)
	(segment
		(start 33.909 -35.79495)
		(end 33.738312 -35.624262)
		(width 0.4572)
		(layer "F.Cu")
		(net "P3V3_AUX")
	)
	(segment
		(start 60.230258 -30.148784)
		(end 60.230258 -29.609542)
		(width 0.381)
		(layer "F.Cu")
		(net "P3V3_AUX")
	)
	(segment
		(start 74.4982 -91.061032)
		(end 74.676 -91.061032)
		(width 0.381)
		(layer "F.Cu")
		(net "P3V3_AUX")
	)
	(segment
		(start 33.782 -68.05295)
		(end 33.730946 -68.104004)
		(width 0.254)
		(layer "F.Cu")
		(net "P3V3_AUX")
	)
	(segment
		(start 31.983172 -84.217002)
		(end 31.983172 -85.089492)
		(width 0.381)
		(layer "F.Cu")
		(net "P3V3_AUX")
	)
	(segment
		(start 50.64887 -109.010958)
		(end 51.650392 -109.010958)
		(width 0.381)
		(layer "F.Cu")
		(net "P3V3_AUX")
	)
	(segment
		(start 29.1592 -65.46215)
		(end 28.2956 -65.46215)
		(width 0.381)
		(layer "F.Cu")
		(net "P3V3_AUX")
	)
	(segment
		(start 17.678146 -65.427352)
		(end 17.672812 -65.427352)
		(width 0.4572)
		(layer "F.Cu")
		(net "P3V3_AUX")
	)
	(segment
		(start 24.311864 -30.23235)
		(end 24.3332 -30.23235)
		(width 0.4572)
		(layer "F.Cu")
		(net "P3V3_AUX")
	)
	(segment
		(start 40.226996 -79.64424)
		(end 40.226996 -78.664054)
		(width 0.381)
		(layer "F.Cu")
		(net "P3V3_AUX")
	)
	(segment
		(start 22.84095 -65.3669)
		(end 23.0632 -65.58915)
		(width 0.4572)
		(layer "F.Cu")
		(net "P3V3_AUX")
	)
	(segment
		(start 56.5912 -97.15627)
		(end 56.78297 -97.34804)
		(width 0.381)
		(layer "F.Cu")
		(net "P3V3_AUX")
	)
	(segment
		(start 31.56204 -70.136004)
		(end 31.56204 -69.73824)
		(width 0.381)
		(layer "F.Cu")
		(net "P3V3_AUX")
	)
	(segment
		(start 37.53993 -42.43578)
		(end 36.162234 -42.43578)
		(width 0.4572)
		(layer "F.Cu")
		(net "P3V3_AUX")
	)
	(segment
		(start 13.17625 -65.67805)
		(end 13.17625 -66.2432)
		(width 0.381)
		(layer "F.Cu")
		(net "P3V3_AUX")
	)
	(segment
		(start 48.91405 -78.9432)
		(end 49.783746 -78.9432)
		(width 0.4572)
		(layer "F.Cu")
		(net "P3V3_AUX")
	)
	(segment
		(start 56.5658 -86.4108)
		(end 57.370218 -87.215218)
		(width 0.4572)
		(layer "F.Cu")
		(net "P3V3_AUX")
	)
	(segment
		(start 59.08421 -92.85605)
		(end 60.591954 -92.85605)
		(width 0.381)
		(layer "F.Cu")
		(net "P3V3_AUX")
	)
	(segment
		(start 38.394132 -84.8614)
		(end 38.3032 -84.8614)
		(width 0.381)
		(layer "F.Cu")
		(net "P3V3_AUX")
	)
	(segment
		(start 44.30395 -109.56671)
		(end 43.82262 -109.08538)
		(width 0.381)
		(layer "F.Cu")
		(net "P3V3_AUX")
	)
	(segment
		(start 48.0949 -51.371246)
		(end 48.0949 -51.361594)
		(width 0.3556)
		(layer "F.Cu")
		(net "P3V3_AUX")
	)
	(segment
		(start 57.01665 -84.30895)
		(end 56.5658 -84.7598)
		(width 0.4572)
		(layer "F.Cu")
		(net "P3V3_AUX")
	)
	(segment
		(start 31.23565 -87.7062)
		(end 31.5976 -87.7062)
		(width 0.4572)
		(layer "F.Cu")
		(net "P3V3_AUX")
	)
	(segment
		(start 79.8449 -16.35125)
		(end 79.8449 -17.0053)
		(width 0.3556)
		(layer "F.Cu")
		(net "P3V3_AUX")
	)
	(segment
		(start 18.415 -65.63995)
		(end 17.890744 -65.63995)
		(width 0.4572)
		(layer "F.Cu")
		(net "P3V3_AUX")
	)
	(segment
		(start 23.47087 -34.304224)
		(end 23.47087 -34.85007)
		(width 0.4572)
		(layer "F.Cu")
		(net "P3V3_AUX")
	)
	(segment
		(start 8.2296 -81.661254)
		(end 8.2296 -82.042)
		(width 0.381)
		(layer "F.Cu")
		(net "P3V3_AUX")
	)
	(segment
		(start 35.031172 -84.217002)
		(end 36.047172 -84.217002)
		(width 0.381)
		(layer "F.Cu")
		(net "P3V3_AUX")
	)
	(segment
		(start 30.24505 -104.906318)
		(end 30.426914 -104.724454)
		(width 0.381)
		(layer "F.Cu")
		(net "P3V3_AUX")
	)
	(segment
		(start 24.257 -68.43395)
		(end 25.273 -68.43395)
		(width 0.381)
		(layer "F.Cu")
		(net "P3V3_AUX")
	)
	(segment
		(start 60.230258 -29.609542)
		(end 60.6806 -29.1592)
		(width 0.381)
		(layer "F.Cu")
		(net "P3V3_AUX")
	)
	(segment
		(start 15.86611 -9.906)
		(end 16.690086 -10.729976)
		(width 0.4572)
		(layer "F.Cu")
		(net "P3V3_AUX")
	)
	(segment
		(start 10.670794 -14.812518)
		(end 8.967216 -14.812518)
		(width 0.4572)
		(layer "F.Cu")
		(net "P3V3_AUX")
	)
	(segment
		(start 85.804756 -74.422)
		(end 85.572346 -74.18959)
		(width 0.381)
		(layer "F.Cu")
		(net "P3V3_AUX")
	)
	(segment
		(start 13.081 -65.5828)
		(end 13.17625 -65.67805)
		(width 0.381)
		(layer "F.Cu")
		(net "P3V3_AUX")
	)
	(segment
		(start 73.6981 -93.347032)
		(end 73.365868 -93.0148)
		(width 0.381)
		(layer "F.Cu")
		(net "P3V3_AUX")
	)
	(segment
		(start 56.5658 -84.7598)
		(end 56.5658 -86.4108)
		(width 0.4572)
		(layer "F.Cu")
		(net "P3V3_AUX")
	)
	(segment
		(start 40.0304 -109.87405)
		(end 41.0083 -109.87405)
		(width 0.381)
		(layer "F.Cu")
		(net "P3V3_AUX")
	)
	(segment
		(start 35.700716 -43.608752)
		(end 35.97275 -43.608752)
		(width 0.4572)
		(layer "F.Cu")
		(net "P3V3_AUX")
	)
	(segment
		(start 13.73505 -9.906)
		(end 13.662914 -9.833864)
		(width 0.4572)
		(layer "F.Cu")
		(net "P3V3_AUX")
	)
	(segment
		(start 56.5912 -96.3549)
		(end 56.5912 -97.15627)
		(width 0.381)
		(layer "F.Cu")
		(net "P3V3_AUX")
	)
	(segment
		(start 32.27705 -44.04995)
		(end 32.131 -44.196)
		(width 0.4572)
		(layer "F.Cu")
		(net "P3V3_AUX")
	)
	(segment
		(start 37.6174 -110.0836)
		(end 38.03015 -110.0836)
		(width 0.381)
		(layer "F.Cu")
		(net "P3V3_AUX")
	)
	(segment
		(start 70.358 -12.08405)
		(end 70.358 -13.12291)
		(width 0.4572)
		(layer "F.Cu")
		(net "P3V3_AUX")
	)
	(segment
		(start 24.218138 -65.217548)
		(end 24.178768 -65.256918)
		(width 0.254)
		(layer "F.Cu")
		(net "P3V3_AUX")
	)
	(segment
		(start 34.565082 -108.942632)
		(end 34.58845 -108.966)
		(width 0.381)
		(layer "F.Cu")
		(net "P3V3_AUX")
	)
	(segment
		(start 36.119308 -84.289138)
		(end 36.119308 -84.836)
		(width 0.381)
		(layer "F.Cu")
		(net "P3V3_AUX")
	)
	(segment
		(start 35.503104 -88.111584)
		(end 35.20186 -87.81034)
		(width 0.381)
		(layer "F.Cu")
		(net "P3V3_AUX")
	)
	(segment
		(start 53.388006 -30.017974)
		(end 53.68798 -29.718)
		(width 0.381)
		(layer "F.Cu")
		(net "P3V3_AUX")
	)
	(segment
		(start 17.890744 -65.63995)
		(end 17.678146 -65.427352)
		(width 0.4572)
		(layer "F.Cu")
		(net "P3V3_AUX")
	)
	(segment
		(start 13.111226 -77.653134)
		(end 13.49248 -77.27188)
		(width 0.381)
		(layer "F.Cu")
		(net "P3V3_AUX")
	)
	(segment
		(start 41.18864 -79.64424)
		(end 40.226996 -79.64424)
		(width 0.4572)
		(layer "F.Cu")
		(net "P3V3_AUX")
	)
	(segment
		(start 85.69325 -17.78)
		(end 86.106 -17.78)
		(width 0.381)
		(layer "F.Cu")
		(net "P3V3_AUX")
	)
	(segment
		(start 11.15695 -9.652)
		(end 11.15695 -10.14095)
		(width 0.4572)
		(layer "F.Cu")
		(net "P3V3_AUX")
	)
	(segment
		(start 75.819 -74.69505)
		(end 75.946 -74.82205)
		(width 0.4572)
		(layer "F.Cu")
		(net "P3V3_AUX")
	)
	(segment
		(start 11.3792 -29.6418)
		(end 6.5024 -29.6418)
		(width 0.4572)
		(layer "F.Cu")
		(net "P3V3_AUX")
	)
	(segment
		(start 83.77555 -70.858888)
		(end 83.099148 -70.858888)
		(width 0.381)
		(layer "F.Cu")
		(net "P3V3_AUX")
	)
	(segment
		(start 72.25665 -95.3516)
		(end 72.63765 -95.7326)
		(width 0.381)
		(layer "F.Cu")
		(net "P3V3_AUX")
	)
	(segment
		(start 23.241 -65.76695)
		(end 23.0632 -65.58915)
		(width 0.4572)
		(layer "F.Cu")
		(net "P3V3_AUX")
	)
	(segment
		(start 31.131256 -13.7922)
		(end 32.11195 -13.7922)
		(width 0.4572)
		(layer "F.Cu")
		(net "P3V3_AUX")
	)
	(segment
		(start 30.967172 -84.217002)
		(end 31.983172 -84.217002)
		(width 0.381)
		(layer "F.Cu")
		(net "P3V3_AUX")
	)
	(segment
		(start 57.370218 -87.215218)
		(end 57.370218 -87.638382)
		(width 0.4572)
		(layer "F.Cu")
		(net "P3V3_AUX")
	)
	(segment
		(start 14.979904 -9.246108)
		(end 14.979904 -9.432798)
		(width 0.4572)
		(layer "F.Cu")
		(net "P3V3_AUX")
	)
	(segment
		(start 12.02055 -101.0539)
		(end 11.30046 -101.0539)
		(width 0.4572)
		(layer "F.Cu")
		(net "P3V3_AUX")
	)
	(segment
		(start 36.325302 -92.760038)
		(end 36.325302 -91.919044)
		(width 0.4572)
		(layer "F.Cu")
		(net "P3V3_AUX")
	)
	(segment
		(start 33.281112 -34.6964)
		(end 33.738312 -35.1536)
		(width 0.4572)
		(layer "F.Cu")
		(net "P3V3_AUX")
	)
	(segment
		(start 76.66863 -92.85605)
		(end 76.016612 -92.204032)
		(width 0.381)
		(layer "F.Cu")
		(net "P3V3_AUX")
	)
	(segment
		(start 56.78551 -94.18955)
		(end 57.03951 -93.93555)
		(width 0.381)
		(layer "F.Cu")
		(net "P3V3_AUX")
	)
	(segment
		(start 49.7586 -30.074616)
		(end 49.7586 -30.425644)
		(width 0.381)
		(layer "F.Cu")
		(net "P3V3_AUX")
	)
	(segment
		(start 80.27035 -15.9258)
		(end 79.8449 -16.35125)
		(width 0.3556)
		(layer "F.Cu")
		(net "P3V3_AUX")
	)
	(segment
		(start 48.0949 -49.7713)
		(end 47.699676 -50.166524)
		(width 0.3556)
		(layer "F.Cu")
		(net "P3V3_AUX")
	)
	(segment
		(start 28.2194 -70.13575)
		(end 28.2194 -69.5198)
		(width 0.4572)
		(layer "F.Cu")
		(net "P3V3_AUX")
	)
	(segment
		(start 74.422 -14.492986)
		(end 76.292964 -14.492986)
		(width 0.381)
		(layer "F.Cu")
		(net "P3V3_AUX")
	)
	(segment
		(start 16.637 -45.35805)
		(end 16.827754 -45.167296)
		(width 0.381)
		(layer "F.Cu")
		(net "P3V3_AUX")
	)
	(segment
		(start 58.32475 -65.5828)
		(end 58.32475 -65.9638)
		(width 0.381)
		(layer "F.Cu")
		(net "P3V3_AUX")
	)
	(segment
		(start 58.14314 -91.91498)
		(end 59.08421 -92.85605)
		(width 0.381)
		(layer "F.Cu")
		(net "P3V3_AUX")
	)
	(segment
		(start 76.016612 -92.204032)
		(end 74.4982 -92.204032)
		(width 0.381)
		(layer "F.Cu")
		(net "P3V3_AUX")
	)
	(segment
		(start 41.0083 -109.87405)
		(end 41.0083 -110.197646)
		(width 0.381)
		(layer "F.Cu")
		(net "P3V3_AUX")
	)
	(segment
		(start 12.71905 -90.44305)
		(end 12.46505 -90.18905)
		(width 0.4572)
		(layer "F.Cu")
		(net "P3V3_AUX")
	)
	(segment
		(start 49.91735 -68.709032)
		(end 49.62398 -69.417438)
		(width 0.381)
		(layer "F.Cu")
		(net "P3V3_AUX")
	)
	(segment
		(start 61.068966 -80.428084)
		(end 61.087 -80.41005)
		(width 0.4572)
		(layer "F.Cu")
		(net "P3V3_AUX")
	)
	(segment
		(start 45.259244 -30.102556)
		(end 45.259244 -30.391354)
		(width 0.381)
		(layer "F.Cu")
		(net "P3V3_AUX")
	)
	(segment
		(start 17.119346 -65.6336)
		(end 17.474946 -65.278)
		(width 0.381)
		(layer "F.Cu")
		(net "P3V3_AUX")
	)
	(segment
		(start 18.415 -64.770254)
		(end 18.655538 -64.529716)
		(width 0.254)
		(layer "F.Cu")
		(net "P3V3_AUX")
	)
	(segment
		(start 37.14115 -110.0836)
		(end 37.6174 -110.0836)
		(width 0.381)
		(layer "F.Cu")
		(net "P3V3_AUX")
	)
	(segment
		(start 37.110162 -38.93566)
		(end 37.690298 -38.93566)
		(width 0.381)
		(layer "F.Cu")
		(net "P3V3_AUX")
	)
	(segment
		(start 24.218138 -63.65621)
		(end 24.218138 -65.217548)
		(width 0.254)
		(layer "F.Cu")
		(net "P3V3_AUX")
	)
	(segment
		(start 15.062962 -106.988356)
		(end 16.799306 -106.988356)
		(width 0.381)
		(layer "F.Cu")
		(net "P3V3_AUX")
	)
	(segment
		(start 79.8449 -17.0053)
		(end 80.096614 -17.257014)
		(width 0.3556)
		(layer "F.Cu")
		(net "P3V3_AUX")
	)
	(segment
		(start 51.650392 -109.010958)
		(end 51.6636 -108.99775)
		(width 0.381)
		(layer "F.Cu")
		(net "P3V3_AUX")
	)
	(segment
		(start 83.80095 -96.774)
		(end 83.80095 -96.95815)
		(width 0.4572)
		(layer "F.Cu")
		(net "P3V3_AUX")
	)
	(segment
		(start 29.1592 -65.46215)
		(end 29.234638 -65.46215)
		(width 0.381)
		(layer "F.Cu")
		(net "P3V3_AUX")
	)
	(segment
		(start 12.319 -28.702)
		(end 11.3792 -29.6418)
		(width 0.4572)
		(layer "F.Cu")
		(net "P3V3_AUX")
	)
	(segment
		(start 30.95625 -87.9856)
		(end 31.23565 -87.7062)
		(width 0.4572)
		(layer "F.Cu")
		(net "P3V3_AUX")
	)
	(segment
		(start 48.83785 -78.355698)
		(end 48.881792 -78.311756)
		(width 0.4572)
		(layer "F.Cu")
		(net "P3V3_AUX")
	)
	(segment
		(start 13.662914 -9.833864)
		(end 13.662914 -9.779)
		(width 0.4572)
		(layer "F.Cu")
		(net "P3V3_AUX")
	)
	(segment
		(start 47.04715 -75.55865)
		(end 47.656242 -75.55865)
		(width 0.4572)
		(layer "F.Cu")
		(net "P3V3_AUX")
	)
	(segment
		(start 28.1432 -64.84112)
		(end 28.2956 -64.68872)
		(width 0.381)
		(layer "F.Cu")
		(net "P3V3_AUX")
	)
	(segment
		(start 48.27905 -68.80225)
		(end 48.27905 -67.818)
		(width 0.381)
		(layer "F.Cu")
		(net "P3V3_AUX")
	)
	(segment
		(start 51.61915 -30.46095)
		(end 51.816 -30.46095)
		(width 0.3048)
		(layer "F.Cu")
		(net "P3V3_AUX")
	)
	(segment
		(start 50.041048 -75.32751)
		(end 48.77816 -75.32751)
		(width 0.4572)
		(layer "F.Cu")
		(net "P3V3_AUX")
	)
	(segment
		(start 45.593 -29.7688)
		(end 45.259244 -30.102556)
		(width 0.381)
		(layer "F.Cu")
		(net "P3V3_AUX")
	)
	(segment
		(start 57.44845 -87.56015)
		(end 57.370218 -87.638382)
		(width 0.4572)
		(layer "F.Cu")
		(net "P3V3_AUX")
	)
	(segment
		(start 73.66 -16.65605)
		(end 73.66 -17.26565)
		(width 0.381)
		(layer "F.Cu")
		(net "P3V3_AUX")
	)
	(segment
		(start 29.406596 -68.104004)
		(end 29.8196 -67.691)
		(width 0.254)
		(layer "F.Cu")
		(net "P3V3_AUX")
	)
	(segment
		(start 23.47087 -34.304224)
		(end 22.671024 -34.304224)
		(width 0.4572)
		(layer "F.Cu")
		(net "P3V3_AUX")
	)
	(segment
		(start 37.281358 -47.587916)
		(end 36.905184 -47.96409)
		(width 0.4572)
		(layer "F.Cu")
		(net "P3V3_AUX")
	)
	(segment
		(start 36.047172 -84.217002)
		(end 36.119308 -84.289138)
		(width 0.381)
		(layer "F.Cu")
		(net "P3V3_AUX")
	)
	(segment
		(start 32.766 -44.04995)
		(end 32.27705 -44.04995)
		(width 0.4572)
		(layer "F.Cu")
		(net "P3V3_AUX")
	)
	(segment
		(start 12.71905 -91.44)
		(end 13.4366 -91.44)
		(width 0.4572)
		(layer "F.Cu")
		(net "P3V3_AUX")
	)
	(segment
		(start 37.465254 -47.587916)
		(end 37.281358 -47.587916)
		(width 0.4572)
		(layer "F.Cu")
		(net "P3V3_AUX")
	)
	(segment
		(start 36.57092 -50.717196)
		(end 36.855908 -50.717196)
		(width 0.4572)
		(layer "F.Cu")
		(net "P3V3_AUX")
	)
	(segment
		(start 53.6702 -81.661)
		(end 55.28945 -83.28025)
		(width 0.4572)
		(layer "F.Cu")
		(net "P3V3_AUX")
	)
	(segment
		(start 49.699418 -69.342)
		(end 49.62398 -69.417438)
		(width 0.4572)
		(layer "F.Cu")
		(net "P3V3_AUX")
	)
	(segment
		(start 37.5666 -89.32545)
		(end 36.574222 -89.32545)
		(width 0.4572)
		(layer "F.Cu")
		(net "P3V3_AUX")
	)
	(segment
		(start 35.5346 -108.94695)
		(end 34.6075 -108.94695)
		(width 0.381)
		(layer "F.Cu")
		(net "P3V3_AUX")
	)
	(segment
		(start 30.633924 -61.6712)
		(end 31.210504 -61.6712)
		(width 0.4572)
		(layer "F.Cu")
		(net "P3V3_AUX")
	)
	(segment
		(start 30.892496 -14.03096)
		(end 31.131256 -13.7922)
		(width 0.4572)
		(layer "F.Cu")
		(net "P3V3_AUX")
	)
	(segment
		(start 18.4912 -46.70425)
		(end 19.1262 -46.70425)
		(width 0.4572)
		(layer "F.Cu")
		(net "P3V3_AUX")
	)
	(segment
		(start 46.46295 -24.384)
		(end 46.46295 -24.593296)
		(width 0.4572)
		(layer "F.Cu")
		(net "P3V3_AUX")
	)
	(segment
		(start 16.0782 -65.46215)
		(end 16.24965 -65.6336)
		(width 0.381)
		(layer "F.Cu")
		(net "P3V3_AUX")
	)
	(segment
		(start 23.47087 -34.85007)
		(end 24.062182 -35.441382)
		(width 0.4572)
		(layer "F.Cu")
		(net "P3V3_AUX")
	)
	(segment
		(start 74.676 -91.061032)
		(end 75.057 -90.680032)
		(width 0.381)
		(layer "F.Cu")
		(net "P3V3_AUX")
	)
	(segment
		(start 10.4648 -108.45165)
		(end 10.3632 -108.35005)
		(width 0.4572)
		(layer "F.Cu")
		(net "P3V3_AUX")
	)
	(segment
		(start 43.848528 -30.467554)
		(end 42.828464 -30.467554)
		(width 0.381)
		(layer "F.Cu")
		(net "P3V3_AUX")
	)
	(segment
		(start 13.7922 -65.41643)
		(end 13.31976 -64.94399)
		(width 0.381)
		(layer "F.Cu")
		(net "P3V3_AUX")
	)
	(segment
		(start 80.096614 -17.257014)
		(end 80.66532 -17.257014)
		(width 0.3556)
		(layer "F.Cu")
		(net "P3V3_AUX")
	)
	(segment
		(start 24.7142 -66.26225)
		(end 24.7142 -66.852038)
		(width 0.4572)
		(layer "F.Cu")
		(net "P3V3_AUX")
	)
	(segment
		(start 36.1061 -47.5361)
		(end 36.53409 -47.96409)
		(width 0.4572)
		(layer "F.Cu")
		(net "P3V3_AUX")
	)
	(segment
		(start 38.349682 -49.7078)
		(end 39.17315 -49.7078)
		(width 0.4572)
		(layer "F.Cu")
		(net "P3V3_AUX")
	)
	(segment
		(start 37.68598 -44.53255)
		(end 37.60343 -44.45)
		(width 0.4572)
		(layer "F.Cu")
		(net "P3V3_AUX")
	)
	(segment
		(start 24.062182 -35.441382)
		(end 26.126948 -36.2966)
		(width 0.4572)
		(layer "F.Cu")
		(net "P3V3_AUX")
	)
	(segment
		(start 14.506702 -9.906)
		(end 13.73505 -9.906)
		(width 0.4572)
		(layer "F.Cu")
		(net "P3V3_AUX")
	)
	(segment
		(start 76.327 -76.581)
		(end 75.946 -76.2)
		(width 0.4572)
		(layer "F.Cu")
		(net "P3V3_AUX")
	)
	(segment
		(start 16.8275 -107.01655)
		(end 16.8275 -107.5817)
		(width 0.4572)
		(layer "F.Cu")
		(net "P3V3_AUX")
	)
	(segment
		(start 45.183044 -30.467554)
		(end 45.259244 -30.391354)
		(width 0.381)
		(layer "F.Cu")
		(net "P3V3_AUX")
	)
	(segment
		(start 68.4276 -75.5396)
		(end 68.3006 -75.6666)
		(width 0.381)
		(layer "F.Cu")
		(net "P3V3_AUX")
	)
	(segment
		(start 10.670794 -14.812518)
		(end 10.670794 -14.49959)
		(width 0.4572)
		(layer "F.Cu")
		(net "P3V3_AUX")
	)
	(segment
		(start 45.16755 -69.2912)
		(end 44.31665 -69.2912)
		(width 0.4572)
		(layer "F.Cu")
		(net "P3V3_AUX")
	)
	(segment
		(start 40.9702 -89.08415)
		(end 40.9702 -90.0684)
		(width 0.4572)
		(layer "F.Cu")
		(net "P3V3_AUX")
	)
	(segment
		(start 57.03951 -93.93555)
		(end 57.056528 -93.93555)
		(width 0.381)
		(layer "F.Cu")
		(net "P3V3_AUX")
	)
	(segment
		(start 12.9286 -72.5424)
		(end 12.9286 -68.690236)
		(width 0.381)
		(layer "F.Cu")
		(net "P3V3_AUX")
	)
	(segment
		(start 16.8275 -107.5817)
		(end 17.2974 -108.0516)
		(width 0.4572)
		(layer "F.Cu")
		(net "P3V3_AUX")
	)
	(segment
		(start 36.574222 -89.32545)
		(end 36.56203 -89.337642)
		(width 0.4572)
		(layer "F.Cu")
		(net "P3V3_AUX")
	)
	(segment
		(start 38.735 -73.51395)
		(end 39.37 -73.51395)
		(width 0.3556)
		(layer "F.Cu")
		(net "P3V3_AUX")
	)
	(segment
		(start 32.11195 -14.478)
		(end 32.11195 -13.7922)
		(width 0.4572)
		(layer "F.Cu")
		(net "P3V3_AUX")
	)
	(segment
		(start 18.415 -65.63995)
		(end 18.415 -65.62344)
		(width 0.4572)
		(layer "F.Cu")
		(net "P3V3_AUX")
	)
	(segment
		(start 24.7142 -66.852038)
		(end 24.682958 -66.88328)
		(width 0.4572)
		(layer "F.Cu")
		(net "P3V3_AUX")
	)
	(segment
		(start 13.7922 -67.826636)
		(end 13.7922 -65.41643)
		(width 0.381)
		(layer "F.Cu")
		(net "P3V3_AUX")
	)
	(segment
		(start 48.4886 -69.0118)
		(end 48.27905 -68.80225)
		(width 0.381)
		(layer "F.Cu")
		(net "P3V3_AUX")
	)
	(segment
		(start 13.49248 -77.27188)
		(end 13.49248 -73.10628)
		(width 0.381)
		(layer "F.Cu")
		(net "P3V3_AUX")
	)
	(segment
		(start 19.100546 -65.8368)
		(end 18.903696 -65.63995)
		(width 0.4572)
		(layer "F.Cu")
		(net "P3V3_AUX")
	)
	(segment
		(start 72.63765 -95.7326)
		(end 73.025 -95.7326)
		(width 0.381)
		(layer "F.Cu")
		(net "P3V3_AUX")
	)
	(segment
		(start 49.046384 -29.3624)
		(end 49.7586 -30.074616)
		(width 0.381)
		(layer "F.Cu")
		(net "P3V3_AUX")
	)
	(segment
		(start 58.039 -87.56015)
		(end 57.44845 -87.56015)
		(width 0.4572)
		(layer "F.Cu")
		(net "P3V3_AUX")
	)
	(segment
		(start 39.52875 -43.434)
		(end 38.91534 -43.434)
		(width 0.4572)
		(layer "F.Cu")
		(net "P3V3_AUX")
	)
	(segment
		(start 29.234638 -65.46215)
		(end 28.6512 -64.053466)
		(width 0.381)
		(layer "F.Cu")
		(net "P3V3_AUX")
	)
	(segment
		(start 49.7586 -30.425644)
		(end 49.80051 -30.467554)
		(width 0.381)
		(layer "F.Cu")
		(net "P3V3_AUX")
	)
	(segment
		(start 42.932604 -87.279734)
		(end 42.813478 -87.160608)
		(width 0.381)
		(layer "F.Cu")
		(net "P3V3_AUX")
	)
	(segment
		(start 43.848528 -30.467554)
		(end 45.183044 -30.467554)
		(width 0.381)
		(layer "F.Cu")
		(net "P3V3_AUX")
	)
	(segment
		(start 46.46295 -24.593296)
		(end 46.9392 -25.069546)
		(width 0.4572)
		(layer "F.Cu")
		(net "P3V3_AUX")
	)
	(segment
		(start 50.78476 -29.845)
		(end 51.0032 -29.845)
		(width 0.3048)
		(layer "F.Cu")
		(net "P3V3_AUX")
	)
	(segment
		(start 26.289 -68.43395)
		(end 25.273 -68.43395)
		(width 0.381)
		(layer "F.Cu")
		(net "P3V3_AUX")
	)
	(segment
		(start 34.565082 -107.716828)
		(end 34.565082 -108.942632)
		(width 0.381)
		(layer "F.Cu")
		(net "P3V3_AUX")
	)
	(segment
		(start 32.95904 -43.85691)
		(end 32.766 -44.04995)
		(width 0.4572)
		(layer "F.Cu")
		(net "P3V3_AUX")
	)
	(segment
		(start 10.670794 -14.49959)
		(end 10.90168 -14.268704)
		(width 0.4572)
		(layer "F.Cu")
		(net "P3V3_AUX")
	)
	(segment
		(start 32.95904 -41.55821)
		(end 32.95904 -43.85691)
		(width 0.4572)
		(layer "F.Cu")
		(net "P3V3_AUX")
	)
	(segment
		(start 37.360352 -50.212752)
		(end 37.84473 -50.212752)
		(width 0.4572)
		(layer "F.Cu")
		(net "P3V3_AUX")
	)
	(segment
		(start 39.095172 -84.217002)
		(end 39.03853 -84.217002)
		(width 0.381)
		(layer "F.Cu")
		(net "P3V3_AUX")
	)
	(segment
		(start 68.961 -12.079986)
		(end 70.353936 -12.079986)
		(width 0.4572)
		(layer "F.Cu")
		(net "P3V3_AUX")
	)
	(segment
		(start 8.2296 -82.042)
		(end 8.7376 -82.55)
		(width 0.381)
		(layer "F.Cu")
		(net "P3V3_AUX")
	)
	(segment
		(start 70.353936 -12.079986)
		(end 70.358 -12.08405)
		(width 0.4572)
		(layer "F.Cu")
		(net "P3V3_AUX")
	)
	(segment
		(start 75.057 -90.680032)
		(end 75.057 -90.14968)
		(width 0.381)
		(layer "F.Cu")
		(net "P3V3_AUX")
	)
	(segment
		(start 61.068966 -80.392016)
		(end 61.087 -80.41005)
		(width 0.4572)
		(layer "F.Cu")
		(net "P3V3_AUX")
	)
	(segment
		(start 37.84473 -50.212752)
		(end 38.349682 -49.7078)
		(width 0.4572)
		(layer "F.Cu")
		(net "P3V3_AUX")
	)
	(segment
		(start 11.33475 -98.4758)
		(end 11.91895 -98.4758)
		(width 0.381)
		(layer "F.Cu")
		(net "P3V3_AUX")
	)
	(segment
		(start 58.32475 -65.9638)
		(end 58.70575 -66.3448)
		(width 0.381)
		(layer "F.Cu")
		(net "P3V3_AUX")
	)
	(segment
		(start 50.4444 -108.3564)
		(end 50.4444 -108.806488)
		(width 0.381)
		(layer "F.Cu")
		(net "P3V3_AUX")
	)
	(segment
		(start 56.78297 -97.3836)
		(end 56.78297 -97.34804)
		(width 0.381)
		(layer "F.Cu")
		(net "P3V3_AUX")
	)
	(segment
		(start 26.1874 -83.34375)
		(end 26.758646 -83.34375)
		(width 0.381)
		(layer "F.Cu")
		(net "P3V3_AUX")
	)
	(segment
		(start 30.028896 -14.03096)
		(end 30.892496 -14.03096)
		(width 0.4572)
		(layer "F.Cu")
		(net "P3V3_AUX")
	)
	(segment
		(start 36.957 -37.64915)
		(end 36.390326 -38.215824)
		(width 0.381)
		(layer "F.Cu")
		(net "P3V3_AUX")
	)
	(segment
		(start 39.50462 -30.23743)
		(end 39.50462 -29.62656)
		(width 0.4572)
		(layer "F.Cu")
		(net "P3V3_AUX")
	)
	(segment
		(start 57.3278 -92.075)
		(end 57.48782 -91.91498)
		(width 0.381)
		(layer "F.Cu")
		(net "P3V3_AUX")
	)
	(segment
		(start 21.971 -65.17005)
		(end 22.225 -64.91605)
		(width 0.381)
		(layer "F.Cu")
		(net "P3V3_AUX")
	)
	(segment
		(start 12.9286 -68.690236)
		(end 13.7922 -67.826636)
		(width 0.381)
		(layer "F.Cu")
		(net "P3V3_AUX")
	)
	(segment
		(start 68.3006 -75.6666)
		(end 67.6275 -75.6666)
		(width 0.381)
		(layer "F.Cu")
		(net "P3V3_AUX")
	)
	(segment
		(start 35.55365 -88.4682)
		(end 35.503104 -88.417654)
		(width 0.381)
		(layer "F.Cu")
		(net "P3V3_AUX")
	)
	(segment
		(start 50.373788 -80.72755)
		(end 50.462688 -80.81645)
		(width 0.4572)
		(layer "F.Cu")
		(net "P3V3_AUX")
	)
	(segment
		(start 23.495 -29.5148)
		(end 23.594314 -29.5148)
		(width 0.4572)
		(layer "F.Cu")
		(net "P3V3_AUX")
	)
	(segment
		(start 36.61918 -91.625166)
		(end 36.61918 -90.010234)
		(width 0.4572)
		(layer "F.Cu")
		(net "P3V3_AUX")
	)
	(segment
		(start 56.01081 -97.7646)
		(end 56.40197 -97.7646)
		(width 0.381)
		(layer "F.Cu")
		(net "P3V3_AUX")
	)
	(segment
		(start 29.27604 -68.104004)
		(end 29.406596 -68.104004)
		(width 0.254)
		(layer "F.Cu")
		(net "P3V3_AUX")
	)
	(segment
		(start 40.226996 -78.664054)
		(end 40.22725 -78.6638)
		(width 0.381)
		(layer "F.Cu")
		(net "P3V3_AUX")
	)
	(segment
		(start 43.504104 -108.766864)
		(end 43.82262 -109.08538)
		(width 0.381)
		(layer "F.Cu")
		(net "P3V3_AUX")
	)
	(segment
		(start 34.6075 -108.94695)
		(end 34.58845 -108.966)
		(width 0.381)
		(layer "F.Cu")
		(net "P3V3_AUX")
	)
	(segment
		(start 47.752 -80.72755)
		(end 50.373788 -80.72755)
		(width 0.4572)
		(layer "F.Cu")
		(net "P3V3_AUX")
	)
	(segment
		(start 53.695092 -44.971208)
		(end 53.299868 -44.575984)
		(width 0.3556)
		(layer "F.Cu")
		(net "P3V3_AUX")
	)
	(segment
		(start 51.41595 -69.342)
		(end 49.699418 -69.342)
		(width 0.4572)
		(layer "F.Cu")
		(net "P3V3_AUX")
	)
	(segment
		(start 20.701 -55.78475)
		(end 20.701 -55.174642)
		(width 0.4572)
		(layer "F.Cu")
		(net "P3V3_AUX")
	)
	(segment
		(start 30.226 -11.06805)
		(end 30.226 -11.3284)
		(width 0.4572)
		(layer "F.Cu")
		(net "P3V3_AUX")
	)
	(segment
		(start 48.25365 -74.803)
		(end 47.66945 -74.803)
		(width 0.4572)
		(layer "F.Cu")
		(net "P3V3_AUX")
	)
	(segment
		(start 19.882358 -54.356)
		(end 19.05 -54.356)
		(width 0.4572)
		(layer "F.Cu")
		(net "P3V3_AUX")
	)
	(segment
		(start 51.307238 -81.661)
		(end 53.6702 -81.661)
		(width 0.4572)
		(layer "F.Cu")
		(net "P3V3_AUX")
	)
	(segment
		(start 35.700716 -42.897298)
		(end 35.700716 -43.608752)
		(width 0.4572)
		(layer "F.Cu")
		(net "P3V3_AUX")
	)
	(segment
		(start 12.46505 -90.18905)
		(end 12.065 -90.18905)
		(width 0.4572)
		(layer "F.Cu")
		(net "P3V3_AUX")
	)
	(segment
		(start 83.80095 -96.95815)
		(end 84.201 -97.3582)
		(width 0.4572)
		(layer "F.Cu")
		(net "P3V3_AUX")
	)
	(segment
		(start 68.4276 -72.28205)
		(end 68.4276 -75.5396)
		(width 0.381)
		(layer "F.Cu")
		(net "P3V3_AUX")
	)
	(segment
		(start 18.655538 -64.529716)
		(end 18.655538 -63.68161)
		(width 0.254)
		(layer "F.Cu")
		(net "P3V3_AUX")
	)
	(segment
		(start 80.27035 -15.9258)
		(end 80.27035 -15.2908)
		(width 0.3556)
		(layer "F.Cu")
		(net "P3V3_AUX")
	)
	(segment
		(start 36.9189 -109.86135)
		(end 37.14115 -110.0836)
		(width 0.381)
		(layer "F.Cu")
		(net "P3V3_AUX")
	)
	(segment
		(start 72.25665 -95.271082)
		(end 72.25665 -95.3516)
		(width 0.381)
		(layer "F.Cu")
		(net "P3V3_AUX")
	)
	(segment
		(start 40.91305 -89.027)
		(end 40.9702 -89.08415)
		(width 0.4572)
		(layer "F.Cu")
		(net "P3V3_AUX")
	)
	(segment
		(start 42.672 -34.27095)
		(end 42.3418 -33.94075)
		(width 0.4572)
		(layer "F.Cu")
		(net "P3V3_AUX")
	)
	(segment
		(start 18.415 -65.62344)
		(end 18.415 -64.770254)
		(width 0.254)
		(layer "F.Cu")
		(net "P3V3_AUX")
	)
	(segment
		(start 77.851 -76.581)
		(end 76.327 -76.581)
		(width 0.4572)
		(layer "F.Cu")
		(net "P3V3_AUX")
	)
	(segment
		(start 7.18185 -80.4926)
		(end 7.18185 -80.613504)
		(width 0.381)
		(layer "F.Cu")
		(net "P3V3_AUX")
	)
	(segment
		(start 51.699668 -54.166516)
		(end 52.094892 -53.771292)
		(width 0.3556)
		(layer "F.Cu")
		(net "P3V3_AUX")
	)
	(segment
		(start 51.295046 -53.771292)
		(end 50.899822 -54.166516)
		(width 0.3556)
		(layer "F.Cu")
		(net "P3V3_AUX")
	)
	(segment
		(start 75.53198 -21.336)
		(end 76.21778 -21.336)
		(width 0.4572)
		(layer "F.Cu")
		(net "P3V3_AUX")
	)
	(segment
		(start 52.094892 -53.771292)
		(end 52.894992 -53.771292)
		(width 0.3556)
		(layer "F.Cu")
		(net "P3V3_AUX")
	)
	(segment
		(start 74.4982 -92.204032)
		(end 74.4982 -91.061032)
		(width 0.381)
		(layer "F.Cu")
		(net "P3V3_AUX")
	)
	(segment
		(start 36.46805 -44.104052)
		(end 36.46805 -44.5008)
		(width 0.4572)
		(layer "F.Cu")
		(net "P3V3_AUX")
	)
	(segment
		(start 31.56204 -69.73824)
		(end 31.7754 -69.52488)
		(width 0.381)
		(layer "F.Cu")
		(net "P3V3_AUX")
	)
	(segment
		(start 45.16755 -68.84035)
		(end 44.9326 -68.6054)
		(width 0.4572)
		(layer "F.Cu")
		(net "P3V3_AUX")
	)
	(segment
		(start 45.16755 -69.2912)
		(end 45.16755 -68.84035)
		(width 0.4572)
		(layer "F.Cu")
		(net "P3V3_AUX")
	)
	(segment
		(start 36.325302 -91.919044)
		(end 36.61918 -91.625166)
		(width 0.4572)
		(layer "F.Cu")
		(net "P3V3_AUX")
	)
	(segment
		(start 51.0032 -29.845)
		(end 51.61915 -30.46095)
		(width 0.3048)
		(layer "F.Cu")
		(net "P3V3_AUX")
	)
	(segment
		(start 22.225 -64.91605)
		(end 22.225 -63.306198)
		(width 0.381)
		(layer "F.Cu")
		(net "P3V3_AUX")
	)
	(segment
		(start 48.199548 -109.010958)
		(end 48.852836 -109.010958)
		(width 0.381)
		(layer "F.Cu")
		(net "P3V3_AUX")
	)
	(segment
		(start 36.957 -36.46805)
		(end 36.957 -37.64915)
		(width 0.381)
		(layer "F.Cu")
		(net "P3V3_AUX")
	)
	(segment
		(start 8.7376 -82.55)
		(end 9.07796 -82.55)
		(width 0.381)
		(layer "F.Cu")
		(net "P3V3_AUX")
	)
	(segment
		(start 28.2956 -65.46215)
		(end 28.1432 -65.30975)
		(width 0.381)
		(layer "F.Cu")
		(net "P3V3_AUX")
	)
	(segment
		(start 42.3418 -33.94075)
		(end 42.3418 -33.61944)
		(width 0.4572)
		(layer "F.Cu")
		(net "P3V3_AUX")
	)
	(segment
		(start 49.783746 -78.9432)
		(end 50.037746 -78.6892)
		(width 0.4572)
		(layer "F.Cu")
		(net "P3V3_AUX")
	)
	(segment
		(start 36.162234 -42.43578)
		(end 35.700716 -42.897298)
		(width 0.4572)
		(layer "F.Cu")
		(net "P3V3_AUX")
	)
	(segment
		(start 6.5024 -29.6418)
		(end 6.4008 -29.5402)
		(width 0.4572)
		(layer "F.Cu")
		(net "P3V3_AUX")
	)
	(segment
		(start 26.289 -68.43395)
		(end 26.289 -68.228464)
		(width 0.381)
		(layer "F.Cu")
		(net "P3V3_AUX")
	)
	(segment
		(start 20.701 -55.174642)
		(end 19.882358 -54.356)
		(width 0.4572)
		(layer "F.Cu")
		(net "P3V3_AUX")
	)
	(segment
		(start 50.037746 -78.6892)
		(end 51.30038 -78.6892)
		(width 0.4572)
		(layer "F.Cu")
		(net "P3V3_AUX")
	)
	(segment
		(start 57.48782 -91.91498)
		(end 58.14314 -91.91498)
		(width 0.381)
		(layer "F.Cu")
		(net "P3V3_AUX")
	)
	(segment
		(start 48.0949 -50.571146)
		(end 47.699676 -50.96637)
		(width 0.3556)
		(layer "F.Cu")
		(net "P3V3_AUX")
	)
	(segment
		(start 33.730946 -68.104004)
		(end 32.70504 -68.104004)
		(width 0.254)
		(layer "F.Cu")
		(net "P3V3_AUX")
	)
	(segment
		(start 12.30376 -64.94399)
		(end 13.31976 -64.94399)
		(width 0.381)
		(layer "F.Cu")
		(net "P3V3_AUX")
	)
	(segment
		(start 16.24965 -65.6336)
		(end 17.119346 -65.6336)
		(width 0.381)
		(layer "F.Cu")
		(net "P3V3_AUX")
	)
	(segment
		(start 16.637 -45.90415)
		(end 16.637 -45.35805)
		(width 0.381)
		(layer "F.Cu")
		(net "P3V3_AUX")
	)
	(segment
		(start 44.30395 -109.8804)
		(end 44.30395 -109.56671)
		(width 0.381)
		(layer "F.Cu")
		(net "P3V3_AUX")
	)
	(segment
		(start 16.0782 -63.306198)
		(end 16.0782 -65.46215)
		(width 0.381)
		(layer "F.Cu")
		(net "P3V3_AUX")
	)
	(segment
		(start 11.15695 -10.14095)
		(end 11.557 -10.541)
		(width 0.4572)
		(layer "F.Cu")
		(net "P3V3_AUX")
	)
	(segment
		(start 7.18185 -80.613504)
		(end 8.2296 -81.661254)
		(width 0.381)
		(layer "F.Cu")
		(net "P3V3_AUX")
	)
	(segment
		(start 26.126948 -36.2966)
		(end 30.9372 -36.2966)
		(width 0.4572)
		(layer "F.Cu")
		(net "P3V3_AUX")
	)
	(segment
		(start 14.979904 -9.432798)
		(end 14.506702 -9.906)
		(width 0.4572)
		(layer "F.Cu")
		(net "P3V3_AUX")
	)
	(segment
		(start 47.66945 -74.803)
		(end 47.66945 -75.545442)
		(width 0.4572)
		(layer "F.Cu")
		(net "P3V3_AUX")
	)
	(segment
		(start 18.903696 -65.63995)
		(end 18.415 -65.63995)
		(width 0.4572)
		(layer "F.Cu")
		(net "P3V3_AUX")
	)
	(segment
		(start 37.60343 -44.45)
		(end 36.51885 -44.45)
		(width 0.4572)
		(layer "F.Cu")
		(net "P3V3_AUX")
	)
	(segment
		(start 40.557704 -110.648242)
		(end 39.952676 -110.648242)
		(width 0.381)
		(layer "F.Cu")
		(net "P3V3_AUX")
	)
	(segment
		(start 28.1432 -65.30975)
		(end 28.1432 -64.84112)
		(width 0.381)
		(layer "F.Cu")
		(net "P3V3_AUX")
	)
	(segment
		(start 50.504598 -53.771292)
		(end 50.899822 -54.166516)
		(width 0.3556)
		(layer "F.Cu")
		(net "P3V3_AUX")
	)
	(segment
		(start 70.0278 -102.489)
		(end 69.36105 -101.82225)
		(width 0.381)
		(layer "F.Cu")
		(net "P3V3_AUX")
	)
	(segment
		(start 61.068966 -79.632556)
		(end 61.068966 -80.392016)
		(width 0.4572)
		(layer "F.Cu")
		(net "P3V3_AUX")
	)
	(segment
		(start 12.684252 -77.653134)
		(end 13.111226 -77.653134)
		(width 0.381)
		(layer "F.Cu")
		(net "P3V3_AUX")
	)
	(segment
		(start 38.91534 -43.434)
		(end 38.9128 -43.43146)
		(width 0.4572)
		(layer "F.Cu")
		(net "P3V3_AUX")
	)
	(segment
		(start 13.49248 -73.10628)
		(end 12.9286 -72.5424)
		(width 0.381)
		(layer "F.Cu")
		(net "P3V3_AUX")
	)
	(segment
		(start 29.8196 -67.691)
		(end 30.232604 -68.104004)
		(width 0.254)
		(layer "F.Cu")
		(net "P3V3_AUX")
	)
	(segment
		(start 83.80095 -90.428064)
		(end 83.80095 -91.059)
		(width 0.4572)
		(layer "F.Cu")
		(net "P3V3_AUX")
	)
	(via
		(at 38.735 -73.51395)
		(size 0.508)
		(drill 0.254)
		(layers "F.Cu" "B.Cu")
		(net "P3V3_AUX")
	)
	(via
		(at 51.699668 -54.166516)
		(size 0.508)
		(drill 0.254)
		(layers "F.Cu" "B.Cu")
		(net "P3V3_AUX")
	)
	(via
		(at 38.1 -105.3465)
		(size 0.508)
		(drill 0.254)
		(layers "F.Cu" "B.Cu")
		(net "P3V3_AUX")
	)
	(via
		(at 13.3604 -95.6564)
		(size 0.508)
		(drill 0.254)
		(layers "F.Cu" "B.Cu")
		(net "P3V3_AUX")
	)
	(via
		(at 61.14034 -25.29078)
		(size 0.508)
		(drill 0.254)
		(layers "F.Cu" "B.Cu")
		(net "P3V3_AUX")
	)
	(via
		(at 7.782052 -77.368908)
		(size 0.508)
		(drill 0.254)
		(layers "F.Cu" "B.Cu")
		(net "P3V3_AUX")
	)
	(via
		(at 49.62398 -69.417438)
		(size 0.508)
		(drill 0.254)
		(layers "F.Cu" "B.Cu")
		(net "P3V3_AUX")
	)
	(via
		(at 64.77 -21.0058)
		(size 0.508)
		(drill 0.254)
		(layers "F.Cu" "B.Cu")
		(net "P3V3_AUX")
	)
	(via
		(at 48.4886 -69.0118)
		(size 0.508)
		(drill 0.254)
		(layers "F.Cu" "B.Cu")
		(net "P3V3_AUX")
	)
	(via
		(at 60.6806 -29.1592)
		(size 0.508)
		(drill 0.254)
		(layers "F.Cu" "B.Cu")
		(net "P3V3_AUX")
	)
	(via
		(at 61.00064 -27.178)
		(size 0.508)
		(drill 0.254)
		(layers "F.Cu" "B.Cu")
		(net "P3V3_AUX")
	)
	(via
		(at 9.915906 -77.286612)
		(size 0.508)
		(drill 0.254)
		(layers "F.Cu" "B.Cu")
		(net "P3V3_AUX")
	)
	(via
		(at 49.046384 -29.3624)
		(size 0.508)
		(drill 0.254)
		(layers "F.Cu" "B.Cu")
		(net "P3V3_AUX")
	)
	(via
		(at 68.986908 -30.8356)
		(size 0.508)
		(drill 0.254)
		(layers "F.Cu" "B.Cu")
		(net "P3V3_AUX")
	)
	(via
		(at 37.9984 -104.267)
		(size 0.508)
		(drill 0.254)
		(layers "F.Cu" "B.Cu")
		(net "P3V3_AUX")
	)
	(via
		(at 20.955 -100.9904)
		(size 0.508)
		(drill 0.254)
		(layers "F.Cu" "B.Cu")
		(net "P3V3_AUX")
	)
	(via
		(at 55.245 -67.056)
		(size 0.508)
		(drill 0.254)
		(layers "F.Cu" "B.Cu")
		(net "P3V3_AUX")
	)
	(via
		(at 39.50462 -29.62656)
		(size 0.508)
		(drill 0.254)
		(layers "F.Cu" "B.Cu")
		(net "P3V3_AUX")
	)
	(via
		(at 36.4236 -30.9118)
		(size 0.508)
		(drill 0.254)
		(layers "F.Cu" "B.Cu")
		(net "P3V3_AUX")
	)
	(via
		(at 61.087 -80.41005)
		(size 0.508)
		(drill 0.254)
		(layers "F.Cu" "B.Cu")
		(net "P3V3_AUX")
	)
	(via
		(at 68.468494 -33.270698)
		(size 0.508)
		(drill 0.254)
		(layers "F.Cu" "B.Cu")
		(net "P3V3_AUX")
	)
	(via
		(at 80.27035 -15.2908)
		(size 0.508)
		(drill 0.254)
		(layers "F.Cu" "B.Cu")
		(net "P3V3_AUX")
	)
	(via
		(at 47.699676 -50.166524)
		(size 0.4572)
		(drill 0.254)
		(layers "F.Cu" "B.Cu")
		(net "P3V3_AUX")
	)
	(via
		(at 36.905184 -47.96409)
		(size 0.508)
		(drill 0.254)
		(layers "F.Cu" "B.Cu")
		(net "P3V3_AUX")
	)
	(via
		(at 59.572398 -18.958052)
		(size 0.508)
		(drill 0.254)
		(layers "F.Cu" "B.Cu")
		(net "P3V3_AUX")
	)
	(via
		(at 76.21778 -21.336)
		(size 0.508)
		(drill 0.254)
		(layers "F.Cu" "B.Cu")
		(net "P3V3_AUX")
	)
	(via
		(at 12.04976 -76.539344)
		(size 0.508)
		(drill 0.254)
		(layers "F.Cu" "B.Cu")
		(net "P3V3_AUX")
	)
	(via
		(at 86.336632 -28.602686)
		(size 0.508)
		(drill 0.254)
		(layers "F.Cu" "B.Cu")
		(net "P3V3_AUX")
	)
	(via
		(at 50.4444 -108.3564)
		(size 0.508)
		(drill 0.254)
		(layers "F.Cu" "B.Cu")
		(net "P3V3_AUX")
	)
	(via
		(at 58.5724 -23.2918)
		(size 0.508)
		(drill 0.254)
		(layers "F.Cu" "B.Cu")
		(net "P3V3_AUX")
	)
	(via
		(at 9.915906 -76.529946)
		(size 0.508)
		(drill 0.254)
		(layers "F.Cu" "B.Cu")
		(net "P3V3_AUX")
	)
	(via
		(at 86.2838 -74.422)
		(size 0.508)
		(drill 0.254)
		(layers "F.Cu" "B.Cu")
		(net "P3V3_AUX")
	)
	(via
		(at 42.3418 -33.61944)
		(size 0.508)
		(drill 0.254)
		(layers "F.Cu" "B.Cu")
		(net "P3V3_AUX")
	)
	(via
		(at 3.488944 -77.03312)
		(size 0.508)
		(drill 0.254)
		(layers "F.Cu" "B.Cu")
		(net "P3V3_AUX")
	)
	(via
		(at 52.499768 -44.575984)
		(size 0.4572)
		(drill 0.254)
		(layers "F.Cu" "B.Cu")
		(net "P3V3_AUX")
	)
	(via
		(at 11.557 -10.541)
		(size 0.508)
		(drill 0.254)
		(layers "F.Cu" "B.Cu")
		(net "P3V3_AUX")
	)
	(via
		(at 17.78 -71.12)
		(size 0.508)
		(drill 0.254)
		(layers "F.Cu" "B.Cu")
		(net "P3V3_AUX")
	)
	(via
		(at 48.199548 -109.010958)
		(size 0.508)
		(drill 0.254)
		(layers "F.Cu" "B.Cu")
		(net "P3V3_AUX")
	)
	(via
		(at 50.462688 -80.81645)
		(size 0.508)
		(drill 0.254)
		(layers "F.Cu" "B.Cu")
		(net "P3V3_AUX")
	)
	(via
		(at 47.699676 -50.96637)
		(size 0.4572)
		(drill 0.254)
		(layers "F.Cu" "B.Cu")
		(net "P3V3_AUX")
	)
	(via
		(at 31.210504 -61.6712)
		(size 0.508)
		(drill 0.254)
		(layers "F.Cu" "B.Cu")
		(net "P3V3_AUX")
	)
	(via
		(at 40.9448 -59.3344)
		(size 0.508)
		(drill 0.254)
		(layers "F.Cu" "B.Cu")
		(net "P3V3_AUX")
	)
	(via
		(at 57.370218 -87.638382)
		(size 0.508)
		(drill 0.254)
		(layers "F.Cu" "B.Cu")
		(net "P3V3_AUX")
	)
	(via
		(at 13.4366 -91.44)
		(size 0.508)
		(drill 0.254)
		(layers "F.Cu" "B.Cu")
		(net "P3V3_AUX")
	)
	(via
		(at 56.8452 -64.7192)
		(size 0.508)
		(drill 0.254)
		(layers "F.Cu" "B.Cu")
		(net "P3V3_AUX")
	)
	(via
		(at 19.12112 -19.228816)
		(size 0.508)
		(drill 0.254)
		(layers "F.Cu" "B.Cu")
		(net "P3V3_AUX")
	)
	(via
		(at 51.2826 -21.1582)
		(size 0.508)
		(drill 0.254)
		(layers "F.Cu" "B.Cu")
		(net "P3V3_AUX")
	)
	(via
		(at 86.336632 -27.582622)
		(size 0.508)
		(drill 0.254)
		(layers "F.Cu" "B.Cu")
		(net "P3V3_AUX")
	)
	(via
		(at 55.6387 -106.3879)
		(size 0.508)
		(drill 0.254)
		(layers "F.Cu" "B.Cu")
		(net "P3V3_AUX")
	)
	(via
		(at 32.131 -44.196)
		(size 0.508)
		(drill 0.254)
		(layers "F.Cu" "B.Cu")
		(net "P3V3_AUX")
	)
	(via
		(at 36.390326 -38.215824)
		(size 0.508)
		(drill 0.254)
		(layers "F.Cu" "B.Cu")
		(net "P3V3_AUX")
	)
	(via
		(at 13.081 -65.5828)
		(size 0.508)
		(drill 0.254)
		(layers "F.Cu" "B.Cu")
		(net "P3V3_AUX")
	)
	(via
		(at 46.21784 -25.21204)
		(size 0.508)
		(drill 0.254)
		(layers "F.Cu" "B.Cu")
		(net "P3V3_AUX")
	)
	(via
		(at 67.6275 -75.6666)
		(size 0.508)
		(drill 0.254)
		(layers "F.Cu" "B.Cu")
		(net "P3V3_AUX")
	)
	(via
		(at 18.034 -100.1776)
		(size 0.508)
		(drill 0.254)
		(layers "F.Cu" "B.Cu")
		(net "P3V3_AUX")
	)
	(via
		(at 24.9174 -104.7496)
		(size 0.508)
		(drill 0.254)
		(layers "F.Cu" "B.Cu")
		(net "P3V3_AUX")
	)
	(via
		(at 12.04976 -77.27315)
		(size 0.508)
		(drill 0.254)
		(layers "F.Cu" "B.Cu")
		(net "P3V3_AUX")
	)
	(via
		(at 3.488944 -76.172314)
		(size 0.508)
		(drill 0.254)
		(layers "F.Cu" "B.Cu")
		(net "P3V3_AUX")
	)
	(via
		(at 25.019 -16.891)
		(size 0.508)
		(drill 0.254)
		(layers "F.Cu" "B.Cu")
		(net "P3V3_AUX")
	)
	(via
		(at 22.987 -100.9904)
		(size 0.508)
		(drill 0.254)
		(layers "F.Cu" "B.Cu")
		(net "P3V3_AUX")
	)
	(via
		(at 4.4958 -108.6104)
		(size 0.508)
		(drill 0.254)
		(layers "F.Cu" "B.Cu")
		(net "P3V3_AUX")
	)
	(via
		(at 68.8594 -88.03005)
		(size 0.508)
		(drill 0.254)
		(layers "F.Cu" "B.Cu")
		(net "P3V3_AUX")
	)
	(via
		(at 6.4008 -29.5402)
		(size 0.508)
		(drill 0.254)
		(layers "F.Cu" "B.Cu")
		(net "P3V3_AUX")
	)
	(via
		(at 57.056528 -93.93555)
		(size 0.508)
		(drill 0.254)
		(layers "F.Cu" "B.Cu")
		(net "P3V3_AUX")
	)
	(via
		(at 37.6174 -110.0836)
		(size 0.508)
		(drill 0.254)
		(layers "F.Cu" "B.Cu")
		(net "P3V3_AUX")
	)
	(via
		(at 73.025 -95.7326)
		(size 0.508)
		(drill 0.254)
		(layers "F.Cu" "B.Cu")
		(net "P3V3_AUX")
	)
	(via
		(at 5.648198 -77.375004)
		(size 0.508)
		(drill 0.254)
		(layers "F.Cu" "B.Cu")
		(net "P3V3_AUX")
	)
	(via
		(at 37.672264 -91.207844)
		(size 0.508)
		(drill 0.254)
		(layers "F.Cu" "B.Cu")
		(net "P3V3_AUX")
	)
	(via
		(at 82.301842 -30.973522)
		(size 0.508)
		(drill 0.254)
		(layers "F.Cu" "B.Cu")
		(net "P3V3_AUX")
	)
	(via
		(at 34.37001 -71.072502)
		(size 0.508)
		(drill 0.254)
		(layers "F.Cu" "B.Cu")
		(net "P3V3_AUX")
	)
	(via
		(at 32.70504 -67.494404)
		(size 0.508)
		(drill 0.254)
		(layers "F.Cu" "B.Cu")
		(net "P3V3_AUX")
	)
	(via
		(at 72.621394 -68.554346)
		(size 0.508)
		(drill 0.254)
		(layers "F.Cu" "B.Cu")
		(net "P3V3_AUX")
	)
	(via
		(at 82.298794 -30.186122)
		(size 0.508)
		(drill 0.254)
		(layers "F.Cu" "B.Cu")
		(net "P3V3_AUX")
	)
	(via
		(at 28.2956 -64.68872)
		(size 0.508)
		(drill 0.254)
		(layers "F.Cu" "B.Cu")
		(net "P3V3_AUX")
	)
	(via
		(at 47.656242 -75.55865)
		(size 0.508)
		(drill 0.254)
		(layers "F.Cu" "B.Cu")
		(net "P3V3_AUX")
	)
	(via
		(at 13.572236 -27.066748)
		(size 0.508)
		(drill 0.254)
		(layers "F.Cu" "B.Cu")
		(net "P3V3_AUX")
	)
	(via
		(at 5.2324 -108.9406)
		(size 0.508)
		(drill 0.254)
		(layers "F.Cu" "B.Cu")
		(net "P3V3_AUX")
	)
	(via
		(at 17.52346 -65.278)
		(size 0.508)
		(drill 0.254)
		(layers "F.Cu" "B.Cu")
		(net "P3V3_AUX")
	)
	(via
		(at 84.201 -97.3582)
		(size 0.508)
		(drill 0.254)
		(layers "F.Cu" "B.Cu")
		(net "P3V3_AUX")
	)
	(via
		(at 80.2386 -31.9786)
		(size 0.508)
		(drill 0.254)
		(layers "F.Cu" "B.Cu")
		(net "P3V3_AUX")
	)
	(via
		(at 7.782052 -76.508102)
		(size 0.508)
		(drill 0.254)
		(layers "F.Cu" "B.Cu")
		(net "P3V3_AUX")
	)
	(via
		(at 78.462124 -92.109798)
		(size 0.508)
		(drill 0.254)
		(layers "F.Cu" "B.Cu")
		(net "P3V3_AUX")
	)
	(via
		(at 35.94608 -101.5238)
		(size 0.508)
		(drill 0.254)
		(layers "F.Cu" "B.Cu")
		(net "P3V3_AUX")
	)
	(via
		(at 75.057 -90.14968)
		(size 0.508)
		(drill 0.254)
		(layers "F.Cu" "B.Cu")
		(net "P3V3_AUX")
	)
	(via
		(at 22.671024 -34.304224)
		(size 0.508)
		(drill 0.254)
		(layers "F.Cu" "B.Cu")
		(net "P3V3_AUX")
	)
	(via
		(at 43.82262 -109.08538)
		(size 0.508)
		(drill 0.254)
		(layers "F.Cu" "B.Cu")
		(net "P3V3_AUX")
	)
	(via
		(at 71.599806 -68.554346)
		(size 0.508)
		(drill 0.254)
		(layers "F.Cu" "B.Cu")
		(net "P3V3_AUX")
	)
	(via
		(at 17.2974 -108.0516)
		(size 0.508)
		(drill 0.254)
		(layers "F.Cu" "B.Cu")
		(net "P3V3_AUX")
	)
	(via
		(at 5.648198 -76.514198)
		(size 0.508)
		(drill 0.254)
		(layers "F.Cu" "B.Cu")
		(net "P3V3_AUX")
	)
	(via
		(at 50.899822 -54.166516)
		(size 0.4572)
		(drill 0.254)
		(layers "F.Cu" "B.Cu")
		(net "P3V3_AUX")
	)
	(via
		(at 34.60242 -107.67949)
		(size 0.508)
		(drill 0.254)
		(layers "F.Cu" "B.Cu")
		(net "P3V3_AUX")
	)
	(via
		(at 11.30935 -98.5012)
		(size 0.508)
		(drill 0.254)
		(layers "F.Cu" "B.Cu")
		(net "P3V3_AUX")
	)
	(via
		(at 46.9392 -25.4762)
		(size 0.508)
		(drill 0.254)
		(layers "F.Cu" "B.Cu")
		(net "P3V3_AUX")
	)
	(via
		(at 82.301842 -29.373322)
		(size 0.508)
		(drill 0.254)
		(layers "F.Cu" "B.Cu")
		(net "P3V3_AUX")
	)
	(via
		(at 70.0278 -102.489)
		(size 0.508)
		(drill 0.254)
		(layers "F.Cu" "B.Cu")
		(net "P3V3_AUX")
	)
	(via
		(at 48.881792 -78.311756)
		(size 0.508)
		(drill 0.254)
		(layers "F.Cu" "B.Cu")
		(net "P3V3_AUX")
	)
	(via
		(at 31.7754 -69.52488)
		(size 0.508)
		(drill 0.254)
		(layers "F.Cu" "B.Cu")
		(net "P3V3_AUX")
	)
	(via
		(at 86.3346 -17.5514)
		(size 0.508)
		(drill 0.254)
		(layers "F.Cu" "B.Cu")
		(net "P3V3_AUX")
	)
	(via
		(at 10.4648 -108.9914)
		(size 0.508)
		(drill 0.254)
		(layers "F.Cu" "B.Cu")
		(net "P3V3_AUX")
	)
	(via
		(at 53.68798 -29.718)
		(size 0.508)
		(drill 0.254)
		(layers "F.Cu" "B.Cu")
		(net "P3V3_AUX")
	)
	(via
		(at 45.8724 -91.4908)
		(size 0.508)
		(drill 0.254)
		(layers "F.Cu" "B.Cu")
		(net "P3V3_AUX")
	)
	(via
		(at 18.4658 -76.5048)
		(size 0.508)
		(drill 0.254)
		(layers "F.Cu" "B.Cu")
		(net "P3V3_AUX")
	)
	(via
		(at 35.20186 -87.81034)
		(size 0.508)
		(drill 0.254)
		(layers "F.Cu" "B.Cu")
		(net "P3V3_AUX")
	)
	(via
		(at 23.0632 -65.58915)
		(size 0.508)
		(drill 0.254)
		(layers "F.Cu" "B.Cu")
		(net "P3V3_AUX")
	)
	(via
		(at 14.979904 -9.246108)
		(size 0.508)
		(drill 0.254)
		(layers "F.Cu" "B.Cu")
		(net "P3V3_AUX")
	)
	(via
		(at 41.18864 -79.64424)
		(size 0.508)
		(drill 0.254)
		(layers "F.Cu" "B.Cu")
		(net "P3V3_AUX")
	)
	(via
		(at 67.39128 -99.64166)
		(size 0.508)
		(drill 0.254)
		(layers "F.Cu" "B.Cu")
		(net "P3V3_AUX")
	)
	(via
		(at 14.3764 -81.407)
		(size 0.508)
		(drill 0.254)
		(layers "F.Cu" "B.Cu")
		(net "P3V3_AUX")
	)
	(via
		(at 69.723 -14.732)
		(size 0.508)
		(drill 0.254)
		(layers "F.Cu" "B.Cu")
		(net "P3V3_AUX")
	)
	(via
		(at 35.700716 -42.897298)
		(size 0.508)
		(drill 0.254)
		(layers "F.Cu" "B.Cu")
		(net "P3V3_AUX")
	)
	(via
		(at 62.5348 -18.9484)
		(size 0.508)
		(drill 0.254)
		(layers "F.Cu" "B.Cu")
		(net "P3V3_AUX")
	)
	(via
		(at 29.8196 -67.691)
		(size 0.508)
		(drill 0.254)
		(layers "F.Cu" "B.Cu")
		(net "P3V3_AUX")
	)
	(via
		(at 19.05 -54.356)
		(size 0.508)
		(drill 0.254)
		(layers "F.Cu" "B.Cu")
		(net "P3V3_AUX")
	)
	(via
		(at 23.495 -29.5148)
		(size 0.508)
		(drill 0.254)
		(layers "F.Cu" "B.Cu")
		(net "P3V3_AUX")
	)
	(via
		(at 26.0604 -67.818)
		(size 0.508)
		(drill 0.254)
		(layers "F.Cu" "B.Cu")
		(net "P3V3_AUX")
	)
	(via
		(at 77.851 -76.581)
		(size 0.508)
		(drill 0.254)
		(layers "F.Cu" "B.Cu")
		(net "P3V3_AUX")
	)
	(via
		(at 59.0042 -66.3448)
		(size 0.508)
		(drill 0.254)
		(layers "F.Cu" "B.Cu")
		(net "P3V3_AUX")
	)
	(via
		(at 31.98114 -85.091524)
		(size 0.508)
		(drill 0.254)
		(layers "F.Cu" "B.Cu")
		(net "P3V3_AUX")
	)
	(via
		(at 30.226 -11.3284)
		(size 0.508)
		(drill 0.254)
		(layers "F.Cu" "B.Cu")
		(net "P3V3_AUX")
	)
	(via
		(at 60.8965 -100.32238)
		(size 0.508)
		(drill 0.254)
		(layers "F.Cu" "B.Cu")
		(net "P3V3_AUX")
	)
	(via
		(at 78.63078 -21.336)
		(size 0.508)
		(drill 0.254)
		(layers "F.Cu" "B.Cu")
		(net "P3V3_AUX")
	)
	(via
		(at 48.4632 -29.7688)
		(size 0.508)
		(drill 0.254)
		(layers "F.Cu" "B.Cu")
		(net "P3V3_AUX")
	)
	(via
		(at 45.593 -29.6672)
		(size 0.508)
		(drill 0.254)
		(layers "F.Cu" "B.Cu")
		(net "P3V3_AUX")
	)
	(via
		(at 19.7866 -69.7738)
		(size 0.508)
		(drill 0.254)
		(layers "F.Cu" "B.Cu")
		(net "P3V3_AUX")
	)
	(via
		(at 22.2504 -105.283)
		(size 0.508)
		(drill 0.254)
		(layers "F.Cu" "B.Cu")
		(net "P3V3_AUX")
	)
	(via
		(at 73.66 -17.26565)
		(size 0.508)
		(drill 0.254)
		(layers "F.Cu" "B.Cu")
		(net "P3V3_AUX")
	)
	(via
		(at 76.30795 -13.847064)
		(size 0.508)
		(drill 0.254)
		(layers "F.Cu" "B.Cu")
		(net "P3V3_AUX")
	)
	(via
		(at 35.4838 -105.4354)
		(size 0.508)
		(drill 0.254)
		(layers "F.Cu" "B.Cu")
		(net "P3V3_AUX")
	)
	(via
		(at 24.682958 -66.88328)
		(size 0.508)
		(drill 0.254)
		(layers "F.Cu" "B.Cu")
		(net "P3V3_AUX")
	)
	(via
		(at 42.813478 -86.670134)
		(size 0.508)
		(drill 0.254)
		(layers "F.Cu" "B.Cu")
		(net "P3V3_AUX")
	)
	(via
		(at 50.78476 -29.845)
		(size 0.508)
		(drill 0.254)
		(layers "F.Cu" "B.Cu")
		(net "P3V3_AUX")
	)
	(via
		(at 19.1262 -46.70425)
		(size 0.508)
		(drill 0.254)
		(layers "F.Cu" "B.Cu")
		(net "P3V3_AUX")
	)
	(via
		(at 56.01081 -97.7646)
		(size 0.508)
		(drill 0.254)
		(layers "F.Cu" "B.Cu")
		(net "P3V3_AUX")
	)
	(via
		(at 72.009 -32.004)
		(size 0.508)
		(drill 0.254)
		(layers "F.Cu" "B.Cu")
		(net "P3V3_AUX")
	)
	(via
		(at 12.319 -28.589986)
		(size 0.508)
		(drill 0.254)
		(layers "F.Cu" "B.Cu")
		(net "P3V3_AUX")
	)
	(via
		(at 83.099148 -70.858888)
		(size 0.508)
		(drill 0.254)
		(layers "F.Cu" "B.Cu")
		(net "P3V3_AUX")
	)
	(via
		(at 31.5976 -87.7062)
		(size 0.508)
		(drill 0.254)
		(layers "F.Cu" "B.Cu")
		(net "P3V3_AUX")
	)
	(via
		(at 11.30046 -101.0539)
		(size 0.508)
		(drill 0.254)
		(layers "F.Cu" "B.Cu")
		(net "P3V3_AUX")
	)
	(via
		(at 17.10182 -42.993818)
		(size 0.508)
		(drill 0.254)
		(layers "F.Cu" "B.Cu")
		(net "P3V3_AUX")
	)
	(via
		(at 36.56203 -89.953084)
		(size 0.508)
		(drill 0.254)
		(layers "F.Cu" "B.Cu")
		(net "P3V3_AUX")
	)
	(via
		(at 61.9125 -93.91142)
		(size 0.508)
		(drill 0.254)
		(layers "F.Cu" "B.Cu")
		(net "P3V3_AUX")
	)
	(via
		(at 17.399 -16.891)
		(size 0.508)
		(drill 0.254)
		(layers "F.Cu" "B.Cu")
		(net "P3V3_AUX")
	)
	(via
		(at 18.0086 -61.341)
		(size 0.508)
		(drill 0.254)
		(layers "F.Cu" "B.Cu")
		(net "P3V3_AUX")
	)
	(via
		(at 68.9102 -33.7566)
		(size 0.508)
		(drill 0.254)
		(layers "F.Cu" "B.Cu")
		(net "P3V3_AUX")
	)
	(via
		(at 54.4576 -77.215238)
		(size 0.508)
		(drill 0.254)
		(layers "F.Cu" "B.Cu")
		(net "P3V3_AUX")
	)
	(via
		(at 53.299868 -44.575984)
		(size 0.4572)
		(drill 0.254)
		(layers "F.Cu" "B.Cu")
		(net "P3V3_AUX")
	)
	(via
		(at 32.11195 -14.478)
		(size 0.508)
		(drill 0.254)
		(layers "F.Cu" "B.Cu")
		(net "P3V3_AUX")
	)
	(via
		(at 7.7978 -80.137)
		(size 0.508)
		(drill 0.254)
		(layers "F.Cu" "B.Cu")
		(net "P3V3_AUX")
	)
	(via
		(at 44.9326 -68.6054)
		(size 0.508)
		(drill 0.254)
		(layers "F.Cu" "B.Cu")
		(net "P3V3_AUX")
	)
	(via
		(at 11.2268 -84.328)
		(size 0.508)
		(drill 0.254)
		(layers "F.Cu" "B.Cu")
		(net "P3V3_AUX")
	)
	(via
		(at 38.43528 -81.9658)
		(size 0.508)
		(drill 0.254)
		(layers "F.Cu" "B.Cu")
		(net "P3V3_AUX")
	)
	(via
		(at 54.684676 -29.741876)
		(size 0.508)
		(drill 0.254)
		(layers "F.Cu" "B.Cu")
		(net "P3V3_AUX")
	)
	(via
		(at 86.336632 -26.562558)
		(size 0.508)
		(drill 0.254)
		(layers "F.Cu" "B.Cu")
		(net "P3V3_AUX")
	)
	(via
		(at 38.9128 -43.43146)
		(size 0.508)
		(drill 0.254)
		(layers "F.Cu" "B.Cu")
		(net "P3V3_AUX")
	)
	(via
		(at 40.549322 -57.526936)
		(size 0.508)
		(drill 0.254)
		(layers "F.Cu" "B.Cu")
		(net "P3V3_AUX")
	)
	(via
		(at 30.2768 -103.16845)
		(size 0.508)
		(drill 0.254)
		(layers "F.Cu" "B.Cu")
		(net "P3V3_AUX")
	)
	(via
		(at 36.57092 -50.717196)
		(size 0.508)
		(drill 0.254)
		(layers "F.Cu" "B.Cu")
		(net "P3V3_AUX")
	)
	(via
		(at 70.358 -13.12291)
		(size 0.508)
		(drill 0.254)
		(layers "F.Cu" "B.Cu")
		(net "P3V3_AUX")
	)
	(via
		(at 33.738312 -35.1536)
		(size 0.508)
		(drill 0.254)
		(layers "F.Cu" "B.Cu")
		(net "P3V3_AUX")
	)
	(via
		(at 33.782 -91.821)
		(size 0.508)
		(drill 0.254)
		(layers "F.Cu" "B.Cu")
		(net "P3V3_AUX")
	)
	(via
		(at 36.119308 -84.836)
		(size 0.508)
		(drill 0.254)
		(layers "F.Cu" "B.Cu")
		(net "P3V3_AUX")
	)
	(via
		(at 37.7444 -85.4202)
		(size 0.508)
		(drill 0.254)
		(layers "F.Cu" "B.Cu")
		(net "P3V3_AUX")
	)
	(via
		(at 33.655 -56.3626)
		(size 0.508)
		(drill 0.254)
		(layers "F.Cu" "B.Cu")
		(net "P3V3_AUX")
	)
	(via
		(at 4.8768 -26.0858)
		(size 0.508)
		(drill 0.254)
		(layers "F.Cu" "B.Cu")
		(net "P3V3_AUX")
	)
	(via
		(at 41.313862 -55.586122)
		(size 0.508)
		(drill 0.254)
		(layers "F.Cu" "B.Cu")
		(net "P3V3_AUX")
	)
	(via
		(at 64.24295 -13.716)
		(size 0.508)
		(drill 0.254)
		(layers "F.Cu" "B.Cu")
		(net "P3V3_AUX")
	)
	(via
		(at 30.426914 -104.724454)
		(size 0.508)
		(drill 0.254)
		(layers "F.Cu" "B.Cu")
		(net "P3V3_AUX")
	)
	(via
		(at 83.80095 -90.428064)
		(size 0.508)
		(drill 0.254)
		(layers "F.Cu" "B.Cu")
		(net "P3V3_AUX")
	)
	(via
		(at 80.280764 -27.535378)
		(size 0.508)
		(drill 0.254)
		(layers "F.Cu" "B.Cu")
		(net "P3V3_AUX")
	)
	(via
		(at 49.7967 -91.12758)
		(size 0.508)
		(drill 0.254)
		(layers "F.Cu" "B.Cu")
		(net "P3V3_AUX")
	)
	(via
		(at 28.2194 -69.5198)
		(size 0.508)
		(drill 0.254)
		(layers "F.Cu" "B.Cu")
		(net "P3V3_AUX")
	)
	(via
		(at 35.86988 -31.25978)
		(size 0.508)
		(drill 0.254)
		(layers "F.Cu" "B.Cu")
		(net "P3V3_AUX")
	)
	(via
		(at 34.29 -56.1848)
		(size 0.508)
		(drill 0.254)
		(layers "F.Cu" "B.Cu")
		(net "P3V3_AUX")
	)
	(via
		(at 35.700716 -43.608752)
		(size 0.508)
		(drill 0.254)
		(layers "F.Cu" "B.Cu")
		(net "P3V3_AUX")
	)
	(via
		(at 39.952676 -110.648242)
		(size 0.508)
		(drill 0.254)
		(layers "F.Cu" "B.Cu")
		(net "P3V3_AUX")
	)
	(via
		(at 57.3278 -92.075)
		(size 0.508)
		(drill 0.254)
		(layers "F.Cu" "B.Cu")
		(net "P3V3_AUX")
	)
	(via
		(at 52.197 -65.6082)
		(size 0.508)
		(drill 0.254)
		(layers "F.Cu" "B.Cu")
		(net "P3V3_AUX")
	)
	(via
		(at 9.62025 -95.99295)
		(size 0.508)
		(drill 0.254)
		(layers "F.Cu" "B.Cu")
		(net "P3V3_AUX")
	)
	(via
		(at 73.091294 -93.0148)
		(size 0.508)
		(drill 0.254)
		(layers "F.Cu" "B.Cu")
		(net "P3V3_AUX")
	)
	(via
		(at 40.95496 -45.16628)
		(size 0.508)
		(drill 0.254)
		(layers "F.Cu" "B.Cu")
		(net "P3V3_AUX")
	)
	(via
		(at 8.967216 -14.812518)
		(size 0.508)
		(drill 0.254)
		(layers "F.Cu" "B.Cu")
		(net "P3V3_AUX")
	)
	(via
		(at 26.86177 -83.240626)
		(size 0.508)
		(drill 0.254)
		(layers "F.Cu" "B.Cu")
		(net "P3V3_AUX")
	)
	(via
		(at 51.699668 -44.575984)
		(size 0.4572)
		(drill 0.254)
		(layers "F.Cu" "B.Cu")
		(net "P3V3_AUX")
	)
	(via
		(at 30.77845 -97.82175)
		(size 0.508)
		(drill 0.254)
		(layers "F.Cu" "B.Cu")
		(net "P3V3_AUX")
	)
	(via
		(at 40.9702 -90.0684)
		(size 0.508)
		(drill 0.254)
		(layers "F.Cu" "B.Cu")
		(net "P3V3_AUX")
	)
	(segment
		(start 54.787292 -94.2213)
		(end 54.442106 -94.2213)
		(width 0.381)
		(layer "B.Cu")
		(net "P3V3_AUX")
	)
	(segment
		(start 6.3754 -29.5148)
		(end 5.04825 -29.5148)
		(width 0.4572)
		(layer "B.Cu")
		(net "P3V3_AUX")
	)
	(segment
		(start 44.0182 -26.162)
		(end 45.395896 -26.162)
		(width 0.381)
		(layer "B.Cu")
		(net "P3V3_AUX")
	)
	(segment
		(start 45.395896 -26.162)
		(end 46.21784 -25.340056)
		(width 0.381)
		(layer "B.Cu")
		(net "P3V3_AUX")
	)
	(segment
		(start 9.62025 -95.99295)
		(end 9.829546 -95.99295)
		(width 0.4572)
		(layer "B.Cu")
		(net "P3V3_AUX")
	)
	(segment
		(start 50.84445 -91.3765)
		(end 50.04562 -91.3765)
		(width 0.381)
		(layer "B.Cu")
		(net "P3V3_AUX")
	)
	(segment
		(start 47.879 -51.193446)
		(end 47.879 -51.74615)
		(width 0.4572)
		(layer "B.Cu")
		(net "P3V3_AUX")
	)
	(segment
		(start 38.1 -105.96245)
		(end 37.084 -105.96245)
		(width 0.381)
		(layer "B.Cu")
		(net "P3V3_AUX")
	)
	(segment
		(start 16.764 -70.50405)
		(end 17.78 -70.50405)
		(width 0.4572)
		(layer "B.Cu")
		(net "P3V3_AUX")
	)
	(segment
		(start 37.826696 -91.85275)
		(end 37.6047 -91.85275)
		(width 0.254)
		(layer "B.Cu")
		(net "P3V3_AUX")
	)
	(segment
		(start 39.329868 -92.24899)
		(end 38.222936 -92.24899)
		(width 0.254)
		(layer "B.Cu")
		(net "P3V3_AUX")
	)
	(segment
		(start 39.0652 -105.97515)
		(end 38.1127 -105.97515)
		(width 0.381)
		(layer "B.Cu")
		(net "P3V3_AUX")
	)
	(segment
		(start 50.91684 -64.34709)
		(end 51.80584 -64.34709)
		(width 0.381)
		(layer "B.Cu")
		(net "P3V3_AUX")
	)
	(segment
		(start 45.8724 -91.4908)
		(end 45.8724 -88.784938)
		(width 0.4572)
		(layer "B.Cu")
		(net "P3V3_AUX")
	)
	(segment
		(start 57.03951 -93.93555)
		(end 56.87568 -94.09938)
		(width 0.381)
		(layer "B.Cu")
		(net "P3V3_AUX")
	)
	(segment
		(start 62.2808 -28.276042)
		(end 61.996828 -28.276042)
		(width 0.381)
		(layer "B.Cu")
		(net "P3V3_AUX")
	)
	(segment
		(start 51.13782 -76.49083)
		(end 51.32705 -76.3016)
		(width 0.381)
		(layer "B.Cu")
		(net "P3V3_AUX")
	)
	(segment
		(start 56.87568 -94.09938)
		(end 56.87568 -94.86519)
		(width 0.381)
		(layer "B.Cu")
		(net "P3V3_AUX")
	)
	(segment
		(start 44.418504 -92.13215)
		(end 45.085 -92.13215)
		(width 0.254)
		(layer "B.Cu")
		(net "P3V3_AUX")
	)
	(segment
		(start 71.5518 -29.735272)
		(end 71.469758 -29.817314)
		(width 0.381)
		(layer "B.Cu")
		(net "P3V3_AUX")
	)
	(segment
		(start 39.1668 -103.632)
		(end 37.80155 -103.632)
		(width 0.4572)
		(layer "B.Cu")
		(net "P3V3_AUX")
	)
	(segment
		(start 61.996828 -28.276042)
		(end 61.676788 -28.276042)
		(width 0.4572)
		(layer "B.Cu")
		(net "P3V3_AUX")
	)
	(segment
		(start 74.717148 -92.958158)
		(end 75.565508 -92.109798)
		(width 0.381)
		(layer "B.Cu")
		(net "P3V3_AUX")
	)
	(segment
		(start 19.7866 -69.7738)
		(end 19.74215 -69.72935)
		(width 0.3556)
		(layer "B.Cu")
		(net "P3V3_AUX")
	)
	(segment
		(start 51.861466 -77.685138)
		(end 51.51882 -77.685138)
		(width 0.381)
		(layer "B.Cu")
		(net "P3V3_AUX")
	)
	(segment
		(start 18.0086 -61.08065)
		(end 18.0086 -61.341)
		(width 0.3556)
		(layer "B.Cu")
		(net "P3V3_AUX")
	)
	(segment
		(start 59.572398 -18.958052)
		(end 59.572398 -18.151348)
		(width 0.4572)
		(layer "B.Cu")
		(net "P3V3_AUX")
	)
	(segment
		(start 56.727852 -30.467554)
		(end 55.705502 -30.467554)
		(width 0.381)
		(layer "B.Cu")
		(net "P3V3_AUX")
	)
	(segment
		(start 39.014908 -82.836512)
		(end 39.014908 -83.861656)
		(width 0.381)
		(layer "B.Cu")
		(net "P3V3_AUX")
	)
	(segment
		(start 10.287 -95.535496)
		(end 10.287 -95.16745)
		(width 0.4572)
		(layer "B.Cu")
		(net "P3V3_AUX")
	)
	(segment
		(start 18.4658 -75.844654)
		(end 18.948654 -75.3618)
		(width 0.381)
		(layer "B.Cu")
		(net "P3V3_AUX")
	)
	(segment
		(start 39.77513 -44.63288)
		(end 40.44696 -44.63288)
		(width 0.4572)
		(layer "B.Cu")
		(net "P3V3_AUX")
	)
	(segment
		(start 35.433 -105.4354)
		(end 35.052 -105.8164)
		(width 0.381)
		(layer "B.Cu")
		(net "P3V3_AUX")
	)
	(segment
		(start 47.6758 -50.990246)
		(end 47.879 -51.193446)
		(width 0.4572)
		(layer "B.Cu")
		(net "P3V3_AUX")
	)
	(segment
		(start 47.701962 -20.31238)
		(end 49.48301 -20.31238)
		(width 0.4572)
		(layer "B.Cu")
		(net "P3V3_AUX")
	)
	(segment
		(start 63.014098 -27.956256)
		(end 62.600586 -27.956256)
		(width 0.381)
		(layer "B.Cu")
		(net "P3V3_AUX")
	)
	(segment
		(start 58.5724 -23.6474)
		(end 58.78195 -23.85695)
		(width 0.4572)
		(layer "B.Cu")
		(net "P3V3_AUX")
	)
	(segment
		(start 30.988 -68.436998)
		(end 30.988 -68.897246)
		(width 0.3556)
		(layer "B.Cu")
		(net "P3V3_AUX")
	)
	(segment
		(start 62.306454 -93.97492)
		(end 61.976 -93.97492)
		(width 0.381)
		(layer "B.Cu")
		(net "P3V3_AUX")
	)
	(segment
		(start 45.405294 -30.416754)
		(end 45.405294 -30.13837)
		(width 0.381)
		(layer "B.Cu")
		(net "P3V3_AUX")
	)
	(segment
		(start 40.9194 -59.3344)
		(end 40.9448 -59.3344)
		(width 0.4572)
		(layer "B.Cu")
		(net "P3V3_AUX")
	)
	(segment
		(start 55.36565 -95.21444)
		(end 55.086758 -94.935548)
		(width 0.381)
		(layer "B.Cu")
		(net "P3V3_AUX")
	)
	(segment
		(start 36.911026 -38.822376)
		(end 36.390326 -38.301676)
		(width 0.4572)
		(layer "B.Cu")
		(net "P3V3_AUX")
	)
	(segment
		(start 20.955 -101.58095)
		(end 20.955 -100.9904)
		(width 0.381)
		(layer "B.Cu")
		(net "P3V3_AUX")
	)
	(segment
		(start 85.72246 -27.607768)
		(end 86.311486 -27.607768)
		(width 0.381)
		(layer "B.Cu")
		(net "P3V3_AUX")
	)
	(segment
		(start 42.350182 -27.830018)
		(end 44.0182 -26.162)
		(width 0.381)
		(layer "B.Cu")
		(net "P3V3_AUX")
	)
	(segment
		(start 50.673 -30.46095)
		(end 50.673 -29.95676)
		(width 0.381)
		(layer "B.Cu")
		(net "P3V3_AUX")
	)
	(segment
		(start 58.77941 -30.467554)
		(end 57.75198 -30.467554)
		(width 0.381)
		(layer "B.Cu")
		(net "P3V3_AUX")
	)
	(segment
		(start 71.469758 -30.956758)
		(end 72.009 -31.496)
		(width 0.381)
		(layer "B.Cu")
		(net "P3V3_AUX")
	)
	(segment
		(start 39.53002 -46.119542)
		(end 39.53002 -45.79366)
		(width 0.4572)
		(layer "B.Cu")
		(net "P3V3_AUX")
	)
	(segment
		(start 17.399 -17.50695)
		(end 17.399 -16.891)
		(width 0.4572)
		(layer "B.Cu")
		(net "P3V3_AUX")
	)
	(segment
		(start 18.2626 -76.708)
		(end 18.2626 -77.95895)
		(width 0.381)
		(layer "B.Cu")
		(net "P3V3_AUX")
	)
	(segment
		(start 16.05788 -81.48828)
		(end 16.599154 -82.029554)
		(width 0.381)
		(layer "B.Cu")
		(net "P3V3_AUX")
	)
	(segment
		(start 38.222936 -92.24899)
		(end 37.826696 -91.85275)
		(width 0.254)
		(layer "B.Cu")
		(net "P3V3_AUX")
	)
	(segment
		(start 54.442106 -94.2213)
		(end 54.061106 -93.8403)
		(width 0.381)
		(layer "B.Cu")
		(net "P3V3_AUX")
	)
	(segment
		(start 72.621394 -69.176138)
		(end 72.621394 -68.554346)
		(width 0.381)
		(layer "B.Cu")
		(net "P3V3_AUX")
	)
	(segment
		(start 50.673 -29.95676)
		(end 50.78476 -29.845)
		(width 0.381)
		(layer "B.Cu")
		(net "P3V3_AUX")
	)
	(segment
		(start 19.751294 -76.681838)
		(end 19.23415 -76.164694)
		(width 0.381)
		(layer "B.Cu")
		(net "P3V3_AUX")
	)
	(segment
		(start 55.6387 -106.3879)
		(end 55.41645 -106.61015)
		(width 0.381)
		(layer "B.Cu")
		(net "P3V3_AUX")
	)
	(segment
		(start 80.772 -33.06445)
		(end 80.772 -32.512)
		(width 0.381)
		(layer "B.Cu")
		(net "P3V3_AUX")
	)
	(segment
		(start 33.612836 -61.7728)
		(end 31.7246 -61.7728)
		(width 0.4572)
		(layer "B.Cu")
		(net "P3V3_AUX")
	)
	(segment
		(start 56.200294 -95.21444)
		(end 55.36565 -95.21444)
		(width 0.381)
		(layer "B.Cu")
		(net "P3V3_AUX")
	)
	(segment
		(start 26.8224 -83.97875)
		(end 26.86177 -83.93938)
		(width 0.4572)
		(layer "B.Cu")
		(net "P3V3_AUX")
	)
	(segment
		(start 49.461166 -62.516512)
		(end 48.436022 -62.516512)
		(width 0.381)
		(layer "B.Cu")
		(net "P3V3_AUX")
	)
	(segment
		(start 61.3918 -24.65705)
		(end 61.3918 -25.03932)
		(width 0.4572)
		(layer "B.Cu")
		(net "P3V3_AUX")
	)
	(segment
		(start 12.84605 -90.44305)
		(end 12.7 -90.44305)
		(width 0.4572)
		(layer "B.Cu")
		(net "P3V3_AUX")
	)
	(segment
		(start 62.27445 -18.68805)
		(end 62.5348 -18.9484)
		(width 0.381)
		(layer "B.Cu")
		(net "P3V3_AUX")
	)
	(segment
		(start 52.375054 -65.786254)
		(end 52.914296 -65.786254)
		(width 0.381)
		(layer "B.Cu")
		(net "P3V3_AUX")
	)
	(segment
		(start 19.05 -99.1616)
		(end 18.034 -100.1776)
		(width 0.4572)
		(layer "B.Cu")
		(net "P3V3_AUX")
	)
	(segment
		(start 39.53002 -45.79366)
		(end 39.77513 -45.54855)
		(width 0.4572)
		(layer "B.Cu")
		(net "P3V3_AUX")
	)
	(segment
		(start 13.4366 -91.0336)
		(end 12.84605 -90.44305)
		(width 0.4572)
		(layer "B.Cu")
		(net "P3V3_AUX")
	)
	(segment
		(start 57.2516 -65.66535)
		(end 57.242202 -65.66535)
		(width 0.381)
		(layer "B.Cu")
		(net "P3V3_AUX")
	)
	(segment
		(start 25.019 -17.63395)
		(end 25.019 -16.891)
		(width 0.4572)
		(layer "B.Cu")
		(net "P3V3_AUX")
	)
	(segment
		(start 22.5552 -106.10215)
		(end 22.5552 -105.5878)
		(width 0.4572)
		(layer "B.Cu")
		(net "P3V3_AUX")
	)
	(segment
		(start 16.599154 -82.029554)
		(end 16.599154 -82.975196)
		(width 0.381)
		(layer "B.Cu")
		(net "P3V3_AUX")
	)
	(segment
		(start 50.790856 -64.34709)
		(end 49.461166 -63.0174)
		(width 0.381)
		(layer "B.Cu")
		(net "P3V3_AUX")
	)
	(segment
		(start 13.081 -65.5828)
		(end 12.954 -65.7098)
		(width 0.381)
		(layer "B.Cu")
		(net "P3V3_AUX")
	)
	(segment
		(start 37.9984 -104.267)
		(end 37.80155 -104.07015)
		(width 0.381)
		(layer "B.Cu")
		(net "P3V3_AUX")
	)
	(segment
		(start 44.301664 -92.24899)
		(end 44.418504 -92.13215)
		(width 0.254)
		(layer "B.Cu")
		(net "P3V3_AUX")
	)
	(segment
		(start 52.959 -65.74155)
		(end 54.3687 -65.74155)
		(width 0.381)
		(layer "B.Cu")
		(net "P3V3_AUX")
	)
	(segment
		(start 62.27445 -18.2626)
		(end 62.27445 -18.68805)
		(width 0.381)
		(layer "B.Cu")
		(net "P3V3_AUX")
	)
	(segment
		(start 45.405294 -30.13837)
		(end 45.593 -29.950664)
		(width 0.381)
		(layer "B.Cu")
		(net "P3V3_AUX")
	)
	(segment
		(start 86.311486 -28.627832)
		(end 86.336632 -28.602686)
		(width 0.381)
		(layer "B.Cu")
		(net "P3V3_AUX")
	)
	(segment
		(start 72.009 -31.496)
		(end 72.009 -32.004)
		(width 0.381)
		(layer "B.Cu")
		(net "P3V3_AUX")
	)
	(segment
		(start 56.8452 -65.25895)
		(end 56.8452 -64.7192)
		(width 0.381)
		(layer "B.Cu")
		(net "P3V3_AUX")
	)
	(segment
		(start 51.94427 -65.40627)
		(end 52.1462 -65.6082)
		(width 0.381)
		(layer "B.Cu")
		(net "P3V3_AUX")
	)
	(segment
		(start 58.724546 -65.747392)
		(end 58.23331 -65.747392)
		(width 0.381)
		(layer "B.Cu")
		(net "P3V3_AUX")
	)
	(segment
		(start 12.319 -28.589986)
		(end 12.319 -27.686)
		(width 0.4572)
		(layer "B.Cu")
		(net "P3V3_AUX")
	)
	(segment
		(start 64.236346 -21.981922)
		(end 62.980062 -21.981922)
		(width 0.4572)
		(layer "B.Cu")
		(net "P3V3_AUX")
	)
	(segment
		(start 24.9174 -105.2576)
		(end 24.590756 -105.584244)
		(width 0.381)
		(layer "B.Cu")
		(net "P3V3_AUX")
	)
	(segment
		(start 52.914296 -65.786254)
		(end 52.959 -65.74155)
		(width 0.381)
		(layer "B.Cu")
		(net "P3V3_AUX")
	)
	(segment
		(start 31.09595 -69.005196)
		(end 31.09595 -70.358)
		(width 0.3556)
		(layer "B.Cu")
		(net "P3V3_AUX")
	)
	(segment
		(start 52.197 -65.6082)
		(end 52.375054 -65.786254)
		(width 0.381)
		(layer "B.Cu")
		(net "P3V3_AUX")
	)
	(segment
		(start 40.2082 -59.0042)
		(end 40.5892 -59.0042)
		(width 0.4572)
		(layer "B.Cu")
		(net "P3V3_AUX")
	)
	(segment
		(start 72.783446 -28.135072)
		(end 71.940928 -28.135072)
		(width 0.381)
		(layer "B.Cu")
		(net "P3V3_AUX")
	)
	(segment
		(start 69.469 -14.478)
		(end 69.723 -14.732)
		(width 0.4572)
		(layer "B.Cu")
		(net "P3V3_AUX")
	)
	(segment
		(start 39.530782 -47.137828)
		(end 39.530782 -46.120304)
		(width 0.381)
		(layer "B.Cu")
		(net "P3V3_AUX")
	)
	(segment
		(start 37.80155 -104.07015)
		(end 37.80155 -103.632)
		(width 0.381)
		(layer "B.Cu")
		(net "P3V3_AUX")
	)
	(segment
		(start 12.954 -65.7098)
		(end 12.954 -75.635104)
		(width 0.381)
		(layer "B.Cu")
		(net "P3V3_AUX")
	)
	(segment
		(start 64.77 -21.448268)
		(end 64.236346 -21.981922)
		(width 0.4572)
		(layer "B.Cu")
		(net "P3V3_AUX")
	)
	(segment
		(start 17.612106 -67.385946)
		(end 17.612106 -68.15836)
		(width 0.3556)
		(layer "B.Cu")
		(net "P3V3_AUX")
	)
	(segment
		(start 29.8196 -105.331768)
		(end 29.8196 -105.84815)
		(width 0.4572)
		(layer "B.Cu")
		(net "P3V3_AUX")
	)
	(segment
		(start 43.530012 -92.24899)
		(end 44.301664 -92.24899)
		(width 0.254)
		(layer "B.Cu")
		(net "P3V3_AUX")
	)
	(segment
		(start 38.43528 -82.256884)
		(end 39.014908 -82.836512)
		(width 0.381)
		(layer "B.Cu")
		(net "P3V3_AUX")
	)
	(segment
		(start 41.180004 -91.005152)
		(end 41.180004 -91.398852)
		(width 0.254)
		(layer "B.Cu")
		(net "P3V3_AUX")
	)
	(segment
		(start 49.461166 -63.0174)
		(end 49.461166 -62.516512)
		(width 0.381)
		(layer "B.Cu")
		(net "P3V3_AUX")
	)
	(segment
		(start 41.313862 -55.586122)
		(end 41.881298 -55.586122)
		(width 0.4572)
		(layer "B.Cu")
		(net "P3V3_AUX")
	)
	(segment
		(start 68.98005 -14.478)
		(end 69.469 -14.478)
		(width 0.4572)
		(layer "B.Cu")
		(net "P3V3_AUX")
	)
	(segment
		(start 56.6674 -64.10325)
		(end 56.6674 -64.5414)
		(width 0.381)
		(layer "B.Cu")
		(net "P3V3_AUX")
	)
	(segment
		(start 12.954 -75.635104)
		(end 12.04976 -76.539344)
		(width 0.381)
		(layer "B.Cu")
		(net "P3V3_AUX")
	)
	(segment
		(start 61.676788 -28.276042)
		(end 61.279786 -27.87904)
		(width 0.4572)
		(layer "B.Cu")
		(net "P3V3_AUX")
	)
	(segment
		(start 29.0576 -70.358)
		(end 28.2194 -69.5198)
		(width 0.4572)
		(layer "B.Cu")
		(net "P3V3_AUX")
	)
	(segment
		(start 14.17955 -95.7834)
		(end 14.38275 -95.5802)
		(width 0.381)
		(layer "B.Cu")
		(net "P3V3_AUX")
	)
	(segment
		(start 84.052918 -97.506282)
		(end 84.201 -97.3582)
		(width 0.381)
		(layer "B.Cu")
		(net "P3V3_AUX")
	)
	(segment
		(start 31.09595 -70.358)
		(end 29.0576 -70.358)
		(width 0.4572)
		(layer "B.Cu")
		(net "P3V3_AUX")
	)
	(segment
		(start 61.3918 -25.03932)
		(end 61.14034 -25.29078)
		(width 0.4572)
		(layer "B.Cu")
		(net "P3V3_AUX")
	)
	(segment
		(start 18.124424 -69.077078)
		(end 18.776696 -69.72935)
		(width 0.3556)
		(layer "B.Cu")
		(net "P3V3_AUX")
	)
	(segment
		(start 6.4008 -29.5402)
		(end 6.3754 -29.5148)
		(width 0.4572)
		(layer "B.Cu")
		(net "P3V3_AUX")
	)
	(segment
		(start 62.600586 -27.956256)
		(end 62.2808 -28.276042)
		(width 0.381)
		(layer "B.Cu")
		(net "P3V3_AUX")
	)
	(segment
		(start 40.95496 -45.14088)
		(end 40.95496 -45.16628)
		(width 0.4572)
		(layer "B.Cu")
		(net "P3V3_AUX")
	)
	(segment
		(start 54.061106 -93.434408)
		(end 54.200044 -93.29547)
		(width 0.381)
		(layer "B.Cu")
		(net "P3V3_AUX")
	)
	(segment
		(start 13.797026 -27.066748)
		(end 14.593824 -26.26995)
		(width 0.4572)
		(layer "B.Cu")
		(net "P3V3_AUX")
	)
	(segment
		(start 40.9702 -90.0684)
		(end 40.9702 -90.498422)
		(width 0.254)
		(layer "B.Cu")
		(net "P3V3_AUX")
	)
	(segment
		(start 61.7855 -100.53955)
		(end 61.11367 -100.53955)
		(width 0.381)
		(layer "B.Cu")
		(net "P3V3_AUX")
	)
	(segment
		(start 37.6936 -91.76385)
		(end 37.6936 -91.207844)
		(width 0.4572)
		(layer "B.Cu")
		(net "P3V3_AUX")
	)
	(segment
		(start 13.4366 -91.44)
		(end 13.4366 -91.0336)
		(width 0.4572)
		(layer "B.Cu")
		(net "P3V3_AUX")
	)
	(segment
		(start 36.905184 -46.521116)
		(end 36.905184 -47.96409)
		(width 0.4572)
		(layer "B.Cu")
		(net "P3V3_AUX")
	)
	(segment
		(start 51.13782 -77.304138)
		(end 51.13782 -76.49083)
		(width 0.381)
		(layer "B.Cu")
		(net "P3V3_AUX")
	)
	(segment
		(start 48.4632 -30.296612)
		(end 48.4632 -29.7688)
		(width 0.381)
		(layer "B.Cu")
		(net "P3V3_AUX")
	)
	(segment
		(start 45.8724 -88.784938)
		(end 45.181012 -88.09355)
		(width 0.4572)
		(layer "B.Cu")
		(net "P3V3_AUX")
	)
	(segment
		(start 71.599806 -69.176138)
		(end 71.599806 -68.554346)
		(width 0.381)
		(layer "B.Cu")
		(net "P3V3_AUX")
	)
	(segment
		(start 64.036194 -27.956256)
		(end 63.014098 -27.956256)
		(width 0.381)
		(layer "B.Cu")
		(net "P3V3_AUX")
	)
	(segment
		(start 54.061106 -93.8403)
		(end 54.061106 -93.434408)
		(width 0.381)
		(layer "B.Cu")
		(net "P3V3_AUX")
	)
	(segment
		(start 62.992 -23.85695)
		(end 62.992 -21.99386)
		(width 0.4572)
		(layer "B.Cu")
		(net "P3V3_AUX")
	)
	(segment
		(start 47.699676 -50.96637)
		(end 47.6758 -50.990246)
		(width 0.4572)
		(layer "B.Cu")
		(net "P3V3_AUX")
	)
	(segment
		(start 57.242456 -65.656206)
		(end 56.8452 -65.25895)
		(width 0.381)
		(layer "B.Cu")
		(net "P3V3_AUX")
	)
	(segment
		(start 16.599154 -82.975196)
		(end 16.2814 -83.29295)
		(width 0.381)
		(layer "B.Cu")
		(net "P3V3_AUX")
	)
	(segment
		(start 85.72246 -28.627832)
		(end 86.311486 -28.627832)
		(width 0.381)
		(layer "B.Cu")
		(net "P3V3_AUX")
	)
	(segment
		(start 17.526 -99.07905)
		(end 17.526 -99.6696)
		(width 0.4572)
		(layer "B.Cu")
		(net "P3V3_AUX")
	)
	(segment
		(start 18.124424 -68.670678)
		(end 18.124424 -69.077078)
		(width 0.3556)
		(layer "B.Cu")
		(net "P3V3_AUX")
	)
	(segment
		(start 19.12112 -19.228816)
		(end 19.717766 -19.228816)
		(width 0.4572)
		(layer "B.Cu")
		(net "P3V3_AUX")
	)
	(segment
		(start 37.6936 -91.207844)
		(end 37.672264 -91.207844)
		(width 0.4572)
		(layer "B.Cu")
		(net "P3V3_AUX")
	)
	(segment
		(start 75.565508 -92.109798)
		(end 78.462124 -92.109798)
		(width 0.381)
		(layer "B.Cu")
		(net "P3V3_AUX")
	)
	(segment
		(start 84.052918 -99.238054)
		(end 84.052918 -98.20529)
		(width 0.381)
		(layer "B.Cu")
		(net "P3V3_AUX")
	)
	(segment
		(start 47.00905 -107.3912)
		(end 47.00905 -107.82046)
		(width 0.381)
		(layer "B.Cu")
		(net "P3V3_AUX")
	)
	(segment
		(start 86.311486 -26.587704)
		(end 86.336632 -26.562558)
		(width 0.381)
		(layer "B.Cu")
		(net "P3V3_AUX")
	)
	(segment
		(start 54.4576 -77.215238)
		(end 53.778912 -77.215238)
		(width 0.381)
		(layer "B.Cu")
		(net "P3V3_AUX")
	)
	(segment
		(start 55.705502 -30.467554)
		(end 54.684676 -30.467554)
		(width 0.381)
		(layer "B.Cu")
		(net "P3V3_AUX")
	)
	(segment
		(start 50.44059 -20.31619)
		(end 51.2826 -21.1582)
		(width 0.4572)
		(layer "B.Cu")
		(net "P3V3_AUX")
	)
	(segment
		(start 58.78195 -23.85695)
		(end 59.309 -23.85695)
		(width 0.4572)
		(layer "B.Cu")
		(net "P3V3_AUX")
	)
	(segment
		(start 39.512748 -103.977948)
		(end 39.1668 -103.632)
		(width 0.3556)
		(layer "B.Cu")
		(net "P3V3_AUX")
	)
	(segment
		(start 84.052918 -98.20529)
		(end 84.052918 -97.506282)
		(width 0.381)
		(layer "B.Cu")
		(net "P3V3_AUX")
	)
	(segment
		(start 46.0756 -91.694)
		(end 45.8724 -91.4908)
		(width 0.4572)
		(layer "B.Cu")
		(net "P3V3_AUX")
	)
	(segment
		(start 56.6674 -64.5414)
		(end 56.8452 -64.7192)
		(width 0.381)
		(layer "B.Cu")
		(net "P3V3_AUX")
	)
	(segment
		(start 53.4924 -77.50175)
		(end 52.775104 -77.50175)
		(width 0.381)
		(layer "B.Cu")
		(net "P3V3_AUX")
	)
	(segment
		(start 36.46678 -102.0445)
		(end 35.94608 -101.5238)
		(width 0.381)
		(layer "B.Cu")
		(net "P3V3_AUX")
	)
	(segment
		(start 57.242202 -65.66535)
		(end 57.242456 -65.665096)
		(width 0.381)
		(layer "B.Cu")
		(net "P3V3_AUX")
	)
	(segment
		(start 26.86177 -83.93938)
		(end 26.86177 -83.240626)
		(width 0.4572)
		(layer "B.Cu")
		(net "P3V3_AUX")
	)
	(segment
		(start 31.961836 -95.7072)
		(end 30.77845 -95.7072)
		(width 0.4572)
		(layer "B.Cu")
		(net "P3V3_AUX")
	)
	(segment
		(start 30.426914 -104.724454)
		(end 29.8196 -105.331768)
		(width 0.4572)
		(layer "B.Cu")
		(net "P3V3_AUX")
	)
	(segment
		(start 49.48301 -20.31238)
		(end 49.48682 -20.31619)
		(width 0.4572)
		(layer "B.Cu")
		(net "P3V3_AUX")
	)
	(segment
		(start 85.72246 -26.587704)
		(end 86.311486 -26.587704)
		(width 0.381)
		(layer "B.Cu")
		(net "P3V3_AUX")
	)
	(segment
		(start 34.163 -68.9102)
		(end 34.163 -68.436998)
		(width 0.3556)
		(layer "B.Cu")
		(net "P3V3_AUX")
	)
	(segment
		(start 17.526 -99.6696)
		(end 18.034 -100.1776)
		(width 0.4572)
		(layer "B.Cu")
		(net "P3V3_AUX")
	)
	(segment
		(start 57.242456 -65.665096)
		(end 57.242456 -65.656206)
		(width 0.381)
		(layer "B.Cu")
		(net "P3V3_AUX")
	)
	(segment
		(start 46.21784 -24.51735)
		(end 46.21784 -25.21204)
		(width 0.4572)
		(layer "B.Cu")
		(net "P3V3_AUX")
	)
	(segment
		(start 7.02564 -27.7368)
		(end 6.629146 -27.7368)
		(width 0.4064)
		(layer "B.Cu")
		(net "P3V3_AUX")
	)
	(segment
		(start 22.987 -100.9904)
		(end 22.987 -101.58095)
		(width 0.381)
		(layer "B.Cu")
		(net "P3V3_AUX")
	)
	(segment
		(start 10.287 -95.16745)
		(end 10.40892 -95.04553)
		(width 0.4572)
		(layer "B.Cu")
		(net "P3V3_AUX")
	)
	(segment
		(start 44.384214 -30.416754)
		(end 45.405294 -30.416754)
		(width 0.381)
		(layer "B.Cu")
		(net "P3V3_AUX")
	)
	(segment
		(start 13.572236 -27.066748)
		(end 13.797026 -27.066748)
		(width 0.4572)
		(layer "B.Cu")
		(net "P3V3_AUX")
	)
	(segment
		(start 40.9702 -90.498422)
		(end 41.180004 -91.005152)
		(width 0.254)
		(layer "B.Cu")
		(net "P3V3_AUX")
	)
	(segment
		(start 13.4874 -95.7834)
		(end 14.17955 -95.7834)
		(width 0.381)
		(layer "B.Cu")
		(net "P3V3_AUX")
	)
	(segment
		(start 58.23331 -65.747392)
		(end 58.13171 -65.747392)
		(width 0.381)
		(layer "B.Cu")
		(net "P3V3_AUX")
	)
	(segment
		(start 62.533784 -94.20225)
		(end 62.306454 -93.97492)
		(width 0.381)
		(layer "B.Cu")
		(net "P3V3_AUX")
	)
	(segment
		(start 32.15894 -95.904304)
		(end 31.961836 -95.7072)
		(width 0.4572)
		(layer "B.Cu")
		(net "P3V3_AUX")
	)
	(segment
		(start 18.776696 -69.72935)
		(end 18.8722 -69.72935)
		(width 0.3556)
		(layer "B.Cu")
		(net "P3V3_AUX")
	)
	(segment
		(start 45.181012 -88.09355)
		(end 44.8818 -88.09355)
		(width 0.4572)
		(layer "B.Cu")
		(net "P3V3_AUX")
	)
	(segment
		(start 71.940928 -28.135072)
		(end 71.5518 -28.5242)
		(width 0.381)
		(layer "B.Cu")
		(net "P3V3_AUX")
	)
	(segment
		(start 24.9174 -104.7496)
		(end 24.9174 -105.2576)
		(width 0.381)
		(layer "B.Cu")
		(net "P3V3_AUX")
	)
	(segment
		(start 66.662554 -99.64166)
		(end 67.39128 -99.64166)
		(width 0.381)
		(layer "B.Cu")
		(net "P3V3_AUX")
	)
	(segment
		(start 58.5724 -23.2918)
		(end 58.5724 -23.6474)
		(width 0.4572)
		(layer "B.Cu")
		(net "P3V3_AUX")
	)
	(segment
		(start 5.12445 -26.797)
		(end 5.12445 -26.33345)
		(width 0.4572)
		(layer "B.Cu")
		(net "P3V3_AUX")
	)
	(segment
		(start 56.549544 -94.86519)
		(end 56.200294 -95.21444)
		(width 0.381)
		(layer "B.Cu")
		(net "P3V3_AUX")
	)
	(segment
		(start 42.350182 -30.416754)
		(end 42.350182 -27.830018)
		(width 0.381)
		(layer "B.Cu")
		(net "P3V3_AUX")
	)
	(segment
		(start 86.311486 -27.607768)
		(end 86.336632 -27.582622)
		(width 0.381)
		(layer "B.Cu")
		(net "P3V3_AUX")
	)
	(segment
		(start 49.046384 -29.850334)
		(end 49.046384 -29.3624)
		(width 0.381)
		(layer "B.Cu")
		(net "P3V3_AUX")
	)
	(segment
		(start 24.590756 -105.584244)
		(end 24.590756 -106.10977)
		(width 0.381)
		(layer "B.Cu")
		(net "P3V3_AUX")
	)
	(segment
		(start 35.052 -105.8164)
		(end 35.052 -105.96245)
		(width 0.381)
		(layer "B.Cu")
		(net "P3V3_AUX")
	)
	(segment
		(start 22.987 -101.58095)
		(end 24.003 -101.58095)
		(width 0.381)
		(layer "B.Cu")
		(net "P3V3_AUX")
	)
	(segment
		(start 12.71905 -95.504)
		(end 13.208 -95.504)
		(width 0.381)
		(layer "B.Cu")
		(net "P3V3_AUX")
	)
	(segment
		(start 64.940434 -90.2208)
		(end 64.35725 -90.2208)
		(width 0.381)
		(layer "B.Cu")
		(net "P3V3_AUX")
	)
	(segment
		(start 57.056528 -93.93555)
		(end 57.03951 -93.93555)
		(width 0.381)
		(layer "B.Cu")
		(net "P3V3_AUX")
	)
	(segment
		(start 30.77845 -95.7072)
		(end 30.77845 -97.82175)
		(width 0.4572)
		(layer "B.Cu")
		(net "P3V3_AUX")
	)
	(segment
		(start 33.16605 -91.821)
		(end 33.782 -91.821)
		(width 0.4572)
		(layer "B.Cu")
		(net "P3V3_AUX")
	)
	(segment
		(start 38.43528 -81.9658)
		(end 38.43528 -82.256884)
		(width 0.381)
		(layer "B.Cu")
		(net "P3V3_AUX")
	)
	(segment
		(start 17.612106 -68.15836)
		(end 18.124424 -68.670678)
		(width 0.3556)
		(layer "B.Cu")
		(net "P3V3_AUX")
	)
	(segment
		(start 19.717766 -19.228816)
		(end 19.79295 -19.304)
		(width 0.4572)
		(layer "B.Cu")
		(net "P3V3_AUX")
	)
	(segment
		(start 47.607474 -30.457648)
		(end 48.624236 -30.457648)
		(width 0.381)
		(layer "B.Cu")
		(net "P3V3_AUX")
	)
	(segment
		(start 37.467286 -49.82083)
		(end 36.57092 -50.717196)
		(width 0.4572)
		(layer "B.Cu")
		(net "P3V3_AUX")
	)
	(segment
		(start 17.78 -70.50405)
		(end 17.78 -71.12)
		(width 0.4572)
		(layer "B.Cu")
		(net "P3V3_AUX")
	)
	(segment
		(start 59.572398 -18.151348)
		(end 59.45505 -18.034)
		(width 0.4572)
		(layer "B.Cu")
		(net "P3V3_AUX")
	)
	(segment
		(start 40.5892 -59.0042)
		(end 40.9194 -59.3344)
		(width 0.4572)
		(layer "B.Cu")
		(net "P3V3_AUX")
	)
	(segment
		(start 37.6047 -91.85275)
		(end 37.6936 -91.76385)
		(width 0.4572)
		(layer "B.Cu")
		(net "P3V3_AUX")
	)
	(segment
		(start 55.086758 -94.520766)
		(end 54.787292 -94.2213)
		(width 0.381)
		(layer "B.Cu")
		(net "P3V3_AUX")
	)
	(segment
		(start 34.244026 -61.14161)
		(end 33.612836 -61.7728)
		(width 0.4572)
		(layer "B.Cu")
		(net "P3V3_AUX")
	)
	(segment
		(start 54.5973 -65.72885)
		(end 54.9783 -66.10985)
		(width 0.381)
		(layer "B.Cu")
		(net "P3V3_AUX")
	)
	(segment
		(start 17.151858 -61.729112)
		(end 17.151858 -61.226192)
		(width 0.3556)
		(layer "B.Cu")
		(net "P3V3_AUX")
	)
	(segment
		(start 37.467286 -48.9204)
		(end 37.362638 -48.9204)
		(width 0.4572)
		(layer "B.Cu")
		(net "P3V3_AUX")
	)
	(segment
		(start 53.778912 -77.215238)
		(end 53.4924 -77.50175)
		(width 0.381)
		(layer "B.Cu")
		(net "P3V3_AUX")
	)
	(segment
		(start 46.0756 -92.13215)
		(end 45.085 -92.13215)
		(width 0.4572)
		(layer "B.Cu")
		(net "P3V3_AUX")
	)
	(segment
		(start 31.7246 -61.7728)
		(end 31.623 -61.6712)
		(width 0.4572)
		(layer "B.Cu")
		(net "P3V3_AUX")
	)
	(segment
		(start 50.91684 -64.34709)
		(end 50.790856 -64.34709)
		(width 0.381)
		(layer "B.Cu")
		(net "P3V3_AUX")
	)
	(segment
		(start 31.623 -61.6712)
		(end 31.210504 -61.6712)
		(width 0.4572)
		(layer "B.Cu")
		(net "P3V3_AUX")
	)
	(segment
		(start 17.151858 -61.226192)
		(end 17.653 -60.72505)
		(width 0.3556)
		(layer "B.Cu")
		(net "P3V3_AUX")
	)
	(segment
		(start 54.3814 -65.72885)
		(end 54.5973 -65.72885)
		(width 0.381)
		(layer "B.Cu")
		(net "P3V3_AUX")
	)
	(segment
		(start 12.319 -27.686)
		(end 12.31265 -27.67965)
		(width 0.4572)
		(layer "B.Cu")
		(net "P3V3_AUX")
	)
	(segment
		(start 39.530782 -46.120304)
		(end 39.53002 -46.119542)
		(width 0.381)
		(layer "B.Cu")
		(net "P3V3_AUX")
	)
	(segment
		(start 22.5552 -105.5878)
		(end 22.2504 -105.283)
		(width 0.4572)
		(layer "B.Cu")
		(net "P3V3_AUX")
	)
	(segment
		(start 34.05505 -70.358)
		(end 34.05505 -70.757542)
		(width 0.4572)
		(layer "B.Cu")
		(net "P3V3_AUX")
	)
	(segment
		(start 13.3604 -95.6564)
		(end 13.4874 -95.7834)
		(width 0.381)
		(layer "B.Cu")
		(net "P3V3_AUX")
	)
	(segment
		(start 69.597778 -30.8356)
		(end 68.986908 -30.8356)
		(width 0.381)
		(layer "B.Cu")
		(net "P3V3_AUX")
	)
	(segment
		(start 58.13171 -65.747392)
		(end 58.058812 -65.82029)
		(width 0.381)
		(layer "B.Cu")
		(net "P3V3_AUX")
	)
	(segment
		(start 52.7812 -30.46095)
		(end 53.6829 -30.46095)
		(width 0.381)
		(layer "B.Cu")
		(net "P3V3_AUX")
	)
	(segment
		(start 49.657 -30.46095)
		(end 49.046384 -29.850334)
		(width 0.381)
		(layer "B.Cu")
		(net "P3V3_AUX")
	)
	(segment
		(start 52.591716 -77.685138)
		(end 51.861466 -77.685138)
		(width 0.381)
		(layer "B.Cu")
		(net "P3V3_AUX")
	)
	(segment
		(start 58.058812 -65.82029)
		(end 57.40654 -65.82029)
		(width 0.381)
		(layer "B.Cu")
		(net "P3V3_AUX")
	)
	(segment
		(start 5.689346 -26.797)
		(end 5.12445 -26.797)
		(width 0.4064)
		(layer "B.Cu")
		(net "P3V3_AUX")
	)
	(segment
		(start 71.469758 -29.817314)
		(end 71.469758 -30.956758)
		(width 0.381)
		(layer "B.Cu")
		(net "P3V3_AUX")
	)
	(segment
		(start 55.41645 -106.61015)
		(end 54.8132 -106.61015)
		(width 0.381)
		(layer "B.Cu")
		(net "P3V3_AUX")
	)
	(segment
		(start 37.17036 -46.25594)
		(end 36.905184 -46.521116)
		(width 0.4572)
		(layer "B.Cu")
		(net "P3V3_AUX")
	)
	(segment
		(start 64.24295 -13.716)
		(end 64.24295 -13.081)
		(width 0.381)
		(layer "B.Cu")
		(net "P3V3_AUX")
	)
	(segment
		(start 34.05505 -70.757542)
		(end 34.37001 -71.072502)
		(width 0.4572)
		(layer "B.Cu")
		(net "P3V3_AUX")
	)
	(segment
		(start 59.0042 -66.3448)
		(end 59.0042 -66.027046)
		(width 0.381)
		(layer "B.Cu")
		(net "P3V3_AUX")
	)
	(segment
		(start 5.12445 -26.33345)
		(end 4.8768 -26.0858)
		(width 0.4572)
		(layer "B.Cu")
		(net "P3V3_AUX")
	)
	(segment
		(start 42.119296 -55.348124)
		(end 42.119296 -55.297324)
		(width 0.4572)
		(layer "B.Cu")
		(net "P3V3_AUX")
	)
	(segment
		(start 41.881298 -55.586122)
		(end 42.119296 -55.348124)
		(width 0.4572)
		(layer "B.Cu")
		(net "P3V3_AUX")
	)
	(segment
		(start 19.74215 -69.72935)
		(end 18.8722 -69.72935)
		(width 0.3556)
		(layer "B.Cu")
		(net "P3V3_AUX")
	)
	(segment
		(start 52.775104 -77.50175)
		(end 52.591716 -77.685138)
		(width 0.381)
		(layer "B.Cu")
		(net "P3V3_AUX")
	)
	(segment
		(start 38.1127 -105.97515)
		(end 38.1 -105.96245)
		(width 0.381)
		(layer "B.Cu")
		(net "P3V3_AUX")
	)
	(segment
		(start 49.48682 -20.31619)
		(end 50.44059 -20.31619)
		(width 0.4572)
		(layer "B.Cu")
		(net "P3V3_AUX")
	)
	(segment
		(start 61.11367 -100.53955)
		(end 60.8965 -100.32238)
		(width 0.381)
		(layer "B.Cu")
		(net "P3V3_AUX")
	)
	(segment
		(start 30.988 -68.897246)
		(end 31.09595 -69.005196)
		(width 0.3556)
		(layer "B.Cu")
		(net "P3V3_AUX")
	)
	(segment
		(start 68.8594 -88.03005)
		(end 67.131184 -88.03005)
		(width 0.381)
		(layer "B.Cu")
		(net "P3V3_AUX")
	)
	(segment
		(start 43.83405 -67.818)
		(end 45.974 -67.818)
		(width 0.4572)
		(layer "B.Cu")
		(net "P3V3_AUX")
	)
	(segment
		(start 53.68798 -30.46603)
		(end 53.68798 -29.718)
		(width 0.381)
		(layer "B.Cu")
		(net "P3V3_AUX")
	)
	(segment
		(start 38.1 -105.3465)
		(end 38.1 -105.96245)
		(width 0.381)
		(layer "B.Cu")
		(net "P3V3_AUX")
	)
	(segment
		(start 61.00064 -27.73045)
		(end 61.00064 -27.178)
		(width 0.4572)
		(layer "B.Cu")
		(net "P3V3_AUX")
	)
	(segment
		(start 13.208 -95.504)
		(end 13.3604 -95.6564)
		(width 0.381)
		(layer "B.Cu")
		(net "P3V3_AUX")
	)
	(segment
		(start 63.5762 -94.20225)
		(end 62.533784 -94.20225)
		(width 0.381)
		(layer "B.Cu")
		(net "P3V3_AUX")
	)
	(segment
		(start 17.612106 -62.916054)
		(end 17.612106 -62.18936)
		(width 0.3556)
		(layer "B.Cu")
		(net "P3V3_AUX")
	)
	(segment
		(start 17.612106 -62.18936)
		(end 17.151858 -61.729112)
		(width 0.3556)
		(layer "B.Cu")
		(net "P3V3_AUX")
	)
	(segment
		(start 54.200044 -93.29547)
		(end 54.71668 -93.29547)
		(width 0.381)
		(layer "B.Cu")
		(net "P3V3_AUX")
	)
	(segment
		(start 35.4838 -105.4354)
		(end 35.433 -105.4354)
		(width 0.381)
		(layer "B.Cu")
		(net "P3V3_AUX")
	)
	(segment
		(start 46.21784 -25.340056)
		(end 46.21784 -25.21204)
		(width 0.381)
		(layer "B.Cu")
		(net "P3V3_AUX")
	)
	(segment
		(start 43.367452 -30.416754)
		(end 44.384214 -30.416754)
		(width 0.381)
		(layer "B.Cu")
		(net "P3V3_AUX")
	)
	(segment
		(start 46.0756 -92.13215)
		(end 46.0756 -91.694)
		(width 0.4572)
		(layer "B.Cu")
		(net "P3V3_AUX")
	)
	(segment
		(start 39.77513 -45.54855)
		(end 39.77513 -44.63288)
		(width 0.4572)
		(layer "B.Cu")
		(net "P3V3_AUX")
	)
	(segment
		(start 15.24 -26.26995)
		(end 15.24 -25.445974)
		(width 0.4572)
		(layer "B.Cu")
		(net "P3V3_AUX")
	)
	(segment
		(start 10.40892 -95.04553)
		(end 10.40892 -95.04045)
		(width 0.4572)
		(layer "B.Cu")
		(net "P3V3_AUX")
	)
	(segment
		(start 62.992 -21.99386)
		(end 62.980062 -21.981922)
		(width 0.4572)
		(layer "B.Cu")
		(net "P3V3_AUX")
	)
	(segment
		(start 15.24 -25.445974)
		(end 14.873986 -25.07996)
		(width 0.4572)
		(layer "B.Cu")
		(net "P3V3_AUX")
	)
	(segment
		(start 9.829546 -95.99295)
		(end 10.287 -95.535496)
		(width 0.4572)
		(layer "B.Cu")
		(net "P3V3_AUX")
	)
	(segment
		(start 12.31265 -27.67965)
		(end 12.31265 -26.9748)
		(width 0.4572)
		(layer "B.Cu")
		(net "P3V3_AUX")
	)
	(segment
		(start 34.21888 -70.19417)
		(end 34.21888 -68.96608)
		(width 0.3556)
		(layer "B.Cu")
		(net "P3V3_AUX")
	)
	(segment
		(start 19.23415 -76.164694)
		(end 19.23415 -75.3618)
		(width 0.381)
		(layer "B.Cu")
		(net "P3V3_AUX")
	)
	(segment
		(start 54.3687 -65.74155)
		(end 54.3814 -65.72885)
		(width 0.381)
		(layer "B.Cu")
		(net "P3V3_AUX")
	)
	(segment
		(start 37.62375 -46.25594)
		(end 37.17036 -46.25594)
		(width 0.4572)
		(layer "B.Cu")
		(net "P3V3_AUX")
	)
	(segment
		(start 61.976 -93.97492)
		(end 61.9125 -93.91142)
		(width 0.381)
		(layer "B.Cu")
		(net "P3V3_AUX")
	)
	(segment
		(start 60.85205 -27.87904)
		(end 61.00064 -27.73045)
		(width 0.4572)
		(layer "B.Cu")
		(net "P3V3_AUX")
	)
	(segment
		(start 19.05 -99.07905)
		(end 19.05 -99.1616)
		(width 0.4572)
		(layer "B.Cu")
		(net "P3V3_AUX")
	)
	(segment
		(start 34.21888 -68.96608)
		(end 34.163 -68.9102)
		(width 0.3556)
		(layer "B.Cu")
		(net "P3V3_AUX")
	)
	(segment
		(start 80.772 -32.512)
		(end 80.2386 -31.9786)
		(width 0.381)
		(layer "B.Cu")
		(net "P3V3_AUX")
	)
	(segment
		(start 55.086758 -94.935548)
		(end 55.086758 -94.520766)
		(width 0.381)
		(layer "B.Cu")
		(net "P3V3_AUX")
	)
	(segment
		(start 66.62674 -97.6376)
		(end 66.336672 -97.927668)
		(width 0.381)
		(layer "B.Cu")
		(net "P3V3_AUX")
	)
	(segment
		(start 18.4658 -76.5048)
		(end 18.4658 -75.844654)
		(width 0.381)
		(layer "B.Cu")
		(net "P3V3_AUX")
	)
	(segment
		(start 66.336672 -99.315778)
		(end 66.662554 -99.64166)
		(width 0.381)
		(layer "B.Cu")
		(net "P3V3_AUX")
	)
	(segment
		(start 52.1462 -65.6082)
		(end 52.197 -65.6082)
		(width 0.381)
		(layer "B.Cu")
		(net "P3V3_AUX")
	)
	(segment
		(start 45.593 -29.950664)
		(end 45.593 -29.6672)
		(width 0.381)
		(layer "B.Cu")
		(net "P3V3_AUX")
	)
	(segment
		(start 51.7652 -64.38773)
		(end 51.7652 -64.972946)
		(width 0.381)
		(layer "B.Cu")
		(net "P3V3_AUX")
	)
	(segment
		(start 40.969184 -103.977948)
		(end 39.512748 -103.977948)
		(width 0.3556)
		(layer "B.Cu")
		(net "P3V3_AUX")
	)
	(segment
		(start 6.629146 -27.7368)
		(end 5.689346 -26.797)
		(width 0.4064)
		(layer "B.Cu")
		(net "P3V3_AUX")
	)
	(segment
		(start 43.4086 -108.67136)
		(end 43.4086 -107.690158)
		(width 0.381)
		(layer "B.Cu")
		(net "P3V3_AUX")
	)
	(segment
		(start 43.82262 -109.08538)
		(end 43.4086 -108.67136)
		(width 0.381)
		(layer "B.Cu")
		(net "P3V3_AUX")
	)
	(segment
		(start 40.44696 -44.63288)
		(end 40.95496 -45.14088)
		(width 0.4572)
		(layer "B.Cu")
		(net "P3V3_AUX")
	)
	(segment
		(start 14.593824 -26.26995)
		(end 15.24 -26.26995)
		(width 0.4572)
		(layer "B.Cu")
		(net "P3V3_AUX")
	)
	(segment
		(start 48.624236 -30.457648)
		(end 48.4632 -30.296612)
		(width 0.381)
		(layer "B.Cu")
		(net "P3V3_AUX")
	)
	(segment
		(start 36.576 -60.833)
		(end 36.26739 -61.14161)
		(width 0.4572)
		(layer "B.Cu")
		(net "P3V3_AUX")
	)
	(segment
		(start 36.905184 -48.462946)
		(end 36.905184 -47.96409)
		(width 0.4572)
		(layer "B.Cu")
		(net "P3V3_AUX")
	)
	(segment
		(start 59.309 -23.85695)
		(end 59.309 -21.99386)
		(width 0.4572)
		(layer "B.Cu")
		(net "P3V3_AUX")
	)
	(segment
		(start 14.45768 -81.48828)
		(end 16.05788 -81.48828)
		(width 0.381)
		(layer "B.Cu")
		(net "P3V3_AUX")
	)
	(segment
		(start 51.7652 -64.972946)
		(end 51.94427 -65.40627)
		(width 0.381)
		(layer "B.Cu")
		(net "P3V3_AUX")
	)
	(segment
		(start 14.3764 -81.407)
		(end 14.45768 -81.48828)
		(width 0.381)
		(layer "B.Cu")
		(net "P3V3_AUX")
	)
	(segment
		(start 56.87568 -94.86519)
		(end 56.549544 -94.86519)
		(width 0.381)
		(layer "B.Cu")
		(net "P3V3_AUX")
	)
	(segment
		(start 64.35725 -91.2114)
		(end 64.35725 -90.2208)
		(width 0.381)
		(layer "B.Cu")
		(net "P3V3_AUX")
	)
	(segment
		(start 37.00145 -102.0445)
		(end 36.46678 -102.0445)
		(width 0.381)
		(layer "B.Cu")
		(net "P3V3_AUX")
	)
	(segment
		(start 47.00905 -107.82046)
		(end 48.199548 -109.010958)
		(width 0.381)
		(layer "B.Cu")
		(net "P3V3_AUX")
	)
	(segment
		(start 71.5518 -28.5242)
		(end 71.5518 -29.735272)
		(width 0.381)
		(layer "B.Cu")
		(net "P3V3_AUX")
	)
	(segment
		(start 66.336672 -97.927668)
		(end 66.336672 -99.315778)
		(width 0.381)
		(layer "B.Cu")
		(net "P3V3_AUX")
	)
	(segment
		(start 51.51882 -77.685138)
		(end 51.13782 -77.304138)
		(width 0.381)
		(layer "B.Cu")
		(net "P3V3_AUX")
	)
	(segment
		(start 18.948654 -75.3618)
		(end 19.23415 -75.3618)
		(width 0.381)
		(layer "B.Cu")
		(net "P3V3_AUX")
	)
	(segment
		(start 50.04562 -91.3765)
		(end 49.7967 -91.12758)
		(width 0.381)
		(layer "B.Cu")
		(net "P3V3_AUX")
	)
	(segment
		(start 37.467286 -48.9204)
		(end 37.467286 -49.82083)
		(width 0.4572)
		(layer "B.Cu")
		(net "P3V3_AUX")
	)
	(segment
		(start 67.131184 -88.03005)
		(end 64.940434 -90.2208)
		(width 0.381)
		(layer "B.Cu")
		(net "P3V3_AUX")
	)
	(segment
		(start 59.309 -21.99386)
		(end 59.297062 -21.981922)
		(width 0.4572)
		(layer "B.Cu")
		(net "P3V3_AUX")
	)
	(segment
		(start 53.6829 -30.46095)
		(end 53.68798 -30.46603)
		(width 0.381)
		(layer "B.Cu")
		(net "P3V3_AUX")
	)
	(segment
		(start 34.05505 -70.358)
		(end 34.21888 -70.19417)
		(width 0.3556)
		(layer "B.Cu")
		(net "P3V3_AUX")
	)
	(segment
		(start 54.9783 -66.10985)
		(end 54.9783 -66.7893)
		(width 0.381)
		(layer "B.Cu")
		(net "P3V3_AUX")
	)
	(segment
		(start 59.0042 -66.027046)
		(end 58.724546 -65.747392)
		(width 0.381)
		(layer "B.Cu")
		(net "P3V3_AUX")
	)
	(segment
		(start 61.279786 -27.87904)
		(end 60.85205 -27.87904)
		(width 0.4572)
		(layer "B.Cu")
		(net "P3V3_AUX")
	)
	(segment
		(start 17.653 -60.72505)
		(end 18.0086 -61.08065)
		(width 0.3556)
		(layer "B.Cu")
		(net "P3V3_AUX")
	)
	(segment
		(start 18.4658 -76.5048)
		(end 18.2626 -76.708)
		(width 0.381)
		(layer "B.Cu")
		(net "P3V3_AUX")
	)
	(segment
		(start 37.362638 -48.9204)
		(end 36.905184 -48.462946)
		(width 0.4572)
		(layer "B.Cu")
		(net "P3V3_AUX")
	)
	(segment
		(start 57.40654 -65.82029)
		(end 57.2516 -65.66535)
		(width 0.381)
		(layer "B.Cu")
		(net "P3V3_AUX")
	)
	(segment
		(start 36.390326 -38.301676)
		(end 36.390326 -38.215824)
		(width 0.4572)
		(layer "B.Cu")
		(net "P3V3_AUX")
	)
	(segment
		(start 51.80584 -64.34709)
		(end 51.7652 -64.38773)
		(width 0.381)
		(layer "B.Cu")
		(net "P3V3_AUX")
	)
	(segment
		(start 57.75198 -30.467554)
		(end 56.727852 -30.467554)
		(width 0.381)
		(layer "B.Cu")
		(net "P3V3_AUX")
	)
	(segment
		(start 64.77 -21.0058)
		(end 64.77 -21.448268)
		(width 0.4572)
		(layer "B.Cu")
		(net "P3V3_AUX")
	)
	(segment
		(start 54.684676 -30.467554)
		(end 54.684676 -29.741876)
		(width 0.381)
		(layer "B.Cu")
		(net "P3V3_AUX")
	)
	(segment
		(start 54.9783 -66.7893)
		(end 55.245 -67.056)
		(width 0.381)
		(layer "B.Cu")
		(net "P3V3_AUX")
	)
	(segment
		(start 43.4086 -107.690158)
		(end 42.967402 -107.24896)
		(width 0.381)
		(layer "B.Cu")
		(net "P3V3_AUX")
	)
	(segment
		(start 36.26739 -61.14161)
		(end 34.244026 -61.14161)
		(width 0.4572)
		(layer "B.Cu")
		(net "P3V3_AUX")
	)
	(segment
		(start 37.30244 -32.65678)
		(end 35.90544 -31.25978)
		(width 0.381)
		(layer "In4.Cu")
		(net "P3V3_AUX")
	)
	(segment
		(start 40.46474 -31.1277)
		(end 39.02202 -31.1277)
		(width 0.381)
		(layer "In4.Cu")
		(net "P3V3_AUX")
	)
	(segment
		(start 19.12112 -19.120866)
		(end 17.399 -17.398746)
		(width 0.4572)
		(layer "In4.Cu")
		(net "P3V3_AUX")
	)
	(segment
		(start 38.14064 -32.65678)
		(end 37.30244 -32.65678)
		(width 0.381)
		(layer "In4.Cu")
		(net "P3V3_AUX")
	)
	(segment
		(start 39.02202 -31.1277)
		(end 38.52164 -31.62808)
		(width 0.381)
		(layer "In4.Cu")
		(net "P3V3_AUX")
	)
	(segment
		(start 41.02862 -32.1818)
		(end 41.02862 -31.69158)
		(width 0.381)
		(layer "In4.Cu")
		(net "P3V3_AUX")
	)
	(segment
		(start 41.82618 -32.97936)
		(end 41.02862 -32.1818)
		(width 0.381)
		(layer "In4.Cu")
		(net "P3V3_AUX")
	)
	(segment
		(start 41.82618 -33.10382)
		(end 41.82618 -32.97936)
		(width 0.381)
		(layer "In4.Cu")
		(net "P3V3_AUX")
	)
	(segment
		(start 17.399 -17.398746)
		(end 17.399 -16.891)
		(width 0.4572)
		(layer "In4.Cu")
		(net "P3V3_AUX")
	)
	(segment
		(start 41.02862 -31.69158)
		(end 40.46474 -31.1277)
		(width 0.381)
		(layer "In4.Cu")
		(net "P3V3_AUX")
	)
	(segment
		(start 38.52164 -32.27578)
		(end 38.14064 -32.65678)
		(width 0.381)
		(layer "In4.Cu")
		(net "P3V3_AUX")
	)
	(segment
		(start 38.52164 -31.62808)
		(end 38.52164 -32.27578)
		(width 0.381)
		(layer "In4.Cu")
		(net "P3V3_AUX")
	)
	(segment
		(start 19.12112 -19.228816)
		(end 19.12112 -19.120866)
		(width 0.4572)
		(layer "In4.Cu")
		(net "P3V3_AUX")
	)
	(segment
		(start 35.90544 -31.25978)
		(end 35.86988 -31.25978)
		(width 0.381)
		(layer "In4.Cu")
		(net "P3V3_AUX")
	)
	(segment
		(start 42.3418 -33.61944)
		(end 41.82618 -33.10382)
		(width 0.381)
		(layer "In4.Cu")
		(net "P3V3_AUX")
	)
	(segment
		(start 23.495 -30.1498)
		(end 23.7744 -30.4292)
		(width 0.4572)
		(layer "In7.Cu")
		(net "P3V3_AUX")
	)
	(segment
		(start 23.7744 -30.4292)
		(end 23.7744 -32.3342)
		(width 0.4572)
		(layer "In7.Cu")
		(net "P3V3_AUX")
	)
	(segment
		(start 23.7744 -32.3342)
		(end 22.671024 -33.437576)
		(width 0.4572)
		(layer "In7.Cu")
		(net "P3V3_AUX")
	)
	(segment
		(start 22.671024 -33.437576)
		(end 22.671024 -34.304224)
		(width 0.4572)
		(layer "In7.Cu")
		(net "P3V3_AUX")
	)
	(segment
		(start 23.495 -29.5148)
		(end 23.495 -30.1498)
		(width 0.4572)
		(layer "In7.Cu")
		(net "P3V3_AUX")
	)
	(segment
		(start 56.72709 -64.929004)
		(end 56.72709 -65.29451)
		(width 0.381)
		(layer "In9.Cu")
		(net "P3V3_AUX")
	)
	(segment
		(start 56.8452 -64.810894)
		(end 56.72709 -64.929004)
		(width 0.381)
		(layer "In9.Cu")
		(net "P3V3_AUX")
	)
	(segment
		(start 56.72709 -65.29451)
		(end 55.245 -66.7766)
		(width 0.381)
		(layer "In9.Cu")
		(net "P3V3_AUX")
	)
	(segment
		(start 56.8452 -64.7192)
		(end 56.8452 -64.810894)
		(width 0.381)
		(layer "In9.Cu")
		(net "P3V3_AUX")
	)
	(segment
		(start 55.245 -66.7766)
		(end 55.245 -67.056)
		(width 0.381)
		(layer "In9.Cu")
		(net "P3V3_AUX")
	)
	(segment
		(start 40.386 -35.808158)
		(end 40.386 -34.29)
		(width 0.3556)
		(layer "F.Cu")
		(net "P2V5_AUX")
	)
	(segment
		(start 40.756078 -36.178236)
		(end 40.386 -35.808158)
		(width 0.3556)
		(layer "F.Cu")
		(net "P2V5_AUX")
	)
	(segment
		(start 79.452216 -42.70756)
		(end 79.99222 -42.70756)
		(width 0.3556)
		(layer "F.Cu")
		(net "P2V5_AUX")
	)
	(segment
		(start 73.052432 -53.107336)
		(end 73.052432 -53.10759)
		(width 0.3048)
		(layer "F.Cu")
		(net "P2V5_AUX")
	)
	(segment
		(start 73.052432 -53.10759)
		(end 72.670924 -53.489098)
		(width 0.3048)
		(layer "F.Cu")
		(net "P2V5_AUX")
	)
	(via
		(at 55.712106 -72.171052)
		(size 0.508)
		(drill 0.254)
		(layers "F.Cu" "B.Cu")
		(net "P2V5_AUX")
	)
	(via
		(at 84.262214 -35.113722)
		(size 0.508)
		(drill 0.254)
		(layers "F.Cu" "B.Cu")
		(net "P2V5_AUX")
	)
	(via
		(at 84.236814 -36.002722)
		(size 0.508)
		(drill 0.254)
		(layers "F.Cu" "B.Cu")
		(net "P2V5_AUX")
	)
	(via
		(at 55.717186 -71.52132)
		(size 0.508)
		(drill 0.254)
		(layers "F.Cu" "B.Cu")
		(net "P2V5_AUX")
	)
	(via
		(at 72.670924 -53.489098)
		(size 0.4572)
		(drill 0.254)
		(layers "F.Cu" "B.Cu")
		(net "P2V5_AUX")
	)
	(via
		(at 83.334098 -35.968432)
		(size 0.508)
		(drill 0.254)
		(layers "F.Cu" "B.Cu")
		(net "P2V5_AUX")
	)
	(via
		(at 85.7758 -36.6522)
		(size 0.6604)
		(drill 0.3302)
		(layers "F.Cu" "B.Cu")
		(net "P2V5_AUX")
	)
	(via
		(at 40.386 -34.29)
		(size 0.508)
		(drill 0.254)
		(layers "F.Cu" "B.Cu")
		(net "P2V5_AUX")
	)
	(via
		(at 79.99222 -42.70756)
		(size 0.4572)
		(drill 0.254)
		(layers "F.Cu" "B.Cu")
		(net "P2V5_AUX")
	)
	(segment
		(start 80.729836 -43.022012)
		(end 80.306672 -43.022012)
		(width 0.381)
		(layer "B.Cu")
		(net "P2V5_AUX")
	)
	(segment
		(start 71.434706 -53.215794)
		(end 72.39762 -53.215794)
		(width 0.381)
		(layer "B.Cu")
		(net "P2V5_AUX")
	)
	(segment
		(start 72.39762 -53.215794)
		(end 72.670924 -53.489098)
		(width 0.381)
		(layer "B.Cu")
		(net "P2V5_AUX")
	)
	(segment
		(start 80.306672 -43.022012)
		(end 79.99222 -42.70756)
		(width 0.381)
		(layer "B.Cu")
		(net "P2V5_AUX")
	)
	(segment
		(start 62.494922 -58.57113)
		(end 62.890146 -58.966354)
		(width 0.13716)
		(layer "F.Cu")
		(net "P2E_PCH_TX_DP")
	)
	(via
		(at 62.890146 -58.966354)
		(size 0.4572)
		(drill 0.254)
		(layers "F.Cu" "B.Cu")
		(net "P2E_PCH_TX_DP")
	)
	(segment
		(start 62.2681 -61.048646)
		(end 62.50051 -60.816236)
		(width 0.14224)
		(layer "B.Cu")
		(net "P2E_PCH_TX_DP")
	)
	(segment
		(start 62.6745 -59.384692)
		(end 62.6745 -59.182)
		(width 0.14224)
		(layer "B.Cu")
		(net "P2E_PCH_TX_DP")
	)
	(segment
		(start 62.6745 -59.182)
		(end 62.890146 -58.966354)
		(width 0.14224)
		(layer "B.Cu")
		(net "P2E_PCH_TX_DP")
	)
	(segment
		(start 62.7507 -60.21197)
		(end 62.7507 -59.460892)
		(width 0.14224)
		(layer "B.Cu")
		(net "P2E_PCH_TX_DP")
	)
	(segment
		(start 62.50051 -60.816236)
		(end 62.7507 -60.21197)
		(width 0.14224)
		(layer "B.Cu")
		(net "P2E_PCH_TX_DP")
	)
	(segment
		(start 62.2681 -61.260736)
		(end 62.2681 -61.048646)
		(width 0.14224)
		(layer "B.Cu")
		(net "P2E_PCH_TX_DP")
	)
	(segment
		(start 62.7507 -59.460892)
		(end 62.6745 -59.384692)
		(width 0.14224)
		(layer "B.Cu")
		(net "P2E_PCH_TX_DP")
	)
	(segment
		(start 62.59322 -61.585856)
		(end 62.2681 -61.260736)
		(width 0.14224)
		(layer "B.Cu")
		(net "P2E_PCH_TX_DP")
	)
	(segment
		(start 61.695076 -58.57113)
		(end 62.0903 -58.966354)
		(width 0.13716)
		(layer "F.Cu")
		(net "P2E_PCH_TX_DN")
	)
	(via
		(at 62.0903 -58.966354)
		(size 0.4572)
		(drill 0.254)
		(layers "F.Cu" "B.Cu")
		(net "P2E_PCH_TX_DN")
	)
	(segment
		(start 61.8998 -60.895992)
		(end 62.18809 -60.607448)
		(width 0.14224)
		(layer "B.Cu")
		(net "P2E_PCH_TX_DN")
	)
	(segment
		(start 62.3062 -59.537346)
		(end 62.3062 -59.182254)
		(width 0.14224)
		(layer "B.Cu")
		(net "P2E_PCH_TX_DN")
	)
	(segment
		(start 62.3824 -60.138564)
		(end 62.3824 -59.613546)
		(width 0.14224)
		(layer "B.Cu")
		(net "P2E_PCH_TX_DN")
	)
	(segment
		(start 62.3062 -59.182254)
		(end 62.0903 -58.966354)
		(width 0.14224)
		(layer "B.Cu")
		(net "P2E_PCH_TX_DN")
	)
	(segment
		(start 62.18809 -60.607448)
		(end 62.3824 -60.138564)
		(width 0.14224)
		(layer "B.Cu")
		(net "P2E_PCH_TX_DN")
	)
	(segment
		(start 62.3824 -59.613546)
		(end 62.3062 -59.537346)
		(width 0.14224)
		(layer "B.Cu")
		(net "P2E_PCH_TX_DN")
	)
	(segment
		(start 61.57722 -61.585856)
		(end 61.8998 -61.263276)
		(width 0.14224)
		(layer "B.Cu")
		(net "P2E_PCH_TX_DN")
	)
	(segment
		(start 61.8998 -61.263276)
		(end 61.8998 -60.895992)
		(width 0.14224)
		(layer "B.Cu")
		(net "P2E_PCH_TX_DN")
	)
	(segment
		(start 58.090308 -53.366416)
		(end 57.695084 -52.971192)
		(width 0.3556)
		(layer "F.Cu")
		(net "P1V8_STBY_RC_VCC18A")
	)
	(via
		(at 58.090308 -53.366416)
		(size 0.4572)
		(drill 0.254)
		(layers "F.Cu" "B.Cu")
		(net "P1V8_STBY_RC_VCC18A")
	)
	(via
		(at 69.1642 -63.754)
		(size 0.508)
		(drill 0.254)
		(layers "F.Cu" "B.Cu")
		(net "P1V8_STBY_RC_VCC18A")
	)
	(via
		(at 67.728338 -64.169544)
		(size 0.6604)
		(drill 0.3302)
		(layers "F.Cu" "B.Cu")
		(net "P1V8_STBY_RC_VCC18A")
	)
	(segment
		(start 57.383426 -53.376322)
		(end 58.080402 -53.376322)
		(width 0.3556)
		(layer "B.Cu")
		(net "P1V8_STBY_RC_VCC18A")
	)
	(segment
		(start 58.080402 -53.376322)
		(end 58.090308 -53.366416)
		(width 0.3556)
		(layer "B.Cu")
		(net "P1V8_STBY_RC_VCC18A")
	)
	(segment
		(start 58.49493 -52.971192)
		(end 58.890154 -53.366416)
		(width 0.381)
		(layer "F.Cu")
		(net "P1V8_STBY_PE_VCC18A")
	)
	(via
		(at 58.890154 -53.366416)
		(size 0.4572)
		(drill 0.254)
		(layers "F.Cu" "B.Cu")
		(net "P1V8_STBY_PE_VCC18A")
	)
	(via
		(at 70.1548 -63.881)
		(size 0.508)
		(drill 0.254)
		(layers "F.Cu" "B.Cu")
		(net "P1V8_STBY_PE_VCC18A")
	)
	(via
		(at 71.140828 -63.837312)
		(size 0.508)
		(drill 0.254)
		(layers "F.Cu" "B.Cu")
		(net "P1V8_STBY_PE_VCC18A")
	)
	(via
		(at 70.619366 -63.273432)
		(size 0.6604)
		(drill 0.3302)
		(layers "F.Cu" "B.Cu")
		(net "P1V8_STBY_PE_VCC18A")
	)
	(segment
		(start 58.679334 -53.577236)
		(end 58.890154 -53.366416)
		(width 0.3556)
		(layer "B.Cu")
		(net "P1V8_STBY_PE_VCC18A")
	)
	(segment
		(start 58.679334 -54.016148)
		(end 58.679334 -53.577236)
		(width 0.3556)
		(layer "B.Cu")
		(net "P1V8_STBY_PE_VCC18A")
	)
	(segment
		(start 59.29503 -52.971192)
		(end 59.690254 -53.366416)
		(width 0.3556)
		(layer "F.Cu")
		(net "P1V8_STBY_DP_VCC18A")
	)
	(via
		(at 59.690254 -53.366416)
		(size 0.4572)
		(drill 0.254)
		(layers "F.Cu" "B.Cu")
		(net "P1V8_STBY_DP_VCC18A")
	)
	(via
		(at 73.584054 -64.942466)
		(size 0.6604)
		(drill 0.3302)
		(layers "F.Cu" "B.Cu")
		(net "P1V8_STBY_DP_VCC18A")
	)
	(via
		(at 72.129396 -63.848488)
		(size 0.508)
		(drill 0.254)
		(layers "F.Cu" "B.Cu")
		(net "P1V8_STBY_DP_VCC18A")
	)
	(via
		(at 72.8472 -63.8556)
		(size 0.508)
		(drill 0.254)
		(layers "F.Cu" "B.Cu")
		(net "P1V8_STBY_DP_VCC18A")
	)
	(segment
		(start 59.706256 -54.016148)
		(end 59.706256 -53.382418)
		(width 0.3556)
		(layer "B.Cu")
		(net "P1V8_STBY_DP_VCC18A")
	)
	(segment
		(start 59.706256 -53.382418)
		(end 59.690254 -53.366416)
		(width 0.3556)
		(layer "B.Cu")
		(net "P1V8_STBY_DP_VCC18A")
	)
	(segment
		(start 61.695076 -48.9712)
		(end 62.0903 -48.575976)
		(width 0.381)
		(layer "F.Cu")
		(net "P1V8_STBY_AVDDPLL")
	)
	(via
		(at 68.327016 -36.6903)
		(size 0.508)
		(drill 0.254)
		(layers "F.Cu" "B.Cu")
		(net "P1V8_STBY_AVDDPLL")
	)
	(via
		(at 68.327016 -36.0553)
		(size 0.508)
		(drill 0.254)
		(layers "F.Cu" "B.Cu")
		(net "P1V8_STBY_AVDDPLL")
	)
	(via
		(at 62.0903 -48.575976)
		(size 0.4572)
		(drill 0.254)
		(layers "F.Cu" "B.Cu")
		(net "P1V8_STBY_AVDDPLL")
	)
	(segment
		(start 61.730636 -48.93564)
		(end 62.0903 -48.575976)
		(width 0.3556)
		(layer "B.Cu")
		(net "P1V8_STBY_AVDDPLL")
	)
	(segment
		(start 61.730636 -49.314354)
		(end 61.730636 -48.93564)
		(width 0.3556)
		(layer "B.Cu")
		(net "P1V8_STBY_AVDDPLL")
	)
	(segment
		(start 57.695084 -46.571154)
		(end 58.090308 -46.17593)
		(width 0.3556)
		(layer "F.Cu")
		(net "P1V8_BMC_USB2AV18")
	)
	(via
		(at 72.644 -39.878)
		(size 0.6604)
		(drill 0.3302)
		(layers "F.Cu" "B.Cu")
		(net "P1V8_BMC_USB2AV18")
	)
	(via
		(at 58.090308 -46.17593)
		(size 0.4572)
		(drill 0.254)
		(layers "F.Cu" "B.Cu")
		(net "P1V8_BMC_USB2AV18")
	)
	(via
		(at 71.983346 -38.999668)
		(size 0.508)
		(drill 0.254)
		(layers "F.Cu" "B.Cu")
		(net "P1V8_BMC_USB2AV18")
	)
	(via
		(at 72.618346 -38.999668)
		(size 0.508)
		(drill 0.254)
		(layers "F.Cu" "B.Cu")
		(net "P1V8_BMC_USB2AV18")
	)
	(segment
		(start 59.29503 -44.971208)
		(end 59.690254 -44.575984)
		(width 0.3556)
		(layer "F.Cu")
		(net "P1V8_AUX")
	)
	(segment
		(start 55.295038 -49.7713)
		(end 55.295038 -48.9712)
		(width 0.381)
		(layer "F.Cu")
		(net "P1V8_AUX")
	)
	(segment
		(start 70.5866 -18.4658)
		(end 71.0692 -18.4658)
		(width 0.4572)
		(layer "F.Cu")
		(net "P1V8_AUX")
	)
	(segment
		(start 55.295038 -48.171354)
		(end 55.690262 -47.77613)
		(width 0.3556)
		(layer "F.Cu")
		(net "P1V8_AUX")
	)
	(segment
		(start 56.094884 -50.571146)
		(end 56.094884 -50.561748)
		(width 0.381)
		(layer "F.Cu")
		(net "P1V8_AUX")
	)
	(segment
		(start 60.894976 -52.971192)
		(end 61.2902 -53.366416)
		(width 0.3556)
		(layer "F.Cu")
		(net "P1V8_AUX")
	)
	(segment
		(start 60.894976 -52.171346)
		(end 60.894976 -52.971192)
		(width 0.3556)
		(layer "F.Cu")
		(net "P1V8_AUX")
	)
	(segment
		(start 55.295038 -52.171346)
		(end 55.690262 -52.56657)
		(width 0.3556)
		(layer "F.Cu")
		(net "P1V8_AUX")
	)
	(segment
		(start 56.094884 -45.771308)
		(end 56.490108 -45.376084)
		(width 0.381)
		(layer "F.Cu")
		(net "P1V8_AUX")
	)
	(segment
		(start 55.295038 -53.771292)
		(end 55.690262 -54.166516)
		(width 0.3556)
		(layer "F.Cu")
		(net "P1V8_AUX")
	)
	(segment
		(start 54.494938 -53.771292)
		(end 54.099714 -54.166516)
		(width 0.381)
		(layer "F.Cu")
		(net "P1V8_AUX")
	)
	(segment
		(start 56.094884 -49.7713)
		(end 56.490108 -50.166524)
		(width 0.381)
		(layer "F.Cu")
		(net "P1V8_AUX")
	)
	(segment
		(start 55.295038 -51.371246)
		(end 55.690262 -51.76647)
		(width 0.3556)
		(layer "F.Cu")
		(net "P1V8_AUX")
	)
	(segment
		(start 56.094884 -50.561748)
		(end 56.490108 -50.166524)
		(width 0.381)
		(layer "F.Cu")
		(net "P1V8_AUX")
	)
	(segment
		(start 70.358 -19.28495)
		(end 70.358 -18.6944)
		(width 0.4572)
		(layer "F.Cu")
		(net "P1V8_AUX")
	)
	(segment
		(start 70.358 -18.6944)
		(end 70.5866 -18.4658)
		(width 0.4572)
		(layer "F.Cu")
		(net "P1V8_AUX")
	)
	(segment
		(start 56.094884 -44.98086)
		(end 56.490108 -45.376084)
		(width 0.381)
		(layer "F.Cu")
		(net "P1V8_AUX")
	)
	(segment
		(start 55.295038 -52.971192)
		(end 55.690262 -53.366416)
		(width 0.3556)
		(layer "F.Cu")
		(net "P1V8_AUX")
	)
	(segment
		(start 56.094884 -44.971208)
		(end 56.094884 -44.98086)
		(width 0.381)
		(layer "F.Cu")
		(net "P1V8_AUX")
	)
	(segment
		(start 72.39 -19.28495)
		(end 71.374 -19.28495)
		(width 0.381)
		(layer "F.Cu")
		(net "P1V8_AUX")
	)
	(segment
		(start 59.29503 -45.771308)
		(end 59.690254 -45.376084)
		(width 0.3556)
		(layer "F.Cu")
		(net "P1V8_AUX")
	)
	(segment
		(start 55.295038 -47.380906)
		(end 55.690262 -47.77613)
		(width 0.3556)
		(layer "F.Cu")
		(net "P1V8_AUX")
	)
	(segment
		(start 55.690262 -50.166524)
		(end 55.295038 -49.7713)
		(width 0.381)
		(layer "F.Cu")
		(net "P1V8_AUX")
	)
	(segment
		(start 56.094884 -48.9712)
		(end 56.490108 -48.575976)
		(width 0.3556)
		(layer "F.Cu")
		(net "P1V8_AUX")
	)
	(segment
		(start 55.295038 -50.571146)
		(end 55.690262 -50.96637)
		(width 0.3556)
		(layer "F.Cu")
		(net "P1V8_AUX")
	)
	(segment
		(start 71.374 -19.28495)
		(end 70.358 -19.28495)
		(width 0.381)
		(layer "F.Cu")
		(net "P1V8_AUX")
	)
	(segment
		(start 55.295038 -47.371254)
		(end 55.295038 -47.380906)
		(width 0.3556)
		(layer "F.Cu")
		(net "P1V8_AUX")
	)
	(via
		(at 71.0692 -18.4658)
		(size 0.508)
		(drill 0.254)
		(layers "F.Cu" "B.Cu")
		(net "P1V8_AUX")
	)
	(via
		(at 56.490108 -50.166524)
		(size 0.4572)
		(drill 0.254)
		(layers "F.Cu" "B.Cu")
		(net "P1V8_AUX")
	)
	(via
		(at 55.690262 -51.76647)
		(size 0.4572)
		(drill 0.254)
		(layers "F.Cu" "B.Cu")
		(net "P1V8_AUX")
	)
	(via
		(at 55.690262 -50.166524)
		(size 0.4572)
		(drill 0.254)
		(layers "F.Cu" "B.Cu")
		(net "P1V8_AUX")
	)
	(via
		(at 72.226678 -67.824858)
		(size 0.508)
		(drill 0.254)
		(layers "F.Cu" "B.Cu")
		(net "P1V8_AUX")
	)
	(via
		(at 56.490108 -45.376084)
		(size 0.4572)
		(drill 0.254)
		(layers "F.Cu" "B.Cu")
		(net "P1V8_AUX")
	)
	(via
		(at 61.2902 -53.366416)
		(size 0.4572)
		(drill 0.254)
		(layers "F.Cu" "B.Cu")
		(net "P1V8_AUX")
	)
	(via
		(at 59.690254 -44.575984)
		(size 0.4572)
		(drill 0.254)
		(layers "F.Cu" "B.Cu")
		(net "P1V8_AUX")
	)
	(via
		(at 68.184268 -38.937946)
		(size 0.508)
		(drill 0.254)
		(layers "F.Cu" "B.Cu")
		(net "P1V8_AUX")
	)
	(via
		(at 39.050976 -55.22849)
		(size 0.508)
		(drill 0.254)
		(layers "F.Cu" "B.Cu")
		(net "P1V8_AUX")
	)
	(via
		(at 55.690262 -52.56657)
		(size 0.4572)
		(drill 0.254)
		(layers "F.Cu" "B.Cu")
		(net "P1V8_AUX")
	)
	(via
		(at 55.690262 -54.166516)
		(size 0.4572)
		(drill 0.254)
		(layers "F.Cu" "B.Cu")
		(net "P1V8_AUX")
	)
	(via
		(at 56.490108 -48.575976)
		(size 0.4572)
		(drill 0.254)
		(layers "F.Cu" "B.Cu")
		(net "P1V8_AUX")
	)
	(via
		(at 65.786 -12.065)
		(size 0.508)
		(drill 0.254)
		(layers "F.Cu" "B.Cu")
		(net "P1V8_AUX")
	)
	(via
		(at 67.8434 -67.31)
		(size 0.508)
		(drill 0.254)
		(layers "F.Cu" "B.Cu")
		(net "P1V8_AUX")
	)
	(via
		(at 71.12762 -67.842892)
		(size 0.508)
		(drill 0.254)
		(layers "F.Cu" "B.Cu")
		(net "P1V8_AUX")
	)
	(via
		(at 39.45255 -35.41776)
		(size 0.508)
		(drill 0.254)
		(layers "F.Cu" "B.Cu")
		(net "P1V8_AUX")
	)
	(via
		(at 72.226678 -67.062858)
		(size 0.508)
		(drill 0.254)
		(layers "F.Cu" "B.Cu")
		(net "P1V8_AUX")
	)
	(via
		(at 38.5826 -54.1528)
		(size 0.508)
		(drill 0.254)
		(layers "F.Cu" "B.Cu")
		(net "P1V8_AUX")
	)
	(via
		(at 55.690262 -47.77613)
		(size 0.4572)
		(drill 0.254)
		(layers "F.Cu" "B.Cu")
		(net "P1V8_AUX")
	)
	(via
		(at 51.881532 -72.819514)
		(size 0.508)
		(drill 0.254)
		(layers "F.Cu" "B.Cu")
		(net "P1V8_AUX")
	)
	(via
		(at 55.690262 -50.96637)
		(size 0.4572)
		(drill 0.254)
		(layers "F.Cu" "B.Cu")
		(net "P1V8_AUX")
	)
	(via
		(at 39.0652 -54.5846)
		(size 0.508)
		(drill 0.254)
		(layers "F.Cu" "B.Cu")
		(net "P1V8_AUX")
	)
	(via
		(at 67.549268 -38.937946)
		(size 0.508)
		(drill 0.254)
		(layers "F.Cu" "B.Cu")
		(net "P1V8_AUX")
	)
	(via
		(at 69.08546 -92.03944)
		(size 0.508)
		(drill 0.254)
		(layers "F.Cu" "B.Cu")
		(net "P1V8_AUX")
	)
	(via
		(at 72.60844 -85.377274)
		(size 0.508)
		(drill 0.254)
		(layers "F.Cu" "B.Cu")
		(net "P1V8_AUX")
	)
	(via
		(at 39.1287 -34.8234)
		(size 0.508)
		(drill 0.254)
		(layers "F.Cu" "B.Cu")
		(net "P1V8_AUX")
	)
	(via
		(at 55.690262 -53.366416)
		(size 0.4572)
		(drill 0.254)
		(layers "F.Cu" "B.Cu")
		(net "P1V8_AUX")
	)
	(via
		(at 68.184268 -38.302946)
		(size 0.508)
		(drill 0.254)
		(layers "F.Cu" "B.Cu")
		(net "P1V8_AUX")
	)
	(via
		(at 74.041 -72.43318)
		(size 0.508)
		(drill 0.254)
		(layers "F.Cu" "B.Cu")
		(net "P1V8_AUX")
	)
	(via
		(at 57.871614 -70.046342)
		(size 0.508)
		(drill 0.254)
		(layers "F.Cu" "B.Cu")
		(net "P1V8_AUX")
	)
	(via
		(at 67.549268 -38.302946)
		(size 0.508)
		(drill 0.254)
		(layers "F.Cu" "B.Cu")
		(net "P1V8_AUX")
	)
	(via
		(at 71.12762 -67.080892)
		(size 0.508)
		(drill 0.254)
		(layers "F.Cu" "B.Cu")
		(net "P1V8_AUX")
	)
	(via
		(at 54.099714 -54.166516)
		(size 0.4572)
		(drill 0.254)
		(layers "F.Cu" "B.Cu")
		(net "P1V8_AUX")
	)
	(via
		(at 59.690254 -45.376084)
		(size 0.4572)
		(drill 0.254)
		(layers "F.Cu" "B.Cu")
		(net "P1V8_AUX")
	)
	(via
		(at 50.900584 -74.048874)
		(size 0.6604)
		(drill 0.3302)
		(layers "F.Cu" "B.Cu")
		(net "P1V8_AUX")
	)
	(via
		(at 74.041 -73.06818)
		(size 0.508)
		(drill 0.254)
		(layers "F.Cu" "B.Cu")
		(net "P1V8_AUX")
	)
	(via
		(at 68.330064 -67.815714)
		(size 0.508)
		(drill 0.254)
		(layers "F.Cu" "B.Cu")
		(net "P1V8_AUX")
	)
	(segment
		(start 67.05346 -93.618304)
		(end 67.05346 -93.82506)
		(width 0.4572)
		(layer "B.Cu")
		(net "P1V8_AUX")
	)
	(segment
		(start 68.94195 -94.48165)
		(end 69.4436 -93.98)
		(width 0.4572)
		(layer "B.Cu")
		(net "P1V8_AUX")
	)
	(segment
		(start 69.4436 -93.98)
		(end 69.4436 -92.39758)
		(width 0.4572)
		(layer "B.Cu")
		(net "P1V8_AUX")
	)
	(segment
		(start 65.786 -12.065)
		(end 66.167 -12.446)
		(width 0.4572)
		(layer "B.Cu")
		(net "P1V8_AUX")
	)
	(segment
		(start 67.05346 -93.82506)
		(end 67.71005 -94.48165)
		(width 0.4572)
		(layer "B.Cu")
		(net "P1V8_AUX")
	)
	(segment
		(start 61.354208 -53.366416)
		(end 62.103 -54.115208)
		(width 0.254)
		(layer "B.Cu")
		(net "P1V8_AUX")
	)
	(segment
		(start 62.103 -54.115208)
		(end 62.103 -54.20995)
		(width 0.254)
		(layer "B.Cu")
		(net "P1V8_AUX")
	)
	(segment
		(start 68.6308 -94.48165)
		(end 68.94195 -94.48165)
		(width 0.4572)
		(layer "B.Cu")
		(net "P1V8_AUX")
	)
	(segment
		(start 66.167 -12.446)
		(end 66.40195 -12.446)
		(width 0.4572)
		(layer "B.Cu")
		(net "P1V8_AUX")
	)
	(segment
		(start 68.6308 -94.48165)
		(end 68.6308 -94.488)
		(width 0.4572)
		(layer "B.Cu")
		(net "P1V8_AUX")
	)
	(segment
		(start 69.4436 -92.39758)
		(end 69.08546 -92.03944)
		(width 0.4572)
		(layer "B.Cu")
		(net "P1V8_AUX")
	)
	(segment
		(start 57.871614 -70.046342)
		(end 57.262014 -70.046342)
		(width 0.381)
		(layer "B.Cu")
		(net "P1V8_AUX")
	)
	(segment
		(start 61.2902 -53.366416)
		(end 61.354208 -53.366416)
		(width 0.254)
		(layer "B.Cu")
		(net "P1V8_AUX")
	)
	(segment
		(start 67.71005 -94.48165)
		(end 68.6308 -94.48165)
		(width 0.4572)
		(layer "B.Cu")
		(net "P1V8_AUX")
	)
	(segment
		(start 67.1068 -35.9918)
		(end 67.1068 -37.338)
		(width 0.4572)
		(layer "In4.Cu")
		(net "P1V8_AUX")
	)
	(segment
		(start 71.0692 -18.4658)
		(end 71.0692 -19.1008)
		(width 0.4572)
		(layer "In4.Cu")
		(net "P1V8_AUX")
	)
	(segment
		(start 67.1068 -37.338)
		(end 67.549268 -37.780468)
		(width 0.4572)
		(layer "In4.Cu")
		(net "P1V8_AUX")
	)
	(segment
		(start 67.517772 -30.564836)
		(end 67.517772 -31.1531)
		(width 0.4572)
		(layer "In4.Cu")
		(net "P1V8_AUX")
	)
	(segment
		(start 72.0725 -24.0411)
		(end 72.0725 -26.3271)
		(width 0.4572)
		(layer "In4.Cu")
		(net "P1V8_AUX")
	)
	(segment
		(start 72.39635 -21.60905)
		(end 72.0344 -21.971)
		(width 0.4572)
		(layer "In4.Cu")
		(net "P1V8_AUX")
	)
	(segment
		(start 71.6534 -21.971)
		(end 71.2724 -22.352)
		(width 0.4572)
		(layer "In4.Cu")
		(net "P1V8_AUX")
	)
	(segment
		(start 72.39635 -20.42795)
		(end 72.39635 -21.60905)
		(width 0.4572)
		(layer "In4.Cu")
		(net "P1V8_AUX")
	)
	(segment
		(start 67.517772 -31.1531)
		(end 67.7672 -31.402528)
		(width 0.4572)
		(layer "In4.Cu")
		(net "P1V8_AUX")
	)
	(segment
		(start 72.0344 -21.971)
		(end 71.6534 -21.971)
		(width 0.4572)
		(layer "In4.Cu")
		(net "P1V8_AUX")
	)
	(segment
		(start 68.286884 -34.022284)
		(end 68.286884 -34.430716)
		(width 0.4572)
		(layer "In4.Cu")
		(net "P1V8_AUX")
	)
	(segment
		(start 72.0725 -26.3271)
		(end 69.4182 -28.9814)
		(width 0.4572)
		(layer "In4.Cu")
		(net "P1V8_AUX")
	)
	(segment
		(start 70.0151 -92.03944)
		(end 71.76008 -90.29446)
		(width 0.508)
		(layer "In4.Cu")
		(net "P1V8_AUX")
	)
	(segment
		(start 69.08546 -92.03944)
		(end 70.0151 -92.03944)
		(width 0.508)
		(layer "In4.Cu")
		(net "P1V8_AUX")
	)
	(segment
		(start 71.0692 -19.1008)
		(end 72.39635 -20.42795)
		(width 0.4572)
		(layer "In4.Cu")
		(net "P1V8_AUX")
	)
	(segment
		(start 71.2724 -23.241)
		(end 72.0725 -24.0411)
		(width 0.4572)
		(layer "In4.Cu")
		(net "P1V8_AUX")
	)
	(segment
		(start 68.286884 -34.430716)
		(end 67.7672 -34.9504)
		(width 0.4572)
		(layer "In4.Cu")
		(net "P1V8_AUX")
	)
	(segment
		(start 67.549268 -37.780468)
		(end 67.549268 -38.302946)
		(width 0.4572)
		(layer "In4.Cu")
		(net "P1V8_AUX")
	)
	(segment
		(start 67.7672 -33.5026)
		(end 68.286884 -34.022284)
		(width 0.4572)
		(layer "In4.Cu")
		(net "P1V8_AUX")
	)
	(segment
		(start 71.2724 -22.352)
		(end 71.2724 -23.241)
		(width 0.4572)
		(layer "In4.Cu")
		(net "P1V8_AUX")
	)
	(segment
		(start 67.7672 -35.3314)
		(end 67.1068 -35.9918)
		(width 0.4572)
		(layer "In4.Cu")
		(net "P1V8_AUX")
	)
	(segment
		(start 69.101208 -28.9814)
		(end 67.517772 -30.564836)
		(width 0.4572)
		(layer "In4.Cu")
		(net "P1V8_AUX")
	)
	(segment
		(start 67.7672 -31.402528)
		(end 67.7672 -33.5026)
		(width 0.4572)
		(layer "In4.Cu")
		(net "P1V8_AUX")
	)
	(segment
		(start 71.76008 -86.225634)
		(end 72.60844 -85.377274)
		(width 0.508)
		(layer "In4.Cu")
		(net "P1V8_AUX")
	)
	(segment
		(start 71.76008 -90.29446)
		(end 71.76008 -86.225634)
		(width 0.508)
		(layer "In4.Cu")
		(net "P1V8_AUX")
	)
	(segment
		(start 69.4182 -28.9814)
		(end 69.101208 -28.9814)
		(width 0.4572)
		(layer "In4.Cu")
		(net "P1V8_AUX")
	)
	(segment
		(start 67.7672 -34.9504)
		(end 67.7672 -35.3314)
		(width 0.4572)
		(layer "In4.Cu")
		(net "P1V8_AUX")
	)
	(segment
		(start 65.786 -13.1826)
		(end 71.0692 -18.4658)
		(width 0.4572)
		(layer "In9.Cu")
		(net "P1V8_AUX")
	)
	(segment
		(start 65.786 -12.065)
		(end 65.786 -13.1826)
		(width 0.4572)
		(layer "In9.Cu")
		(net "P1V8_AUX")
	)
	(segment
		(start 60.894976 -48.171354)
		(end 61.2902 -47.77613)
		(width 0.381)
		(layer "F.Cu")
		(net "P1V2_STBY_MVDD_CK")
	)
	(via
		(at 65.659 -42.926)
		(size 0.6604)
		(drill 0.3302)
		(layers "F.Cu" "B.Cu")
		(net "P1V2_STBY_MVDD_CK")
	)
	(via
		(at 67.1068 -43.7642)
		(size 0.6604)
		(drill 0.3302)
		(layers "F.Cu" "B.Cu")
		(net "P1V2_STBY_MVDD_CK")
	)
	(via
		(at 67.367404 -41.905428)
		(size 0.508)
		(drill 0.254)
		(layers "F.Cu" "B.Cu")
		(net "P1V2_STBY_MVDD_CK")
	)
	(via
		(at 61.2902 -47.77613)
		(size 0.4572)
		(drill 0.254)
		(layers "F.Cu" "B.Cu")
		(net "P1V2_STBY_MVDD_CK")
	)
	(via
		(at 65.8368 -41.5544)
		(size 0.6604)
		(drill 0.3302)
		(layers "F.Cu" "B.Cu")
		(net "P1V2_STBY_MVDD_CK")
	)
	(via
		(at 68.359782 -41.905428)
		(size 0.508)
		(drill 0.254)
		(layers "F.Cu" "B.Cu")
		(net "P1V2_STBY_MVDD_CK")
	)
	(segment
		(start 48.895 -52.171346)
		(end 48.499776 -51.776122)
		(width 0.381)
		(layer "F.Cu")
		(net "P1V2_P1V0_I3C_VDDL2")
	)
	(segment
		(start 48.499776 -51.776122)
		(end 48.499776 -51.76647)
		(width 0.381)
		(layer "F.Cu")
		(net "P1V2_P1V0_I3C_VDDL2")
	)
	(via
		(at 48.499776 -51.76647)
		(size 0.4572)
		(drill 0.254)
		(layers "F.Cu" "B.Cu")
		(net "P1V2_P1V0_I3C_VDDL2")
	)
	(via
		(at 41.656 -50.2158)
		(size 0.6604)
		(drill 0.3302)
		(layers "F.Cu" "B.Cu")
		(net "P1V2_P1V0_I3C_VDDL2")
	)
	(via
		(at 42.006774 -51.123596)
		(size 0.508)
		(drill 0.254)
		(layers "F.Cu" "B.Cu")
		(net "P1V2_P1V0_I3C_VDDL2")
	)
	(via
		(at 42.926 -50.546)
		(size 0.6604)
		(drill 0.3302)
		(layers "F.Cu" "B.Cu")
		(net "P1V2_P1V0_I3C_VDDL2")
	)
	(via
		(at 42.19956 -52.31257)
		(size 0.508)
		(drill 0.254)
		(layers "F.Cu" "B.Cu")
		(net "P1V2_P1V0_I3C_VDDL2")
	)
	(segment
		(start 48.0949 -52.971192)
		(end 48.104552 -52.971192)
		(width 0.3556)
		(layer "F.Cu")
		(net "P1V2_P1V0_I3C_VDDL1")
	)
	(segment
		(start 48.104552 -52.971192)
		(end 48.499776 -53.366416)
		(width 0.3556)
		(layer "F.Cu")
		(net "P1V2_P1V0_I3C_VDDL1")
	)
	(via
		(at 40.005 -54.5338)
		(size 0.6604)
		(drill 0.3302)
		(layers "F.Cu" "B.Cu")
		(net "P1V2_P1V0_I3C_VDDL1")
	)
	(via
		(at 48.499776 -53.366416)
		(size 0.4572)
		(drill 0.254)
		(layers "F.Cu" "B.Cu")
		(net "P1V2_P1V0_I3C_VDDL1")
	)
	(via
		(at 41.298876 -53.36159)
		(size 0.508)
		(drill 0.254)
		(layers "F.Cu" "B.Cu")
		(net "P1V2_P1V0_I3C_VDDL1")
	)
	(via
		(at 43.05808 -64.21374)
		(size 0.6604)
		(drill 0.3302)
		(layers "F.Cu" "B.Cu")
		(net "P1V2_P1V0_I3C_VDDL1")
	)
	(via
		(at 44.2976 -64.702944)
		(size 0.508)
		(drill 0.254)
		(layers "F.Cu" "B.Cu")
		(net "P1V2_P1V0_I3C_VDDL1")
	)
	(via
		(at 41.298876 -53.99659)
		(size 0.508)
		(drill 0.254)
		(layers "F.Cu" "B.Cu")
		(net "P1V2_P1V0_I3C_VDDL1")
	)
	(segment
		(start 44.2976 -65.239392)
		(end 44.193968 -65.343024)
		(width 0.381)
		(layer "B.Cu")
		(net "P1V2_P1V0_I3C_VDDL1")
	)
	(segment
		(start 48.499776 -53.366416)
		(end 49.001934 -53.366416)
		(width 0.3048)
		(layer "B.Cu")
		(net "P1V2_P1V0_I3C_VDDL1")
	)
	(segment
		(start 44.19346 -65.343532)
		(end 43.163236 -65.343532)
		(width 0.381)
		(layer "B.Cu")
		(net "P1V2_P1V0_I3C_VDDL1")
	)
	(segment
		(start 41.913302 -63.356744)
		(end 40.887142 -63.356744)
		(width 0.381)
		(layer "B.Cu")
		(net "P1V2_P1V0_I3C_VDDL1")
	)
	(segment
		(start 44.2976 -64.702944)
		(end 44.2976 -65.239392)
		(width 0.381)
		(layer "B.Cu")
		(net "P1V2_P1V0_I3C_VDDL1")
	)
	(segment
		(start 39.803578 -65.376552)
		(end 39.80053 -65.3796)
		(width 0.381)
		(layer "B.Cu")
		(net "P1V2_P1V0_I3C_VDDL1")
	)
	(segment
		(start 44.193968 -65.343024)
		(end 44.19346 -65.343532)
		(width 0.381)
		(layer "B.Cu")
		(net "P1V2_P1V0_I3C_VDDL1")
	)
	(segment
		(start 43.05808 -64.21374)
		(end 43.547284 -64.702944)
		(width 0.381)
		(layer "B.Cu")
		(net "P1V2_P1V0_I3C_VDDL1")
	)
	(segment
		(start 40.83431 -65.376552)
		(end 39.803578 -65.376552)
		(width 0.381)
		(layer "B.Cu")
		(net "P1V2_P1V0_I3C_VDDL1")
	)
	(segment
		(start 43.05808 -64.21374)
		(end 42.201084 -63.356744)
		(width 0.381)
		(layer "B.Cu")
		(net "P1V2_P1V0_I3C_VDDL1")
	)
	(segment
		(start 41.859454 -65.376044)
		(end 40.834818 -65.376044)
		(width 0.381)
		(layer "B.Cu")
		(net "P1V2_P1V0_I3C_VDDL1")
	)
	(segment
		(start 43.547284 -64.702944)
		(end 44.2976 -64.702944)
		(width 0.381)
		(layer "B.Cu")
		(net "P1V2_P1V0_I3C_VDDL1")
	)
	(segment
		(start 49.001934 -53.366416)
		(end 49.10455 -53.2638)
		(width 0.3048)
		(layer "B.Cu")
		(net "P1V2_P1V0_I3C_VDDL1")
	)
	(segment
		(start 40.887142 -63.356744)
		(end 39.868602 -63.356744)
		(width 0.381)
		(layer "B.Cu")
		(net "P1V2_P1V0_I3C_VDDL1")
	)
	(segment
		(start 43.163236 -65.343532)
		(end 43.130724 -65.376044)
		(width 0.381)
		(layer "B.Cu")
		(net "P1V2_P1V0_I3C_VDDL1")
	)
	(segment
		(start 40.834818 -65.376044)
		(end 40.83431 -65.376552)
		(width 0.381)
		(layer "B.Cu")
		(net "P1V2_P1V0_I3C_VDDL1")
	)
	(segment
		(start 43.130724 -65.376044)
		(end 41.859454 -65.376044)
		(width 0.381)
		(layer "B.Cu")
		(net "P1V2_P1V0_I3C_VDDL1")
	)
	(segment
		(start 42.201084 -63.356744)
		(end 41.913302 -63.356744)
		(width 0.381)
		(layer "B.Cu")
		(net "P1V2_P1V0_I3C_VDDL1")
	)
	(segment
		(start 83.819238 -71.930514)
		(end 84.789518 -71.930514)
		(width 0.381)
		(layer "F.Cu")
		(net "P1V2_AUX_VCC")
	)
	(segment
		(start 80.293972 -71.930514)
		(end 79.592424 -71.930514)
		(width 0.254)
		(layer "F.Cu")
		(net "P1V2_AUX_VCC")
	)
	(segment
		(start 83.194144 -71.930514)
		(end 83.819238 -71.930514)
		(width 0.254)
		(layer "F.Cu")
		(net "P1V2_AUX_VCC")
	)
	(segment
		(start 84.795106 -71.930514)
		(end 84.792312 -71.933308)
		(width 0.381)
		(layer "F.Cu")
		(net "P1V2_AUX_VCC")
	)
	(segment
		(start 84.792312 -71.933308)
		(end 85.461094 -71.933308)
		(width 0.381)
		(layer "F.Cu")
		(net "P1V2_AUX_VCC")
	)
	(segment
		(start 84.789518 -71.930514)
		(end 84.792312 -71.933308)
		(width 0.381)
		(layer "F.Cu")
		(net "P1V2_AUX_VCC")
	)
	(segment
		(start 84.795106 -70.858888)
		(end 84.795106 -71.930514)
		(width 0.381)
		(layer "F.Cu")
		(net "P1V2_AUX_VCC")
	)
	(segment
		(start 79.592424 -71.930514)
		(end 79.317088 -71.655178)
		(width 0.254)
		(layer "F.Cu")
		(net "P1V2_AUX_VCC")
	)
	(via
		(at 85.461094 -71.933308)
		(size 0.508)
		(drill 0.254)
		(layers "F.Cu" "B.Cu")
		(net "P1V2_AUX_VCC")
	)
	(via
		(at 79.317088 -71.655178)
		(size 0.508)
		(drill 0.254)
		(layers "F.Cu" "B.Cu")
		(net "P1V2_AUX_VCC")
	)
	(segment
		(start 85.461094 -71.933308)
		(end 85.182964 -71.655178)
		(width 0.254)
		(layer "B.Cu")
		(net "P1V2_AUX_VCC")
	)
	(segment
		(start 85.182964 -71.655178)
		(end 79.317088 -71.655178)
		(width 0.254)
		(layer "B.Cu")
		(net "P1V2_AUX_VCC")
	)
	(segment
		(start 78.830424 -69.407024)
		(end 78.898496 -69.338952)
		(width 0.254)
		(layer "F.Cu")
		(net "P1V2_AUX_MODE")
	)
	(segment
		(start 81.244186 -71.730616)
		(end 81.244186 -71.336408)
		(width 0.254)
		(layer "F.Cu")
		(net "P1V2_AUX_MODE")
	)
	(segment
		(start 81.244186 -71.336408)
		(end 79.695802 -69.788024)
		(width 0.254)
		(layer "F.Cu")
		(net "P1V2_AUX_MODE")
	)
	(segment
		(start 79.24673 -69.338952)
		(end 79.695802 -69.788024)
		(width 0.254)
		(layer "F.Cu")
		(net "P1V2_AUX_MODE")
	)
	(segment
		(start 78.898496 -69.338952)
		(end 79.24673 -69.338952)
		(width 0.254)
		(layer "F.Cu")
		(net "P1V2_AUX_MODE")
	)
	(segment
		(start 78.347824 -69.407024)
		(end 78.830424 -69.407024)
		(width 0.254)
		(layer "F.Cu")
		(net "P1V2_AUX_MODE")
	)
	(via
		(at 79.695802 -69.788024)
		(size 0.762)
		(drill 0.381)
		(layers "F.Cu" "B.Cu")
		(net "P1V2_AUX_MODE")
	)
	(segment
		(start 79.452216 -45.907452)
		(end 79.99222 -45.907452)
		(width 0.3556)
		(layer "F.Cu")
		(net "P1V2_AUX")
	)
	(segment
		(start 54.494938 -50.571146)
		(end 54.099714 -50.96637)
		(width 0.381)
		(layer "F.Cu")
		(net "P1V2_AUX")
	)
	(segment
		(start 52.094892 -46.571154)
		(end 52.104544 -46.571154)
		(width 0.381)
		(layer "F.Cu")
		(net "P1V2_AUX")
	)
	(segment
		(start 50.494946 -46.571154)
		(end 50.494946 -46.580806)
		(width 0.381)
		(layer "F.Cu")
		(net "P1V2_AUX")
	)
	(segment
		(start 48.895 -48.9712)
		(end 48.499776 -48.575976)
		(width 0.381)
		(layer "F.Cu")
		(net "P1V2_AUX")
	)
	(segment
		(start 73.852278 -47.507398)
		(end 73.470516 -47.125636)
		(width 0.3556)
		(layer "F.Cu")
		(net "P1V2_AUX")
	)
	(segment
		(start 54.494938 -47.371254)
		(end 54.099714 -46.97603)
		(width 0.381)
		(layer "F.Cu")
		(net "P1V2_AUX")
	)
	(segment
		(start 79.452216 -53.907436)
		(end 79.833978 -54.289198)
		(width 0.3556)
		(layer "F.Cu")
		(net "P1V2_AUX")
	)
	(segment
		(start 73.052432 -47.507398)
		(end 72.67067 -47.125636)
		(width 0.3556)
		(layer "F.Cu")
		(net "P1V2_AUX")
	)
	(segment
		(start 73.052432 -45.907452)
		(end 73.434194 -45.52569)
		(width 0.3556)
		(layer "F.Cu")
		(net "P1V2_AUX")
	)
	(segment
		(start 54.494938 -51.371246)
		(end 54.099714 -51.76647)
		(width 0.381)
		(layer "F.Cu")
		(net "P1V2_AUX")
	)
	(segment
		(start 73.052432 -53.907436)
		(end 72.67067 -54.285134)
		(width 0.3556)
		(layer "F.Cu")
		(net "P1V2_AUX")
	)
	(segment
		(start 79.739744 -37.159438)
		(end 79.739744 -36.549838)
		(width 0.381)
		(layer "F.Cu")
		(net "P1V2_AUX")
	)
	(segment
		(start 78.65237 -47.507398)
		(end 79.034132 -47.88916)
		(width 0.3556)
		(layer "F.Cu")
		(net "P1V2_AUX")
	)
	(segment
		(start 60.894976 -44.971208)
		(end 61.2902 -44.575984)
		(width 0.381)
		(layer "F.Cu")
		(net "P1V2_AUX")
	)
	(segment
		(start 48.895 -49.7713)
		(end 48.499776 -50.166524)
		(width 0.381)
		(layer "F.Cu")
		(net "P1V2_AUX")
	)
	(segment
		(start 53.695092 -52.171346)
		(end 53.299868 -52.56657)
		(width 0.381)
		(layer "F.Cu")
		(net "P1V2_AUX")
	)
	(segment
		(start 83.194144 -72.930512)
		(end 83.598766 -72.930512)
		(width 0.254)
		(layer "F.Cu")
		(net "P1V2_AUX")
	)
	(segment
		(start 60.894976 -47.371254)
		(end 61.2902 -46.97603)
		(width 0.381)
		(layer "F.Cu")
		(net "P1V2_AUX")
	)
	(segment
		(start 50.494946 -46.580806)
		(end 50.099722 -46.97603)
		(width 0.381)
		(layer "F.Cu")
		(net "P1V2_AUX")
	)
	(segment
		(start 48.895 -47.371254)
		(end 48.499776 -46.97603)
		(width 0.381)
		(layer "F.Cu")
		(net "P1V2_AUX")
	)
	(segment
		(start 60.894976 -46.571154)
		(end 60.894976 -45.771308)
		(width 0.381)
		(layer "F.Cu")
		(net "P1V2_AUX")
	)
	(segment
		(start 74.652378 -53.107336)
		(end 75.03414 -53.489098)
		(width 0.3556)
		(layer "F.Cu")
		(net "P1V2_AUX")
	)
	(segment
		(start 54.494938 -49.7713)
		(end 54.099714 -50.166524)
		(width 0.381)
		(layer "F.Cu")
		(net "P1V2_AUX")
	)
	(segment
		(start 54.494938 -48.9712)
		(end 54.494938 -49.7713)
		(width 0.381)
		(layer "F.Cu")
		(net "P1V2_AUX")
	)
	(segment
		(start 77.85227 -49.107344)
		(end 78.234032 -49.489106)
		(width 0.3556)
		(layer "F.Cu")
		(net "P1V2_AUX")
	)
	(segment
		(start 87.449914 -59.342528)
		(end 85.654642 -59.342528)
		(width 0.381)
		(layer "F.Cu")
		(net "P1V2_AUX")
	)
	(segment
		(start 79.452216 -51.50739)
		(end 79.833978 -51.889152)
		(width 0.3556)
		(layer "F.Cu")
		(net "P1V2_AUX")
	)
	(segment
		(start 60.894976 -50.571146)
		(end 61.2902 -50.96637)
		(width 0.381)
		(layer "F.Cu")
		(net "P1V2_AUX")
	)
	(segment
		(start 83.598766 -72.930512)
		(end 84.098384 -73.43013)
		(width 0.254)
		(layer "F.Cu")
		(net "P1V2_AUX")
	)
	(segment
		(start 76.691744 -37.159438)
		(end 76.691744 -36.549838)
		(width 0.381)
		(layer "F.Cu")
		(net "P1V2_AUX")
	)
	(segment
		(start 61.2902 -50.166524)
		(end 60.894976 -49.7713)
		(width 0.381)
		(layer "F.Cu")
		(net "P1V2_AUX")
	)
	(segment
		(start 60.315856 -49.19218)
		(end 60.315856 -47.950374)
		(width 0.381)
		(layer "F.Cu")
		(net "P1V2_AUX")
	)
	(segment
		(start 52.894992 -46.571154)
		(end 52.499768 -46.17593)
		(width 0.381)
		(layer "F.Cu")
		(net "P1V2_AUX")
	)
	(segment
		(start 73.852278 -49.907444)
		(end 73.470516 -50.289206)
		(width 0.3556)
		(layer "F.Cu")
		(net "P1V2_AUX")
	)
	(segment
		(start 52.104544 -46.571154)
		(end 52.499768 -46.17593)
		(width 0.381)
		(layer "F.Cu")
		(net "P1V2_AUX")
	)
	(segment
		(start 60.894976 -51.361594)
		(end 61.2902 -50.96637)
		(width 0.381)
		(layer "F.Cu")
		(net "P1V2_AUX")
	)
	(segment
		(start 48.895 -51.361594)
		(end 48.499776 -50.96637)
		(width 0.381)
		(layer "F.Cu")
		(net "P1V2_AUX")
	)
	(segment
		(start 73.052432 -42.70756)
		(end 72.512428 -42.697908)
		(width 0.3556)
		(layer "F.Cu")
		(net "P1V2_AUX")
	)
	(segment
		(start 87.885778 -59.778392)
		(end 87.449914 -59.342528)
		(width 0.381)
		(layer "F.Cu")
		(net "P1V2_AUX")
	)
	(segment
		(start 79.452216 -41.90746)
		(end 79.833978 -41.525698)
		(width 0.3556)
		(layer "F.Cu")
		(net "P1V2_AUX")
	)
	(segment
		(start 76.691744 -36.549838)
		(end 76.354432 -36.549838)
		(width 0.254)
		(layer "F.Cu")
		(net "P1V2_AUX")
	)
	(segment
		(start 84.098384 -73.43013)
		(end 85.221064 -73.43013)
		(width 0.254)
		(layer "F.Cu")
		(net "P1V2_AUX")
	)
	(segment
		(start 79.452216 -53.107336)
		(end 79.833978 -53.489098)
		(width 0.3556)
		(layer "F.Cu")
		(net "P1V2_AUX")
	)
	(segment
		(start 79.452216 -49.107344)
		(end 79.833978 -49.489106)
		(width 0.381)
		(layer "F.Cu")
		(net "P1V2_AUX")
	)
	(segment
		(start 54.494938 -48.171354)
		(end 54.494938 -47.371254)
		(width 0.381)
		(layer "F.Cu")
		(net "P1V2_AUX")
	)
	(segment
		(start 76.354432 -36.549838)
		(end 76.102972 -36.298378)
		(width 0.254)
		(layer "F.Cu")
		(net "P1V2_AUX")
	)
	(segment
		(start 60.894976 -49.7713)
		(end 60.315856 -49.19218)
		(width 0.381)
		(layer "F.Cu")
		(net "P1V2_AUX")
	)
	(segment
		(start 72.67067 -51.889152)
		(end 73.052432 -52.30749)
		(width 0.3556)
		(layer "F.Cu")
		(net "P1V2_AUX")
	)
	(segment
		(start 85.221064 -73.43013)
		(end 87.259414 -73.43013)
		(width 0.381)
		(layer "F.Cu")
		(net "P1V2_AUX")
	)
	(segment
		(start 60.894976 -51.371246)
		(end 60.894976 -51.361594)
		(width 0.381)
		(layer "F.Cu")
		(net "P1V2_AUX")
	)
	(segment
		(start 60.894976 -44.171362)
		(end 61.2902 -43.776138)
		(width 0.381)
		(layer "F.Cu")
		(net "P1V2_AUX")
	)
	(segment
		(start 73.052432 -51.50739)
		(end 72.67067 -51.889152)
		(width 0.3556)
		(layer "F.Cu")
		(net "P1V2_AUX")
	)
	(segment
		(start 51.295046 -46.571154)
		(end 50.494946 -46.571154)
		(width 0.381)
		(layer "F.Cu")
		(net "P1V2_AUX")
	)
	(segment
		(start 60.315856 -47.950374)
		(end 60.894976 -47.371254)
		(width 0.381)
		(layer "F.Cu")
		(net "P1V2_AUX")
	)
	(segment
		(start 48.895 -48.171354)
		(end 48.499776 -47.77613)
		(width 0.381)
		(layer "F.Cu")
		(net "P1V2_AUX")
	)
	(segment
		(start 79.452216 -47.507398)
		(end 79.833978 -47.125636)
		(width 0.3556)
		(layer "F.Cu")
		(net "P1V2_AUX")
	)
	(segment
		(start 77.707744 -37.159438)
		(end 77.707744 -36.549838)
		(width 0.381)
		(layer "F.Cu")
		(net "P1V2_AUX")
	)
	(segment
		(start 48.895 -50.571146)
		(end 48.499776 -50.96637)
		(width 0.381)
		(layer "F.Cu")
		(net "P1V2_AUX")
	)
	(segment
		(start 51.295046 -52.171346)
		(end 50.899822 -52.56657)
		(width 0.381)
		(layer "F.Cu")
		(net "P1V2_AUX")
	)
	(segment
		(start 73.052432 -49.107344)
		(end 72.67067 -49.489106)
		(width 0.3556)
		(layer "F.Cu")
		(net "P1V2_AUX")
	)
	(segment
		(start 76.102972 -36.298378)
		(end 75.65009 -36.298378)
		(width 0.254)
		(layer "F.Cu")
		(net "P1V2_AUX")
	)
	(segment
		(start 52.094892 -52.171346)
		(end 51.699668 -52.56657)
		(width 0.381)
		(layer "F.Cu")
		(net "P1V2_AUX")
	)
	(segment
		(start 78.723744 -37.159438)
		(end 78.723744 -36.549838)
		(width 0.381)
		(layer "F.Cu")
		(net "P1V2_AUX")
	)
	(segment
		(start 87.885778 -72.803766)
		(end 87.885778 -59.778392)
		(width 0.381)
		(layer "F.Cu")
		(net "P1V2_AUX")
	)
	(segment
		(start 80.755744 -37.159438)
		(end 80.755744 -36.549838)
		(width 0.381)
		(layer "F.Cu")
		(net "P1V2_AUX")
	)
	(segment
		(start 52.894992 -52.171346)
		(end 52.499768 -52.56657)
		(width 0.381)
		(layer "F.Cu")
		(net "P1V2_AUX")
	)
	(segment
		(start 48.895 -51.371246)
		(end 48.895 -51.361594)
		(width 0.381)
		(layer "F.Cu")
		(net "P1V2_AUX")
	)
	(segment
		(start 60.894976 -45.771308)
		(end 61.2902 -45.376084)
		(width 0.381)
		(layer "F.Cu")
		(net "P1V2_AUX")
	)
	(segment
		(start 78.65237 -49.907444)
		(end 79.034132 -50.289206)
		(width 0.3556)
		(layer "F.Cu")
		(net "P1V2_AUX")
	)
	(segment
		(start 87.259414 -73.43013)
		(end 87.885778 -72.803766)
		(width 0.381)
		(layer "F.Cu")
		(net "P1V2_AUX")
	)
	(via
		(at 75.03414 -53.489098)
		(size 0.4572)
		(drill 0.254)
		(layers "F.Cu" "B.Cu")
		(net "P1V2_AUX")
	)
	(via
		(at 37.800026 -31.927038)
		(size 0.508)
		(drill 0.254)
		(layers "F.Cu" "B.Cu")
		(net "P1V2_AUX")
	)
	(via
		(at 85.6996 -49.136046)
		(size 0.508)
		(drill 0.254)
		(layers "F.Cu" "B.Cu")
		(net "P1V2_AUX")
	)
	(via
		(at 70.982078 -43.514772)
		(size 0.508)
		(drill 0.254)
		(layers "F.Cu" "B.Cu")
		(net "P1V2_AUX")
	)
	(via
		(at 80.752188 -59.773312)
		(size 0.508)
		(drill 0.254)
		(layers "F.Cu" "B.Cu")
		(net "P1V2_AUX")
	)
	(via
		(at 72.67067 -54.285134)
		(size 0.4572)
		(drill 0.254)
		(layers "F.Cu" "B.Cu")
		(net "P1V2_AUX")
	)
	(via
		(at 78.618334 -59.779408)
		(size 0.508)
		(drill 0.254)
		(layers "F.Cu" "B.Cu")
		(net "P1V2_AUX")
	)
	(via
		(at 84.17687 -42.522394)
		(size 0.508)
		(drill 0.254)
		(layers "F.Cu" "B.Cu")
		(net "P1V2_AUX")
	)
	(via
		(at 82.886042 -59.767216)
		(size 0.508)
		(drill 0.254)
		(layers "F.Cu" "B.Cu")
		(net "P1V2_AUX")
	)
	(via
		(at 79.833978 -53.489098)
		(size 0.4572)
		(drill 0.254)
		(layers "F.Cu" "B.Cu")
		(net "P1V2_AUX")
	)
	(via
		(at 48.499776 -50.166524)
		(size 0.4572)
		(drill 0.254)
		(layers "F.Cu" "B.Cu")
		(net "P1V2_AUX")
	)
	(via
		(at 51.699668 -52.56657)
		(size 0.4572)
		(drill 0.254)
		(layers "F.Cu" "B.Cu")
		(net "P1V2_AUX")
	)
	(via
		(at 79.034132 -47.88916)
		(size 0.4572)
		(drill 0.254)
		(layers "F.Cu" "B.Cu")
		(net "P1V2_AUX")
	)
	(via
		(at 61.2902 -44.575984)
		(size 0.4572)
		(drill 0.254)
		(layers "F.Cu" "B.Cu")
		(net "P1V2_AUX")
	)
	(via
		(at 73.470516 -47.125636)
		(size 0.4572)
		(drill 0.254)
		(layers "F.Cu" "B.Cu")
		(net "P1V2_AUX")
	)
	(via
		(at 73.434194 -45.52569)
		(size 0.4572)
		(drill 0.254)
		(layers "F.Cu" "B.Cu")
		(net "P1V2_AUX")
	)
	(via
		(at 81.293716 -50.460402)
		(size 0.508)
		(drill 0.254)
		(layers "F.Cu" "B.Cu")
		(net "P1V2_AUX")
	)
	(via
		(at 79.739744 -36.549838)
		(size 0.508)
		(drill 0.254)
		(layers "F.Cu" "B.Cu")
		(net "P1V2_AUX")
	)
	(via
		(at 72.67067 -49.489106)
		(size 0.4572)
		(drill 0.254)
		(layers "F.Cu" "B.Cu")
		(net "P1V2_AUX")
	)
	(via
		(at 78.723744 -36.549838)
		(size 0.508)
		(drill 0.254)
		(layers "F.Cu" "B.Cu")
		(net "P1V2_AUX")
	)
	(via
		(at 52.499768 -52.56657)
		(size 0.4572)
		(drill 0.254)
		(layers "F.Cu" "B.Cu")
		(net "P1V2_AUX")
	)
	(via
		(at 79.99222 -45.907452)
		(size 0.4572)
		(drill 0.254)
		(layers "F.Cu" "B.Cu")
		(net "P1V2_AUX")
	)
	(via
		(at 48.499776 -47.77613)
		(size 0.4572)
		(drill 0.254)
		(layers "F.Cu" "B.Cu")
		(net "P1V2_AUX")
	)
	(via
		(at 76.691744 -36.549838)
		(size 0.508)
		(drill 0.254)
		(layers "F.Cu" "B.Cu")
		(net "P1V2_AUX")
	)
	(via
		(at 79.034132 -50.289206)
		(size 0.4572)
		(drill 0.254)
		(layers "F.Cu" "B.Cu")
		(net "P1V2_AUX")
	)
	(via
		(at 72.512428 -42.697908)
		(size 0.4572)
		(drill 0.254)
		(layers "F.Cu" "B.Cu")
		(net "P1V2_AUX")
	)
	(via
		(at 52.499768 -46.17593)
		(size 0.4572)
		(drill 0.254)
		(layers "F.Cu" "B.Cu")
		(net "P1V2_AUX")
	)
	(via
		(at 82.886042 -60.628022)
		(size 0.508)
		(drill 0.254)
		(layers "F.Cu" "B.Cu")
		(net "P1V2_AUX")
	)
	(via
		(at 83.56727 -38.774878)
		(size 0.508)
		(drill 0.254)
		(layers "F.Cu" "B.Cu")
		(net "P1V2_AUX")
	)
	(via
		(at 61.2902 -43.776138)
		(size 0.4572)
		(drill 0.254)
		(layers "F.Cu" "B.Cu")
		(net "P1V2_AUX")
	)
	(via
		(at 54.099714 -50.96637)
		(size 0.4572)
		(drill 0.254)
		(layers "F.Cu" "B.Cu")
		(net "P1V2_AUX")
	)
	(via
		(at 48.499776 -50.96637)
		(size 0.4572)
		(drill 0.254)
		(layers "F.Cu" "B.Cu")
		(net "P1V2_AUX")
	)
	(via
		(at 85.716618 -60.193936)
		(size 0.508)
		(drill 0.254)
		(layers "F.Cu" "B.Cu")
		(net "P1V2_AUX")
	)
	(via
		(at 79.833978 -49.489106)
		(size 0.4572)
		(drill 0.254)
		(layers "F.Cu" "B.Cu")
		(net "P1V2_AUX")
	)
	(via
		(at 78.618334 -60.640214)
		(size 0.508)
		(drill 0.254)
		(layers "F.Cu" "B.Cu")
		(net "P1V2_AUX")
	)
	(via
		(at 78.234032 -49.489106)
		(size 0.4572)
		(drill 0.254)
		(layers "F.Cu" "B.Cu")
		(net "P1V2_AUX")
	)
	(via
		(at 81.293716 -49.571402)
		(size 0.508)
		(drill 0.254)
		(layers "F.Cu" "B.Cu")
		(net "P1V2_AUX")
	)
	(via
		(at 72.67067 -47.125636)
		(size 0.4572)
		(drill 0.254)
		(layers "F.Cu" "B.Cu")
		(net "P1V2_AUX")
	)
	(via
		(at 54.099714 -46.97603)
		(size 0.4572)
		(drill 0.254)
		(layers "F.Cu" "B.Cu")
		(net "P1V2_AUX")
	)
	(via
		(at 79.833978 -47.125636)
		(size 0.4572)
		(drill 0.254)
		(layers "F.Cu" "B.Cu")
		(net "P1V2_AUX")
	)
	(via
		(at 50.899822 -52.56657)
		(size 0.4572)
		(drill 0.254)
		(layers "F.Cu" "B.Cu")
		(net "P1V2_AUX")
	)
	(via
		(at 55.809388 -72.828912)
		(size 0.508)
		(drill 0.254)
		(layers "F.Cu" "B.Cu")
		(net "P1V2_AUX")
	)
	(via
		(at 61.2902 -45.376084)
		(size 0.4572)
		(drill 0.254)
		(layers "F.Cu" "B.Cu")
		(net "P1V2_AUX")
	)
	(via
		(at 38.59276 -51.74234)
		(size 0.508)
		(drill 0.254)
		(layers "F.Cu" "B.Cu")
		(net "P1V2_AUX")
	)
	(via
		(at 80.752188 -60.634118)
		(size 0.508)
		(drill 0.254)
		(layers "F.Cu" "B.Cu")
		(net "P1V2_AUX")
	)
	(via
		(at 54.099714 -51.76647)
		(size 0.4572)
		(drill 0.254)
		(layers "F.Cu" "B.Cu")
		(net "P1V2_AUX")
	)
	(via
		(at 54.099714 -50.166524)
		(size 0.4572)
		(drill 0.254)
		(layers "F.Cu" "B.Cu")
		(net "P1V2_AUX")
	)
	(via
		(at 48.499776 -46.97603)
		(size 0.4572)
		(drill 0.254)
		(layers "F.Cu" "B.Cu")
		(net "P1V2_AUX")
	)
	(via
		(at 76.708254 -61.6966)
		(size 0.762)
		(drill 0.381)
		(layers "F.Cu" "B.Cu")
		(net "P1V2_AUX")
	)
	(via
		(at 86.312248 -44.03852)
		(size 0.508)
		(drill 0.254)
		(layers "F.Cu" "B.Cu")
		(net "P1V2_AUX")
	)
	(via
		(at 86.344506 -41.379394)
		(size 0.508)
		(drill 0.254)
		(layers "F.Cu" "B.Cu")
		(net "P1V2_AUX")
	)
	(via
		(at 37.800026 -31.292038)
		(size 0.508)
		(drill 0.254)
		(layers "F.Cu" "B.Cu")
		(net "P1V2_AUX")
	)
	(via
		(at 73.03897 -36.174426)
		(size 0.508)
		(drill 0.254)
		(layers "F.Cu" "B.Cu")
		(net "P1V2_AUX")
	)
	(via
		(at 61.2902 -46.97603)
		(size 0.4572)
		(drill 0.254)
		(layers "F.Cu" "B.Cu")
		(net "P1V2_AUX")
	)
	(via
		(at 85.019896 -60.621926)
		(size 0.508)
		(drill 0.254)
		(layers "F.Cu" "B.Cu")
		(net "P1V2_AUX")
	)
	(via
		(at 73.470516 -50.289206)
		(size 0.4572)
		(drill 0.254)
		(layers "F.Cu" "B.Cu")
		(net "P1V2_AUX")
	)
	(via
		(at 79.833978 -54.289198)
		(size 0.4572)
		(drill 0.254)
		(layers "F.Cu" "B.Cu")
		(net "P1V2_AUX")
	)
	(via
		(at 74.219816 -36.22294)
		(size 0.508)
		(drill 0.254)
		(layers "F.Cu" "B.Cu")
		(net "P1V2_AUX")
	)
	(via
		(at 81.2038 -63.1444)
		(size 0.6604)
		(drill 0.3302)
		(layers "F.Cu" "B.Cu")
		(net "P1V2_AUX")
	)
	(via
		(at 79.833978 -41.525698)
		(size 0.4572)
		(drill 0.254)
		(layers "F.Cu" "B.Cu")
		(net "P1V2_AUX")
	)
	(via
		(at 84.17687 -43.792394)
		(size 0.508)
		(drill 0.254)
		(layers "F.Cu" "B.Cu")
		(net "P1V2_AUX")
	)
	(via
		(at 72.67067 -51.889152)
		(size 0.4572)
		(drill 0.254)
		(layers "F.Cu" "B.Cu")
		(net "P1V2_AUX")
	)
	(via
		(at 61.2902 -50.96637)
		(size 0.4572)
		(drill 0.254)
		(layers "F.Cu" "B.Cu")
		(net "P1V2_AUX")
	)
	(via
		(at 77.707744 -36.549838)
		(size 0.508)
		(drill 0.254)
		(layers "F.Cu" "B.Cu")
		(net "P1V2_AUX")
	)
	(via
		(at 76.48448 -60.64631)
		(size 0.508)
		(drill 0.254)
		(layers "F.Cu" "B.Cu")
		(net "P1V2_AUX")
	)
	(via
		(at 82.171286 -38.957758)
		(size 0.508)
		(drill 0.254)
		(layers "F.Cu" "B.Cu")
		(net "P1V2_AUX")
	)
	(via
		(at 80.755744 -36.549838)
		(size 0.508)
		(drill 0.254)
		(layers "F.Cu" "B.Cu")
		(net "P1V2_AUX")
	)
	(via
		(at 61.2902 -50.166524)
		(size 0.4572)
		(drill 0.254)
		(layers "F.Cu" "B.Cu")
		(net "P1V2_AUX")
	)
	(via
		(at 48.499776 -48.575976)
		(size 0.4572)
		(drill 0.254)
		(layers "F.Cu" "B.Cu")
		(net "P1V2_AUX")
	)
	(via
		(at 79.833978 -51.889152)
		(size 0.4572)
		(drill 0.254)
		(layers "F.Cu" "B.Cu")
		(net "P1V2_AUX")
	)
	(via
		(at 53.299868 -52.56657)
		(size 0.4572)
		(drill 0.254)
		(layers "F.Cu" "B.Cu")
		(net "P1V2_AUX")
	)
	(via
		(at 78.003654 -63.2714)
		(size 0.762)
		(drill 0.381)
		(layers "F.Cu" "B.Cu")
		(net "P1V2_AUX")
	)
	(via
		(at 86.199726 -38.595808)
		(size 0.508)
		(drill 0.254)
		(layers "F.Cu" "B.Cu")
		(net "P1V2_AUX")
	)
	(via
		(at 50.099722 -46.97603)
		(size 0.4572)
		(drill 0.254)
		(layers "F.Cu" "B.Cu")
		(net "P1V2_AUX")
	)
	(via
		(at 86.3092 -46.463204)
		(size 0.508)
		(drill 0.254)
		(layers "F.Cu" "B.Cu")
		(net "P1V2_AUX")
	)
	(via
		(at 85.019896 -59.76112)
		(size 0.508)
		(drill 0.254)
		(layers "F.Cu" "B.Cu")
		(net "P1V2_AUX")
	)
	(via
		(at 76.48448 -59.849004)
		(size 0.508)
		(drill 0.254)
		(layers "F.Cu" "B.Cu")
		(net "P1V2_AUX")
	)
	(segment
		(start 85.681312 -43.411394)
		(end 85.681312 -44.427394)
		(width 0.381)
		(layer "B.Cu")
		(net "P1V2_AUX")
	)
	(segment
		(start 75.762104 -52.286916)
		(end 75.41514 -52.286916)
		(width 0.381)
		(layer "B.Cu")
		(net "P1V2_AUX")
	)
	(segment
		(start 79.739744 -37.159438)
		(end 79.739744 -36.549838)
		(width 0.381)
		(layer "B.Cu")
		(net "P1V2_AUX")
	)
	(segment
		(start 85.6996 -39.347394)
		(end 85.6996 -39.095934)
		(width 0.381)
		(layer "B.Cu")
		(net "P1V2_AUX")
	)
	(segment
		(start 80.006698 -49.661826)
		(end 79.833978 -49.489106)
		(width 0.381)
		(layer "B.Cu")
		(net "P1V2_AUX")
	)
	(segment
		(start 80.755744 -37.159438)
		(end 80.755744 -36.549838)
		(width 0.381)
		(layer "B.Cu")
		(net "P1V2_AUX")
	)
	(segment
		(start 81.292192 -52.746656)
		(end 80.758284 -52.212748)
		(width 0.381)
		(layer "B.Cu")
		(net "P1V2_AUX")
	)
	(segment
		(start 80.758284 -52.212748)
		(end 80.157574 -52.212748)
		(width 0.381)
		(layer "B.Cu")
		(net "P1V2_AUX")
	)
	(segment
		(start 80.98917 -46.586394)
		(end 80.671162 -46.586394)
		(width 0.381)
		(layer "B.Cu")
		(net "P1V2_AUX")
	)
	(segment
		(start 84.17687 -42.522394)
		(end 84.7725 -42.522394)
		(width 0.381)
		(layer "B.Cu")
		(net "P1V2_AUX")
	)
	(segment
		(start 81.561686 -38.957758)
		(end 82.171286 -38.957758)
		(width 0.381)
		(layer "B.Cu")
		(net "P1V2_AUX")
	)
	(segment
		(start 83.56727 -42.522394)
		(end 84.17687 -42.522394)
		(width 0.381)
		(layer "B.Cu")
		(net "P1V2_AUX")
	)
	(segment
		(start 79.97952 -54.898798)
		(end 79.97952 -54.43474)
		(width 0.381)
		(layer "B.Cu")
		(net "P1V2_AUX")
	)
	(segment
		(start 78.723744 -37.159438)
		(end 78.723744 -36.549838)
		(width 0.381)
		(layer "B.Cu")
		(net "P1V2_AUX")
	)
	(segment
		(start 85.6996 -46.463204)
		(end 86.3092 -46.463204)
		(width 0.381)
		(layer "B.Cu")
		(net "P1V2_AUX")
	)
	(segment
		(start 85.6996 -40.363394)
		(end 85.6996 -41.379394)
		(width 0.381)
		(layer "B.Cu")
		(net "P1V2_AUX")
	)
	(segment
		(start 85.6996 -48.504094)
		(end 85.6996 -49.136046)
		(width 0.381)
		(layer "B.Cu")
		(net "P1V2_AUX")
	)
	(segment
		(start 82.618834 -38.51021)
		(end 82.618834 -38.13556)
		(width 0.381)
		(layer "B.Cu")
		(net "P1V2_AUX")
	)
	(segment
		(start 81.274666 -48.38573)
		(end 80.7339 -48.161702)
		(width 0.381)
		(layer "B.Cu")
		(net "P1V2_AUX")
	)
	(segment
		(start 85.6996 -39.095934)
		(end 86.199726 -38.595808)
		(width 0.381)
		(layer "B.Cu")
		(net "P1V2_AUX")
	)
	(segment
		(start 81.686908 -48.38573)
		(end 81.274666 -48.38573)
		(width 0.381)
		(layer "B.Cu")
		(net "P1V2_AUX")
	)
	(segment
		(start 83.56727 -39.474394)
		(end 83.56727 -38.774878)
		(width 0.381)
		(layer "B.Cu")
		(net "P1V2_AUX")
	)
	(segment
		(start 73.917048 -47.572168)
		(end 73.470516 -47.125636)
		(width 0.381)
		(layer "B.Cu")
		(net "P1V2_AUX")
	)
	(segment
		(start 80.512666 -49.661826)
		(end 80.006698 -49.661826)
		(width 0.381)
		(layer "B.Cu")
		(net "P1V2_AUX")
	)
	(segment
		(start 73.917048 -47.730156)
		(end 73.917048 -47.572168)
		(width 0.381)
		(layer "B.Cu")
		(net "P1V2_AUX")
	)
	(segment
		(start 77.707744 -37.159438)
		(end 77.707744 -36.549838)
		(width 0.381)
		(layer "B.Cu")
		(net "P1V2_AUX")
	)
	(segment
		(start 85.6996 -45.443394)
		(end 85.6996 -46.463204)
		(width 0.381)
		(layer "B.Cu")
		(net "P1V2_AUX")
	)
	(segment
		(start 75.03414 -52.667916)
		(end 75.03414 -53.489098)
		(width 0.381)
		(layer "B.Cu")
		(net "P1V2_AUX")
	)
	(segment
		(start 80.671162 -46.586394)
		(end 79.99222 -45.907452)
		(width 0.381)
		(layer "B.Cu")
		(net "P1V2_AUX")
	)
	(segment
		(start 71.434706 -54.23662)
		(end 72.622156 -54.23662)
		(width 0.381)
		(layer "B.Cu")
		(net "P1V2_AUX")
	)
	(segment
		(start 83.56727 -41.506394)
		(end 83.56727 -42.522394)
		(width 0.381)
		(layer "B.Cu")
		(net "P1V2_AUX")
	)
	(segment
		(start 80.157574 -52.212748)
		(end 79.833978 -51.889152)
		(width 0.381)
		(layer "B.Cu")
		(net "P1V2_AUX")
	)
	(segment
		(start 81.708244 -51.730656)
		(end 81.708244 -52.746656)
		(width 0.381)
		(layer "B.Cu")
		(net "P1V2_AUX")
	)
	(segment
		(start 71.858378 -47.506382)
		(end 72.289924 -47.506382)
		(width 0.381)
		(layer "B.Cu")
		(net "P1V2_AUX")
	)
	(segment
		(start 85.6996 -47.488094)
		(end 85.6996 -48.504094)
		(width 0.381)
		(layer "B.Cu")
		(net "P1V2_AUX")
	)
	(segment
		(start 76.691744 -37.159438)
		(end 76.691744 -36.549838)
		(width 0.381)
		(layer "B.Cu")
		(net "P1V2_AUX")
	)
	(segment
		(start 71.68896 -49.449736)
		(end 72.6313 -49.449736)
		(width 0.381)
		(layer "B.Cu")
		(net "P1V2_AUX")
	)
	(segment
		(start 72.622156 -54.23662)
		(end 72.67067 -54.285134)
		(width 0.381)
		(layer "B.Cu")
		(net "P1V2_AUX")
	)
	(segment
		(start 85.6996 -41.379394)
		(end 86.344506 -41.379394)
		(width 0.381)
		(layer "B.Cu")
		(net "P1V2_AUX")
	)
	(segment
		(start 81.708244 -52.746656)
		(end 81.292192 -52.746656)
		(width 0.381)
		(layer "B.Cu")
		(net "P1V2_AUX")
	)
	(segment
		(start 79.97952 -54.43474)
		(end 79.833978 -54.289198)
		(width 0.381)
		(layer "B.Cu")
		(net "P1V2_AUX")
	)
	(segment
		(start 72.289924 -47.506382)
		(end 72.67067 -47.125636)
		(width 0.381)
		(layer "B.Cu")
		(net "P1V2_AUX")
	)
	(segment
		(start 72.6313 -49.449736)
		(end 72.67067 -49.489106)
		(width 0.381)
		(layer "B.Cu")
		(net "P1V2_AUX")
	)
	(segment
		(start 75.41514 -52.286916)
		(end 75.03414 -52.667916)
		(width 0.381)
		(layer "B.Cu")
		(net "P1V2_AUX")
	)
	(segment
		(start 80.418686 -47.846488)
		(end 80.418686 -47.710344)
		(width 0.381)
		(layer "B.Cu")
		(net "P1V2_AUX")
	)
	(segment
		(start 84.7725 -42.522394)
		(end 84.8995 -42.395394)
		(width 0.381)
		(layer "B.Cu")
		(net "P1V2_AUX")
	)
	(segment
		(start 85.681312 -44.427394)
		(end 85.923374 -44.427394)
		(width 0.381)
		(layer "B.Cu")
		(net "P1V2_AUX")
	)
	(segment
		(start 80.087216 -53.742336)
		(end 79.833978 -53.489098)
		(width 0.381)
		(layer "B.Cu")
		(net "P1V2_AUX")
	)
	(segment
		(start 85.923374 -44.427394)
		(end 86.312248 -44.03852)
		(width 0.381)
		(layer "B.Cu")
		(net "P1V2_AUX")
	)
	(segment
		(start 80.418686 -47.710344)
		(end 79.833978 -47.125636)
		(width 0.381)
		(layer "B.Cu")
		(net "P1V2_AUX")
	)
	(segment
		(start 80.7339 -48.161702)
		(end 80.418686 -47.846488)
		(width 0.381)
		(layer "B.Cu")
		(net "P1V2_AUX")
	)
	(segment
		(start 77.598778 -49.03089)
		(end 77.775816 -49.03089)
		(width 0.381)
		(layer "B.Cu")
		(net "P1V2_AUX")
	)
	(segment
		(start 77.775816 -49.03089)
		(end 78.234032 -49.489106)
		(width 0.381)
		(layer "B.Cu")
		(net "P1V2_AUX")
	)
	(segment
		(start 80.546194 -53.742336)
		(end 80.087216 -53.742336)
		(width 0.381)
		(layer "B.Cu")
		(net "P1V2_AUX")
	)
	(segment
		(start 82.171286 -38.957758)
		(end 82.618834 -38.51021)
		(width 0.381)
		(layer "B.Cu")
		(net "P1V2_AUX")
	)
	(segment
		(start 57.695084 -51.371246)
		(end 58.090308 -51.76647)
		(width 0.3556)
		(layer "F.Cu")
		(net "P1V0_STBY_RC_VCC10A")
	)
	(via
		(at 67.651884 -55.72252)
		(size 0.6604)
		(drill 0.3302)
		(layers "F.Cu" "B.Cu")
		(net "P1V0_STBY_RC_VCC10A")
	)
	(via
		(at 68.158106 -56.420004)
		(size 0.508)
		(drill 0.254)
		(layers "F.Cu" "B.Cu")
		(net "P1V0_STBY_RC_VCC10A")
	)
	(via
		(at 58.090308 -51.76647)
		(size 0.4572)
		(drill 0.254)
		(layers "F.Cu" "B.Cu")
		(net "P1V0_STBY_RC_VCC10A")
	)
	(segment
		(start 57.899808 -51.95697)
		(end 58.090308 -51.76647)
		(width 0.3556)
		(layer "B.Cu")
		(net "P1V0_STBY_RC_VCC10A")
	)
	(segment
		(start 57.34939 -51.95697)
		(end 57.899808 -51.95697)
		(width 0.3556)
		(layer "B.Cu")
		(net "P1V0_STBY_RC_VCC10A")
	)
	(segment
		(start 58.49493 -43.371262)
		(end 58.890154 -42.976038)
		(width 0.3556)
		(layer "F.Cu")
		(net "P1V0_STBY_PLAVDD")
	)
	(segment
		(start 59.690254 -42.976038)
		(end 59.690508 -42.975784)
		(width 0.3556)
		(layer "F.Cu")
		(net "P1V0_STBY_PLAVDD")
	)
	(segment
		(start 58.49493 -42.571162)
		(end 58.890154 -42.175938)
		(width 0.3556)
		(layer "F.Cu")
		(net "P1V0_STBY_PLAVDD")
	)
	(segment
		(start 59.690508 -42.975784)
		(end 60.094876 -42.571162)
		(width 0.3556)
		(layer "F.Cu")
		(net "P1V0_STBY_PLAVDD")
	)
	(segment
		(start 60.094876 -42.571162)
		(end 60.4901 -42.175938)
		(width 0.3556)
		(layer "F.Cu")
		(net "P1V0_STBY_PLAVDD")
	)
	(segment
		(start 58.49493 -45.771308)
		(end 58.890154 -45.376084)
		(width 0.3556)
		(layer "F.Cu")
		(net "P1V0_STBY_PLAVDD")
	)
	(segment
		(start 58.883296 -42.959528)
		(end 58.49493 -42.571162)
		(width 0.3556)
		(layer "F.Cu")
		(net "P1V0_STBY_PLAVDD")
	)
	(segment
		(start 60.078874 -43.364658)
		(end 59.690254 -42.976038)
		(width 0.3556)
		(layer "F.Cu")
		(net "P1V0_STBY_PLAVDD")
	)
	(via
		(at 59.690254 -42.976038)
		(size 0.4572)
		(drill 0.254)
		(layers "F.Cu" "B.Cu")
		(net "P1V0_STBY_PLAVDD")
	)
	(via
		(at 71.276464 -38.346634)
		(size 0.508)
		(drill 0.254)
		(layers "F.Cu" "B.Cu")
		(net "P1V0_STBY_PLAVDD")
	)
	(via
		(at 58.890154 -45.376084)
		(size 0.4572)
		(drill 0.254)
		(layers "F.Cu" "B.Cu")
		(net "P1V0_STBY_PLAVDD")
	)
	(via
		(at 72.038464 -38.346634)
		(size 0.508)
		(drill 0.254)
		(layers "F.Cu" "B.Cu")
		(net "P1V0_STBY_PLAVDD")
	)
	(via
		(at 58.890154 -42.976038)
		(size 0.4572)
		(drill 0.254)
		(layers "F.Cu" "B.Cu")
		(net "P1V0_STBY_PLAVDD")
	)
	(via
		(at 60.4901 -42.175938)
		(size 0.4572)
		(drill 0.254)
		(layers "F.Cu" "B.Cu")
		(net "P1V0_STBY_PLAVDD")
	)
	(via
		(at 58.890154 -42.175938)
		(size 0.4572)
		(drill 0.254)
		(layers "F.Cu" "B.Cu")
		(net "P1V0_STBY_PLAVDD")
	)
	(arc
		(start 60.094876 -43.371262)
		(mid 60.086225 -43.369541)
		(end 60.078874 -43.364658)
		(width 0.3556)
		(layer "F.Cu")
		(net "P1V0_STBY_PLAVDD")
	)
	(arc
		(start 58.890154 -42.976038)
		(mid 58.888375 -42.967095)
		(end 58.883296 -42.959528)
		(width 0.3556)
		(layer "F.Cu")
		(net "P1V0_STBY_PLAVDD")
	)
	(segment
		(start 58.49493 -51.371246)
		(end 58.890154 -51.76647)
		(width 0.3556)
		(layer "F.Cu")
		(net "P1V0_STBY_PE_VCC10A")
	)
	(via
		(at 71.750682 -59.754516)
		(size 0.508)
		(drill 0.254)
		(layers "F.Cu" "B.Cu")
		(net "P1V0_STBY_PE_VCC10A")
	)
	(via
		(at 58.890154 -51.76647)
		(size 0.4572)
		(drill 0.254)
		(layers "F.Cu" "B.Cu")
		(net "P1V0_STBY_PE_VCC10A")
	)
	(via
		(at 71.115682 -59.754516)
		(size 0.508)
		(drill 0.254)
		(layers "F.Cu" "B.Cu")
		(net "P1V0_STBY_PE_VCC10A")
	)
	(via
		(at 73.200768 -60.376816)
		(size 0.6604)
		(drill 0.3302)
		(layers "F.Cu" "B.Cu")
		(net "P1V0_STBY_PE_VCC10A")
	)
	(segment
		(start 59.109102 -51.547522)
		(end 58.890154 -51.76647)
		(width 0.3556)
		(layer "B.Cu")
		(net "P1V0_STBY_PE_VCC10A")
	)
	(segment
		(start 59.109102 -51.11369)
		(end 59.109102 -51.547522)
		(width 0.3556)
		(layer "B.Cu")
		(net "P1V0_STBY_PE_VCC10A")
	)
	(segment
		(start 59.29503 -51.371246)
		(end 59.690254 -51.76647)
		(width 0.3556)
		(layer "F.Cu")
		(net "P1V0_STBY_DP_VCC10A")
	)
	(via
		(at 77.195172 -61.786008)
		(size 0.6604)
		(drill 0.3302)
		(layers "F.Cu" "B.Cu")
		(net "P1V0_STBY_DP_VCC10A")
	)
	(via
		(at 59.690254 -51.76647)
		(size 0.4572)
		(drill 0.254)
		(layers "F.Cu" "B.Cu")
		(net "P1V0_STBY_DP_VCC10A")
	)
	(via
		(at 77.136752 -60.206636)
		(size 0.6604)
		(drill 0.3302)
		(layers "F.Cu" "B.Cu")
		(net "P1V0_STBY_DP_VCC10A")
	)
	(via
		(at 73.173844 -59.650376)
		(size 0.508)
		(drill 0.254)
		(layers "F.Cu" "B.Cu")
		(net "P1V0_STBY_DP_VCC10A")
	)
	(via
		(at 73.808844 -59.650376)
		(size 0.508)
		(drill 0.254)
		(layers "F.Cu" "B.Cu")
		(net "P1V0_STBY_DP_VCC10A")
	)
	(segment
		(start 59.126882 -52.329842)
		(end 59.690254 -51.76647)
		(width 0.3556)
		(layer "B.Cu")
		(net "P1V0_STBY_DP_VCC10A")
	)
	(segment
		(start 59.126882 -52.58816)
		(end 59.126882 -52.329842)
		(width 0.3556)
		(layer "B.Cu")
		(net "P1V0_STBY_DP_VCC10A")
	)
	(segment
		(start 22.0218 -30.2514)
		(end 22.373082 -30.602682)
		(width 0.4572)
		(layer "F.Cu")
		(net "P1V0_AUX_VCC")
	)
	(segment
		(start 20.770088 -31.562294)
		(end 21.015706 -31.562294)
		(width 0.254)
		(layer "F.Cu")
		(net "P1V0_AUX_VCC")
	)
	(segment
		(start 21.61921 -30.95879)
		(end 22.370034 -30.95879)
		(width 0.254)
		(layer "F.Cu")
		(net "P1V0_AUX_VCC")
	)
	(segment
		(start 16.985996 -33.16986)
		(end 17.24914 -33.16986)
		(width 0.254)
		(layer "F.Cu")
		(net "P1V0_AUX_VCC")
	)
	(segment
		(start 17.24914 -33.16986)
		(end 17.356582 -33.062418)
		(width 0.254)
		(layer "F.Cu")
		(net "P1V0_AUX_VCC")
	)
	(segment
		(start 22.778466 -30.2514)
		(end 22.0218 -30.2514)
		(width 0.381)
		(layer "F.Cu")
		(net "P1V0_AUX_VCC")
	)
	(segment
		(start 22.370034 -30.95879)
		(end 22.373082 -30.961838)
		(width 0.254)
		(layer "F.Cu")
		(net "P1V0_AUX_VCC")
	)
	(segment
		(start 23.325836 -30.254448)
		(end 22.781514 -30.254448)
		(width 0.381)
		(layer "F.Cu")
		(net "P1V0_AUX_VCC")
	)
	(segment
		(start 17.592548 -31.562294)
		(end 17.869916 -31.562294)
		(width 0.254)
		(layer "F.Cu")
		(net "P1V0_AUX_VCC")
	)
	(segment
		(start 23.34895 -30.231334)
		(end 23.325836 -30.254448)
		(width 0.381)
		(layer "F.Cu")
		(net "P1V0_AUX_VCC")
	)
	(segment
		(start 16.97482 -31.071566)
		(end 17.10182 -31.071566)
		(width 0.254)
		(layer "F.Cu")
		(net "P1V0_AUX_VCC")
	)
	(segment
		(start 22.373082 -30.602682)
		(end 22.373082 -30.961838)
		(width 0.4572)
		(layer "F.Cu")
		(net "P1V0_AUX_VCC")
	)
	(segment
		(start 21.015706 -31.562294)
		(end 21.61921 -30.95879)
		(width 0.254)
		(layer "F.Cu")
		(net "P1V0_AUX_VCC")
	)
	(segment
		(start 17.10182 -31.071566)
		(end 17.592548 -31.562294)
		(width 0.254)
		(layer "F.Cu")
		(net "P1V0_AUX_VCC")
	)
	(segment
		(start 22.781514 -30.254448)
		(end 22.778466 -30.2514)
		(width 0.381)
		(layer "F.Cu")
		(net "P1V0_AUX_VCC")
	)
	(segment
		(start 17.356582 -33.062418)
		(end 17.869916 -33.062418)
		(width 0.254)
		(layer "F.Cu")
		(net "P1V0_AUX_VCC")
	)
	(via
		(at 22.0218 -30.2514)
		(size 0.508)
		(drill 0.254)
		(layers "F.Cu" "B.Cu")
		(net "P1V0_AUX_VCC")
	)
	(via
		(at 19.45132 -30.963616)
		(size 0.6604)
		(drill 0.3302)
		(layers "F.Cu" "B.Cu")
		(net "P1V0_AUX_VCC")
	)
	(via
		(at 16.985996 -33.16986)
		(size 0.508)
		(drill 0.254)
		(layers "F.Cu" "B.Cu")
		(net "P1V0_AUX_VCC")
	)
	(via
		(at 16.97482 -31.071566)
		(size 0.508)
		(drill 0.254)
		(layers "F.Cu" "B.Cu")
		(net "P1V0_AUX_VCC")
	)
	(segment
		(start 19.45132 -30.963616)
		(end 21.309584 -30.963616)
		(width 0.4572)
		(layer "B.Cu")
		(net "P1V0_AUX_VCC")
	)
	(segment
		(start 17.72158 -31.071566)
		(end 17.82953 -30.963616)
		(width 0.4572)
		(layer "B.Cu")
		(net "P1V0_AUX_VCC")
	)
	(segment
		(start 16.22806 -31.477966)
		(end 16.63446 -31.071566)
		(width 0.4064)
		(layer "B.Cu")
		(net "P1V0_AUX_VCC")
	)
	(segment
		(start 16.97482 -31.071566)
		(end 17.72158 -31.071566)
		(width 0.4572)
		(layer "B.Cu")
		(net "P1V0_AUX_VCC")
	)
	(segment
		(start 16.63446 -31.071566)
		(end 16.97482 -31.071566)
		(width 0.4064)
		(layer "B.Cu")
		(net "P1V0_AUX_VCC")
	)
	(segment
		(start 21.309584 -30.963616)
		(end 22.0218 -30.2514)
		(width 0.4572)
		(layer "B.Cu")
		(net "P1V0_AUX_VCC")
	)
	(segment
		(start 16.985996 -33.16986)
		(end 16.63446 -33.16986)
		(width 0.4064)
		(layer "B.Cu")
		(net "P1V0_AUX_VCC")
	)
	(segment
		(start 17.82953 -30.963616)
		(end 19.45132 -30.963616)
		(width 0.4572)
		(layer "B.Cu")
		(net "P1V0_AUX_VCC")
	)
	(segment
		(start 16.63446 -33.16986)
		(end 16.22806 -32.76346)
		(width 0.4064)
		(layer "B.Cu")
		(net "P1V0_AUX_VCC")
	)
	(segment
		(start 16.22806 -32.76346)
		(end 16.22806 -31.477966)
		(width 0.4064)
		(layer "B.Cu")
		(net "P1V0_AUX_VCC")
	)
	(segment
		(start 16.9037 -29.5783)
		(end 16.9037 -30.05074)
		(width 0.254)
		(layer "F.Cu")
		(net "P1V0_AUX_MODE")
	)
	(segment
		(start 18.82013 -31.108904)
		(end 18.82013 -31.362396)
		(width 0.254)
		(layer "F.Cu")
		(net "P1V0_AUX_MODE")
	)
	(segment
		(start 16.9037 -30.05074)
		(end 17.70634 -30.85338)
		(width 0.254)
		(layer "F.Cu")
		(net "P1V0_AUX_MODE")
	)
	(segment
		(start 17.70634 -30.85338)
		(end 18.564606 -30.85338)
		(width 0.254)
		(layer "F.Cu")
		(net "P1V0_AUX_MODE")
	)
	(segment
		(start 18.564606 -30.85338)
		(end 18.82013 -31.108904)
		(width 0.254)
		(layer "F.Cu")
		(net "P1V0_AUX_MODE")
	)
	(segment
		(start 26.0096 -26.0096)
		(end 26.0858 -26.0858)
		(width 0.254)
		(layer "F.Cu")
		(net "P1V0_AUX")
	)
	(segment
		(start 59.29503 -48.9712)
		(end 59.690254 -48.575976)
		(width 0.381)
		(layer "F.Cu")
		(net "P1V0_AUX")
	)
	(segment
		(start 25.90546 -23.74646)
		(end 26.0096 -23.998936)
		(width 0.254)
		(layer "F.Cu")
		(net "P1V0_AUX")
	)
	(segment
		(start 25.0444 -31.9532)
		(end 25.0444 -32.512)
		(width 0.254)
		(layer "F.Cu")
		(net "P1V0_AUX")
	)
	(segment
		(start 57.695084 -50.571146)
		(end 58.090308 -50.96637)
		(width 0.3556)
		(layer "F.Cu")
		(net "P1V0_AUX")
	)
	(segment
		(start 24.638 -32.9184)
		(end 23.0124 -32.9184)
		(width 0.254)
		(layer "F.Cu")
		(net "P1V0_AUX")
	)
	(segment
		(start 57.695084 -47.371254)
		(end 58.49493 -47.371254)
		(width 0.381)
		(layer "F.Cu")
		(net "P1V0_AUX")
	)
	(segment
		(start 23.0124 -32.9184)
		(end 22.8346 -33.0962)
		(width 0.254)
		(layer "F.Cu")
		(net "P1V0_AUX")
	)
	(segment
		(start 59.29503 -49.7713)
		(end 59.690254 -50.166524)
		(width 0.381)
		(layer "F.Cu")
		(net "P1V0_AUX")
	)
	(segment
		(start 26.0096 -23.998936)
		(end 26.0096 -26.0096)
		(width 0.254)
		(layer "F.Cu")
		(net "P1V0_AUX")
	)
	(segment
		(start 58.49493 -50.571146)
		(end 58.485532 -50.571146)
		(width 0.3556)
		(layer "F.Cu")
		(net "P1V0_AUX")
	)
	(segment
		(start 58.485532 -50.571146)
		(end 58.090308 -50.96637)
		(width 0.3556)
		(layer "F.Cu")
		(net "P1V0_AUX")
	)
	(segment
		(start 21.360892 -32.562292)
		(end 20.770088 -32.562292)
		(width 0.254)
		(layer "F.Cu")
		(net "P1V0_AUX")
	)
	(segment
		(start 22.8346 -33.0962)
		(end 21.8948 -33.0962)
		(width 0.254)
		(layer "F.Cu")
		(net "P1V0_AUX")
	)
	(segment
		(start 56.894984 -48.171354)
		(end 57.290208 -47.77613)
		(width 0.381)
		(layer "F.Cu")
		(net "P1V0_AUX")
	)
	(segment
		(start 33.655 -42.4942)
		(end 33.909 -42.2402)
		(width 0.254)
		(layer "F.Cu")
		(net "P1V0_AUX")
	)
	(segment
		(start 26.0858 -31.35884)
		(end 25.77084 -31.6738)
		(width 0.254)
		(layer "F.Cu")
		(net "P1V0_AUX")
	)
	(segment
		(start 25.76195 -23.60295)
		(end 25.90546 -23.74646)
		(width 0.254)
		(layer "F.Cu")
		(net "P1V0_AUX")
	)
	(segment
		(start 56.894984 -48.9712)
		(end 57.290208 -48.575976)
		(width 0.381)
		(layer "F.Cu")
		(net "P1V0_AUX")
	)
	(segment
		(start 56.894984 -49.7713)
		(end 56.894984 -48.9712)
		(width 0.381)
		(layer "F.Cu")
		(net "P1V0_AUX")
	)
	(segment
		(start 26.0858 -26.0858)
		(end 26.0858 -31.35884)
		(width 0.254)
		(layer "F.Cu")
		(net "P1V0_AUX")
	)
	(segment
		(start 25.3238 -31.6738)
		(end 25.0444 -31.9532)
		(width 0.254)
		(layer "F.Cu")
		(net "P1V0_AUX")
	)
	(segment
		(start 57.290208 -47.77613)
		(end 57.695084 -47.371254)
		(width 0.381)
		(layer "F.Cu")
		(net "P1V0_AUX")
	)
	(segment
		(start 25.77084 -31.6738)
		(end 25.3238 -31.6738)
		(width 0.254)
		(layer "F.Cu")
		(net "P1V0_AUX")
	)
	(segment
		(start 25.4 -23.60295)
		(end 25.76195 -23.60295)
		(width 0.254)
		(layer "F.Cu")
		(net "P1V0_AUX")
	)
	(segment
		(start 33.909 -42.2402)
		(end 33.909 -41.55821)
		(width 0.254)
		(layer "F.Cu")
		(net "P1V0_AUX")
	)
	(segment
		(start 59.690254 -47.77613)
		(end 59.29503 -48.171354)
		(width 0.381)
		(layer "F.Cu")
		(net "P1V0_AUX")
	)
	(segment
		(start 21.8948 -33.0962)
		(end 21.360892 -32.562292)
		(width 0.254)
		(layer "F.Cu")
		(net "P1V0_AUX")
	)
	(segment
		(start 25.0444 -32.512)
		(end 24.638 -32.9184)
		(width 0.254)
		(layer "F.Cu")
		(net "P1V0_AUX")
	)
	(via
		(at 77.6478 -54.9402)
		(size 0.6604)
		(drill 0.3302)
		(layers "F.Cu" "B.Cu")
		(net "P1V0_AUX")
	)
	(via
		(at 57.290208 -47.77613)
		(size 0.4572)
		(drill 0.254)
		(layers "F.Cu" "B.Cu")
		(net "P1V0_AUX")
	)
	(via
		(at 59.690254 -48.575976)
		(size 0.4572)
		(drill 0.254)
		(layers "F.Cu" "B.Cu")
		(net "P1V0_AUX")
	)
	(via
		(at 39.742618 -51.689)
		(size 0.508)
		(drill 0.254)
		(layers "F.Cu" "B.Cu")
		(net "P1V0_AUX")
	)
	(via
		(at 58.090308 -50.96637)
		(size 0.4572)
		(drill 0.254)
		(layers "F.Cu" "B.Cu")
		(net "P1V0_AUX")
	)
	(via
		(at 18.988278 -22.79523)
		(size 0.508)
		(drill 0.254)
		(layers "F.Cu" "B.Cu")
		(net "P1V0_AUX")
	)
	(via
		(at 23.204932 -23.55723)
		(size 0.508)
		(drill 0.254)
		(layers "F.Cu" "B.Cu")
		(net "P1V0_AUX")
	)
	(via
		(at 78.101698 -55.753762)
		(size 0.508)
		(drill 0.254)
		(layers "F.Cu" "B.Cu")
		(net "P1V0_AUX")
	)
	(via
		(at 75.69327 -37.113972)
		(size 0.508)
		(drill 0.254)
		(layers "F.Cu" "B.Cu")
		(net "P1V0_AUX")
	)
	(via
		(at 18.988278 -23.55723)
		(size 0.508)
		(drill 0.254)
		(layers "F.Cu" "B.Cu")
		(net "P1V0_AUX")
	)
	(via
		(at 75.370436 -54.884066)
		(size 0.508)
		(drill 0.254)
		(layers "F.Cu" "B.Cu")
		(net "P1V0_AUX")
	)
	(via
		(at 73.8378 -56.2864)
		(size 0.6604)
		(drill 0.3302)
		(layers "F.Cu" "B.Cu")
		(net "P1V0_AUX")
	)
	(via
		(at 18.988278 -21.27123)
		(size 0.508)
		(drill 0.254)
		(layers "F.Cu" "B.Cu")
		(net "P1V0_AUX")
	)
	(via
		(at 23.204932 -21.27123)
		(size 0.508)
		(drill 0.254)
		(layers "F.Cu" "B.Cu")
		(net "P1V0_AUX")
	)
	(via
		(at 23.204932 -22.03323)
		(size 0.508)
		(drill 0.254)
		(layers "F.Cu" "B.Cu")
		(net "P1V0_AUX")
	)
	(via
		(at 75.69327 -38.383972)
		(size 0.508)
		(drill 0.254)
		(layers "F.Cu" "B.Cu")
		(net "P1V0_AUX")
	)
	(via
		(at 33.655 -42.4942)
		(size 0.508)
		(drill 0.254)
		(layers "F.Cu" "B.Cu")
		(net "P1V0_AUX")
	)
	(via
		(at 75.69327 -37.748972)
		(size 0.508)
		(drill 0.254)
		(layers "F.Cu" "B.Cu")
		(net "P1V0_AUX")
	)
	(via
		(at 18.988278 -22.03323)
		(size 0.508)
		(drill 0.254)
		(layers "F.Cu" "B.Cu")
		(net "P1V0_AUX")
	)
	(via
		(at 78.854046 -55.528718)
		(size 0.508)
		(drill 0.254)
		(layers "F.Cu" "B.Cu")
		(net "P1V0_AUX")
	)
	(via
		(at 57.290208 -48.575976)
		(size 0.4572)
		(drill 0.254)
		(layers "F.Cu" "B.Cu")
		(net "P1V0_AUX")
	)
	(via
		(at 77.466698 -55.753762)
		(size 0.508)
		(drill 0.254)
		(layers "F.Cu" "B.Cu")
		(net "P1V0_AUX")
	)
	(via
		(at 29.3116 -40.513)
		(size 0.508)
		(drill 0.254)
		(layers "F.Cu" "B.Cu")
		(net "P1V0_AUX")
	)
	(via
		(at 23.204932 -22.79523)
		(size 0.508)
		(drill 0.254)
		(layers "F.Cu" "B.Cu")
		(net "P1V0_AUX")
	)
	(via
		(at 49.84496 -64.37122)
		(size 0.508)
		(drill 0.254)
		(layers "F.Cu" "B.Cu")
		(net "P1V0_AUX")
	)
	(via
		(at 59.690254 -50.166524)
		(size 0.4572)
		(drill 0.254)
		(layers "F.Cu" "B.Cu")
		(net "P1V0_AUX")
	)
	(via
		(at 59.690254 -47.77613)
		(size 0.4572)
		(drill 0.254)
		(layers "F.Cu" "B.Cu")
		(net "P1V0_AUX")
	)
	(segment
		(start 57.059322 -48.007016)
		(end 57.290208 -47.77613)
		(width 0.3556)
		(layer "B.Cu")
		(net "P1V0_AUX")
	)
	(segment
		(start 39.764462 -52.40147)
		(end 39.742618 -52.379626)
		(width 0.381)
		(layer "B.Cu")
		(net "P1V0_AUX")
	)
	(segment
		(start 40.743886 -52.40147)
		(end 39.764462 -52.40147)
		(width 0.381)
		(layer "B.Cu")
		(net "P1V0_AUX")
	)
	(segment
		(start 50.292 -66.31305)
		(end 50.292 -64.81826)
		(width 0.381)
		(layer "B.Cu")
		(net "P1V0_AUX")
	)
	(segment
		(start 39.742618 -52.379626)
		(end 39.742618 -51.689)
		(width 0.381)
		(layer "B.Cu")
		(net "P1V0_AUX")
	)
	(segment
		(start 56.43626 -48.007016)
		(end 57.059322 -48.007016)
		(width 0.3556)
		(layer "B.Cu")
		(net "P1V0_AUX")
	)
	(segment
		(start 50.292 -64.81826)
		(end 49.84496 -64.37122)
		(width 0.381)
		(layer "B.Cu")
		(net "P1V0_AUX")
	)
	(segment
		(start 32.6644 -40.894)
		(end 29.6926 -40.894)
		(width 0.381)
		(layer "In2.Cu")
		(net "P1V0_AUX")
	)
	(segment
		(start 29.6926 -40.894)
		(end 29.3116 -40.513)
		(width 0.381)
		(layer "In2.Cu")
		(net "P1V0_AUX")
	)
	(segment
		(start 33.655 -41.8846)
		(end 32.6644 -40.894)
		(width 0.381)
		(layer "In2.Cu")
		(net "P1V0_AUX")
	)
	(segment
		(start 33.655 -42.4942)
		(end 33.655 -41.8846)
		(width 0.381)
		(layer "In2.Cu")
		(net "P1V0_AUX")
	)
	(segment
		(start 13.169646 -52.973986)
		(end 13.2207 -53.02504)
		(width 0.4572)
		(layer "F.Cu")
		(net "P12V_AUX")
	)
	(segment
		(start 55.626 -14.614906)
		(end 54.433724 -15.807182)
		(width 0.4572)
		(layer "F.Cu")
		(net "P12V_AUX")
	)
	(segment
		(start 55.626 -11.19505)
		(end 55.626 -14.614906)
		(width 0.4572)
		(layer "F.Cu")
		(net "P12V_AUX")
	)
	(segment
		(start 13.169646 -52.408582)
		(end 13.169646 -52.973986)
		(width 0.4572)
		(layer "F.Cu")
		(net "P12V_AUX")
	)
	(via
		(at 81.811622 -103.251)
		(size 0.508)
		(drill 0.254)
		(layers "F.Cu" "B.Cu")
		(net "P12V_AUX")
	)
	(via
		(at 4.044188 -57.700672)
		(size 0.508)
		(drill 0.254)
		(layers "F.Cu" "B.Cu")
		(net "P12V_AUX")
	)
	(via
		(at 75.625452 -116.438172)
		(size 0.508)
		(drill 0.254)
		(layers "F.Cu" "B.Cu")
		(net "P12V_AUX")
	)
	(via
		(at 82.551778 -82.806032)
		(size 0.508)
		(drill 0.254)
		(layers "F.Cu" "B.Cu")
		(net "P12V_AUX")
	)
	(via
		(at 5.334 -57.023)
		(size 0.508)
		(drill 0.254)
		(layers "F.Cu" "B.Cu")
		(net "P12V_AUX")
	)
	(via
		(at 84.6582 -102.4636)
		(size 0.6604)
		(drill 0.3302)
		(layers "F.Cu" "B.Cu")
		(net "P12V_AUX")
	)
	(via
		(at 31.44266 -57.824624)
		(size 0.508)
		(drill 0.254)
		(layers "F.Cu" "B.Cu")
		(net "P12V_AUX")
	)
	(via
		(at 75.115166 -116.817648)
		(size 0.508)
		(drill 0.254)
		(layers "F.Cu" "B.Cu")
		(net "P12V_AUX")
	)
	(via
		(at 83.589622 -103.251)
		(size 0.508)
		(drill 0.254)
		(layers "F.Cu" "B.Cu")
		(net "P12V_AUX")
	)
	(via
		(at 82.551778 -83.466432)
		(size 0.508)
		(drill 0.254)
		(layers "F.Cu" "B.Cu")
		(net "P12V_AUX")
	)
	(via
		(at 83.236816 -82.17789)
		(size 0.508)
		(drill 0.254)
		(layers "F.Cu" "B.Cu")
		(net "P12V_AUX")
	)
	(via
		(at 21.21408 -40.26408)
		(size 0.508)
		(drill 0.254)
		(layers "F.Cu" "B.Cu")
		(net "P12V_AUX")
	)
	(via
		(at 75.625452 -115.676172)
		(size 0.508)
		(drill 0.254)
		(layers "F.Cu" "B.Cu")
		(net "P12V_AUX")
	)
	(via
		(at 31.41726 -58.459624)
		(size 0.508)
		(drill 0.254)
		(layers "F.Cu" "B.Cu")
		(net "P12V_AUX")
	)
	(via
		(at 82.700622 -103.251)
		(size 0.508)
		(drill 0.254)
		(layers "F.Cu" "B.Cu")
		(net "P12V_AUX")
	)
	(via
		(at 75.115166 -116.055648)
		(size 0.508)
		(drill 0.254)
		(layers "F.Cu" "B.Cu")
		(net "P12V_AUX")
	)
	(via
		(at 54.433724 -15.807182)
		(size 0.508)
		(drill 0.254)
		(layers "F.Cu" "B.Cu")
		(net "P12V_AUX")
	)
	(via
		(at 83.236816 -82.81289)
		(size 0.508)
		(drill 0.254)
		(layers "F.Cu" "B.Cu")
		(net "P12V_AUX")
	)
	(via
		(at 4.679188 -57.040272)
		(size 0.508)
		(drill 0.254)
		(layers "F.Cu" "B.Cu")
		(net "P12V_AUX")
	)
	(via
		(at 21.8694 -40.23106)
		(size 0.508)
		(drill 0.254)
		(layers "F.Cu" "B.Cu")
		(net "P12V_AUX")
	)
	(via
		(at 81.5594 -104.2416)
		(size 0.6604)
		(drill 0.3302)
		(layers "F.Cu" "B.Cu")
		(net "P12V_AUX")
	)
	(via
		(at 32.3088 -56.8198)
		(size 0.6604)
		(drill 0.3302)
		(layers "F.Cu" "B.Cu")
		(net "P12V_AUX")
	)
	(via
		(at 88.265 -98.552)
		(size 0.6604)
		(drill 0.3302)
		(layers "F.Cu" "B.Cu")
		(net "P12V_AUX")
	)
	(via
		(at 21.18614 -40.89908)
		(size 0.508)
		(drill 0.254)
		(layers "F.Cu" "B.Cu")
		(net "P12V_AUX")
	)
	(via
		(at 13.2207 -53.02504)
		(size 0.508)
		(drill 0.254)
		(layers "F.Cu" "B.Cu")
		(net "P12V_AUX")
	)
	(via
		(at 83.236816 -83.47329)
		(size 0.508)
		(drill 0.254)
		(layers "F.Cu" "B.Cu")
		(net "P12V_AUX")
	)
	(via
		(at 11.213846 -57.081928)
		(size 0.508)
		(drill 0.254)
		(layers "F.Cu" "B.Cu")
		(net "P12V_AUX")
	)
	(via
		(at 10.666222 -56.624728)
		(size 0.508)
		(drill 0.254)
		(layers "F.Cu" "B.Cu")
		(net "P12V_AUX")
	)
	(via
		(at 88.265 -88.9)
		(size 0.6604)
		(drill 0.3302)
		(layers "F.Cu" "B.Cu")
		(net "P12V_AUX")
	)
	(via
		(at 4.679188 -57.700672)
		(size 0.508)
		(drill 0.254)
		(layers "F.Cu" "B.Cu")
		(net "P12V_AUX")
	)
	(via
		(at 75.625452 -114.914172)
		(size 0.508)
		(drill 0.254)
		(layers "F.Cu" "B.Cu")
		(net "P12V_AUX")
	)
	(via
		(at 80.922622 -103.251)
		(size 0.508)
		(drill 0.254)
		(layers "F.Cu" "B.Cu")
		(net "P12V_AUX")
	)
	(via
		(at 10.031222 -56.624728)
		(size 0.508)
		(drill 0.254)
		(layers "F.Cu" "B.Cu")
		(net "P12V_AUX")
	)
	(via
		(at 5.334 -57.658)
		(size 0.508)
		(drill 0.254)
		(layers "F.Cu" "B.Cu")
		(net "P12V_AUX")
	)
	(via
		(at 10.666222 -55.964328)
		(size 0.508)
		(drill 0.254)
		(layers "F.Cu" "B.Cu")
		(net "P12V_AUX")
	)
	(via
		(at 75.115166 -115.293648)
		(size 0.508)
		(drill 0.254)
		(layers "F.Cu" "B.Cu")
		(net "P12V_AUX")
	)
	(via
		(at 82.551778 -82.171032)
		(size 0.508)
		(drill 0.254)
		(layers "F.Cu" "B.Cu")
		(net "P12V_AUX")
	)
	(via
		(at 11.213846 -57.742328)
		(size 0.508)
		(drill 0.254)
		(layers "F.Cu" "B.Cu")
		(net "P12V_AUX")
	)
	(via
		(at 21.8694 -39.58336)
		(size 0.508)
		(drill 0.254)
		(layers "F.Cu" "B.Cu")
		(net "P12V_AUX")
	)
	(via
		(at 10.031222 -55.964328)
		(size 0.508)
		(drill 0.254)
		(layers "F.Cu" "B.Cu")
		(net "P12V_AUX")
	)
	(via
		(at 33.408112 -29.024834)
		(size 0.508)
		(drill 0.254)
		(layers "F.Cu" "B.Cu")
		(net "P12V_AUX")
	)
	(via
		(at 21.8694 -38.94836)
		(size 0.508)
		(drill 0.254)
		(layers "F.Cu" "B.Cu")
		(net "P12V_AUX")
	)
	(via
		(at 4.044188 -57.040272)
		(size 0.508)
		(drill 0.254)
		(layers "F.Cu" "B.Cu")
		(net "P12V_AUX")
	)
	(segment
		(start 21.8694 -40.23106)
		(end 21.8694 -39.58336)
		(width 0.4572)
		(layer "In4.Cu")
		(net "P12V_AUX")
	)
	(segment
		(start 33.408112 -29.024834)
		(end 32.01924 -30.413706)
		(width 0.4572)
		(layer "In4.Cu")
		(net "P12V_AUX")
	)
	(segment
		(start 21.8694 -38.297104)
		(end 21.8694 -38.94836)
		(width 0.4572)
		(layer "In4.Cu")
		(net "P12V_AUX")
	)
	(segment
		(start 26.975816 -30.7086)
		(end 26.042366 -30.7086)
		(width 0.4572)
		(layer "In4.Cu")
		(net "P12V_AUX")
	)
	(segment
		(start 26.042366 -30.7086)
		(end 24.598884 -32.152082)
		(width 0.4572)
		(layer "In4.Cu")
		(net "P12V_AUX")
	)
	(segment
		(start 23.648416 -36.518088)
		(end 21.8694 -38.297104)
		(width 0.4572)
		(layer "In4.Cu")
		(net "P12V_AUX")
	)
	(segment
		(start 24.598884 -32.152082)
		(end 24.598884 -32.85617)
		(width 0.4572)
		(layer "In4.Cu")
		(net "P12V_AUX")
	)
	(segment
		(start 27.299412 -31.032196)
		(end 26.975816 -30.7086)
		(width 0.4572)
		(layer "In4.Cu")
		(net "P12V_AUX")
	)
	(segment
		(start 21.8694 -39.58336)
		(end 21.8694 -38.94836)
		(width 0.4572)
		(layer "In4.Cu")
		(net "P12V_AUX")
	)
	(segment
		(start 23.648416 -33.806638)
		(end 23.648416 -36.518088)
		(width 0.4572)
		(layer "In4.Cu")
		(net "P12V_AUX")
	)
	(segment
		(start 28.423362 -30.413706)
		(end 27.804872 -31.032196)
		(width 0.4572)
		(layer "In4.Cu")
		(net "P12V_AUX")
	)
	(segment
		(start 27.804872 -31.032196)
		(end 27.299412 -31.032196)
		(width 0.4572)
		(layer "In4.Cu")
		(net "P12V_AUX")
	)
	(segment
		(start 24.598884 -32.85617)
		(end 23.648416 -33.806638)
		(width 0.4572)
		(layer "In4.Cu")
		(net "P12V_AUX")
	)
	(segment
		(start 32.01924 -30.413706)
		(end 28.423362 -30.413706)
		(width 0.4572)
		(layer "In4.Cu")
		(net "P12V_AUX")
	)
	(segment
		(start 35.056826 -24.316944)
		(end 35.514026 -23.859744)
		(width 0.4572)
		(layer "In9.Cu")
		(net "P12V_AUX")
	)
	(segment
		(start 37.662358 -23.859744)
		(end 41.465246 -20.056856)
		(width 0.4572)
		(layer "In9.Cu")
		(net "P12V_AUX")
	)
	(segment
		(start 51.95824 -20.056856)
		(end 53.38445 -18.630646)
		(width 0.4572)
		(layer "In9.Cu")
		(net "P12V_AUX")
	)
	(segment
		(start 41.465246 -20.056856)
		(end 51.95824 -20.056856)
		(width 0.4572)
		(layer "In9.Cu")
		(net "P12V_AUX")
	)
	(segment
		(start 33.408112 -29.024834)
		(end 33.408112 -28.87472)
		(width 0.4572)
		(layer "In9.Cu")
		(net "P12V_AUX")
	)
	(segment
		(start 35.514026 -23.859744)
		(end 37.662358 -23.859744)
		(width 0.4572)
		(layer "In9.Cu")
		(net "P12V_AUX")
	)
	(segment
		(start 33.408112 -28.87472)
		(end 35.056826 -27.226006)
		(width 0.4572)
		(layer "In9.Cu")
		(net "P12V_AUX")
	)
	(segment
		(start 35.056826 -27.226006)
		(end 35.056826 -24.316944)
		(width 0.4572)
		(layer "In9.Cu")
		(net "P12V_AUX")
	)
	(segment
		(start 53.38445 -18.630646)
		(end 53.38445 -16.856456)
		(width 0.4572)
		(layer "In9.Cu")
		(net "P12V_AUX")
	)
	(segment
		(start 53.38445 -16.856456)
		(end 54.433724 -15.807182)
		(width 0.4572)
		(layer "In9.Cu")
		(net "P12V_AUX")
	)
	(segment
		(start 61.695076 -52.171346)
		(end 62.0903 -51.776122)
		(width 0.3556)
		(layer "F.Cu")
		(net "P0V6_DDR_VREF_AUX")
	)
	(segment
		(start 62.0903 -51.776122)
		(end 62.0903 -51.76647)
		(width 0.3556)
		(layer "F.Cu")
		(net "P0V6_DDR_VREF_AUX")
	)
	(segment
		(start 61.695076 -51.371246)
		(end 62.0903 -51.76647)
		(width 0.3556)
		(layer "F.Cu")
		(net "P0V6_DDR_VREF_AUX")
	)
	(segment
		(start 73.052432 -45.107352)
		(end 72.67067 -44.72559)
		(width 0.3556)
		(layer "F.Cu")
		(net "P0V6_DDR_VREF_AUX")
	)
	(via
		(at 83.514692 -54.956456)
		(size 0.6604)
		(drill 0.3302)
		(layers "F.Cu" "B.Cu")
		(net "P0V6_DDR_VREF_AUX")
	)
	(via
		(at 62.0903 -51.76647)
		(size 0.4572)
		(drill 0.254)
		(layers "F.Cu" "B.Cu")
		(net "P0V6_DDR_VREF_AUX")
	)
	(via
		(at 82.990182 -53.31079)
		(size 0.508)
		(drill 0.254)
		(layers "F.Cu" "B.Cu")
		(net "P0V6_DDR_VREF_AUX")
	)
	(via
		(at 81.516474 -54.708298)
		(size 0.508)
		(drill 0.254)
		(layers "F.Cu" "B.Cu")
		(net "P0V6_DDR_VREF_AUX")
	)
	(via
		(at 82.244692 -54.956456)
		(size 0.6604)
		(drill 0.3302)
		(layers "F.Cu" "B.Cu")
		(net "P0V6_DDR_VREF_AUX")
	)
	(via
		(at 82.990182 -51.17719)
		(size 0.508)
		(drill 0.254)
		(layers "F.Cu" "B.Cu")
		(net "P0V6_DDR_VREF_AUX")
	)
	(via
		(at 81.54543 -53.405278)
		(size 0.508)
		(drill 0.254)
		(layers "F.Cu" "B.Cu")
		(net "P0V6_DDR_VREF_AUX")
	)
	(via
		(at 77.47 -64.1096)
		(size 0.508)
		(drill 0.254)
		(layers "F.Cu" "B.Cu")
		(net "P0V6_DDR_VREF_AUX")
	)
	(via
		(at 83.040728 -52.24399)
		(size 0.508)
		(drill 0.254)
		(layers "F.Cu" "B.Cu")
		(net "P0V6_DDR_VREF_AUX")
	)
	(via
		(at 81.517998 -54.061106)
		(size 0.508)
		(drill 0.254)
		(layers "F.Cu" "B.Cu")
		(net "P0V6_DDR_VREF_AUX")
	)
	(via
		(at 82.989674 -54.266592)
		(size 0.508)
		(drill 0.254)
		(layers "F.Cu" "B.Cu")
		(net "P0V6_DDR_VREF_AUX")
	)
	(via
		(at 78.1304 -64.0842)
		(size 0.508)
		(drill 0.254)
		(layers "F.Cu" "B.Cu")
		(net "P0V6_DDR_VREF_AUX")
	)
	(via
		(at 72.67067 -44.72559)
		(size 0.4572)
		(drill 0.254)
		(layers "F.Cu" "B.Cu")
		(net "P0V6_DDR_VREF_AUX")
	)
	(segment
		(start 72.088502 -44.583858)
		(end 72.528938 -44.583858)
		(width 0.3048)
		(layer "B.Cu")
		(net "P0V6_DDR_VREF_AUX")
	)
	(segment
		(start 72.06107 -44.61129)
		(end 72.088502 -44.583858)
		(width 0.3048)
		(layer "B.Cu")
		(net "P0V6_DDR_VREF_AUX")
	)
	(segment
		(start 62.103 -52.43195)
		(end 62.103 -51.77917)
		(width 0.381)
		(layer "B.Cu")
		(net "P0V6_DDR_VREF_AUX")
	)
	(segment
		(start 72.528938 -44.583858)
		(end 72.67067 -44.72559)
		(width 0.3048)
		(layer "B.Cu")
		(net "P0V6_DDR_VREF_AUX")
	)
	(segment
		(start 60.722256 -53.133498)
		(end 60.722256 -52.827936)
		(width 0.3556)
		(layer "B.Cu")
		(net "P0V6_DDR_VREF_AUX")
	)
	(segment
		(start 61.063378 -52.136294)
		(end 61.433202 -51.76647)
		(width 0.3556)
		(layer "B.Cu")
		(net "P0V6_DDR_VREF_AUX")
	)
	(segment
		(start 61.063378 -52.486814)
		(end 61.063378 -52.136294)
		(width 0.3556)
		(layer "B.Cu")
		(net "P0V6_DDR_VREF_AUX")
	)
	(segment
		(start 60.722256 -52.827936)
		(end 61.063378 -52.486814)
		(width 0.3556)
		(layer "B.Cu")
		(net "P0V6_DDR_VREF_AUX")
	)
	(segment
		(start 62.103 -51.77917)
		(end 62.0903 -51.76647)
		(width 0.381)
		(layer "B.Cu")
		(net "P0V6_DDR_VREF_AUX")
	)
	(segment
		(start 61.433202 -51.76647)
		(end 62.0903 -51.76647)
		(width 0.3556)
		(layer "B.Cu")
		(net "P0V6_DDR_VREF_AUX")
	)
	(segment
		(start 79.452216 -50.707544)
		(end 79.833978 -51.089306)
		(width 0.11684)
		(layer "F.Cu")
		(net "M_BMC_DDR4_ZQU")
	)
	(via
		(at 79.833978 -51.089306)
		(size 0.4572)
		(drill 0.254)
		(layers "F.Cu" "B.Cu")
		(net "M_BMC_DDR4_ZQU")
	)
	(segment
		(start 77.77988 -51.492912)
		(end 79.430372 -51.492912)
		(width 0.11684)
		(layer "B.Cu")
		(net "M_BMC_DDR4_ZQU")
	)
	(segment
		(start 79.430372 -51.492912)
		(end 79.833978 -51.089306)
		(width 0.11684)
		(layer "B.Cu")
		(net "M_BMC_DDR4_ZQU")
	)
	(segment
		(start 77.62367 -51.000406)
		(end 77.62367 -51.336702)
		(width 0.11684)
		(layer "B.Cu")
		(net "M_BMC_DDR4_ZQU")
	)
	(segment
		(start 77.62367 -51.336702)
		(end 77.77988 -51.492912)
		(width 0.11684)
		(layer "B.Cu")
		(net "M_BMC_DDR4_ZQU")
	)
	(segment
		(start 63.295022 -47.371254)
		(end 63.690246 -46.97603)
		(width 0.11684)
		(layer "F.Cu")
		(net "M_BMC_DDR4_RST_N")
	)
	(segment
		(start 72.735948 -43.507406)
		(end 73.052432 -43.507406)
		(width 0.11684)
		(layer "F.Cu")
		(net "M_BMC_DDR4_RST_N")
	)
	(segment
		(start 71.87565 -43.93565)
		(end 72.008238 -43.803062)
		(width 0.11684)
		(layer "F.Cu")
		(net "M_BMC_DDR4_RST_N")
	)
	(via
		(at 71.87565 -43.93565)
		(size 0.4572)
		(drill 0.254)
		(layers "F.Cu" "B.Cu")
		(net "M_BMC_DDR4_RST_N")
	)
	(via
		(at 63.690246 -46.97603)
		(size 0.4572)
		(drill 0.254)
		(layers "F.Cu" "B.Cu")
		(net "M_BMC_DDR4_RST_N")
	)
	(arc
		(start 72.63003 -43.519852)
		(mid 72.682622 -43.510501)
		(end 72.735948 -43.507406)
		(width 0.11684)
		(layer "F.Cu")
		(net "M_BMC_DDR4_RST_N")
	)
	(arc
		(start 72.106536 -43.727878)
		(mid 72.360856 -43.605179)
		(end 72.63003 -43.519852)
		(width 0.11684)
		(layer "F.Cu")
		(net "M_BMC_DDR4_RST_N")
	)
	(arc
		(start 72.008238 -43.803062)
		(mid 72.0549 -43.762218)
		(end 72.106536 -43.727878)
		(width 0.11684)
		(layer "F.Cu")
		(net "M_BMC_DDR4_RST_N")
	)
	(segment
		(start 70.615556 -44.24426)
		(end 71.38797 -44.24426)
		(width 0.08382)
		(layer "In9.Cu")
		(net "M_BMC_DDR4_RST_N")
	)
	(segment
		(start 70.038976 -43.17873)
		(end 70.409308 -43.17873)
		(width 0.08382)
		(layer "In9.Cu")
		(net "M_BMC_DDR4_RST_N")
	)
	(segment
		(start 66.662554 -43.625008)
		(end 67.096386 -43.625008)
		(width 0.08382)
		(layer "In9.Cu")
		(net "M_BMC_DDR4_RST_N")
	)
	(segment
		(start 61.701426 -47.219108)
		(end 61.701426 -46.685962)
		(width 0.08382)
		(layer "In9.Cu")
		(net "M_BMC_DDR4_RST_N")
	)
	(segment
		(start 68.474844 -43.822112)
		(end 68.474844 -43.97629)
		(width 0.08382)
		(layer "In9.Cu")
		(net "M_BMC_DDR4_RST_N")
	)
	(segment
		(start 65.788794 -44.648882)
		(end 65.788794 -45.470064)
		(width 0.08382)
		(layer "In9.Cu")
		(net "M_BMC_DDR4_RST_N")
	)
	(segment
		(start 65.406778 -44.557696)
		(end 65.697608 -44.557696)
		(width 0.08382)
		(layer "In9.Cu")
		(net "M_BMC_DDR4_RST_N")
	)
	(segment
		(start 67.270884 -44.45)
		(end 67.822064 -44.45)
		(width 0.08382)
		(layer "In9.Cu")
		(net "M_BMC_DDR4_RST_N")
	)
	(segment
		(start 61.539882 -46.524418)
		(end 60.95111 -46.524418)
		(width 0.08382)
		(layer "In9.Cu")
		(net "M_BMC_DDR4_RST_N")
	)
	(segment
		(start 65.320418 -45.083476)
		(end 65.320418 -44.644056)
		(width 0.08382)
		(layer "In9.Cu")
		(net "M_BMC_DDR4_RST_N")
	)
	(segment
		(start 67.905884 -44.36618)
		(end 67.905884 -43.812206)
		(width 0.08382)
		(layer "In9.Cu")
		(net "M_BMC_DDR4_RST_N")
	)
	(segment
		(start 66.33845 -46.00321)
		(end 66.33845 -45.131228)
		(width 0.08382)
		(layer "In9.Cu")
		(net "M_BMC_DDR4_RST_N")
	)
	(segment
		(start 61.004958 -45.782738)
		(end 64.645032 -45.782738)
		(width 0.08382)
		(layer "In9.Cu")
		(net "M_BMC_DDR4_RST_N")
	)
	(segment
		(start 65.315338 -46.160182)
		(end 66.181478 -46.160182)
		(width 0.08382)
		(layer "In9.Cu")
		(net "M_BMC_DDR4_RST_N")
	)
	(segment
		(start 62.36335 -47.36846)
		(end 61.850778 -47.36846)
		(width 0.08382)
		(layer "In9.Cu")
		(net "M_BMC_DDR4_RST_N")
	)
	(segment
		(start 68.747386 -44.248832)
		(end 68.841112 -44.248832)
		(width 0.08382)
		(layer "In9.Cu")
		(net "M_BMC_DDR4_RST_N")
	)
	(segment
		(start 69.06387 -44.47159)
		(end 69.06387 -44.577508)
		(width 0.08382)
		(layer "In9.Cu")
		(net "M_BMC_DDR4_RST_N")
	)
	(segment
		(start 68.03136 -43.68673)
		(end 68.339462 -43.68673)
		(width 0.08382)
		(layer "In9.Cu")
		(net "M_BMC_DDR4_RST_N")
	)
	(segment
		(start 65.174622 -45.72)
		(end 65.174622 -46.019466)
		(width 0.08382)
		(layer "In9.Cu")
		(net "M_BMC_DDR4_RST_N")
	)
	(segment
		(start 69.286628 -44.800266)
		(end 69.745098 -44.800266)
		(width 0.08382)
		(layer "In9.Cu")
		(net "M_BMC_DDR4_RST_N")
	)
	(segment
		(start 62.48146 -46.69282)
		(end 62.48146 -47.25035)
		(width 0.08382)
		(layer "In9.Cu")
		(net "M_BMC_DDR4_RST_N")
	)
	(segment
		(start 65.098676 -45.26788)
		(end 65.136014 -45.26788)
		(width 0.08382)
		(layer "In9.Cu")
		(net "M_BMC_DDR4_RST_N")
	)
	(segment
		(start 60.833 -46.406308)
		(end 60.833 -45.954696)
		(width 0.08382)
		(layer "In9.Cu")
		(net "M_BMC_DDR4_RST_N")
	)
	(segment
		(start 69.934328 -44.611036)
		(end 69.934328 -43.283378)
		(width 0.08382)
		(layer "In9.Cu")
		(net "M_BMC_DDR4_RST_N")
	)
	(segment
		(start 65.650872 -45.607986)
		(end 65.286636 -45.607986)
		(width 0.08382)
		(layer "In9.Cu")
		(net "M_BMC_DDR4_RST_N")
	)
	(segment
		(start 63.603886 -46.578266)
		(end 62.596014 -46.578266)
		(width 0.08382)
		(layer "In9.Cu")
		(net "M_BMC_DDR4_RST_N")
	)
	(segment
		(start 63.690246 -46.97603)
		(end 63.690246 -46.664626)
		(width 0.08382)
		(layer "In9.Cu")
		(net "M_BMC_DDR4_RST_N")
	)
	(segment
		(start 70.529196 -43.298618)
		(end 70.529196 -44.1579)
		(width 0.08382)
		(layer "In9.Cu")
		(net "M_BMC_DDR4_RST_N")
	)
	(segment
		(start 66.556636 -44.89831)
		(end 66.556636 -43.730926)
		(width 0.08382)
		(layer "In9.Cu")
		(net "M_BMC_DDR4_RST_N")
	)
	(segment
		(start 71.693532 -44.117768)
		(end 71.87565 -43.93565)
		(width 0.08382)
		(layer "In9.Cu")
		(net "M_BMC_DDR4_RST_N")
	)
	(segment
		(start 64.893952 -45.533818)
		(end 64.893952 -45.472604)
		(width 0.08382)
		(layer "In9.Cu")
		(net "M_BMC_DDR4_RST_N")
	)
	(segment
		(start 67.18681 -43.715432)
		(end 67.18681 -44.365926)
		(width 0.08382)
		(layer "In9.Cu")
		(net "M_BMC_DDR4_RST_N")
	)
	(arc
		(start 62.596014 -46.578266)
		(mid 62.515012 -46.611818)
		(end 62.48146 -46.69282)
		(width 0.08382)
		(layer "In9.Cu")
		(net "M_BMC_DDR4_RST_N")
	)
	(arc
		(start 71.38797 -44.24426)
		(mid 71.553324 -44.211387)
		(end 71.693532 -44.117768)
		(width 0.08382)
		(layer "In9.Cu")
		(net "M_BMC_DDR4_RST_N")
	)
	(arc
		(start 65.320418 -44.644056)
		(mid 65.345712 -44.58299)
		(end 65.406778 -44.557696)
		(width 0.08382)
		(layer "In9.Cu")
		(net "M_BMC_DDR4_RST_N")
	)
	(arc
		(start 60.95111 -46.524418)
		(mid 60.867594 -46.489824)
		(end 60.833 -46.406308)
		(width 0.08382)
		(layer "In9.Cu")
		(net "M_BMC_DDR4_RST_N")
	)
	(arc
		(start 62.48146 -47.25035)
		(mid 62.446866 -47.333866)
		(end 62.36335 -47.36846)
		(width 0.08382)
		(layer "In9.Cu")
		(net "M_BMC_DDR4_RST_N")
	)
	(arc
		(start 65.174622 -46.019466)
		(mid 65.215837 -46.118967)
		(end 65.315338 -46.160182)
		(width 0.08382)
		(layer "In9.Cu")
		(net "M_BMC_DDR4_RST_N")
	)
	(arc
		(start 63.690246 -46.664626)
		(mid 63.664952 -46.60356)
		(end 63.603886 -46.578266)
		(width 0.08382)
		(layer "In9.Cu")
		(net "M_BMC_DDR4_RST_N")
	)
	(arc
		(start 64.893952 -45.472604)
		(mid 64.953914 -45.327842)
		(end 65.098676 -45.26788)
		(width 0.08382)
		(layer "In9.Cu")
		(net "M_BMC_DDR4_RST_N")
	)
	(arc
		(start 70.409308 -43.17873)
		(mid 70.494082 -43.213844)
		(end 70.529196 -43.298618)
		(width 0.08382)
		(layer "In9.Cu")
		(net "M_BMC_DDR4_RST_N")
	)
	(arc
		(start 60.833 -45.954696)
		(mid 60.883365 -45.833103)
		(end 61.004958 -45.782738)
		(width 0.08382)
		(layer "In9.Cu")
		(net "M_BMC_DDR4_RST_N")
	)
	(arc
		(start 69.745098 -44.800266)
		(mid 69.878904 -44.744842)
		(end 69.934328 -44.611036)
		(width 0.08382)
		(layer "In9.Cu")
		(net "M_BMC_DDR4_RST_N")
	)
	(arc
		(start 66.463672 -44.99737)
		(mid 66.529722 -44.966218)
		(end 66.556636 -44.89831)
		(width 0.08382)
		(layer "In9.Cu")
		(net "M_BMC_DDR4_RST_N")
	)
	(arc
		(start 65.697608 -44.557696)
		(mid 65.762086 -44.584404)
		(end 65.788794 -44.648882)
		(width 0.08382)
		(layer "In9.Cu")
		(net "M_BMC_DDR4_RST_N")
	)
	(arc
		(start 65.286636 -45.607986)
		(mid 65.20743 -45.640794)
		(end 65.174622 -45.72)
		(width 0.08382)
		(layer "In9.Cu")
		(net "M_BMC_DDR4_RST_N")
	)
	(arc
		(start 64.645032 -45.782738)
		(mid 64.821045 -45.709831)
		(end 64.893952 -45.533818)
		(width 0.08382)
		(layer "In9.Cu")
		(net "M_BMC_DDR4_RST_N")
	)
	(arc
		(start 65.788794 -45.470064)
		(mid 65.748398 -45.56759)
		(end 65.650872 -45.607986)
		(width 0.08382)
		(layer "In9.Cu")
		(net "M_BMC_DDR4_RST_N")
	)
	(arc
		(start 68.339462 -43.68673)
		(mid 68.435192 -43.726382)
		(end 68.474844 -43.822112)
		(width 0.08382)
		(layer "In9.Cu")
		(net "M_BMC_DDR4_RST_N")
	)
	(arc
		(start 65.136014 -45.26788)
		(mid 65.266407 -45.213869)
		(end 65.320418 -45.083476)
		(width 0.08382)
		(layer "In9.Cu")
		(net "M_BMC_DDR4_RST_N")
	)
	(arc
		(start 66.556636 -43.730926)
		(mid 66.587659 -43.656031)
		(end 66.662554 -43.625008)
		(width 0.08382)
		(layer "In9.Cu")
		(net "M_BMC_DDR4_RST_N")
	)
	(arc
		(start 69.934328 -43.283378)
		(mid 69.964979 -43.209381)
		(end 70.038976 -43.17873)
		(width 0.08382)
		(layer "In9.Cu")
		(net "M_BMC_DDR4_RST_N")
	)
	(arc
		(start 67.905884 -43.812206)
		(mid 67.942635 -43.723481)
		(end 68.03136 -43.68673)
		(width 0.08382)
		(layer "In9.Cu")
		(net "M_BMC_DDR4_RST_N")
	)
	(arc
		(start 66.181478 -46.160182)
		(mid 66.292474 -46.114206)
		(end 66.33845 -46.00321)
		(width 0.08382)
		(layer "In9.Cu")
		(net "M_BMC_DDR4_RST_N")
	)
	(arc
		(start 67.822064 -44.45)
		(mid 67.881334 -44.42545)
		(end 67.905884 -44.36618)
		(width 0.08382)
		(layer "In9.Cu")
		(net "M_BMC_DDR4_RST_N")
	)
	(arc
		(start 67.18681 -44.365926)
		(mid 67.211435 -44.425375)
		(end 67.270884 -44.45)
		(width 0.08382)
		(layer "In9.Cu")
		(net "M_BMC_DDR4_RST_N")
	)
	(arc
		(start 68.474844 -43.97629)
		(mid 68.55467 -44.169006)
		(end 68.747386 -44.248832)
		(width 0.08382)
		(layer "In9.Cu")
		(net "M_BMC_DDR4_RST_N")
	)
	(arc
		(start 61.701426 -46.685962)
		(mid 61.654111 -46.571733)
		(end 61.539882 -46.524418)
		(width 0.08382)
		(layer "In9.Cu")
		(net "M_BMC_DDR4_RST_N")
	)
	(arc
		(start 61.850778 -47.36846)
		(mid 61.74517 -47.324716)
		(end 61.701426 -47.219108)
		(width 0.08382)
		(layer "In9.Cu")
		(net "M_BMC_DDR4_RST_N")
	)
	(arc
		(start 68.841112 -44.248832)
		(mid 68.998626 -44.314076)
		(end 69.06387 -44.47159)
		(width 0.08382)
		(layer "In9.Cu")
		(net "M_BMC_DDR4_RST_N")
	)
	(arc
		(start 66.33845 -45.131228)
		(mid 66.374639 -45.039592)
		(end 66.463672 -44.99737)
		(width 0.08382)
		(layer "In9.Cu")
		(net "M_BMC_DDR4_RST_N")
	)
	(arc
		(start 69.06387 -44.577508)
		(mid 69.129114 -44.735022)
		(end 69.286628 -44.800266)
		(width 0.08382)
		(layer "In9.Cu")
		(net "M_BMC_DDR4_RST_N")
	)
	(arc
		(start 70.529196 -44.1579)
		(mid 70.55449 -44.218966)
		(end 70.615556 -44.24426)
		(width 0.08382)
		(layer "In9.Cu")
		(net "M_BMC_DDR4_RST_N")
	)
	(arc
		(start 67.096386 -43.625008)
		(mid 67.160325 -43.651493)
		(end 67.18681 -43.715432)
		(width 0.08382)
		(layer "In9.Cu")
		(net "M_BMC_DDR4_RST_N")
	)
	(segment
		(start 61.695076 -44.171362)
		(end 62.0903 -43.776138)
		(width 0.11684)
		(layer "F.Cu")
		(net "M_BMC_DDR4_MWE_N")
	)
	(segment
		(start 73.852278 -45.907452)
		(end 74.23404 -45.52569)
		(width 0.11684)
		(layer "F.Cu")
		(net "M_BMC_DDR4_MWE_N")
	)
	(via
		(at 74.23404 -45.52569)
		(size 0.4572)
		(drill 0.254)
		(layers "F.Cu" "B.Cu")
		(net "M_BMC_DDR4_MWE_N")
	)
	(via
		(at 62.0903 -43.776138)
		(size 0.4572)
		(drill 0.254)
		(layers "F.Cu" "B.Cu")
		(net "M_BMC_DDR4_MWE_N")
	)
	(segment
		(start 79.070708 -41.93032)
		(end 78.050644 -41.93032)
		(width 0.11684)
		(layer "B.Cu")
		(net "M_BMC_DDR4_MWE_N")
	)
	(segment
		(start 76.345796 -44.296076)
		(end 75.579224 -45.062648)
		(width 0.11684)
		(layer "B.Cu")
		(net "M_BMC_DDR4_MWE_N")
	)
	(segment
		(start 79.440532 -41.375838)
		(end 79.440532 -41.566084)
		(width 0.11684)
		(layer "B.Cu")
		(net "M_BMC_DDR4_MWE_N")
	)
	(segment
		(start 77.491336 -42.161968)
		(end 76.643738 -43.009566)
		(width 0.11684)
		(layer "B.Cu")
		(net "M_BMC_DDR4_MWE_N")
	)
	(segment
		(start 82.76717 -40.490394)
		(end 80.293972 -40.490394)
		(width 0.11684)
		(layer "B.Cu")
		(net "M_BMC_DDR4_MWE_N")
	)
	(segment
		(start 82.76717 -39.474394)
		(end 82.76717 -40.490394)
		(width 0.11684)
		(layer "B.Cu")
		(net "M_BMC_DDR4_MWE_N")
	)
	(segment
		(start 75.476354 -45.10532)
		(end 74.966322 -45.10532)
		(width 0.11684)
		(layer "B.Cu")
		(net "M_BMC_DDR4_MWE_N")
	)
	(segment
		(start 79.579978 -40.872664)
		(end 79.440532 -41.375838)
		(width 0.11684)
		(layer "B.Cu")
		(net "M_BMC_DDR4_MWE_N")
	)
	(segment
		(start 74.826114 -45.163486)
		(end 74.572876 -45.416724)
		(width 0.11684)
		(layer "B.Cu")
		(net "M_BMC_DDR4_MWE_N")
	)
	(segment
		(start 74.266044 -45.52569)
		(end 74.23404 -45.52569)
		(width 0.11684)
		(layer "B.Cu")
		(net "M_BMC_DDR4_MWE_N")
	)
	(segment
		(start 79.727806 -40.724836)
		(end 79.579978 -40.872664)
		(width 0.11684)
		(layer "B.Cu")
		(net "M_BMC_DDR4_MWE_N")
	)
	(segment
		(start 76.458064 -43.457876)
		(end 76.458064 -43.884088)
		(width 0.11684)
		(layer "B.Cu")
		(net "M_BMC_DDR4_MWE_N")
	)
	(arc
		(start 76.643738 -43.009566)
		(mid 76.506249 -43.215238)
		(end 76.458064 -43.457876)
		(width 0.11684)
		(layer "B.Cu")
		(net "M_BMC_DDR4_MWE_N")
	)
	(arc
		(start 80.293972 -40.490394)
		(mid 79.987578 -40.551322)
		(end 79.727806 -40.724836)
		(width 0.11684)
		(layer "B.Cu")
		(net "M_BMC_DDR4_MWE_N")
	)
	(arc
		(start 74.966322 -45.10532)
		(mid 74.890408 -45.12042)
		(end 74.826114 -45.163486)
		(width 0.11684)
		(layer "B.Cu")
		(net "M_BMC_DDR4_MWE_N")
	)
	(arc
		(start 74.572876 -45.416724)
		(mid 74.52773 -45.454185)
		(end 74.476356 -45.48251)
		(width 0.11684)
		(layer "B.Cu")
		(net "M_BMC_DDR4_MWE_N")
	)
	(arc
		(start 76.458064 -43.884088)
		(mid 76.4403 -44.06247)
		(end 76.387706 -44.233846)
		(width 0.11684)
		(layer "B.Cu")
		(net "M_BMC_DDR4_MWE_N")
	)
	(arc
		(start 79.18196 -41.903396)
		(mid 79.127953 -41.923546)
		(end 79.070708 -41.93032)
		(width 0.11684)
		(layer "B.Cu")
		(net "M_BMC_DDR4_MWE_N")
	)
	(arc
		(start 79.440532 -41.566084)
		(mid 79.417527 -41.681089)
		(end 79.35214 -41.778428)
		(width 0.11684)
		(layer "B.Cu")
		(net "M_BMC_DDR4_MWE_N")
	)
	(arc
		(start 78.050644 -41.93032)
		(mid 77.747972 -41.990543)
		(end 77.491336 -42.161968)
		(width 0.11684)
		(layer "B.Cu")
		(net "M_BMC_DDR4_MWE_N")
	)
	(arc
		(start 76.387706 -44.233846)
		(mid 76.369745 -44.266975)
		(end 76.345796 -44.296076)
		(width 0.11684)
		(layer "B.Cu")
		(net "M_BMC_DDR4_MWE_N")
	)
	(arc
		(start 75.579224 -45.062648)
		(mid 75.532027 -45.094184)
		(end 75.476354 -45.10532)
		(width 0.11684)
		(layer "B.Cu")
		(net "M_BMC_DDR4_MWE_N")
	)
	(arc
		(start 79.35214 -41.778428)
		(mid 79.271874 -41.847482)
		(end 79.18196 -41.903396)
		(width 0.11684)
		(layer "B.Cu")
		(net "M_BMC_DDR4_MWE_N")
	)
	(arc
		(start 74.476356 -45.48251)
		(mid 74.37341 -45.514854)
		(end 74.266044 -45.52569)
		(width 0.11684)
		(layer "B.Cu")
		(net "M_BMC_DDR4_MWE_N")
	)
	(segment
		(start 62.0903 -43.458638)
		(end 62.0903 -43.776138)
		(width 0.08382)
		(layer "In9.Cu")
		(net "M_BMC_DDR4_MWE_N")
	)
	(segment
		(start 75.940158 -44.762928)
		(end 75.940158 -45.25518)
		(width 0.08382)
		(layer "In9.Cu")
		(net "M_BMC_DDR4_MWE_N")
	)
	(segment
		(start 62.497462 -42.169334)
		(end 62.497462 -43.257978)
		(width 0.08382)
		(layer "In9.Cu")
		(net "M_BMC_DDR4_MWE_N")
	)
	(segment
		(start 75.45832 -45.011086)
		(end 75.45832 -44.762928)
		(width 0.08382)
		(layer "In9.Cu")
		(net "M_BMC_DDR4_MWE_N")
	)
	(segment
		(start 75.56881 -44.652438)
		(end 75.829668 -44.652438)
		(width 0.08382)
		(layer "In9.Cu")
		(net "M_BMC_DDR4_MWE_N")
	)
	(segment
		(start 63.072518 -41.783)
		(end 62.759082 -41.783)
		(width 0.08382)
		(layer "In9.Cu")
		(net "M_BMC_DDR4_MWE_N")
	)
	(segment
		(start 75.450954 -44.155868)
		(end 75.450954 -43.871388)
		(width 0.08382)
		(layer "In9.Cu")
		(net "M_BMC_DDR4_MWE_N")
	)
	(segment
		(start 65.68059 -40.768778)
		(end 65.53708 -40.912288)
		(width 0.08382)
		(layer "In9.Cu")
		(net "M_BMC_DDR4_MWE_N")
	)
	(segment
		(start 75.955398 -42.016934)
		(end 74.910442 -40.971978)
		(width 0.08382)
		(layer "In9.Cu")
		(net "M_BMC_DDR4_MWE_N")
	)
	(segment
		(start 74.076814 -40.63873)
		(end 65.994534 -40.63873)
		(width 0.08382)
		(layer "In9.Cu")
		(net "M_BMC_DDR4_MWE_N")
	)
	(segment
		(start 64.616584 -41.760394)
		(end 64.434466 -41.760394)
		(width 0.08382)
		(layer "In9.Cu")
		(net "M_BMC_DDR4_MWE_N")
	)
	(segment
		(start 74.23404 -45.52569)
		(end 74.495914 -45.416724)
		(width 0.08382)
		(layer "In9.Cu")
		(net "M_BMC_DDR4_MWE_N")
	)
	(segment
		(start 75.063858 -45.136308)
		(end 75.333098 -45.136308)
		(width 0.08382)
		(layer "In9.Cu")
		(net "M_BMC_DDR4_MWE_N")
	)
	(segment
		(start 63.951104 -40.9702)
		(end 63.55842 -40.9702)
		(width 0.08382)
		(layer "In9.Cu")
		(net "M_BMC_DDR4_MWE_N")
	)
	(segment
		(start 65.39103 -40.97274)
		(end 65.138046 -40.97274)
		(width 0.08382)
		(layer "In9.Cu")
		(net "M_BMC_DDR4_MWE_N")
	)
	(segment
		(start 76.031598 -43.53179)
		(end 76.031598 -42.262806)
		(width 0.08382)
		(layer "In9.Cu")
		(net "M_BMC_DDR4_MWE_N")
	)
	(segment
		(start 62.390782 -43.364658)
		(end 62.18428 -43.364658)
		(width 0.08382)
		(layer "In9.Cu")
		(net "M_BMC_DDR4_MWE_N")
	)
	(segment
		(start 76.023978 -45.339)
		(end 76.369418 -45.339)
		(width 0.08382)
		(layer "In9.Cu")
		(net "M_BMC_DDR4_MWE_N")
	)
	(segment
		(start 63.30696 -41.22166)
		(end 63.30696 -41.462452)
		(width 0.08382)
		(layer "In9.Cu")
		(net "M_BMC_DDR4_MWE_N")
	)
	(segment
		(start 64.872616 -41.23817)
		(end 64.872616 -41.504362)
		(width 0.08382)
		(layer "In9.Cu")
		(net "M_BMC_DDR4_MWE_N")
	)
	(segment
		(start 75.544934 -43.777408)
		(end 75.78598 -43.777408)
		(width 0.08382)
		(layer "In9.Cu")
		(net "M_BMC_DDR4_MWE_N")
	)
	(segment
		(start 76.453238 -45.25518)
		(end 76.453238 -44.343828)
		(width 0.08382)
		(layer "In9.Cu")
		(net "M_BMC_DDR4_MWE_N")
	)
	(segment
		(start 64.1096 -41.435528)
		(end 64.1096 -41.215564)
		(width 0.08382)
		(layer "In9.Cu")
		(net "M_BMC_DDR4_MWE_N")
	)
	(segment
		(start 76.359258 -44.249848)
		(end 75.544934 -44.249848)
		(width 0.08382)
		(layer "In9.Cu")
		(net "M_BMC_DDR4_MWE_N")
	)
	(arc
		(start 75.544934 -44.249848)
		(mid 75.47848 -44.222322)
		(end 75.450954 -44.155868)
		(width 0.08382)
		(layer "In9.Cu")
		(net "M_BMC_DDR4_MWE_N")
	)
	(arc
		(start 74.310494 -40.65905)
		(mid 74.1941 -40.643754)
		(end 74.076814 -40.63873)
		(width 0.08382)
		(layer "In9.Cu")
		(net "M_BMC_DDR4_MWE_N")
	)
	(arc
		(start 76.031598 -42.262806)
		(mid 76.024158 -42.17517)
		(end 76.00188 -42.090086)
		(width 0.08382)
		(layer "In9.Cu")
		(net "M_BMC_DDR4_MWE_N")
	)
	(arc
		(start 76.453238 -44.343828)
		(mid 76.425712 -44.277374)
		(end 76.359258 -44.249848)
		(width 0.08382)
		(layer "In9.Cu")
		(net "M_BMC_DDR4_MWE_N")
	)
	(arc
		(start 65.138046 -40.97274)
		(mid 64.950359 -41.050483)
		(end 64.872616 -41.23817)
		(width 0.08382)
		(layer "In9.Cu")
		(net "M_BMC_DDR4_MWE_N")
	)
	(arc
		(start 62.18428 -43.364658)
		(mid 62.117826 -43.392184)
		(end 62.0903 -43.458638)
		(width 0.08382)
		(layer "In9.Cu")
		(net "M_BMC_DDR4_MWE_N")
	)
	(arc
		(start 74.495914 -45.416724)
		(mid 74.642137 -45.341648)
		(end 74.774552 -45.244258)
		(width 0.08382)
		(layer "In9.Cu")
		(net "M_BMC_DDR4_MWE_N")
	)
	(arc
		(start 64.434466 -41.760394)
		(mid 64.204751 -41.665243)
		(end 64.1096 -41.435528)
		(width 0.08382)
		(layer "In9.Cu")
		(net "M_BMC_DDR4_MWE_N")
	)
	(arc
		(start 63.1952 -41.7322)
		(mid 63.138913 -41.76981)
		(end 63.072518 -41.783)
		(width 0.08382)
		(layer "In9.Cu")
		(net "M_BMC_DDR4_MWE_N")
	)
	(arc
		(start 63.30696 -41.462452)
		(mid 63.277919 -41.608449)
		(end 63.1952 -41.7322)
		(width 0.08382)
		(layer "In9.Cu")
		(net "M_BMC_DDR4_MWE_N")
	)
	(arc
		(start 62.759082 -41.783)
		(mid 62.692693 -41.796206)
		(end 62.6364 -41.8338)
		(width 0.08382)
		(layer "In9.Cu")
		(net "M_BMC_DDR4_MWE_N")
	)
	(arc
		(start 75.78598 -43.777408)
		(mid 75.959658 -43.705468)
		(end 76.031598 -43.53179)
		(width 0.08382)
		(layer "In9.Cu")
		(net "M_BMC_DDR4_MWE_N")
	)
	(arc
		(start 74.774552 -45.244258)
		(mid 74.909457 -45.164173)
		(end 75.063858 -45.136308)
		(width 0.08382)
		(layer "In9.Cu")
		(net "M_BMC_DDR4_MWE_N")
	)
	(arc
		(start 64.052704 -41.025064)
		(mid 64.00882 -40.984843)
		(end 63.951104 -40.9702)
		(width 0.08382)
		(layer "In9.Cu")
		(net "M_BMC_DDR4_MWE_N")
	)
	(arc
		(start 74.910442 -40.971978)
		(mid 74.634511 -40.769419)
		(end 74.310494 -40.65905)
		(width 0.08382)
		(layer "In9.Cu")
		(net "M_BMC_DDR4_MWE_N")
	)
	(arc
		(start 63.55842 -40.9702)
		(mid 63.380611 -41.043851)
		(end 63.30696 -41.22166)
		(width 0.08382)
		(layer "In9.Cu")
		(net "M_BMC_DDR4_MWE_N")
	)
	(arc
		(start 75.333098 -45.136308)
		(mid 75.421643 -45.099631)
		(end 75.45832 -45.011086)
		(width 0.08382)
		(layer "In9.Cu")
		(net "M_BMC_DDR4_MWE_N")
	)
	(arc
		(start 75.829668 -44.652438)
		(mid 75.907796 -44.6848)
		(end 75.940158 -44.762928)
		(width 0.08382)
		(layer "In9.Cu")
		(net "M_BMC_DDR4_MWE_N")
	)
	(arc
		(start 75.450954 -43.871388)
		(mid 75.47848 -43.804934)
		(end 75.544934 -43.777408)
		(width 0.08382)
		(layer "In9.Cu")
		(net "M_BMC_DDR4_MWE_N")
	)
	(arc
		(start 62.6364 -41.8338)
		(mid 62.533538 -41.987744)
		(end 62.497462 -42.169334)
		(width 0.08382)
		(layer "In9.Cu")
		(net "M_BMC_DDR4_MWE_N")
	)
	(arc
		(start 76.00188 -42.090086)
		(mid 75.982722 -42.050915)
		(end 75.955398 -42.016934)
		(width 0.08382)
		(layer "In9.Cu")
		(net "M_BMC_DDR4_MWE_N")
	)
	(arc
		(start 64.872616 -41.504362)
		(mid 64.797626 -41.685404)
		(end 64.616584 -41.760394)
		(width 0.08382)
		(layer "In9.Cu")
		(net "M_BMC_DDR4_MWE_N")
	)
	(arc
		(start 62.497462 -43.257978)
		(mid 62.466216 -43.333412)
		(end 62.390782 -43.364658)
		(width 0.08382)
		(layer "In9.Cu")
		(net "M_BMC_DDR4_MWE_N")
	)
	(arc
		(start 76.369418 -45.339)
		(mid 76.428688 -45.31445)
		(end 76.453238 -45.25518)
		(width 0.08382)
		(layer "In9.Cu")
		(net "M_BMC_DDR4_MWE_N")
	)
	(arc
		(start 75.45832 -44.762928)
		(mid 75.490682 -44.6848)
		(end 75.56881 -44.652438)
		(width 0.08382)
		(layer "In9.Cu")
		(net "M_BMC_DDR4_MWE_N")
	)
	(arc
		(start 64.1096 -41.215564)
		(mid 64.095057 -41.116166)
		(end 64.052704 -41.025064)
		(width 0.08382)
		(layer "In9.Cu")
		(net "M_BMC_DDR4_MWE_N")
	)
	(arc
		(start 75.940158 -45.25518)
		(mid 75.964708 -45.31445)
		(end 76.023978 -45.339)
		(width 0.08382)
		(layer "In9.Cu")
		(net "M_BMC_DDR4_MWE_N")
	)
	(arc
		(start 65.994534 -40.63873)
		(mid 65.824626 -40.672527)
		(end 65.68059 -40.768778)
		(width 0.08382)
		(layer "In9.Cu")
		(net "M_BMC_DDR4_MWE_N")
	)
	(arc
		(start 65.53708 -40.912288)
		(mid 65.470057 -40.957008)
		(end 65.39103 -40.97274)
		(width 0.08382)
		(layer "In9.Cu")
		(net "M_BMC_DDR4_MWE_N")
	)
	(segment
		(start 61.695076 -45.771308)
		(end 62.0903 -45.376084)
		(width 0.11684)
		(layer "F.Cu")
		(net "M_BMC_DDR4_MRAS_N")
	)
	(segment
		(start 78.65237 -45.907452)
		(end 78.270608 -45.52569)
		(width 0.11684)
		(layer "F.Cu")
		(net "M_BMC_DDR4_MRAS_N")
	)
	(via
		(at 78.959964 -45.636688)
		(size 0.6604)
		(drill 0.3302)
		(layers "F.Cu" "B.Cu")
		(net "M_BMC_DDR4_MRAS_N")
	)
	(via
		(at 78.270608 -45.52569)
		(size 0.4572)
		(drill 0.254)
		(layers "F.Cu" "B.Cu")
		(net "M_BMC_DDR4_MRAS_N")
	)
	(via
		(at 62.0903 -45.376084)
		(size 0.4572)
		(drill 0.254)
		(layers "F.Cu" "B.Cu")
		(net "M_BMC_DDR4_MRAS_N")
	)
	(segment
		(start 82.53984 -48.391064)
		(end 82.76717 -48.618394)
		(width 0.11684)
		(layer "B.Cu")
		(net "M_BMC_DDR4_MRAS_N")
	)
	(segment
		(start 81.686908 -47.58563)
		(end 81.376774 -47.58563)
		(width 0.11684)
		(layer "B.Cu")
		(net "M_BMC_DDR4_MRAS_N")
	)
	(segment
		(start 81.686908 -47.58563)
		(end 81.686908 -47.625508)
		(width 0.11684)
		(layer "B.Cu")
		(net "M_BMC_DDR4_MRAS_N")
	)
	(segment
		(start 78.401672 -45.52569)
		(end 78.270608 -45.52569)
		(width 0.11684)
		(layer "B.Cu")
		(net "M_BMC_DDR4_MRAS_N")
	)
	(segment
		(start 81.376774 -47.58563)
		(end 81.024984 -47.23384)
		(width 0.11684)
		(layer "B.Cu")
		(net "M_BMC_DDR4_MRAS_N")
	)
	(segment
		(start 82.452464 -48.391064)
		(end 82.53984 -48.391064)
		(width 0.11684)
		(layer "B.Cu")
		(net "M_BMC_DDR4_MRAS_N")
	)
	(segment
		(start 81.024984 -47.23384)
		(end 80.226154 -46.902878)
		(width 0.11684)
		(layer "B.Cu")
		(net "M_BMC_DDR4_MRAS_N")
	)
	(segment
		(start 78.959964 -45.636688)
		(end 78.401672 -45.52569)
		(width 0.11684)
		(layer "B.Cu")
		(net "M_BMC_DDR4_MRAS_N")
	)
	(segment
		(start 80.226154 -46.902878)
		(end 78.959964 -45.636688)
		(width 0.11684)
		(layer "B.Cu")
		(net "M_BMC_DDR4_MRAS_N")
	)
	(segment
		(start 81.686908 -47.625508)
		(end 82.452464 -48.391064)
		(width 0.11684)
		(layer "B.Cu")
		(net "M_BMC_DDR4_MRAS_N")
	)
	(segment
		(start 62.88532 -40.1066)
		(end 63.0428 -40.1066)
		(width 0.08382)
		(layer "In9.Cu")
		(net "M_BMC_DDR4_MRAS_N")
	)
	(segment
		(start 62.0903 -45.376084)
		(end 62.032896 -45.31868)
		(width 0.08382)
		(layer "In9.Cu")
		(net "M_BMC_DDR4_MRAS_N")
	)
	(segment
		(start 75.387708 -40.18661)
		(end 77.781404 -42.580306)
		(width 0.08382)
		(layer "In9.Cu")
		(net "M_BMC_DDR4_MRAS_N")
	)
	(segment
		(start 61.350398 -42.684446)
		(end 61.350398 -42.005504)
		(width 0.08382)
		(layer "In9.Cu")
		(net "M_BMC_DDR4_MRAS_N")
	)
	(segment
		(start 63.187834 -40.052752)
		(end 63.32855 -39.912036)
		(width 0.08382)
		(layer "In9.Cu")
		(net "M_BMC_DDR4_MRAS_N")
	)
	(segment
		(start 78.65237 -43.102276)
		(end 78.65237 -44.895262)
		(width 0.08382)
		(layer "In9.Cu")
		(net "M_BMC_DDR4_MRAS_N")
	)
	(segment
		(start 78.476602 -45.319696)
		(end 78.270608 -45.52569)
		(width 0.08382)
		(layer "In9.Cu")
		(net "M_BMC_DDR4_MRAS_N")
	)
	(segment
		(start 60.89777 -44.60748)
		(end 60.89777 -43.68419)
		(width 0.08382)
		(layer "In9.Cu")
		(net "M_BMC_DDR4_MRAS_N")
	)
	(segment
		(start 78.149196 -42.732706)
		(end 78.2828 -42.732706)
		(width 0.08382)
		(layer "In9.Cu")
		(net "M_BMC_DDR4_MRAS_N")
	)
	(segment
		(start 61.05906 -43.294808)
		(end 61.124846 -43.229022)
		(width 0.08382)
		(layer "In9.Cu")
		(net "M_BMC_DDR4_MRAS_N")
	)
	(segment
		(start 62.484 -40.63238)
		(end 62.484 -40.50792)
		(width 0.08382)
		(layer "In9.Cu")
		(net "M_BMC_DDR4_MRAS_N")
	)
	(segment
		(start 62.0014 -40.98544)
		(end 62.13094 -40.98544)
		(width 0.08382)
		(layer "In9.Cu")
		(net "M_BMC_DDR4_MRAS_N")
	)
	(segment
		(start 61.42101 -41.83507)
		(end 61.630052 -41.626028)
		(width 0.08382)
		(layer "In9.Cu")
		(net "M_BMC_DDR4_MRAS_N")
	)
	(segment
		(start 61.68898 -41.484042)
		(end 61.68898 -41.29786)
		(width 0.08382)
		(layer "In9.Cu")
		(net "M_BMC_DDR4_MRAS_N")
	)
	(segment
		(start 63.557404 -39.817294)
		(end 74.496168 -39.817294)
		(width 0.08382)
		(layer "In9.Cu")
		(net "M_BMC_DDR4_MRAS_N")
	)
	(arc
		(start 77.781404 -42.580306)
		(mid 77.950134 -42.693111)
		(end 78.149196 -42.732706)
		(width 0.08382)
		(layer "In9.Cu")
		(net "M_BMC_DDR4_MRAS_N")
	)
	(arc
		(start 61.630052 -41.626028)
		(mid 61.673663 -41.560899)
		(end 61.68898 -41.484042)
		(width 0.08382)
		(layer "In9.Cu")
		(net "M_BMC_DDR4_MRAS_N")
	)
	(arc
		(start 62.13094 -40.98544)
		(mid 62.380591 -40.882031)
		(end 62.484 -40.63238)
		(width 0.08382)
		(layer "In9.Cu")
		(net "M_BMC_DDR4_MRAS_N")
	)
	(arc
		(start 61.350398 -42.005504)
		(mid 61.368747 -41.91326)
		(end 61.42101 -41.83507)
		(width 0.08382)
		(layer "In9.Cu")
		(net "M_BMC_DDR4_MRAS_N")
	)
	(arc
		(start 60.89777 -43.68419)
		(mid 60.939687 -43.473457)
		(end 61.05906 -43.294808)
		(width 0.08382)
		(layer "In9.Cu")
		(net "M_BMC_DDR4_MRAS_N")
	)
	(arc
		(start 61.68898 -41.29786)
		(mid 61.780486 -41.076946)
		(end 62.0014 -40.98544)
		(width 0.08382)
		(layer "In9.Cu")
		(net "M_BMC_DDR4_MRAS_N")
	)
	(arc
		(start 63.0428 -40.1066)
		(mid 63.120131 -40.092652)
		(end 63.187834 -40.052752)
		(width 0.08382)
		(layer "In9.Cu")
		(net "M_BMC_DDR4_MRAS_N")
	)
	(arc
		(start 61.349636 -44.99991)
		(mid 61.302915 -44.99333)
		(end 61.25591 -44.989242)
		(width 0.08382)
		(layer "In9.Cu")
		(net "M_BMC_DDR4_MRAS_N")
	)
	(arc
		(start 62.484 -40.50792)
		(mid 62.601544 -40.224144)
		(end 62.88532 -40.1066)
		(width 0.08382)
		(layer "In9.Cu")
		(net "M_BMC_DDR4_MRAS_N")
	)
	(arc
		(start 74.496168 -39.817294)
		(mid 74.978677 -39.913271)
		(end 75.387708 -40.18661)
		(width 0.08382)
		(layer "In9.Cu")
		(net "M_BMC_DDR4_MRAS_N")
	)
	(arc
		(start 78.2828 -42.732706)
		(mid 78.544125 -42.840951)
		(end 78.65237 -43.102276)
		(width 0.08382)
		(layer "In9.Cu")
		(net "M_BMC_DDR4_MRAS_N")
	)
	(arc
		(start 62.032896 -45.31868)
		(mid 61.9983 -45.286648)
		(end 61.961268 -45.257466)
		(width 0.08382)
		(layer "In9.Cu")
		(net "M_BMC_DDR4_MRAS_N")
	)
	(arc
		(start 78.65237 -44.895262)
		(mid 78.606697 -45.124964)
		(end 78.476602 -45.319696)
		(width 0.08382)
		(layer "In9.Cu")
		(net "M_BMC_DDR4_MRAS_N")
	)
	(arc
		(start 61.961268 -45.257466)
		(mid 61.670238 -45.093568)
		(end 61.349636 -44.99991)
		(width 0.08382)
		(layer "In9.Cu")
		(net "M_BMC_DDR4_MRAS_N")
	)
	(arc
		(start 61.124846 -43.229022)
		(mid 61.291793 -42.979168)
		(end 61.350398 -42.684446)
		(width 0.08382)
		(layer "In9.Cu")
		(net "M_BMC_DDR4_MRAS_N")
	)
	(arc
		(start 63.32855 -39.912036)
		(mid 63.433563 -39.841932)
		(end 63.557404 -39.817294)
		(width 0.08382)
		(layer "In9.Cu")
		(net "M_BMC_DDR4_MRAS_N")
	)
	(arc
		(start 61.25591 -44.989242)
		(mid 61.00131 -44.869214)
		(end 60.89777 -44.60748)
		(width 0.08382)
		(layer "In9.Cu")
		(net "M_BMC_DDR4_MRAS_N")
	)
	(segment
		(start 67.268852 -42.956734)
		(end 67.044062 -42.956734)
		(width 0.11684)
		(layer "F.Cu")
		(net "M_BMC_DDR4_MODT")
	)
	(segment
		(start 65.268602 -45.439838)
		(end 64.967104 -45.741336)
		(width 0.11684)
		(layer "F.Cu")
		(net "M_BMC_DDR4_MODT")
	)
	(segment
		(start 69.443854 -42.653204)
		(end 69.443854 -42.420286)
		(width 0.11684)
		(layer "F.Cu")
		(net "M_BMC_DDR4_MODT")
	)
	(segment
		(start 69.973952 -43.593512)
		(end 69.974206 -43.593258)
		(width 0.11684)
		(layer "F.Cu")
		(net "M_BMC_DDR4_MODT")
	)
	(segment
		(start 79.739744 -37.887402)
		(end 79.739744 -37.959538)
		(width 0.11684)
		(layer "F.Cu")
		(net "M_BMC_DDR4_MODT")
	)
	(segment
		(start 67.418204 -42.635424)
		(end 67.418204 -42.807382)
		(width 0.11684)
		(layer "F.Cu")
		(net "M_BMC_DDR4_MODT")
	)
	(segment
		(start 66.399664 -43.601132)
		(end 66.399664 -44.015914)
		(width 0.11684)
		(layer "F.Cu")
		(net "M_BMC_DDR4_MODT")
	)
	(segment
		(start 68.068444 -42.832274)
		(end 68.068444 -42.635424)
		(width 0.11684)
		(layer "F.Cu")
		(net "M_BMC_DDR4_MODT")
	)
	(segment
		(start 65.70218 -45.45584)
		(end 65.686178 -45.439838)
		(width 0.11684)
		(layer "F.Cu")
		(net "M_BMC_DDR4_MODT")
	)
	(segment
		(start 67.01917 -43.978576)
		(end 67.01917 -43.955716)
		(width 0.11684)
		(layer "F.Cu")
		(net "M_BMC_DDR4_MODT")
	)
	(segment
		(start 66.143378 -45.432218)
		(end 66.119756 -45.45584)
		(width 0.11684)
		(layer "F.Cu")
		(net "M_BMC_DDR4_MODT")
	)
	(segment
		(start 68.573904 -42.956734)
		(end 68.192904 -42.956734)
		(width 0.11684)
		(layer "F.Cu")
		(net "M_BMC_DDR4_MODT")
	)
	(segment
		(start 66.12128 -44.976796)
		(end 66.143378 -44.998894)
		(width 0.11684)
		(layer "F.Cu")
		(net "M_BMC_DDR4_MODT")
	)
	(segment
		(start 75.03414 -47.125636)
		(end 74.652378 -46.707552)
		(width 0.11684)
		(layer "F.Cu")
		(net "M_BMC_DDR4_MODT")
	)
	(segment
		(start 66.232024 -44.420536)
		(end 66.12128 -44.53128)
		(width 0.11684)
		(layer "F.Cu")
		(net "M_BMC_DDR4_MODT")
	)
	(segment
		(start 68.887086 -45.091096)
		(end 68.887086 -44.673774)
		(width 0.11684)
		(layer "F.Cu")
		(net "M_BMC_DDR4_MODT")
	)
	(segment
		(start 75.034394 -47.125636)
		(end 75.03414 -47.125636)
		(width 0.11684)
		(layer "F.Cu")
		(net "M_BMC_DDR4_MODT")
	)
	(segment
		(start 75.385422 -46.68774)
		(end 76.50607 -43.982894)
		(width 0.11684)
		(layer "F.Cu")
		(net "M_BMC_DDR4_MODT")
	)
	(segment
		(start 69.848476 -42.956734)
		(end 69.747384 -42.956734)
		(width 0.11684)
		(layer "F.Cu")
		(net "M_BMC_DDR4_MODT")
	)
	(segment
		(start 68.830698 -42.420286)
		(end 68.830698 -42.69994)
		(width 0.11684)
		(layer "F.Cu")
		(net "M_BMC_DDR4_MODT")
	)
	(segment
		(start 79.739744 -35.927538)
		(end 79.7941 -35.927538)
		(width 0.11684)
		(layer "F.Cu")
		(net "M_BMC_DDR4_MODT")
	)
	(segment
		(start 68.49237 -44.279058)
		(end 67.319652 -44.279058)
		(width 0.11684)
		(layer "F.Cu")
		(net "M_BMC_DDR4_MODT")
	)
	(segment
		(start 70.027546 -43.45432)
		(end 70.027546 -43.135804)
		(width 0.11684)
		(layer "F.Cu")
		(net "M_BMC_DDR4_MODT")
	)
	(segment
		(start 79.7941 -35.927538)
		(end 80.06715 -36.200588)
		(width 0.11684)
		(layer "F.Cu")
		(net "M_BMC_DDR4_MODT")
	)
	(segment
		(start 76.739242 -40.96004)
		(end 79.739744 -37.959538)
		(width 0.11684)
		(layer "F.Cu")
		(net "M_BMC_DDR4_MODT")
	)
	(segment
		(start 67.319652 -43.655234)
		(end 69.835014 -43.655234)
		(width 0.11684)
		(layer "F.Cu")
		(net "M_BMC_DDR4_MODT")
	)
	(segment
		(start 80.06588 -37.561266)
		(end 79.739744 -37.887402)
		(width 0.11684)
		(layer "F.Cu")
		(net "M_BMC_DDR4_MODT")
	)
	(segment
		(start 75.034394 -47.125636)
		(end 75.21067 -46.94936)
		(width 0.11684)
		(layer "F.Cu")
		(net "M_BMC_DDR4_MODT")
	)
	(segment
		(start 80.23479 -36.604956)
		(end 80.23479 -37.153596)
		(width 0.11684)
		(layer "F.Cu")
		(net "M_BMC_DDR4_MODT")
	)
	(segment
		(start 76.571602 -43.653456)
		(end 76.571602 -41.364408)
		(width 0.11684)
		(layer "F.Cu")
		(net "M_BMC_DDR4_MODT")
	)
	(via
		(at 75.034394 -47.125636)
		(size 0.4572)
		(drill 0.254)
		(layers "F.Cu" "B.Cu")
		(net "M_BMC_DDR4_MODT")
	)
	(via
		(at 68.887086 -45.091096)
		(size 0.4572)
		(drill 0.254)
		(layers "F.Cu" "B.Cu")
		(net "M_BMC_DDR4_MODT")
	)
	(arc
		(start 69.443854 -42.420286)
		(mid 69.137276 -42.113708)
		(end 68.830698 -42.420286)
		(width 0.11684)
		(layer "F.Cu")
		(net "M_BMC_DDR4_MODT")
	)
	(arc
		(start 64.967104 -45.741336)
		(mid 64.934022 -45.763504)
		(end 64.894968 -45.771308)
		(width 0.11684)
		(layer "F.Cu")
		(net "M_BMC_DDR4_MODT")
	)
	(arc
		(start 75.21067 -46.94936)
		(mid 75.310952 -46.827168)
		(end 75.385422 -46.68774)
		(width 0.11684)
		(layer "F.Cu")
		(net "M_BMC_DDR4_MODT")
	)
	(arc
		(start 68.830698 -42.69994)
		(mid 68.755485 -42.881521)
		(end 68.573904 -42.956734)
		(width 0.11684)
		(layer "F.Cu")
		(net "M_BMC_DDR4_MODT")
	)
	(arc
		(start 67.01917 -43.955716)
		(mid 67.107179 -43.743243)
		(end 67.319652 -43.655234)
		(width 0.11684)
		(layer "F.Cu")
		(net "M_BMC_DDR4_MODT")
	)
	(arc
		(start 76.571602 -41.364408)
		(mid 76.615226 -41.145564)
		(end 76.739242 -40.96004)
		(width 0.11684)
		(layer "F.Cu")
		(net "M_BMC_DDR4_MODT")
	)
	(arc
		(start 66.12128 -44.53128)
		(mid 66.029011 -44.754038)
		(end 66.12128 -44.976796)
		(width 0.11684)
		(layer "F.Cu")
		(net "M_BMC_DDR4_MODT")
	)
	(arc
		(start 67.319652 -44.279058)
		(mid 67.107179 -44.191049)
		(end 67.01917 -43.978576)
		(width 0.11684)
		(layer "F.Cu")
		(net "M_BMC_DDR4_MODT")
	)
	(arc
		(start 80.23479 -37.153596)
		(mid 80.190833 -37.374204)
		(end 80.06588 -37.561266)
		(width 0.11684)
		(layer "F.Cu")
		(net "M_BMC_DDR4_MODT")
	)
	(arc
		(start 65.686178 -45.439838)
		(mid 65.47739 -45.353355)
		(end 65.268602 -45.439838)
		(width 0.11684)
		(layer "F.Cu")
		(net "M_BMC_DDR4_MODT")
	)
	(arc
		(start 76.50607 -43.982894)
		(mid 76.555061 -43.821402)
		(end 76.571602 -43.653456)
		(width 0.11684)
		(layer "F.Cu")
		(net "M_BMC_DDR4_MODT")
	)
	(arc
		(start 67.044062 -42.956734)
		(mid 66.588404 -43.145474)
		(end 66.399664 -43.601132)
		(width 0.11684)
		(layer "F.Cu")
		(net "M_BMC_DDR4_MODT")
	)
	(arc
		(start 68.887086 -44.673774)
		(mid 68.771476 -44.394668)
		(end 68.49237 -44.279058)
		(width 0.11684)
		(layer "F.Cu")
		(net "M_BMC_DDR4_MODT")
	)
	(arc
		(start 69.974206 -43.593258)
		(mid 70.013772 -43.528737)
		(end 70.027546 -43.45432)
		(width 0.11684)
		(layer "F.Cu")
		(net "M_BMC_DDR4_MODT")
	)
	(arc
		(start 66.399664 -44.015914)
		(mid 66.356088 -44.234895)
		(end 66.232024 -44.420536)
		(width 0.11684)
		(layer "F.Cu")
		(net "M_BMC_DDR4_MODT")
	)
	(arc
		(start 70.027546 -43.135804)
		(mid 69.975098 -43.009182)
		(end 69.848476 -42.956734)
		(width 0.11684)
		(layer "F.Cu")
		(net "M_BMC_DDR4_MODT")
	)
	(arc
		(start 67.418204 -42.807382)
		(mid 67.37446 -42.91299)
		(end 67.268852 -42.956734)
		(width 0.11684)
		(layer "F.Cu")
		(net "M_BMC_DDR4_MODT")
	)
	(arc
		(start 69.835014 -43.655234)
		(mid 69.911036 -43.639144)
		(end 69.973952 -43.593512)
		(width 0.11684)
		(layer "F.Cu")
		(net "M_BMC_DDR4_MODT")
	)
	(arc
		(start 69.747384 -42.956734)
		(mid 69.532756 -42.867832)
		(end 69.443854 -42.653204)
		(width 0.11684)
		(layer "F.Cu")
		(net "M_BMC_DDR4_MODT")
	)
	(arc
		(start 66.143378 -44.998894)
		(mid 66.233122 -45.215556)
		(end 66.143378 -45.432218)
		(width 0.11684)
		(layer "F.Cu")
		(net "M_BMC_DDR4_MODT")
	)
	(arc
		(start 80.06715 -36.200588)
		(mid 80.191197 -36.386099)
		(end 80.23479 -36.604956)
		(width 0.11684)
		(layer "F.Cu")
		(net "M_BMC_DDR4_MODT")
	)
	(arc
		(start 68.068444 -42.635424)
		(mid 67.743324 -42.310304)
		(end 67.418204 -42.635424)
		(width 0.11684)
		(layer "F.Cu")
		(net "M_BMC_DDR4_MODT")
	)
	(arc
		(start 68.192904 -42.956734)
		(mid 68.104897 -42.920281)
		(end 68.068444 -42.832274)
		(width 0.11684)
		(layer "F.Cu")
		(net "M_BMC_DDR4_MODT")
	)
	(arc
		(start 66.119756 -45.45584)
		(mid 65.910968 -45.542323)
		(end 65.70218 -45.45584)
		(width 0.11684)
		(layer "F.Cu")
		(net "M_BMC_DDR4_MODT")
	)
	(segment
		(start 69.803518 -45.840396)
		(end 69.267324 -46.37659)
		(width 0.08382)
		(layer "In2.Cu")
		(net "M_BMC_DDR4_MODT")
	)
	(segment
		(start 70.354444 -46.10608)
		(end 70.08876 -45.840396)
		(width 0.08382)
		(layer "In2.Cu")
		(net "M_BMC_DDR4_MODT")
	)
	(segment
		(start 71.196962 -46.6598)
		(end 71.12 -46.736762)
		(width 0.08382)
		(layer "In2.Cu")
		(net "M_BMC_DDR4_MODT")
	)
	(segment
		(start 69.257672 -45.091096)
		(end 68.887086 -45.091096)
		(width 0.08382)
		(layer "In2.Cu")
		(net "M_BMC_DDR4_MODT")
	)
	(segment
		(start 72.41794 -46.635162)
		(end 71.256398 -46.635162)
		(width 0.08382)
		(layer "In2.Cu")
		(net "M_BMC_DDR4_MODT")
	)
	(segment
		(start 73.547478 -46.722284)
		(end 72.619362 -46.722284)
		(width 0.08382)
		(layer "In2.Cu")
		(net "M_BMC_DDR4_MODT")
	)
	(segment
		(start 73.89495 -46.457362)
		(end 73.688448 -46.663864)
		(width 0.08382)
		(layer "In2.Cu")
		(net "M_BMC_DDR4_MODT")
	)
	(segment
		(start 69.123306 -46.37659)
		(end 68.871084 -46.124368)
		(width 0.08382)
		(layer "In2.Cu")
		(net "M_BMC_DDR4_MODT")
	)
	(segment
		(start 68.871084 -45.979334)
		(end 69.488558 -45.36186)
		(width 0.08382)
		(layer "In2.Cu")
		(net "M_BMC_DDR4_MODT")
	)
	(segment
		(start 75.034394 -47.125636)
		(end 75.03414 -47.125382)
		(width 0.08382)
		(layer "In2.Cu")
		(net "M_BMC_DDR4_MODT")
	)
	(segment
		(start 70.587362 -46.736762)
		(end 70.40372 -46.55312)
		(width 0.08382)
		(layer "In2.Cu")
		(net "M_BMC_DDR4_MODT")
	)
	(segment
		(start 72.493378 -46.66996)
		(end 72.487282 -46.663864)
		(width 0.08382)
		(layer "In2.Cu")
		(net "M_BMC_DDR4_MODT")
	)
	(segment
		(start 74.09942 -46.411388)
		(end 74.005948 -46.411388)
		(width 0.08382)
		(layer "In2.Cu")
		(net "M_BMC_DDR4_MODT")
	)
	(segment
		(start 74.417936 -46.652942)
		(end 74.230992 -46.465998)
		(width 0.08382)
		(layer "In2.Cu")
		(net "M_BMC_DDR4_MODT")
	)
	(segment
		(start 71.060564 -46.7614)
		(end 70.646798 -46.7614)
		(width 0.08382)
		(layer "In2.Cu")
		(net "M_BMC_DDR4_MODT")
	)
	(segment
		(start 69.488558 -45.36186)
		(end 69.488558 -45.239432)
		(width 0.08382)
		(layer "In2.Cu")
		(net "M_BMC_DDR4_MODT")
	)
	(segment
		(start 75.03414 -47.125382)
		(end 75.03414 -46.808644)
		(width 0.08382)
		(layer "In2.Cu")
		(net "M_BMC_DDR4_MODT")
	)
	(segment
		(start 70.379082 -46.493684)
		(end 70.379082 -46.165516)
		(width 0.08382)
		(layer "In2.Cu")
		(net "M_BMC_DDR4_MODT")
	)
	(segment
		(start 69.488558 -45.239432)
		(end 69.398642 -45.149516)
		(width 0.08382)
		(layer "In2.Cu")
		(net "M_BMC_DDR4_MODT")
	)
	(segment
		(start 74.94778 -46.722284)
		(end 74.585322 -46.722284)
		(width 0.08382)
		(layer "In2.Cu")
		(net "M_BMC_DDR4_MODT")
	)
	(arc
		(start 68.871084 -46.124368)
		(mid 68.841173 -46.051888)
		(end 68.871084 -45.979334)
		(width 0.08382)
		(layer "In2.Cu")
		(net "M_BMC_DDR4_MODT")
	)
	(arc
		(start 70.379082 -46.165516)
		(mid 70.372682 -46.133342)
		(end 70.354444 -46.10608)
		(width 0.08382)
		(layer "In2.Cu")
		(net "M_BMC_DDR4_MODT")
	)
	(arc
		(start 69.398642 -45.149516)
		(mid 69.333964 -45.1063)
		(end 69.257672 -45.091096)
		(width 0.08382)
		(layer "In2.Cu")
		(net "M_BMC_DDR4_MODT")
	)
	(arc
		(start 72.487282 -46.663864)
		(mid 72.455468 -46.642606)
		(end 72.41794 -46.635162)
		(width 0.08382)
		(layer "In2.Cu")
		(net "M_BMC_DDR4_MODT")
	)
	(arc
		(start 72.619362 -46.722284)
		(mid 72.55118 -46.708628)
		(end 72.493378 -46.66996)
		(width 0.08382)
		(layer "In2.Cu")
		(net "M_BMC_DDR4_MODT")
	)
	(arc
		(start 69.267324 -46.37659)
		(mid 69.195352 -46.406364)
		(end 69.123306 -46.37659)
		(width 0.08382)
		(layer "In2.Cu")
		(net "M_BMC_DDR4_MODT")
	)
	(arc
		(start 73.688448 -46.663864)
		(mid 73.62377 -46.70708)
		(end 73.547478 -46.722284)
		(width 0.08382)
		(layer "In2.Cu")
		(net "M_BMC_DDR4_MODT")
	)
	(arc
		(start 74.005948 -46.411388)
		(mid 73.945877 -46.423337)
		(end 73.89495 -46.457362)
		(width 0.08382)
		(layer "In2.Cu")
		(net "M_BMC_DDR4_MODT")
	)
	(arc
		(start 70.40372 -46.55312)
		(mid 70.385499 -46.525851)
		(end 70.379082 -46.493684)
		(width 0.08382)
		(layer "In2.Cu")
		(net "M_BMC_DDR4_MODT")
	)
	(arc
		(start 74.230992 -46.465998)
		(mid 74.170641 -46.42558)
		(end 74.09942 -46.411388)
		(width 0.08382)
		(layer "In2.Cu")
		(net "M_BMC_DDR4_MODT")
	)
	(arc
		(start 71.12 -46.736762)
		(mid 71.092731 -46.754983)
		(end 71.060564 -46.7614)
		(width 0.08382)
		(layer "In2.Cu")
		(net "M_BMC_DDR4_MODT")
	)
	(arc
		(start 75.03414 -46.808644)
		(mid 75.008846 -46.747578)
		(end 74.94778 -46.722284)
		(width 0.08382)
		(layer "In2.Cu")
		(net "M_BMC_DDR4_MODT")
	)
	(arc
		(start 71.256398 -46.635162)
		(mid 71.224224 -46.641562)
		(end 71.196962 -46.6598)
		(width 0.08382)
		(layer "In2.Cu")
		(net "M_BMC_DDR4_MODT")
	)
	(arc
		(start 74.585322 -46.722284)
		(mid 74.49473 -46.704264)
		(end 74.417936 -46.652942)
		(width 0.08382)
		(layer "In2.Cu")
		(net "M_BMC_DDR4_MODT")
	)
	(arc
		(start 70.08876 -45.840396)
		(mid 69.946176 -45.781447)
		(end 69.803518 -45.840396)
		(width 0.08382)
		(layer "In2.Cu")
		(net "M_BMC_DDR4_MODT")
	)
	(arc
		(start 70.646798 -46.7614)
		(mid 70.614624 -46.755)
		(end 70.587362 -46.736762)
		(width 0.08382)
		(layer "In2.Cu")
		(net "M_BMC_DDR4_MODT")
	)
	(segment
		(start 61.695076 -50.571146)
		(end 62.0903 -50.96637)
		(width 0.11684)
		(layer "F.Cu")
		(net "M_BMC_DDR4_MDM1")
	)
	(segment
		(start 73.852278 -50.707544)
		(end 73.470516 -51.089306)
		(width 0.11684)
		(layer "F.Cu")
		(net "M_BMC_DDR4_MDM1")
	)
	(via
		(at 73.470516 -51.089306)
		(size 0.4572)
		(drill 0.254)
		(layers "F.Cu" "B.Cu")
		(net "M_BMC_DDR4_MDM1")
	)
	(via
		(at 62.0903 -50.96637)
		(size 0.4572)
		(drill 0.254)
		(layers "F.Cu" "B.Cu")
		(net "M_BMC_DDR4_MDM1")
	)
	(segment
		(start 60.67425 -52.148994)
		(end 61.618368 -52.148994)
		(width 0.08382)
		(layer "In2.Cu")
		(net "M_BMC_DDR4_MDM1")
	)
	(segment
		(start 63.294768 -50.414936)
		(end 63.294768 -49.829974)
		(width 0.08382)
		(layer "In2.Cu")
		(net "M_BMC_DDR4_MDM1")
	)
	(segment
		(start 62.473586 -51.05273)
		(end 62.473586 -52.617116)
		(width 0.08382)
		(layer "In2.Cu")
		(net "M_BMC_DDR4_MDM1")
	)
	(segment
		(start 61.529468 -52.703476)
		(end 60.67425 -52.703476)
		(width 0.08382)
		(layer "In2.Cu")
		(net "M_BMC_DDR4_MDM1")
	)
	(segment
		(start 64.495172 -49.69891)
		(end 64.495172 -49.37252)
		(width 0.08382)
		(layer "In2.Cu")
		(net "M_BMC_DDR4_MDM1")
	)
	(segment
		(start 72.044814 -50.123598)
		(end 72.044814 -50.585624)
		(width 0.08382)
		(layer "In2.Cu")
		(net "M_BMC_DDR4_MDM1")
	)
	(segment
		(start 62.387226 -52.703476)
		(end 62.211458 -52.703476)
		(width 0.08382)
		(layer "In2.Cu")
		(net "M_BMC_DDR4_MDM1")
	)
	(segment
		(start 73.470516 -50.758344)
		(end 73.470516 -51.089306)
		(width 0.08382)
		(layer "In2.Cu")
		(net "M_BMC_DDR4_MDM1")
	)
	(segment
		(start 65.049146 -49.788826)
		(end 65.37325 -49.788826)
		(width 0.08382)
		(layer "In2.Cu")
		(net "M_BMC_DDR4_MDM1")
	)
	(segment
		(start 70.80123 -50.81778)
		(end 71.21906 -50.81778)
		(width 0.08382)
		(layer "In2.Cu")
		(net "M_BMC_DDR4_MDM1")
	)
	(segment
		(start 60.58789 -52.617116)
		(end 60.58789 -52.235354)
		(width 0.08382)
		(layer "In2.Cu")
		(net "M_BMC_DDR4_MDM1")
	)
	(segment
		(start 61.615828 -53.087778)
		(end 61.615828 -52.789836)
		(width 0.08382)
		(layer "In2.Cu")
		(net "M_BMC_DDR4_MDM1")
	)
	(segment
		(start 64.581532 -49.28616)
		(end 64.876426 -49.28616)
		(width 0.08382)
		(layer "In2.Cu")
		(net "M_BMC_DDR4_MDM1")
	)
	(segment
		(start 66.001392 -49.822862)
		(end 70.62851 -49.822862)
		(width 0.08382)
		(layer "In2.Cu")
		(net "M_BMC_DDR4_MDM1")
	)
	(segment
		(start 62.473586 -49.732184)
		(end 62.473586 -50.475388)
		(width 0.08382)
		(layer "In2.Cu")
		(net "M_BMC_DDR4_MDM1")
	)
	(segment
		(start 62.0903 -50.96637)
		(end 62.387226 -50.96637)
		(width 0.08382)
		(layer "In2.Cu")
		(net "M_BMC_DDR4_MDM1")
	)
	(segment
		(start 65.915032 -49.457102)
		(end 65.915032 -49.736502)
		(width 0.08382)
		(layer "In2.Cu")
		(net "M_BMC_DDR4_MDM1")
	)
	(segment
		(start 62.125098 -52.789836)
		(end 62.125098 -53.087778)
		(width 0.08382)
		(layer "In2.Cu")
		(net "M_BMC_DDR4_MDM1")
	)
	(segment
		(start 61.704728 -52.062634)
		(end 61.704728 -49.732184)
		(width 0.08382)
		(layer "In2.Cu")
		(net "M_BMC_DDR4_MDM1")
	)
	(segment
		(start 65.54597 -49.370742)
		(end 65.828672 -49.370742)
		(width 0.08382)
		(layer "In2.Cu")
		(net "M_BMC_DDR4_MDM1")
	)
	(segment
		(start 64.962786 -49.37252)
		(end 64.962786 -49.702466)
		(width 0.08382)
		(layer "In2.Cu")
		(net "M_BMC_DDR4_MDM1")
	)
	(segment
		(start 62.038738 -53.174138)
		(end 61.702188 -53.174138)
		(width 0.08382)
		(layer "In2.Cu")
		(net "M_BMC_DDR4_MDM1")
	)
	(segment
		(start 64.114172 -49.78527)
		(end 64.408812 -49.78527)
		(width 0.08382)
		(layer "In2.Cu")
		(net "M_BMC_DDR4_MDM1")
	)
	(segment
		(start 71.30542 -50.73142)
		(end 71.30542 -50.123598)
		(width 0.08382)
		(layer "In2.Cu")
		(net "M_BMC_DDR4_MDM1")
	)
	(segment
		(start 61.791088 -49.645824)
		(end 62.387226 -49.645824)
		(width 0.08382)
		(layer "In2.Cu")
		(net "M_BMC_DDR4_MDM1")
	)
	(segment
		(start 71.39178 -50.037238)
		(end 71.958454 -50.037238)
		(width 0.08382)
		(layer "In2.Cu")
		(net "M_BMC_DDR4_MDM1")
	)
	(segment
		(start 62.559946 -50.561748)
		(end 63.147956 -50.561748)
		(width 0.08382)
		(layer "In2.Cu")
		(net "M_BMC_DDR4_MDM1")
	)
	(segment
		(start 63.704978 -49.379124)
		(end 63.941452 -49.379124)
		(width 0.08382)
		(layer "In2.Cu")
		(net "M_BMC_DDR4_MDM1")
	)
	(segment
		(start 64.027812 -49.465484)
		(end 64.027812 -49.69891)
		(width 0.08382)
		(layer "In2.Cu")
		(net "M_BMC_DDR4_MDM1")
	)
	(segment
		(start 72.131174 -50.671984)
		(end 73.384156 -50.671984)
		(width 0.08382)
		(layer "In2.Cu")
		(net "M_BMC_DDR4_MDM1")
	)
	(segment
		(start 65.45961 -49.702466)
		(end 65.45961 -49.457102)
		(width 0.08382)
		(layer "In2.Cu")
		(net "M_BMC_DDR4_MDM1")
	)
	(segment
		(start 70.71487 -49.909222)
		(end 70.71487 -50.73142)
		(width 0.08382)
		(layer "In2.Cu")
		(net "M_BMC_DDR4_MDM1")
	)
	(arc
		(start 63.294768 -49.829974)
		(mid 63.384766 -49.557335)
		(end 63.61938 -49.391824)
		(width 0.08382)
		(layer "In2.Cu")
		(net "M_BMC_DDR4_MDM1")
	)
	(arc
		(start 62.211458 -52.703476)
		(mid 62.150392 -52.72877)
		(end 62.125098 -52.789836)
		(width 0.08382)
		(layer "In2.Cu")
		(net "M_BMC_DDR4_MDM1")
	)
	(arc
		(start 64.962786 -49.702466)
		(mid 64.98808 -49.763532)
		(end 65.049146 -49.788826)
		(width 0.08382)
		(layer "In2.Cu")
		(net "M_BMC_DDR4_MDM1")
	)
	(arc
		(start 60.67425 -52.703476)
		(mid 60.613184 -52.678182)
		(end 60.58789 -52.617116)
		(width 0.08382)
		(layer "In2.Cu")
		(net "M_BMC_DDR4_MDM1")
	)
	(arc
		(start 61.704728 -49.732184)
		(mid 61.730022 -49.671118)
		(end 61.791088 -49.645824)
		(width 0.08382)
		(layer "In2.Cu")
		(net "M_BMC_DDR4_MDM1")
	)
	(arc
		(start 70.62851 -49.822862)
		(mid 70.689576 -49.848156)
		(end 70.71487 -49.909222)
		(width 0.08382)
		(layer "In2.Cu")
		(net "M_BMC_DDR4_MDM1")
	)
	(arc
		(start 71.21906 -50.81778)
		(mid 71.280126 -50.792486)
		(end 71.30542 -50.73142)
		(width 0.08382)
		(layer "In2.Cu")
		(net "M_BMC_DDR4_MDM1")
	)
	(arc
		(start 64.027812 -49.69891)
		(mid 64.053106 -49.759976)
		(end 64.114172 -49.78527)
		(width 0.08382)
		(layer "In2.Cu")
		(net "M_BMC_DDR4_MDM1")
	)
	(arc
		(start 63.941452 -49.379124)
		(mid 64.002518 -49.404418)
		(end 64.027812 -49.465484)
		(width 0.08382)
		(layer "In2.Cu")
		(net "M_BMC_DDR4_MDM1")
	)
	(arc
		(start 62.125098 -53.087778)
		(mid 62.099804 -53.148844)
		(end 62.038738 -53.174138)
		(width 0.08382)
		(layer "In2.Cu")
		(net "M_BMC_DDR4_MDM1")
	)
	(arc
		(start 64.408812 -49.78527)
		(mid 64.469878 -49.759976)
		(end 64.495172 -49.69891)
		(width 0.08382)
		(layer "In2.Cu")
		(net "M_BMC_DDR4_MDM1")
	)
	(arc
		(start 63.147956 -50.561748)
		(mid 63.251768 -50.518748)
		(end 63.294768 -50.414936)
		(width 0.08382)
		(layer "In2.Cu")
		(net "M_BMC_DDR4_MDM1")
	)
	(arc
		(start 64.876426 -49.28616)
		(mid 64.937492 -49.311454)
		(end 64.962786 -49.37252)
		(width 0.08382)
		(layer "In2.Cu")
		(net "M_BMC_DDR4_MDM1")
	)
	(arc
		(start 73.384156 -50.671984)
		(mid 73.445222 -50.697278)
		(end 73.470516 -50.758344)
		(width 0.08382)
		(layer "In2.Cu")
		(net "M_BMC_DDR4_MDM1")
	)
	(arc
		(start 71.30542 -50.123598)
		(mid 71.330714 -50.062532)
		(end 71.39178 -50.037238)
		(width 0.08382)
		(layer "In2.Cu")
		(net "M_BMC_DDR4_MDM1")
	)
	(arc
		(start 71.958454 -50.037238)
		(mid 72.01952 -50.062532)
		(end 72.044814 -50.123598)
		(width 0.08382)
		(layer "In2.Cu")
		(net "M_BMC_DDR4_MDM1")
	)
	(arc
		(start 63.61938 -49.391824)
		(mid 63.661709 -49.382314)
		(end 63.704978 -49.379124)
		(width 0.08382)
		(layer "In2.Cu")
		(net "M_BMC_DDR4_MDM1")
	)
	(arc
		(start 61.702188 -53.174138)
		(mid 61.641122 -53.148844)
		(end 61.615828 -53.087778)
		(width 0.08382)
		(layer "In2.Cu")
		(net "M_BMC_DDR4_MDM1")
	)
	(arc
		(start 65.915032 -49.736502)
		(mid 65.940326 -49.797568)
		(end 66.001392 -49.822862)
		(width 0.08382)
		(layer "In2.Cu")
		(net "M_BMC_DDR4_MDM1")
	)
	(arc
		(start 72.044814 -50.585624)
		(mid 72.070108 -50.64669)
		(end 72.131174 -50.671984)
		(width 0.08382)
		(layer "In2.Cu")
		(net "M_BMC_DDR4_MDM1")
	)
	(arc
		(start 61.618368 -52.148994)
		(mid 61.679434 -52.1237)
		(end 61.704728 -52.062634)
		(width 0.08382)
		(layer "In2.Cu")
		(net "M_BMC_DDR4_MDM1")
	)
	(arc
		(start 62.387226 -50.96637)
		(mid 62.448292 -50.991664)
		(end 62.473586 -51.05273)
		(width 0.08382)
		(layer "In2.Cu")
		(net "M_BMC_DDR4_MDM1")
	)
	(arc
		(start 65.45961 -49.457102)
		(mid 65.484904 -49.396036)
		(end 65.54597 -49.370742)
		(width 0.08382)
		(layer "In2.Cu")
		(net "M_BMC_DDR4_MDM1")
	)
	(arc
		(start 62.473586 -50.475388)
		(mid 62.49888 -50.536454)
		(end 62.559946 -50.561748)
		(width 0.08382)
		(layer "In2.Cu")
		(net "M_BMC_DDR4_MDM1")
	)
	(arc
		(start 60.58789 -52.235354)
		(mid 60.613184 -52.174288)
		(end 60.67425 -52.148994)
		(width 0.08382)
		(layer "In2.Cu")
		(net "M_BMC_DDR4_MDM1")
	)
	(arc
		(start 61.615828 -52.789836)
		(mid 61.590534 -52.72877)
		(end 61.529468 -52.703476)
		(width 0.08382)
		(layer "In2.Cu")
		(net "M_BMC_DDR4_MDM1")
	)
	(arc
		(start 62.387226 -49.645824)
		(mid 62.448292 -49.671118)
		(end 62.473586 -49.732184)
		(width 0.08382)
		(layer "In2.Cu")
		(net "M_BMC_DDR4_MDM1")
	)
	(arc
		(start 65.828672 -49.370742)
		(mid 65.889738 -49.396036)
		(end 65.915032 -49.457102)
		(width 0.08382)
		(layer "In2.Cu")
		(net "M_BMC_DDR4_MDM1")
	)
	(arc
		(start 62.473586 -52.617116)
		(mid 62.448292 -52.678182)
		(end 62.387226 -52.703476)
		(width 0.08382)
		(layer "In2.Cu")
		(net "M_BMC_DDR4_MDM1")
	)
	(arc
		(start 64.495172 -49.37252)
		(mid 64.520466 -49.311454)
		(end 64.581532 -49.28616)
		(width 0.08382)
		(layer "In2.Cu")
		(net "M_BMC_DDR4_MDM1")
	)
	(arc
		(start 65.37325 -49.788826)
		(mid 65.434316 -49.763532)
		(end 65.45961 -49.702466)
		(width 0.08382)
		(layer "In2.Cu")
		(net "M_BMC_DDR4_MDM1")
	)
	(arc
		(start 70.71487 -50.73142)
		(mid 70.740164 -50.792486)
		(end 70.80123 -50.81778)
		(width 0.08382)
		(layer "In2.Cu")
		(net "M_BMC_DDR4_MDM1")
	)
	(segment
		(start 63.295022 -48.9712)
		(end 63.690246 -48.575976)
		(width 0.11684)
		(layer "F.Cu")
		(net "M_BMC_DDR4_MDM0")
	)
	(segment
		(start 77.558646 -51.27371)
		(end 77.763878 -51.068478)
		(width 0.11684)
		(layer "F.Cu")
		(net "M_BMC_DDR4_MDM0")
	)
	(segment
		(start 77.248766 -50.493422)
		(end 77.013562 -50.728626)
		(width 0.11684)
		(layer "F.Cu")
		(net "M_BMC_DDR4_MDM0")
	)
	(segment
		(start 77.013562 -51.257962)
		(end 77.02931 -51.27371)
		(width 0.11684)
		(layer "F.Cu")
		(net "M_BMC_DDR4_MDM0")
	)
	(segment
		(start 78.234032 -50.325782)
		(end 77.653134 -50.325782)
		(width 0.11684)
		(layer "F.Cu")
		(net "M_BMC_DDR4_MDM0")
	)
	(segment
		(start 77.85227 -50.855118)
		(end 77.85227 -50.707544)
		(width 0.11684)
		(layer "F.Cu")
		(net "M_BMC_DDR4_MDM0")
	)
	(via
		(at 63.690246 -48.575976)
		(size 0.4572)
		(drill 0.254)
		(layers "F.Cu" "B.Cu")
		(net "M_BMC_DDR4_MDM0")
	)
	(via
		(at 78.234032 -50.325782)
		(size 0.4572)
		(drill 0.254)
		(layers "F.Cu" "B.Cu")
		(net "M_BMC_DDR4_MDM0")
	)
	(arc
		(start 77.013562 -50.728626)
		(mid 76.903933 -50.993294)
		(end 77.013562 -51.257962)
		(width 0.11684)
		(layer "F.Cu")
		(net "M_BMC_DDR4_MDM0")
	)
	(arc
		(start 77.653134 -50.325782)
		(mid 77.43429 -50.369406)
		(end 77.248766 -50.493422)
		(width 0.11684)
		(layer "F.Cu")
		(net "M_BMC_DDR4_MDM0")
	)
	(arc
		(start 77.02931 -51.27371)
		(mid 77.293978 -51.383339)
		(end 77.558646 -51.27371)
		(width 0.11684)
		(layer "F.Cu")
		(net "M_BMC_DDR4_MDM0")
	)
	(arc
		(start 77.763878 -51.068478)
		(mid 77.829286 -50.970588)
		(end 77.85227 -50.855118)
		(width 0.11684)
		(layer "F.Cu")
		(net "M_BMC_DDR4_MDM0")
	)
	(segment
		(start 77.035152 -50.714402)
		(end 77.035152 -50.29454)
		(width 0.08382)
		(layer "In9.Cu")
		(net "M_BMC_DDR4_MDM0")
	)
	(segment
		(start 68.584064 -49.908968)
		(end 68.584064 -50.873914)
		(width 0.08382)
		(layer "In9.Cu")
		(net "M_BMC_DDR4_MDM0")
	)
	(segment
		(start 78.018894 -49.878488)
		(end 77.877416 -49.878488)
		(width 0.08382)
		(layer "In9.Cu")
		(net "M_BMC_DDR4_MDM0")
	)
	(segment
		(start 78.234032 -50.325782)
		(end 78.234032 -50.093626)
		(width 0.08382)
		(layer "In9.Cu")
		(net "M_BMC_DDR4_MDM0")
	)
	(segment
		(start 75.189334 -48.211994)
		(end 73.117456 -48.211994)
		(width 0.08382)
		(layer "In9.Cu")
		(net "M_BMC_DDR4_MDM0")
	)
	(segment
		(start 68.497704 -50.960274)
		(end 66.016632 -50.960274)
		(width 0.08382)
		(layer "In9.Cu")
		(net "M_BMC_DDR4_MDM0")
	)
	(segment
		(start 71.483728 -48.720502)
		(end 71.02856 -49.17567)
		(width 0.08382)
		(layer "In9.Cu")
		(net "M_BMC_DDR4_MDM0")
	)
	(segment
		(start 63.203074 -49.657508)
		(end 62.96533 -49.657508)
		(width 0.08382)
		(layer "In9.Cu")
		(net "M_BMC_DDR4_MDM0")
	)
	(segment
		(start 75.501246 -49.358804)
		(end 75.501246 -48.523906)
		(width 0.08382)
		(layer "In9.Cu")
		(net "M_BMC_DDR4_MDM0")
	)
	(segment
		(start 76.029312 -50.51044)
		(end 76.029312 -49.79162)
		(width 0.08382)
		(layer "In9.Cu")
		(net "M_BMC_DDR4_MDM0")
	)
	(segment
		(start 62.87897 -49.571148)
		(end 62.87897 -49.398428)
		(width 0.08382)
		(layer "In9.Cu")
		(net "M_BMC_DDR4_MDM0")
	)
	(segment
		(start 63.289434 -50.143156)
		(end 63.289434 -49.743868)
		(width 0.08382)
		(layer "In9.Cu")
		(net "M_BMC_DDR4_MDM0")
	)
	(segment
		(start 65.264792 -50.575972)
		(end 63.72225 -50.575972)
		(width 0.08382)
		(layer "In9.Cu")
		(net "M_BMC_DDR4_MDM0")
	)
	(segment
		(start 70.27799 -49.822608)
		(end 68.670424 -49.822608)
		(width 0.08382)
		(layer "In9.Cu")
		(net "M_BMC_DDR4_MDM0")
	)
	(segment
		(start 76.532232 -50.29454)
		(end 76.532232 -50.51044)
		(width 0.08382)
		(layer "In9.Cu")
		(net "M_BMC_DDR4_MDM0")
	)
	(segment
		(start 72.879966 -48.449484)
		(end 72.879966 -48.477932)
		(width 0.08382)
		(layer "In9.Cu")
		(net "M_BMC_DDR4_MDM0")
	)
	(segment
		(start 63.401956 -48.864266)
		(end 63.690246 -48.575976)
		(width 0.08382)
		(layer "In9.Cu")
		(net "M_BMC_DDR4_MDM0")
	)
	(segment
		(start 70.402704 -49.481994)
		(end 70.402704 -49.697894)
		(width 0.08382)
		(layer "In9.Cu")
		(net "M_BMC_DDR4_MDM0")
	)
	(segment
		(start 77.538072 -50.217832)
		(end 77.538072 -50.714402)
		(width 0.08382)
		(layer "In9.Cu")
		(net "M_BMC_DDR4_MDM0")
	)
	(segment
		(start 76.792328 -50.051716)
		(end 76.775056 -50.051716)
		(width 0.08382)
		(layer "In9.Cu")
		(net "M_BMC_DDR4_MDM0")
	)
	(segment
		(start 62.96533 -49.312068)
		(end 63.203074 -49.312068)
		(width 0.08382)
		(layer "In9.Cu")
		(net "M_BMC_DDR4_MDM0")
	)
	(segment
		(start 72.662796 -48.695102)
		(end 71.544942 -48.695102)
		(width 0.08382)
		(layer "In9.Cu")
		(net "M_BMC_DDR4_MDM0")
	)
	(segment
		(start 63.424816 -50.452782)
		(end 63.412624 -50.44059)
		(width 0.08382)
		(layer "In9.Cu")
		(net "M_BMC_DDR4_MDM0")
	)
	(segment
		(start 75.793092 -49.5554)
		(end 75.697842 -49.5554)
		(width 0.08382)
		(layer "In9.Cu")
		(net "M_BMC_DDR4_MDM0")
	)
	(segment
		(start 76.289408 -50.753264)
		(end 76.272136 -50.753264)
		(width 0.08382)
		(layer "In9.Cu")
		(net "M_BMC_DDR4_MDM0")
	)
	(segment
		(start 70.4977 -49.395634)
		(end 70.489064 -49.395634)
		(width 0.08382)
		(layer "In9.Cu")
		(net "M_BMC_DDR4_MDM0")
	)
	(segment
		(start 63.289434 -49.225708)
		(end 63.289434 -49.135792)
		(width 0.08382)
		(layer "In9.Cu")
		(net "M_BMC_DDR4_MDM0")
	)
	(segment
		(start 65.695068 -50.827178)
		(end 65.570354 -50.702464)
		(width 0.08382)
		(layer "In9.Cu")
		(net "M_BMC_DDR4_MDM0")
	)
	(arc
		(start 77.538072 -50.714402)
		(mid 77.286612 -50.965862)
		(end 77.035152 -50.714402)
		(width 0.08382)
		(layer "In9.Cu")
		(net "M_BMC_DDR4_MDM0")
	)
	(arc
		(start 71.02856 -49.17567)
		(mid 70.785014 -49.338466)
		(end 70.4977 -49.395634)
		(width 0.08382)
		(layer "In9.Cu")
		(net "M_BMC_DDR4_MDM0")
	)
	(arc
		(start 75.697842 -49.5554)
		(mid 75.558828 -49.497818)
		(end 75.501246 -49.358804)
		(width 0.08382)
		(layer "In9.Cu")
		(net "M_BMC_DDR4_MDM0")
	)
	(arc
		(start 76.532232 -50.51044)
		(mid 76.46111 -50.682142)
		(end 76.289408 -50.753264)
		(width 0.08382)
		(layer "In9.Cu")
		(net "M_BMC_DDR4_MDM0")
	)
	(arc
		(start 62.87897 -49.398428)
		(mid 62.904264 -49.337362)
		(end 62.96533 -49.312068)
		(width 0.08382)
		(layer "In9.Cu")
		(net "M_BMC_DDR4_MDM0")
	)
	(arc
		(start 76.775056 -50.051716)
		(mid 76.603354 -50.122838)
		(end 76.532232 -50.29454)
		(width 0.08382)
		(layer "In9.Cu")
		(net "M_BMC_DDR4_MDM0")
	)
	(arc
		(start 75.501246 -48.523906)
		(mid 75.409889 -48.303351)
		(end 75.189334 -48.211994)
		(width 0.08382)
		(layer "In9.Cu")
		(net "M_BMC_DDR4_MDM0")
	)
	(arc
		(start 62.96533 -49.657508)
		(mid 62.904264 -49.632214)
		(end 62.87897 -49.571148)
		(width 0.08382)
		(layer "In9.Cu")
		(net "M_BMC_DDR4_MDM0")
	)
	(arc
		(start 63.289434 -49.743868)
		(mid 63.26414 -49.682802)
		(end 63.203074 -49.657508)
		(width 0.08382)
		(layer "In9.Cu")
		(net "M_BMC_DDR4_MDM0")
	)
	(arc
		(start 70.402704 -49.697894)
		(mid 70.366176 -49.78608)
		(end 70.27799 -49.822608)
		(width 0.08382)
		(layer "In9.Cu")
		(net "M_BMC_DDR4_MDM0")
	)
	(arc
		(start 71.544942 -48.695102)
		(mid 71.511811 -48.70171)
		(end 71.483728 -48.720502)
		(width 0.08382)
		(layer "In9.Cu")
		(net "M_BMC_DDR4_MDM0")
	)
	(arc
		(start 66.016632 -50.960274)
		(mid 65.842613 -50.925695)
		(end 65.695068 -50.827178)
		(width 0.08382)
		(layer "In9.Cu")
		(net "M_BMC_DDR4_MDM0")
	)
	(arc
		(start 63.203074 -49.312068)
		(mid 63.26414 -49.286774)
		(end 63.289434 -49.225708)
		(width 0.08382)
		(layer "In9.Cu")
		(net "M_BMC_DDR4_MDM0")
	)
	(arc
		(start 68.670424 -49.822608)
		(mid 68.609358 -49.847902)
		(end 68.584064 -49.908968)
		(width 0.08382)
		(layer "In9.Cu")
		(net "M_BMC_DDR4_MDM0")
	)
	(arc
		(start 68.584064 -50.873914)
		(mid 68.55877 -50.93498)
		(end 68.497704 -50.960274)
		(width 0.08382)
		(layer "In9.Cu")
		(net "M_BMC_DDR4_MDM0")
	)
	(arc
		(start 77.035152 -50.29454)
		(mid 76.96403 -50.122838)
		(end 76.792328 -50.051716)
		(width 0.08382)
		(layer "In9.Cu")
		(net "M_BMC_DDR4_MDM0")
	)
	(arc
		(start 65.570354 -50.702464)
		(mid 65.430147 -50.608844)
		(end 65.264792 -50.575972)
		(width 0.08382)
		(layer "In9.Cu")
		(net "M_BMC_DDR4_MDM0")
	)
	(arc
		(start 72.879966 -48.477932)
		(mid 72.816358 -48.631494)
		(end 72.662796 -48.695102)
		(width 0.08382)
		(layer "In9.Cu")
		(net "M_BMC_DDR4_MDM0")
	)
	(arc
		(start 78.234032 -50.093626)
		(mid 78.17102 -49.9415)
		(end 78.018894 -49.878488)
		(width 0.08382)
		(layer "In9.Cu")
		(net "M_BMC_DDR4_MDM0")
	)
	(arc
		(start 76.029312 -49.79162)
		(mid 75.960125 -49.624587)
		(end 75.793092 -49.5554)
		(width 0.08382)
		(layer "In9.Cu")
		(net "M_BMC_DDR4_MDM0")
	)
	(arc
		(start 63.412624 -50.44059)
		(mid 63.321442 -50.304126)
		(end 63.289434 -50.143156)
		(width 0.08382)
		(layer "In9.Cu")
		(net "M_BMC_DDR4_MDM0")
	)
	(arc
		(start 63.72225 -50.575972)
		(mid 63.561284 -50.543954)
		(end 63.424816 -50.452782)
		(width 0.08382)
		(layer "In9.Cu")
		(net "M_BMC_DDR4_MDM0")
	)
	(arc
		(start 73.117456 -48.211994)
		(mid 72.949525 -48.281553)
		(end 72.879966 -48.449484)
		(width 0.08382)
		(layer "In9.Cu")
		(net "M_BMC_DDR4_MDM0")
	)
	(arc
		(start 76.272136 -50.753264)
		(mid 76.100434 -50.682142)
		(end 76.029312 -50.51044)
		(width 0.08382)
		(layer "In9.Cu")
		(net "M_BMC_DDR4_MDM0")
	)
	(arc
		(start 63.289434 -49.135792)
		(mid 63.318683 -48.988837)
		(end 63.401956 -48.864266)
		(width 0.08382)
		(layer "In9.Cu")
		(net "M_BMC_DDR4_MDM0")
	)
	(arc
		(start 77.877416 -49.878488)
		(mid 77.637464 -49.97788)
		(end 77.538072 -50.217832)
		(width 0.08382)
		(layer "In9.Cu")
		(net "M_BMC_DDR4_MDM0")
	)
	(arc
		(start 70.489064 -49.395634)
		(mid 70.427998 -49.420928)
		(end 70.402704 -49.481994)
		(width 0.08382)
		(layer "In9.Cu")
		(net "M_BMC_DDR4_MDM0")
	)
	(segment
		(start 83.281012 -39.495984)
		(end 80.123538 -39.495984)
		(width 0.11684)
		(layer "F.Cu")
		(net "M_BMC_DDR4_MCS_N")
	)
	(segment
		(start 77.9907 -40.379396)
		(end 77.069188 -41.300908)
		(width 0.11684)
		(layer "F.Cu")
		(net "M_BMC_DDR4_MCS_N")
	)
	(segment
		(start 64.094868 -44.971208)
		(end 64.490092 -44.575984)
		(width 0.11684)
		(layer "F.Cu")
		(net "M_BMC_DDR4_MCS_N")
	)
	(segment
		(start 84.8995 -39.347394)
		(end 84.17687 -39.347394)
		(width 0.11684)
		(layer "F.Cu")
		(net "M_BMC_DDR4_MCS_N")
	)
	(segment
		(start 77.470508 -45.52569)
		(end 77.85227 -45.907452)
		(width 0.11684)
		(layer "F.Cu")
		(net "M_BMC_DDR4_MCS_N")
	)
	(segment
		(start 77.039216 -41.373044)
		(end 77.039216 -44.981876)
		(width 0.11684)
		(layer "F.Cu")
		(net "M_BMC_DDR4_MCS_N")
	)
	(segment
		(start 77.118718 -45.1739)
		(end 77.470508 -45.52569)
		(width 0.11684)
		(layer "F.Cu")
		(net "M_BMC_DDR4_MCS_N")
	)
	(segment
		(start 83.429602 -39.347394)
		(end 83.281012 -39.495984)
		(width 0.11684)
		(layer "F.Cu")
		(net "M_BMC_DDR4_MCS_N")
	)
	(segment
		(start 84.17687 -39.347394)
		(end 83.429602 -39.347394)
		(width 0.11684)
		(layer "F.Cu")
		(net "M_BMC_DDR4_MCS_N")
	)
	(via
		(at 77.470508 -45.52569)
		(size 0.4572)
		(drill 0.254)
		(layers "F.Cu" "B.Cu")
		(net "M_BMC_DDR4_MCS_N")
	)
	(via
		(at 64.490092 -44.575984)
		(size 0.4572)
		(drill 0.254)
		(layers "F.Cu" "B.Cu")
		(net "M_BMC_DDR4_MCS_N")
	)
	(via
		(at 84.17687 -39.347394)
		(size 0.508)
		(drill 0.254)
		(layers "F.Cu" "B.Cu")
		(net "M_BMC_DDR4_MCS_N")
	)
	(arc
		(start 80.123538 -39.495984)
		(mid 78.969255 -39.725567)
		(end 77.9907 -40.379396)
		(width 0.11684)
		(layer "F.Cu")
		(net "M_BMC_DDR4_MCS_N")
	)
	(arc
		(start 77.039216 -44.981876)
		(mid 77.059885 -45.085785)
		(end 77.118718 -45.1739)
		(width 0.11684)
		(layer "F.Cu")
		(net "M_BMC_DDR4_MCS_N")
	)
	(arc
		(start 77.069188 -41.300908)
		(mid 77.04702 -41.33399)
		(end 77.039216 -41.373044)
		(width 0.11684)
		(layer "F.Cu")
		(net "M_BMC_DDR4_MCS_N")
	)
	(segment
		(start 84.8995 -39.347394)
		(end 84.17687 -39.347394)
		(width 0.11684)
		(layer "B.Cu")
		(net "M_BMC_DDR4_MCS_N")
	)
	(segment
		(start 76.143104 -44.44238)
		(end 76.143104 -44.40682)
		(width 0.08382)
		(layer "In2.Cu")
		(net "M_BMC_DDR4_MCS_N")
	)
	(segment
		(start 75.136502 -44.323)
		(end 75.492864 -44.323)
		(width 0.08382)
		(layer "In2.Cu")
		(net "M_BMC_DDR4_MCS_N")
	)
	(segment
		(start 70.638416 -43.902884)
		(end 70.638416 -44.095162)
		(width 0.08382)
		(layer "In2.Cu")
		(net "M_BMC_DDR4_MCS_N")
	)
	(segment
		(start 75.660504 -44.5262)
		(end 76.059284 -44.5262)
		(width 0.08382)
		(layer "In2.Cu")
		(net "M_BMC_DDR4_MCS_N")
	)
	(segment
		(start 77.47 -45.851318)
		(end 77.47 -45.52569)
		(width 0.08382)
		(layer "In2.Cu")
		(net "M_BMC_DDR4_MCS_N")
	)
	(segment
		(start 64.490092 -44.575984)
		(end 64.490092 -44.863004)
		(width 0.08382)
		(layer "In2.Cu")
		(net "M_BMC_DDR4_MCS_N")
	)
	(segment
		(start 77.203808 -45.117004)
		(end 77.761846 -45.117004)
		(width 0.08382)
		(layer "In2.Cu")
		(net "M_BMC_DDR4_MCS_N")
	)
	(segment
		(start 64.639444 -45.012356)
		(end 65.913 -45.012356)
		(width 0.08382)
		(layer "In2.Cu")
		(net "M_BMC_DDR4_MCS_N")
	)
	(segment
		(start 75.0062 -45.030644)
		(end 75.0062 -44.453302)
		(width 0.08382)
		(layer "In2.Cu")
		(net "M_BMC_DDR4_MCS_N")
	)
	(segment
		(start 76.226924 -44.323)
		(end 76.97724 -44.323)
		(width 0.08382)
		(layer "In2.Cu")
		(net "M_BMC_DDR4_MCS_N")
	)
	(segment
		(start 79.289148 -45.46092)
		(end 79.289148 -45.858938)
		(width 0.08382)
		(layer "In2.Cu")
		(net "M_BMC_DDR4_MCS_N")
	)
	(segment
		(start 77.855826 -45.023024)
		(end 77.855826 -44.408852)
		(width 0.08382)
		(layer "In2.Cu")
		(net "M_BMC_DDR4_MCS_N")
	)
	(segment
		(start 66.00698 -44.918376)
		(end 66.00698 -44.550838)
		(width 0.08382)
		(layer "In2.Cu")
		(net "M_BMC_DDR4_MCS_N")
	)
	(segment
		(start 79.202788 -45.945298)
		(end 77.56398 -45.945298)
		(width 0.08382)
		(layer "In2.Cu")
		(net "M_BMC_DDR4_MCS_N")
	)
	(segment
		(start 66.417698 -44.003468)
		(end 68.978272 -44.003468)
		(width 0.08382)
		(layer "In2.Cu")
		(net "M_BMC_DDR4_MCS_N")
	)
	(segment
		(start 69.37756 -43.816524)
		(end 70.552056 -43.816524)
		(width 0.08382)
		(layer "In2.Cu")
		(net "M_BMC_DDR4_MCS_N")
	)
	(segment
		(start 78.685898 -45.37456)
		(end 79.202788 -45.37456)
		(width 0.08382)
		(layer "In2.Cu")
		(net "M_BMC_DDR4_MCS_N")
	)
	(segment
		(start 70.768718 -44.225464)
		(end 71.021702 -44.225464)
		(width 0.08382)
		(layer "In2.Cu")
		(net "M_BMC_DDR4_MCS_N")
	)
	(segment
		(start 79.297784 -44.408852)
		(end 79.297784 -44.774866)
		(width 0.08382)
		(layer "In2.Cu")
		(net "M_BMC_DDR4_MCS_N")
	)
	(segment
		(start 77.942186 -44.322492)
		(end 79.211424 -44.322492)
		(width 0.08382)
		(layer "In2.Cu")
		(net "M_BMC_DDR4_MCS_N")
	)
	(segment
		(start 78.591918 -44.955206)
		(end 78.591918 -45.28058)
		(width 0.08382)
		(layer "In2.Cu")
		(net "M_BMC_DDR4_MCS_N")
	)
	(segment
		(start 75.576684 -44.40682)
		(end 75.576684 -44.44238)
		(width 0.08382)
		(layer "In2.Cu")
		(net "M_BMC_DDR4_MCS_N")
	)
	(segment
		(start 77.0636 -44.40936)
		(end 77.0636 -44.976796)
		(width 0.08382)
		(layer "In2.Cu")
		(net "M_BMC_DDR4_MCS_N")
	)
	(segment
		(start 71.108062 -44.311824)
		(end 71.108062 -44.878752)
		(width 0.08382)
		(layer "In2.Cu")
		(net "M_BMC_DDR4_MCS_N")
	)
	(segment
		(start 71.319898 -45.117004)
		(end 74.91984 -45.117004)
		(width 0.08382)
		(layer "In2.Cu")
		(net "M_BMC_DDR4_MCS_N")
	)
	(segment
		(start 79.211424 -44.861226)
		(end 78.685898 -44.861226)
		(width 0.08382)
		(layer "In2.Cu")
		(net "M_BMC_DDR4_MCS_N")
	)
	(segment
		(start 77.47 -45.52569)
		(end 77.470508 -45.52569)
		(width 0.08382)
		(layer "In2.Cu")
		(net "M_BMC_DDR4_MCS_N")
	)
	(segment
		(start 66.162174 -44.176188)
		(end 66.244216 -44.094146)
		(width 0.08382)
		(layer "In2.Cu")
		(net "M_BMC_DDR4_MCS_N")
	)
	(arc
		(start 66.244216 -44.094146)
		(mid 66.283671 -44.059037)
		(end 66.32702 -44.028868)
		(width 0.08382)
		(layer "In2.Cu")
		(net "M_BMC_DDR4_MCS_N")
	)
	(arc
		(start 77.56398 -45.945298)
		(mid 77.497526 -45.917772)
		(end 77.47 -45.851318)
		(width 0.08382)
		(layer "In2.Cu")
		(net "M_BMC_DDR4_MCS_N")
	)
	(arc
		(start 77.761846 -45.117004)
		(mid 77.8283 -45.089478)
		(end 77.855826 -45.023024)
		(width 0.08382)
		(layer "In2.Cu")
		(net "M_BMC_DDR4_MCS_N")
	)
	(arc
		(start 70.638416 -44.095162)
		(mid 70.676581 -44.187299)
		(end 70.768718 -44.225464)
		(width 0.08382)
		(layer "In2.Cu")
		(net "M_BMC_DDR4_MCS_N")
	)
	(arc
		(start 75.576684 -44.44238)
		(mid 75.601234 -44.50165)
		(end 75.660504 -44.5262)
		(width 0.08382)
		(layer "In2.Cu")
		(net "M_BMC_DDR4_MCS_N")
	)
	(arc
		(start 77.855826 -44.408852)
		(mid 77.88112 -44.347786)
		(end 77.942186 -44.322492)
		(width 0.08382)
		(layer "In2.Cu")
		(net "M_BMC_DDR4_MCS_N")
	)
	(arc
		(start 78.685898 -44.861226)
		(mid 78.619444 -44.888752)
		(end 78.591918 -44.955206)
		(width 0.08382)
		(layer "In2.Cu")
		(net "M_BMC_DDR4_MCS_N")
	)
	(arc
		(start 77.0636 -44.976796)
		(mid 77.104666 -45.075938)
		(end 77.203808 -45.117004)
		(width 0.08382)
		(layer "In2.Cu")
		(net "M_BMC_DDR4_MCS_N")
	)
	(arc
		(start 71.108062 -44.878752)
		(mid 71.142389 -45.00473)
		(end 71.236078 -45.095668)
		(width 0.08382)
		(layer "In2.Cu")
		(net "M_BMC_DDR4_MCS_N")
	)
	(arc
		(start 71.021702 -44.225464)
		(mid 71.082768 -44.250758)
		(end 71.108062 -44.311824)
		(width 0.08382)
		(layer "In2.Cu")
		(net "M_BMC_DDR4_MCS_N")
	)
	(arc
		(start 79.202788 -45.37456)
		(mid 79.263854 -45.399854)
		(end 79.289148 -45.46092)
		(width 0.08382)
		(layer "In2.Cu")
		(net "M_BMC_DDR4_MCS_N")
	)
	(arc
		(start 66.00698 -44.550838)
		(mid 66.047312 -44.348075)
		(end 66.162174 -44.176188)
		(width 0.08382)
		(layer "In2.Cu")
		(net "M_BMC_DDR4_MCS_N")
	)
	(arc
		(start 66.32702 -44.028868)
		(mid 66.370606 -44.009913)
		(end 66.417698 -44.003468)
		(width 0.08382)
		(layer "In2.Cu")
		(net "M_BMC_DDR4_MCS_N")
	)
	(arc
		(start 64.490092 -44.863004)
		(mid 64.533836 -44.968612)
		(end 64.639444 -45.012356)
		(width 0.08382)
		(layer "In2.Cu")
		(net "M_BMC_DDR4_MCS_N")
	)
	(arc
		(start 70.552056 -43.816524)
		(mid 70.613122 -43.841818)
		(end 70.638416 -43.902884)
		(width 0.08382)
		(layer "In2.Cu")
		(net "M_BMC_DDR4_MCS_N")
	)
	(arc
		(start 79.211424 -44.322492)
		(mid 79.27249 -44.347786)
		(end 79.297784 -44.408852)
		(width 0.08382)
		(layer "In2.Cu")
		(net "M_BMC_DDR4_MCS_N")
	)
	(arc
		(start 79.289148 -45.858938)
		(mid 79.263854 -45.920004)
		(end 79.202788 -45.945298)
		(width 0.08382)
		(layer "In2.Cu")
		(net "M_BMC_DDR4_MCS_N")
	)
	(arc
		(start 76.97724 -44.323)
		(mid 77.038306 -44.348294)
		(end 77.0636 -44.40936)
		(width 0.08382)
		(layer "In2.Cu")
		(net "M_BMC_DDR4_MCS_N")
	)
	(arc
		(start 75.492864 -44.323)
		(mid 75.552134 -44.34755)
		(end 75.576684 -44.40682)
		(width 0.08382)
		(layer "In2.Cu")
		(net "M_BMC_DDR4_MCS_N")
	)
	(arc
		(start 65.913 -45.012356)
		(mid 65.979454 -44.98483)
		(end 66.00698 -44.918376)
		(width 0.08382)
		(layer "In2.Cu")
		(net "M_BMC_DDR4_MCS_N")
	)
	(arc
		(start 69.28612 -43.875706)
		(mid 69.328674 -43.841222)
		(end 69.37756 -43.816524)
		(width 0.08382)
		(layer "In2.Cu")
		(net "M_BMC_DDR4_MCS_N")
	)
	(arc
		(start 68.978272 -44.003468)
		(mid 69.144944 -43.970279)
		(end 69.28612 -43.875706)
		(width 0.08382)
		(layer "In2.Cu")
		(net "M_BMC_DDR4_MCS_N")
	)
	(arc
		(start 76.143104 -44.40682)
		(mid 76.167654 -44.34755)
		(end 76.226924 -44.323)
		(width 0.08382)
		(layer "In2.Cu")
		(net "M_BMC_DDR4_MCS_N")
	)
	(arc
		(start 76.059284 -44.5262)
		(mid 76.118554 -44.50165)
		(end 76.143104 -44.44238)
		(width 0.08382)
		(layer "In2.Cu")
		(net "M_BMC_DDR4_MCS_N")
	)
	(arc
		(start 74.91984 -45.117004)
		(mid 74.980906 -45.09171)
		(end 75.0062 -45.030644)
		(width 0.08382)
		(layer "In2.Cu")
		(net "M_BMC_DDR4_MCS_N")
	)
	(arc
		(start 78.591918 -45.28058)
		(mid 78.619444 -45.347034)
		(end 78.685898 -45.37456)
		(width 0.08382)
		(layer "In2.Cu")
		(net "M_BMC_DDR4_MCS_N")
	)
	(arc
		(start 75.0062 -44.453302)
		(mid 75.044365 -44.361165)
		(end 75.136502 -44.323)
		(width 0.08382)
		(layer "In2.Cu")
		(net "M_BMC_DDR4_MCS_N")
	)
	(arc
		(start 71.236078 -45.095668)
		(mid 71.276642 -45.111611)
		(end 71.319898 -45.117004)
		(width 0.08382)
		(layer "In2.Cu")
		(net "M_BMC_DDR4_MCS_N")
	)
	(arc
		(start 79.297784 -44.774866)
		(mid 79.27249 -44.835932)
		(end 79.211424 -44.861226)
		(width 0.08382)
		(layer "In2.Cu")
		(net "M_BMC_DDR4_MCS_N")
	)
	(segment
		(start 67.366388 -45.588174)
		(end 67.366388 -45.328586)
		(width 0.1016)
		(layer "F.Cu")
		(net "M_BMC_DDR4_MCLK_DP")
	)
	(segment
		(start 64.686434 -46.190154)
		(end 66.66103 -46.190154)
		(width 0.1016)
		(layer "F.Cu")
		(net "M_BMC_DDR4_MCLK_DP")
	)
	(segment
		(start 67.2465 -45.039026)
		(end 67.112388 -44.904914)
		(width 0.1016)
		(layer "F.Cu")
		(net "M_BMC_DDR4_MCLK_DP")
	)
	(segment
		(start 64.094868 -46.571154)
		(end 64.327024 -46.338998)
		(width 0.1016)
		(layer "F.Cu")
		(net "M_BMC_DDR4_MCLK_DP")
	)
	(segment
		(start 66.927476 -46.079664)
		(end 67.32905 -45.67809)
		(width 0.1016)
		(layer "F.Cu")
		(net "M_BMC_DDR4_MCLK_DP")
	)
	(segment
		(start 77.85227 -46.707552)
		(end 78.234032 -47.089314)
		(width 0.1016)
		(layer "F.Cu")
		(net "M_BMC_DDR4_MCLK_DP")
	)
	(via
		(at 78.234032 -47.089314)
		(size 0.4572)
		(drill 0.254)
		(layers "F.Cu" "B.Cu")
		(net "M_BMC_DDR4_MCLK_DP")
	)
	(via
		(at 67.112388 -44.904914)
		(size 0.4572)
		(drill 0.254)
		(layers "F.Cu" "B.Cu")
		(net "M_BMC_DDR4_MCLK_DP")
	)
	(arc
		(start 67.32905 -45.67809)
		(mid 67.356698 -45.636851)
		(end 67.366388 -45.588174)
		(width 0.1016)
		(layer "F.Cu")
		(net "M_BMC_DDR4_MCLK_DP")
	)
	(arc
		(start 64.327024 -46.338998)
		(mid 64.491923 -46.228816)
		(end 64.686434 -46.190154)
		(width 0.1016)
		(layer "F.Cu")
		(net "M_BMC_DDR4_MCLK_DP")
	)
	(arc
		(start 66.66103 -46.190154)
		(mid 66.805223 -46.161379)
		(end 66.927476 -46.079664)
		(width 0.1016)
		(layer "F.Cu")
		(net "M_BMC_DDR4_MCLK_DP")
	)
	(arc
		(start 67.366388 -45.328586)
		(mid 67.335236 -45.171883)
		(end 67.2465 -45.039026)
		(width 0.1016)
		(layer "F.Cu")
		(net "M_BMC_DDR4_MCLK_DP")
	)
	(segment
		(start 77.715872 -46.881796)
		(end 78.045564 -46.881796)
		(width 0.1016)
		(layer "B.Cu")
		(net "M_BMC_DDR4_MCLK_DP")
	)
	(segment
		(start 78.045564 -46.881796)
		(end 78.234032 -47.089314)
		(width 0.1016)
		(layer "B.Cu")
		(net "M_BMC_DDR4_MCLK_DP")
	)
	(segment
		(start 77.382878 -47.21479)
		(end 77.715872 -46.881796)
		(width 0.1016)
		(layer "B.Cu")
		(net "M_BMC_DDR4_MCLK_DP")
	)
	(segment
		(start 67.112388 -44.904914)
		(end 67.235324 -45.02785)
		(width 0.08636)
		(layer "In2.Cu")
		(net "M_BMC_DDR4_MCLK_DP")
	)
	(segment
		(start 75.669648 -47.771812)
		(end 75.753976 -47.687484)
		(width 0.08636)
		(layer "In2.Cu")
		(net "M_BMC_DDR4_MCLK_DP")
	)
	(segment
		(start 76.040488 -45.339)
		(end 76.271374 -45.339)
		(width 0.08636)
		(layer "In2.Cu")
		(net "M_BMC_DDR4_MCLK_DP")
	)
	(segment
		(start 67.264026 -45.791374)
		(end 67.183 -45.8724)
		(width 0.08636)
		(layer "In2.Cu")
		(net "M_BMC_DDR4_MCLK_DP")
	)
	(segment
		(start 76.640436 -46.622462)
		(end 76.725018 -46.707044)
		(width 0.08636)
		(layer "In2.Cu")
		(net "M_BMC_DDR4_MCLK_DP")
	)
	(segment
		(start 75.9333 -45.410374)
		(end 75.979274 -45.3644)
		(width 0.08636)
		(layer "In2.Cu")
		(net "M_BMC_DDR4_MCLK_DP")
	)
	(segment
		(start 64.88938 -46.496986)
		(end 64.88938 -47.558198)
		(width 0.08636)
		(layer "In2.Cu")
		(net "M_BMC_DDR4_MCLK_DP")
	)
	(segment
		(start 77.248004 -46.92396)
		(end 77.96022 -46.92396)
		(width 0.08636)
		(layer "In2.Cu")
		(net "M_BMC_DDR4_MCLK_DP")
	)
	(segment
		(start 75.9079 -47.315628)
		(end 75.9079 -45.471588)
		(width 0.08636)
		(layer "In2.Cu")
		(net "M_BMC_DDR4_MCLK_DP")
	)
	(segment
		(start 65.487042 -48.15586)
		(end 65.795906 -48.15586)
		(width 0.08636)
		(layer "In2.Cu")
		(net "M_BMC_DDR4_MCLK_DP")
	)
	(segment
		(start 76.332588 -45.3644)
		(end 76.38034 -45.412152)
		(width 0.08636)
		(layer "In2.Cu")
		(net "M_BMC_DDR4_MCLK_DP")
	)
	(segment
		(start 76.40574 -45.473366)
		(end 76.40574 -46.056042)
		(width 0.08636)
		(layer "In2.Cu")
		(net "M_BMC_DDR4_MCLK_DP")
	)
	(segment
		(start 67.121786 -45.8978)
		(end 65.488566 -45.8978)
		(width 0.08636)
		(layer "In2.Cu")
		(net "M_BMC_DDR4_MCLK_DP")
	)
	(segment
		(start 68.86448 -47.352458)
		(end 70.143624 -47.882048)
		(width 0.08636)
		(layer "In2.Cu")
		(net "M_BMC_DDR4_MCLK_DP")
	)
	(segment
		(start 66.324734 -47.936658)
		(end 66.890392 -47.371)
		(width 0.08636)
		(layer "In2.Cu")
		(net "M_BMC_DDR4_MCLK_DP")
	)
	(segment
		(start 65.129156 -46.046644)
		(end 65.038224 -46.137322)
		(width 0.08636)
		(layer "In2.Cu")
		(net "M_BMC_DDR4_MCLK_DP")
	)
	(segment
		(start 66.951606 -47.3456)
		(end 68.83146 -47.3456)
		(width 0.08636)
		(layer "In2.Cu")
		(net "M_BMC_DDR4_MCLK_DP")
	)
	(segment
		(start 70.337934 -47.920656)
		(end 75.310238 -47.920656)
		(width 0.08636)
		(layer "In2.Cu")
		(net "M_BMC_DDR4_MCLK_DP")
	)
	(segment
		(start 67.346068 -45.295312)
		(end 67.346068 -45.593508)
		(width 0.08636)
		(layer "In2.Cu")
		(net "M_BMC_DDR4_MCLK_DP")
	)
	(segment
		(start 78.145386 -47.000668)
		(end 78.234032 -47.089314)
		(width 0.08636)
		(layer "In2.Cu")
		(net "M_BMC_DDR4_MCLK_DP")
	)
	(arc
		(start 67.346068 -45.593508)
		(mid 67.324746 -45.70061)
		(end 67.264026 -45.791374)
		(width 0.08636)
		(layer "In2.Cu")
		(net "M_BMC_DDR4_MCLK_DP")
	)
	(arc
		(start 77.96022 -46.92396)
		(mid 78.060435 -46.943894)
		(end 78.145386 -47.000668)
		(width 0.08636)
		(layer "In2.Cu")
		(net "M_BMC_DDR4_MCLK_DP")
	)
	(arc
		(start 75.979274 -45.3644)
		(mid 76.007345 -45.34558)
		(end 76.040488 -45.339)
		(width 0.08636)
		(layer "In2.Cu")
		(net "M_BMC_DDR4_MCLK_DP")
	)
	(arc
		(start 67.235324 -45.02785)
		(mid 67.317264 -45.150577)
		(end 67.346068 -45.295312)
		(width 0.08636)
		(layer "In2.Cu")
		(net "M_BMC_DDR4_MCLK_DP")
	)
	(arc
		(start 70.143624 -47.882048)
		(mid 70.23888 -47.910912)
		(end 70.337934 -47.920656)
		(width 0.08636)
		(layer "In2.Cu")
		(net "M_BMC_DDR4_MCLK_DP")
	)
	(arc
		(start 67.183 -45.8724)
		(mid 67.154929 -45.89122)
		(end 67.121786 -45.8978)
		(width 0.08636)
		(layer "In2.Cu")
		(net "M_BMC_DDR4_MCLK_DP")
	)
	(arc
		(start 66.890392 -47.371)
		(mid 66.918463 -47.35218)
		(end 66.951606 -47.3456)
		(width 0.08636)
		(layer "In2.Cu")
		(net "M_BMC_DDR4_MCLK_DP")
	)
	(arc
		(start 65.488566 -45.8978)
		(mid 65.294066 -45.936489)
		(end 65.129156 -46.046644)
		(width 0.08636)
		(layer "In2.Cu")
		(net "M_BMC_DDR4_MCLK_DP")
	)
	(arc
		(start 64.88938 -47.558198)
		(mid 65.064431 -47.980809)
		(end 65.487042 -48.15586)
		(width 0.08636)
		(layer "In2.Cu")
		(net "M_BMC_DDR4_MCLK_DP")
	)
	(arc
		(start 76.271374 -45.339)
		(mid 76.304505 -45.345608)
		(end 76.332588 -45.3644)
		(width 0.08636)
		(layer "In2.Cu")
		(net "M_BMC_DDR4_MCLK_DP")
	)
	(arc
		(start 68.83146 -47.3456)
		(mid 68.848305 -47.347411)
		(end 68.86448 -47.352458)
		(width 0.08636)
		(layer "In2.Cu")
		(net "M_BMC_DDR4_MCLK_DP")
	)
	(arc
		(start 76.40574 -46.056042)
		(mid 76.466789 -46.362576)
		(end 76.640436 -46.622462)
		(width 0.08636)
		(layer "In2.Cu")
		(net "M_BMC_DDR4_MCLK_DP")
	)
	(arc
		(start 75.753976 -47.687484)
		(mid 75.86789 -47.51686)
		(end 75.9079 -47.315628)
		(width 0.08636)
		(layer "In2.Cu")
		(net "M_BMC_DDR4_MCLK_DP")
	)
	(arc
		(start 76.38034 -45.412152)
		(mid 76.39916 -45.440223)
		(end 76.40574 -45.473366)
		(width 0.08636)
		(layer "In2.Cu")
		(net "M_BMC_DDR4_MCLK_DP")
	)
	(arc
		(start 75.310238 -47.920656)
		(mid 75.504738 -47.881967)
		(end 75.669648 -47.771812)
		(width 0.08636)
		(layer "In2.Cu")
		(net "M_BMC_DDR4_MCLK_DP")
	)
	(arc
		(start 76.725018 -46.707044)
		(mid 76.964922 -46.867563)
		(end 77.248004 -46.92396)
		(width 0.08636)
		(layer "In2.Cu")
		(net "M_BMC_DDR4_MCLK_DP")
	)
	(arc
		(start 65.038224 -46.137322)
		(mid 64.927994 -46.302338)
		(end 64.88938 -46.496986)
		(width 0.08636)
		(layer "In2.Cu")
		(net "M_BMC_DDR4_MCLK_DP")
	)
	(arc
		(start 65.795906 -48.15586)
		(mid 66.082136 -48.09889)
		(end 66.324734 -47.936658)
		(width 0.08636)
		(layer "In2.Cu")
		(net "M_BMC_DDR4_MCLK_DP")
	)
	(arc
		(start 75.9079 -45.471588)
		(mid 75.914508 -45.438457)
		(end 75.9333 -45.410374)
		(width 0.08636)
		(layer "In2.Cu")
		(net "M_BMC_DDR4_MCLK_DP")
	)
	(segment
		(start 67.747388 -45.588174)
		(end 67.747388 -45.328586)
		(width 0.1016)
		(layer "F.Cu")
		(net "M_BMC_DDR4_MCLK_DN")
	)
	(segment
		(start 78.65237 -46.707552)
		(end 78.270608 -46.32579)
		(width 0.1016)
		(layer "F.Cu")
		(net "M_BMC_DDR4_MCLK_DN")
	)
	(segment
		(start 64.894968 -46.571154)
		(end 66.66103 -46.571154)
		(width 0.1016)
		(layer "F.Cu")
		(net "M_BMC_DDR4_MCLK_DN")
	)
	(segment
		(start 67.19697 -46.349158)
		(end 67.598544 -45.947584)
		(width 0.1016)
		(layer "F.Cu")
		(net "M_BMC_DDR4_MCLK_DN")
	)
	(segment
		(start 67.867276 -45.039026)
		(end 68.001388 -44.904914)
		(width 0.1016)
		(layer "F.Cu")
		(net "M_BMC_DDR4_MCLK_DN")
	)
	(via
		(at 68.001388 -44.904914)
		(size 0.4572)
		(drill 0.254)
		(layers "F.Cu" "B.Cu")
		(net "M_BMC_DDR4_MCLK_DN")
	)
	(via
		(at 78.270608 -46.32579)
		(size 0.4572)
		(drill 0.254)
		(layers "F.Cu" "B.Cu")
		(net "M_BMC_DDR4_MCLK_DN")
	)
	(arc
		(start 66.66103 -46.571154)
		(mid 66.95108 -46.51346)
		(end 67.19697 -46.349158)
		(width 0.1016)
		(layer "F.Cu")
		(net "M_BMC_DDR4_MCLK_DN")
	)
	(arc
		(start 67.747388 -45.328586)
		(mid 67.77854 -45.171883)
		(end 67.867276 -45.039026)
		(width 0.1016)
		(layer "F.Cu")
		(net "M_BMC_DDR4_MCLK_DN")
	)
	(arc
		(start 67.598544 -45.947584)
		(mid 67.708726 -45.782685)
		(end 67.747388 -45.588174)
		(width 0.1016)
		(layer "F.Cu")
		(net "M_BMC_DDR4_MCLK_DN")
	)
	(segment
		(start 77.684884 -46.500796)
		(end 78.078076 -46.500796)
		(width 0.1016)
		(layer "B.Cu")
		(net "M_BMC_DDR4_MCLK_DN")
	)
	(segment
		(start 77.382878 -46.19879)
		(end 77.684884 -46.500796)
		(width 0.1016)
		(layer "B.Cu")
		(net "M_BMC_DDR4_MCLK_DN")
	)
	(segment
		(start 78.078076 -46.500796)
		(end 78.270608 -46.32579)
		(width 0.1016)
		(layer "B.Cu")
		(net "M_BMC_DDR4_MCLK_DN")
	)
	(segment
		(start 66.46418 -46.445932)
		(end 66.36639 -46.543722)
		(width 0.08636)
		(layer "In2.Cu")
		(net "M_BMC_DDR4_MCLK_DN")
	)
	(segment
		(start 66.159888 -46.62932)
		(end 66.142616 -46.62932)
		(width 0.08636)
		(layer "In2.Cu")
		(net "M_BMC_DDR4_MCLK_DN")
	)
	(segment
		(start 69.96049 -47.107348)
		(end 70.03542 -47.288196)
		(width 0.08636)
		(layer "In2.Cu")
		(net "M_BMC_DDR4_MCLK_DN")
	)
	(segment
		(start 68.317618 -46.699678)
		(end 68.415408 -46.797468)
		(width 0.08636)
		(layer "In2.Cu")
		(net "M_BMC_DDR4_MCLK_DN")
	)
	(segment
		(start 65.427352 -46.34484)
		(end 65.336166 -46.435772)
		(width 0.08636)
		(layer "In2.Cu")
		(net "M_BMC_DDR4_MCLK_DN")
	)
	(segment
		(start 67.767708 -45.295312)
		(end 67.767708 -45.593762)
		(width 0.08636)
		(layer "In2.Cu")
		(net "M_BMC_DDR4_MCLK_DN")
	)
	(segment
		(start 76.040488 -44.91736)
		(end 76.271374 -44.91736)
		(width 0.08636)
		(layer "In2.Cu")
		(net "M_BMC_DDR4_MCLK_DN")
	)
	(segment
		(start 75.635104 -45.112178)
		(end 75.681078 -45.066204)
		(width 0.08636)
		(layer "In2.Cu")
		(net "M_BMC_DDR4_MCLK_DN")
	)
	(segment
		(start 68.001388 -44.904914)
		(end 67.878452 -45.02785)
		(width 0.08636)
		(layer "In2.Cu")
		(net "M_BMC_DDR4_MCLK_DN")
	)
	(segment
		(start 67.789552 -46.797468)
		(end 67.887342 -46.699678)
		(width 0.08636)
		(layer "In2.Cu")
		(net "M_BMC_DDR4_MCLK_DN")
	)
	(segment
		(start 66.951606 -46.92396)
		(end 67.48399 -46.92396)
		(width 0.08636)
		(layer "In2.Cu")
		(net "M_BMC_DDR4_MCLK_DN")
	)
	(segment
		(start 68.72097 -46.92396)
		(end 68.83146 -46.92396)
		(width 0.08636)
		(layer "In2.Cu")
		(net "M_BMC_DDR4_MCLK_DN")
	)
	(segment
		(start 72.236838 -47.274734)
		(end 72.334628 -47.372524)
		(width 0.08636)
		(layer "In2.Cu")
		(net "M_BMC_DDR4_MCLK_DN")
	)
	(segment
		(start 76.938632 -46.324266)
		(end 77.023468 -46.409102)
		(width 0.08636)
		(layer "In2.Cu")
		(net "M_BMC_DDR4_MCLK_DN")
	)
	(segment
		(start 70.193408 -47.446184)
		(end 70.305168 -47.492412)
		(width 0.08636)
		(layer "In2.Cu")
		(net "M_BMC_DDR4_MCLK_DN")
	)
	(segment
		(start 69.786246 -46.941994)
		(end 69.802756 -46.948852)
		(width 0.08636)
		(layer "In2.Cu")
		(net "M_BMC_DDR4_MCLK_DN")
	)
	(segment
		(start 76.630784 -45.066204)
		(end 76.678536 -45.113702)
		(width 0.08636)
		(layer "In2.Cu")
		(net "M_BMC_DDR4_MCLK_DN")
	)
	(segment
		(start 77.248258 -46.50232)
		(end 77.977746 -46.50232)
		(width 0.08636)
		(layer "In2.Cu")
		(net "M_BMC_DDR4_MCLK_DN")
	)
	(segment
		(start 72.64019 -47.499016)
		(end 75.310238 -47.499016)
		(width 0.08636)
		(layer "In2.Cu")
		(net "M_BMC_DDR4_MCLK_DN")
	)
	(segment
		(start 71.708772 -47.372524)
		(end 71.806562 -47.274734)
		(width 0.08636)
		(layer "In2.Cu")
		(net "M_BMC_DDR4_MCLK_DN")
	)
	(segment
		(start 65.936114 -46.543722)
		(end 65.79743 -46.405038)
		(width 0.08636)
		(layer "In2.Cu")
		(net "M_BMC_DDR4_MCLK_DN")
	)
	(segment
		(start 78.176374 -46.420024)
		(end 78.270608 -46.32579)
		(width 0.08636)
		(layer "In2.Cu")
		(net "M_BMC_DDR4_MCLK_DN")
	)
	(segment
		(start 69.02577 -46.962568)
		(end 69.108828 -46.997112)
		(width 0.08636)
		(layer "In2.Cu")
		(net "M_BMC_DDR4_MCLK_DN")
	)
	(segment
		(start 68.093844 -46.61408)
		(end 68.111116 -46.61408)
		(width 0.08636)
		(layer "In2.Cu")
		(net "M_BMC_DDR4_MCLK_DN")
	)
	(segment
		(start 66.026284 -47.638462)
		(end 66.591942 -47.072804)
		(width 0.08636)
		(layer "In2.Cu")
		(net "M_BMC_DDR4_MCLK_DN")
	)
	(segment
		(start 67.121786 -46.31944)
		(end 66.769742 -46.31944)
		(width 0.08636)
		(layer "In2.Cu")
		(net "M_BMC_DDR4_MCLK_DN")
	)
	(segment
		(start 65.487042 -47.73422)
		(end 65.795906 -47.73422)
		(width 0.08636)
		(layer "In2.Cu")
		(net "M_BMC_DDR4_MCLK_DN")
	)
	(segment
		(start 65.311274 -46.496732)
		(end 65.31102 -46.496732)
		(width 0.08636)
		(layer "In2.Cu")
		(net "M_BMC_DDR4_MCLK_DN")
	)
	(segment
		(start 76.82738 -45.473366)
		(end 76.82738 -46.055788)
		(width 0.08636)
		(layer "In2.Cu")
		(net "M_BMC_DDR4_MCLK_DN")
	)
	(segment
		(start 72.013064 -47.189136)
		(end 72.030336 -47.189136)
		(width 0.08636)
		(layer "In2.Cu")
		(net "M_BMC_DDR4_MCLK_DN")
	)
	(segment
		(start 67.562222 -46.08957)
		(end 67.481196 -46.170596)
		(width 0.08636)
		(layer "In2.Cu")
		(net "M_BMC_DDR4_MCLK_DN")
	)
	(segment
		(start 65.590928 -46.31944)
		(end 65.488566 -46.31944)
		(width 0.08636)
		(layer "In2.Cu")
		(net "M_BMC_DDR4_MCLK_DN")
	)
	(segment
		(start 75.371452 -47.473616)
		(end 75.45578 -47.389288)
		(width 0.08636)
		(layer "In2.Cu")
		(net "M_BMC_DDR4_MCLK_DN")
	)
	(segment
		(start 65.31102 -46.496732)
		(end 65.31102 -47.558198)
		(width 0.08636)
		(layer "In2.Cu")
		(net "M_BMC_DDR4_MCLK_DN")
	)
	(segment
		(start 75.48626 -47.315628)
		(end 75.48626 -45.471588)
		(width 0.08636)
		(layer "In2.Cu")
		(net "M_BMC_DDR4_MCLK_DN")
	)
	(segment
		(start 70.338188 -47.499016)
		(end 71.40321 -47.499016)
		(width 0.08636)
		(layer "In2.Cu")
		(net "M_BMC_DDR4_MCLK_DN")
	)
	(segment
		(start 69.429884 -46.996858)
		(end 69.562472 -46.941994)
		(width 0.08636)
		(layer "In2.Cu")
		(net "M_BMC_DDR4_MCLK_DN")
	)
	(arc
		(start 75.310238 -47.499016)
		(mid 75.343369 -47.492408)
		(end 75.371452 -47.473616)
		(width 0.08636)
		(layer "In2.Cu")
		(net "M_BMC_DDR4_MCLK_DN")
	)
	(arc
		(start 67.887342 -46.699678)
		(mid 67.982072 -46.636318)
		(end 68.093844 -46.61408)
		(width 0.08636)
		(layer "In2.Cu")
		(net "M_BMC_DDR4_MCLK_DN")
	)
	(arc
		(start 71.806562 -47.274734)
		(mid 71.901292 -47.211374)
		(end 72.013064 -47.189136)
		(width 0.08636)
		(layer "In2.Cu")
		(net "M_BMC_DDR4_MCLK_DN")
	)
	(arc
		(start 77.023468 -46.409102)
		(mid 77.126588 -46.478068)
		(end 77.248258 -46.50232)
		(width 0.08636)
		(layer "In2.Cu")
		(net "M_BMC_DDR4_MCLK_DN")
	)
	(arc
		(start 68.83146 -46.92396)
		(mid 68.930514 -46.933706)
		(end 69.02577 -46.962568)
		(width 0.08636)
		(layer "In2.Cu")
		(net "M_BMC_DDR4_MCLK_DN")
	)
	(arc
		(start 66.142616 -46.62932)
		(mid 66.030848 -46.60707)
		(end 65.936114 -46.543722)
		(width 0.08636)
		(layer "In2.Cu")
		(net "M_BMC_DDR4_MCLK_DN")
	)
	(arc
		(start 72.334628 -47.372524)
		(mid 72.474835 -47.466144)
		(end 72.64019 -47.499016)
		(width 0.08636)
		(layer "In2.Cu")
		(net "M_BMC_DDR4_MCLK_DN")
	)
	(arc
		(start 68.415408 -46.797468)
		(mid 68.555615 -46.891088)
		(end 68.72097 -46.92396)
		(width 0.08636)
		(layer "In2.Cu")
		(net "M_BMC_DDR4_MCLK_DN")
	)
	(arc
		(start 71.40321 -47.499016)
		(mid 71.568564 -47.466143)
		(end 71.708772 -47.372524)
		(width 0.08636)
		(layer "In2.Cu")
		(net "M_BMC_DDR4_MCLK_DN")
	)
	(arc
		(start 68.111116 -46.61408)
		(mid 68.222884 -46.63633)
		(end 68.317618 -46.699678)
		(width 0.08636)
		(layer "In2.Cu")
		(net "M_BMC_DDR4_MCLK_DN")
	)
	(arc
		(start 67.767708 -45.593762)
		(mid 67.714242 -45.862082)
		(end 67.562222 -46.08957)
		(width 0.08636)
		(layer "In2.Cu")
		(net "M_BMC_DDR4_MCLK_DN")
	)
	(arc
		(start 65.31102 -47.558198)
		(mid 65.362576 -47.682664)
		(end 65.487042 -47.73422)
		(width 0.08636)
		(layer "In2.Cu")
		(net "M_BMC_DDR4_MCLK_DN")
	)
	(arc
		(start 67.878452 -45.02785)
		(mid 67.796512 -45.150577)
		(end 67.767708 -45.295312)
		(width 0.08636)
		(layer "In2.Cu")
		(net "M_BMC_DDR4_MCLK_DN")
	)
	(arc
		(start 65.795906 -47.73422)
		(mid 65.920631 -47.709281)
		(end 66.026284 -47.638462)
		(width 0.08636)
		(layer "In2.Cu")
		(net "M_BMC_DDR4_MCLK_DN")
	)
	(arc
		(start 67.481196 -46.170596)
		(mid 67.316297 -46.280778)
		(end 67.121786 -46.31944)
		(width 0.08636)
		(layer "In2.Cu")
		(net "M_BMC_DDR4_MCLK_DN")
	)
	(arc
		(start 66.591942 -47.072804)
		(mid 66.756958 -46.962574)
		(end 66.951606 -46.92396)
		(width 0.08636)
		(layer "In2.Cu")
		(net "M_BMC_DDR4_MCLK_DN")
	)
	(arc
		(start 70.03542 -47.288196)
		(mid 70.098685 -47.382919)
		(end 70.193408 -47.446184)
		(width 0.08636)
		(layer "In2.Cu")
		(net "M_BMC_DDR4_MCLK_DN")
	)
	(arc
		(start 69.108828 -46.997112)
		(mid 69.269385 -47.028922)
		(end 69.429884 -46.996858)
		(width 0.08636)
		(layer "In2.Cu")
		(net "M_BMC_DDR4_MCLK_DN")
	)
	(arc
		(start 76.82738 -46.055788)
		(mid 76.8563 -46.20109)
		(end 76.938632 -46.324266)
		(width 0.08636)
		(layer "In2.Cu")
		(net "M_BMC_DDR4_MCLK_DN")
	)
	(arc
		(start 77.977746 -46.50232)
		(mid 78.085251 -46.480936)
		(end 78.176374 -46.420024)
		(width 0.08636)
		(layer "In2.Cu")
		(net "M_BMC_DDR4_MCLK_DN")
	)
	(arc
		(start 76.271374 -44.91736)
		(mid 76.465874 -44.956049)
		(end 76.630784 -45.066204)
		(width 0.08636)
		(layer "In2.Cu")
		(net "M_BMC_DDR4_MCLK_DN")
	)
	(arc
		(start 76.678536 -45.113702)
		(mid 76.788766 -45.278718)
		(end 76.82738 -45.473366)
		(width 0.08636)
		(layer "In2.Cu")
		(net "M_BMC_DDR4_MCLK_DN")
	)
	(arc
		(start 65.488566 -46.31944)
		(mid 65.455435 -46.326048)
		(end 65.427352 -46.34484)
		(width 0.08636)
		(layer "In2.Cu")
		(net "M_BMC_DDR4_MCLK_DN")
	)
	(arc
		(start 75.48626 -45.471588)
		(mid 75.524949 -45.277088)
		(end 75.635104 -45.112178)
		(width 0.08636)
		(layer "In2.Cu")
		(net "M_BMC_DDR4_MCLK_DN")
	)
	(arc
		(start 67.48399 -46.92396)
		(mid 67.649344 -46.891087)
		(end 67.789552 -46.797468)
		(width 0.08636)
		(layer "In2.Cu")
		(net "M_BMC_DDR4_MCLK_DN")
	)
	(arc
		(start 72.030336 -47.189136)
		(mid 72.142104 -47.211386)
		(end 72.236838 -47.274734)
		(width 0.08636)
		(layer "In2.Cu")
		(net "M_BMC_DDR4_MCLK_DN")
	)
	(arc
		(start 69.802756 -46.948852)
		(mid 69.897311 -47.01249)
		(end 69.96049 -47.107348)
		(width 0.08636)
		(layer "In2.Cu")
		(net "M_BMC_DDR4_MCLK_DN")
	)
	(arc
		(start 75.45578 -47.389288)
		(mid 75.478361 -47.355493)
		(end 75.48626 -47.315628)
		(width 0.08636)
		(layer "In2.Cu")
		(net "M_BMC_DDR4_MCLK_DN")
	)
	(arc
		(start 70.305168 -47.492412)
		(mid 70.321355 -47.49732)
		(end 70.338188 -47.499016)
		(width 0.08636)
		(layer "In2.Cu")
		(net "M_BMC_DDR4_MCLK_DN")
	)
	(arc
		(start 69.562472 -46.941994)
		(mid 69.674369 -46.919719)
		(end 69.786246 -46.941994)
		(width 0.08636)
		(layer "In2.Cu")
		(net "M_BMC_DDR4_MCLK_DN")
	)
	(arc
		(start 75.681078 -45.066204)
		(mid 75.845977 -44.956022)
		(end 76.040488 -44.91736)
		(width 0.08636)
		(layer "In2.Cu")
		(net "M_BMC_DDR4_MCLK_DN")
	)
	(arc
		(start 66.36639 -46.543722)
		(mid 66.27166 -46.607082)
		(end 66.159888 -46.62932)
		(width 0.08636)
		(layer "In2.Cu")
		(net "M_BMC_DDR4_MCLK_DN")
	)
	(arc
		(start 65.79743 -46.405038)
		(mid 65.7027 -46.341678)
		(end 65.590928 -46.31944)
		(width 0.08636)
		(layer "In2.Cu")
		(net "M_BMC_DDR4_MCLK_DN")
	)
	(arc
		(start 66.769742 -46.31944)
		(mid 66.604388 -46.352313)
		(end 66.46418 -46.445932)
		(width 0.08636)
		(layer "In2.Cu")
		(net "M_BMC_DDR4_MCLK_DN")
	)
	(arc
		(start 65.336166 -46.435772)
		(mid 65.317668 -46.463784)
		(end 65.311274 -46.496732)
		(width 0.08636)
		(layer "In2.Cu")
		(net "M_BMC_DDR4_MCLK_DN")
	)
	(segment
		(start 76.582778 -46.19879)
		(end 76.582778 -47.21479)
		(width 0.381)
		(layer "B.Cu")
		(net "M_BMC_DDR4_MCLK_C")
	)
	(segment
		(start 76.582778 -48.23079)
		(end 77.598778 -48.23079)
		(width 0.381)
		(layer "B.Cu")
		(net "M_BMC_DDR4_MCLK_C")
	)
	(segment
		(start 76.582778 -47.21479)
		(end 76.582778 -48.23079)
		(width 0.381)
		(layer "B.Cu")
		(net "M_BMC_DDR4_MCLK_C")
	)
	(segment
		(start 73.470516 -46.32579)
		(end 74.166476 -46.32579)
		(width 0.11684)
		(layer "F.Cu")
		(net "M_BMC_DDR4_MCKE")
	)
	(segment
		(start 61.695076 -47.371254)
		(end 62.0903 -46.97603)
		(width 0.11684)
		(layer "F.Cu")
		(net "M_BMC_DDR4_MCKE")
	)
	(segment
		(start 74.268076 -46.42739)
		(end 74.268076 -46.605952)
		(width 0.11684)
		(layer "F.Cu")
		(net "M_BMC_DDR4_MCKE")
	)
	(segment
		(start 74.166476 -46.707552)
		(end 73.852278 -46.707552)
		(width 0.11684)
		(layer "F.Cu")
		(net "M_BMC_DDR4_MCKE")
	)
	(via
		(at 62.0903 -46.97603)
		(size 0.4572)
		(drill 0.254)
		(layers "F.Cu" "B.Cu")
		(net "M_BMC_DDR4_MCKE")
	)
	(via
		(at 73.470516 -46.32579)
		(size 0.4572)
		(drill 0.254)
		(layers "F.Cu" "B.Cu")
		(net "M_BMC_DDR4_MCKE")
	)
	(arc
		(start 74.268076 -46.605952)
		(mid 74.238318 -46.677794)
		(end 74.166476 -46.707552)
		(width 0.11684)
		(layer "F.Cu")
		(net "M_BMC_DDR4_MCKE")
	)
	(arc
		(start 74.166476 -46.32579)
		(mid 74.238318 -46.355548)
		(end 74.268076 -46.42739)
		(width 0.11684)
		(layer "F.Cu")
		(net "M_BMC_DDR4_MCKE")
	)
	(segment
		(start 72.45985 -46.706282)
		(end 71.858378 -46.706282)
		(width 0.11684)
		(layer "B.Cu")
		(net "M_BMC_DDR4_MCKE")
	)
	(segment
		(start 73.470516 -46.32579)
		(end 73.06818 -46.728126)
		(width 0.11684)
		(layer "B.Cu")
		(net "M_BMC_DDR4_MCKE")
	)
	(segment
		(start 73.06818 -46.728126)
		(end 72.481694 -46.728126)
		(width 0.11684)
		(layer "B.Cu")
		(net "M_BMC_DDR4_MCKE")
	)
	(segment
		(start 70.832472 -46.706282)
		(end 71.858378 -46.706282)
		(width 0.11684)
		(layer "B.Cu")
		(net "M_BMC_DDR4_MCKE")
	)
	(segment
		(start 72.481694 -46.728126)
		(end 72.45985 -46.706282)
		(width 0.11684)
		(layer "B.Cu")
		(net "M_BMC_DDR4_MCKE")
	)
	(segment
		(start 60.869576 -46.834044)
		(end 60.869576 -46.190408)
		(width 0.08382)
		(layer "In2.Cu")
		(net "M_BMC_DDR4_MCKE")
	)
	(segment
		(start 60.22594 -47.377604)
		(end 60.22594 -47.006764)
		(width 0.08382)
		(layer "In2.Cu")
		(net "M_BMC_DDR4_MCKE")
	)
	(segment
		(start 68.829174 -44.357544)
		(end 66.5861 -44.357544)
		(width 0.08382)
		(layer "In2.Cu")
		(net "M_BMC_DDR4_MCKE")
	)
	(segment
		(start 63.302642 -47.455074)
		(end 63.302642 -48.750474)
		(width 0.08382)
		(layer "In2.Cu")
		(net "M_BMC_DDR4_MCKE")
	)
	(segment
		(start 60.3123 -46.920404)
		(end 60.783216 -46.920404)
		(width 0.08382)
		(layer "In2.Cu")
		(net "M_BMC_DDR4_MCKE")
	)
	(segment
		(start 61.060584 -45.9994)
		(end 61.40196 -45.9994)
		(width 0.08382)
		(layer "In2.Cu")
		(net "M_BMC_DDR4_MCKE")
	)
	(segment
		(start 63.072772 -48.980344)
		(end 62.65418 -48.980344)
		(width 0.08382)
		(layer "In2.Cu")
		(net "M_BMC_DDR4_MCKE")
	)
	(segment
		(start 62.502288 -48.828452)
		(end 62.502288 -47.483014)
		(width 0.08382)
		(layer "In2.Cu")
		(net "M_BMC_DDR4_MCKE")
	)
	(segment
		(start 63.934086 -47.368714)
		(end 63.389002 -47.368714)
		(width 0.08382)
		(layer "In2.Cu")
		(net "M_BMC_DDR4_MCKE")
	)
	(segment
		(start 65.889632 -45.386752)
		(end 65.247266 -45.386752)
		(width 0.08382)
		(layer "In2.Cu")
		(net "M_BMC_DDR4_MCKE")
	)
	(segment
		(start 70.989698 -46.246796)
		(end 69.564758 -44.821856)
		(width 0.08382)
		(layer "In2.Cu")
		(net "M_BMC_DDR4_MCKE")
	)
	(segment
		(start 61.513974 -46.111414)
		(end 61.513974 -46.484286)
		(width 0.08382)
		(layer "In2.Cu")
		(net "M_BMC_DDR4_MCKE")
	)
	(segment
		(start 60.869576 -48.890936)
		(end 60.869576 -48.637444)
		(width 0.08382)
		(layer "In2.Cu")
		(net "M_BMC_DDR4_MCKE")
	)
	(segment
		(start 61.613034 -46.583346)
		(end 62.00394 -46.583346)
		(width 0.08382)
		(layer "In2.Cu")
		(net "M_BMC_DDR4_MCKE")
	)
	(segment
		(start 60.783216 -47.463964)
		(end 60.3123 -47.463964)
		(width 0.08382)
		(layer "In2.Cu")
		(net "M_BMC_DDR4_MCKE")
	)
	(segment
		(start 73.470516 -46.32579)
		(end 73.141586 -46.32579)
		(width 0.08382)
		(layer "In2.Cu")
		(net "M_BMC_DDR4_MCKE")
	)
	(segment
		(start 62.415928 -47.396654)
		(end 61.84392 -47.396654)
		(width 0.08382)
		(layer "In2.Cu")
		(net "M_BMC_DDR4_MCKE")
	)
	(segment
		(start 66.392806 -44.550838)
		(end 66.392806 -44.883578)
		(width 0.08382)
		(layer "In2.Cu")
		(net "M_BMC_DDR4_MCKE")
	)
	(segment
		(start 73.051162 -46.235366)
		(end 73.051162 -46.097952)
		(width 0.08382)
		(layer "In2.Cu")
		(net "M_BMC_DDR4_MCKE")
	)
	(segment
		(start 61.6712 -47.569374)
		(end 61.6712 -48.846994)
		(width 0.08382)
		(layer "In2.Cu")
		(net "M_BMC_DDR4_MCKE")
	)
	(segment
		(start 60.783216 -48.551084)
		(end 60.294774 -48.551084)
		(width 0.08382)
		(layer "In2.Cu")
		(net "M_BMC_DDR4_MCKE")
	)
	(segment
		(start 60.208414 -48.464724)
		(end 60.208414 -48.093884)
		(width 0.08382)
		(layer "In2.Cu")
		(net "M_BMC_DDR4_MCKE")
	)
	(segment
		(start 72.758808 -45.912278)
		(end 72.526652 -45.912278)
		(width 0.08382)
		(layer "In2.Cu")
		(net "M_BMC_DDR4_MCKE")
	)
	(segment
		(start 64.91478 -45.52442)
		(end 64.755268 -45.683932)
		(width 0.08382)
		(layer "In2.Cu")
		(net "M_BMC_DDR4_MCKE")
	)
	(segment
		(start 61.540898 -48.977296)
		(end 60.955936 -48.977296)
		(width 0.08382)
		(layer "In2.Cu")
		(net "M_BMC_DDR4_MCKE")
	)
	(segment
		(start 64.422782 -45.8216)
		(end 64.2366 -45.8216)
		(width 0.08382)
		(layer "In2.Cu")
		(net "M_BMC_DDR4_MCKE")
	)
	(segment
		(start 71.99503 -46.279054)
		(end 71.067422 -46.279054)
		(width 0.08382)
		(layer "In2.Cu")
		(net "M_BMC_DDR4_MCKE")
	)
	(segment
		(start 62.0903 -46.669706)
		(end 62.0903 -46.97603)
		(width 0.08382)
		(layer "In2.Cu")
		(net "M_BMC_DDR4_MCKE")
	)
	(segment
		(start 64.1096 -45.9486)
		(end 64.1096 -47.1932)
		(width 0.08382)
		(layer "In2.Cu")
		(net "M_BMC_DDR4_MCKE")
	)
	(segment
		(start 69.128132 -44.594526)
		(end 68.934838 -44.401232)
		(width 0.08382)
		(layer "In2.Cu")
		(net "M_BMC_DDR4_MCKE")
	)
	(segment
		(start 69.407278 -44.733464)
		(end 69.35343 -44.720764)
		(width 0.08382)
		(layer "In2.Cu")
		(net "M_BMC_DDR4_MCKE")
	)
	(segment
		(start 60.294774 -48.007524)
		(end 60.783216 -48.007524)
		(width 0.08382)
		(layer "In2.Cu")
		(net "M_BMC_DDR4_MCKE")
	)
	(segment
		(start 60.869576 -47.921164)
		(end 60.869576 -47.550324)
		(width 0.08382)
		(layer "In2.Cu")
		(net "M_BMC_DDR4_MCKE")
	)
	(arc
		(start 64.2366 -45.8216)
		(mid 64.146797 -45.858797)
		(end 64.1096 -45.9486)
		(width 0.08382)
		(layer "In2.Cu")
		(net "M_BMC_DDR4_MCKE")
	)
	(arc
		(start 71.067422 -46.279054)
		(mid 71.025334 -46.270682)
		(end 70.989698 -46.246796)
		(width 0.08382)
		(layer "In2.Cu")
		(net "M_BMC_DDR4_MCKE")
	)
	(arc
		(start 69.35343 -44.720764)
		(mid 69.232072 -44.673193)
		(end 69.128132 -44.594526)
		(width 0.08382)
		(layer "In2.Cu")
		(net "M_BMC_DDR4_MCKE")
	)
	(arc
		(start 60.869576 -47.550324)
		(mid 60.844282 -47.489258)
		(end 60.783216 -47.463964)
		(width 0.08382)
		(layer "In2.Cu")
		(net "M_BMC_DDR4_MCKE")
	)
	(arc
		(start 61.6712 -48.846994)
		(mid 61.633035 -48.939131)
		(end 61.540898 -48.977296)
		(width 0.08382)
		(layer "In2.Cu")
		(net "M_BMC_DDR4_MCKE")
	)
	(arc
		(start 62.502288 -47.483014)
		(mid 62.476994 -47.421948)
		(end 62.415928 -47.396654)
		(width 0.08382)
		(layer "In2.Cu")
		(net "M_BMC_DDR4_MCKE")
	)
	(arc
		(start 61.513974 -46.484286)
		(mid 61.542988 -46.554332)
		(end 61.613034 -46.583346)
		(width 0.08382)
		(layer "In2.Cu")
		(net "M_BMC_DDR4_MCKE")
	)
	(arc
		(start 72.087232 -46.259496)
		(mid 72.042171 -46.274174)
		(end 71.99503 -46.279054)
		(width 0.08382)
		(layer "In2.Cu")
		(net "M_BMC_DDR4_MCKE")
	)
	(arc
		(start 72.990964 -45.983652)
		(mid 72.88027 -45.930432)
		(end 72.758808 -45.912278)
		(width 0.08382)
		(layer "In2.Cu")
		(net "M_BMC_DDR4_MCKE")
	)
	(arc
		(start 62.65418 -48.980344)
		(mid 62.546776 -48.935856)
		(end 62.502288 -48.828452)
		(width 0.08382)
		(layer "In2.Cu")
		(net "M_BMC_DDR4_MCKE")
	)
	(arc
		(start 64.755268 -45.683932)
		(mid 64.602708 -45.785806)
		(end 64.422782 -45.8216)
		(width 0.08382)
		(layer "In2.Cu")
		(net "M_BMC_DDR4_MCKE")
	)
	(arc
		(start 66.5861 -44.357544)
		(mid 66.449421 -44.414159)
		(end 66.392806 -44.550838)
		(width 0.08382)
		(layer "In2.Cu")
		(net "M_BMC_DDR4_MCKE")
	)
	(arc
		(start 60.208414 -48.093884)
		(mid 60.233708 -48.032818)
		(end 60.294774 -48.007524)
		(width 0.08382)
		(layer "In2.Cu")
		(net "M_BMC_DDR4_MCKE")
	)
	(arc
		(start 60.783216 -48.007524)
		(mid 60.844282 -47.98223)
		(end 60.869576 -47.921164)
		(width 0.08382)
		(layer "In2.Cu")
		(net "M_BMC_DDR4_MCKE")
	)
	(arc
		(start 72.526652 -45.912278)
		(mid 72.357088 -45.963236)
		(end 72.243696 -46.099222)
		(width 0.08382)
		(layer "In2.Cu")
		(net "M_BMC_DDR4_MCKE")
	)
	(arc
		(start 60.869576 -46.190408)
		(mid 60.925521 -46.055345)
		(end 61.060584 -45.9994)
		(width 0.08382)
		(layer "In2.Cu")
		(net "M_BMC_DDR4_MCKE")
	)
	(arc
		(start 64.1096 -47.1932)
		(mid 64.058193 -47.317307)
		(end 63.934086 -47.368714)
		(width 0.08382)
		(layer "In2.Cu")
		(net "M_BMC_DDR4_MCKE")
	)
	(arc
		(start 61.84392 -47.396654)
		(mid 61.721789 -47.447243)
		(end 61.6712 -47.569374)
		(width 0.08382)
		(layer "In2.Cu")
		(net "M_BMC_DDR4_MCKE")
	)
	(arc
		(start 60.869576 -48.637444)
		(mid 60.844282 -48.576378)
		(end 60.783216 -48.551084)
		(width 0.08382)
		(layer "In2.Cu")
		(net "M_BMC_DDR4_MCKE")
	)
	(arc
		(start 63.302642 -48.750474)
		(mid 63.235315 -48.913017)
		(end 63.072772 -48.980344)
		(width 0.08382)
		(layer "In2.Cu")
		(net "M_BMC_DDR4_MCKE")
	)
	(arc
		(start 60.22594 -47.006764)
		(mid 60.251234 -46.945698)
		(end 60.3123 -46.920404)
		(width 0.08382)
		(layer "In2.Cu")
		(net "M_BMC_DDR4_MCKE")
	)
	(arc
		(start 60.783216 -46.920404)
		(mid 60.844282 -46.89511)
		(end 60.869576 -46.834044)
		(width 0.08382)
		(layer "In2.Cu")
		(net "M_BMC_DDR4_MCKE")
	)
	(arc
		(start 73.051162 -46.097952)
		(mid 73.035198 -46.033353)
		(end 72.990964 -45.983652)
		(width 0.08382)
		(layer "In2.Cu")
		(net "M_BMC_DDR4_MCKE")
	)
	(arc
		(start 61.40196 -45.9994)
		(mid 61.481166 -46.032208)
		(end 61.513974 -46.111414)
		(width 0.08382)
		(layer "In2.Cu")
		(net "M_BMC_DDR4_MCKE")
	)
	(arc
		(start 69.564758 -44.821856)
		(mid 69.492092 -44.766849)
		(end 69.407278 -44.733464)
		(width 0.08382)
		(layer "In2.Cu")
		(net "M_BMC_DDR4_MCKE")
	)
	(arc
		(start 60.3123 -47.463964)
		(mid 60.251234 -47.43867)
		(end 60.22594 -47.377604)
		(width 0.08382)
		(layer "In2.Cu")
		(net "M_BMC_DDR4_MCKE")
	)
	(arc
		(start 62.00394 -46.583346)
		(mid 62.065006 -46.60864)
		(end 62.0903 -46.669706)
		(width 0.08382)
		(layer "In2.Cu")
		(net "M_BMC_DDR4_MCKE")
	)
	(arc
		(start 73.141586 -46.32579)
		(mid 73.077647 -46.299305)
		(end 73.051162 -46.235366)
		(width 0.08382)
		(layer "In2.Cu")
		(net "M_BMC_DDR4_MCKE")
	)
	(arc
		(start 60.294774 -48.551084)
		(mid 60.233708 -48.52579)
		(end 60.208414 -48.464724)
		(width 0.08382)
		(layer "In2.Cu")
		(net "M_BMC_DDR4_MCKE")
	)
	(arc
		(start 72.243696 -46.099222)
		(mid 72.180606 -46.194147)
		(end 72.087232 -46.259496)
		(width 0.08382)
		(layer "In2.Cu")
		(net "M_BMC_DDR4_MCKE")
	)
	(arc
		(start 63.389002 -47.368714)
		(mid 63.327936 -47.394008)
		(end 63.302642 -47.455074)
		(width 0.08382)
		(layer "In2.Cu")
		(net "M_BMC_DDR4_MCKE")
	)
	(arc
		(start 68.934838 -44.401232)
		(mid 68.886359 -44.368839)
		(end 68.829174 -44.357544)
		(width 0.08382)
		(layer "In2.Cu")
		(net "M_BMC_DDR4_MCKE")
	)
	(arc
		(start 60.955936 -48.977296)
		(mid 60.89487 -48.952002)
		(end 60.869576 -48.890936)
		(width 0.08382)
		(layer "In2.Cu")
		(net "M_BMC_DDR4_MCKE")
	)
	(arc
		(start 65.247266 -45.386752)
		(mid 65.067332 -45.422525)
		(end 64.91478 -45.52442)
		(width 0.08382)
		(layer "In2.Cu")
		(net "M_BMC_DDR4_MCKE")
	)
	(arc
		(start 66.392806 -44.883578)
		(mid 66.24543 -45.239376)
		(end 65.889632 -45.386752)
		(width 0.08382)
		(layer "In2.Cu")
		(net "M_BMC_DDR4_MCKE")
	)
	(segment
		(start 84.107274 -48.237394)
		(end 83.37931 -47.50943)
		(width 0.11684)
		(layer "F.Cu")
		(net "M_BMC_DDR4_MCAS_N")
	)
	(segment
		(start 78.887828 -45.34281)
		(end 78.65237 -45.107352)
		(width 0.11684)
		(layer "F.Cu")
		(net "M_BMC_DDR4_MCAS_N")
	)
	(segment
		(start 81.73593 -46.954948)
		(end 80.403954 -45.622972)
		(width 0.11684)
		(layer "F.Cu")
		(net "M_BMC_DDR4_MCAS_N")
	)
	(segment
		(start 80.116426 -45.503846)
		(end 79.276448 -45.503846)
		(width 0.11684)
		(layer "F.Cu")
		(net "M_BMC_DDR4_MCAS_N")
	)
	(segment
		(start 78.270608 -44.72559)
		(end 78.65237 -45.107352)
		(width 0.11684)
		(layer "F.Cu")
		(net "M_BMC_DDR4_MCAS_N")
	)
	(segment
		(start 83.37931 -47.50943)
		(end 82.824828 -46.954948)
		(width 0.11684)
		(layer "F.Cu")
		(net "M_BMC_DDR4_MCAS_N")
	)
	(segment
		(start 84.17687 -48.237394)
		(end 84.107274 -48.237394)
		(width 0.11684)
		(layer "F.Cu")
		(net "M_BMC_DDR4_MCAS_N")
	)
	(segment
		(start 82.824828 -46.954948)
		(end 81.73593 -46.954948)
		(width 0.11684)
		(layer "F.Cu")
		(net "M_BMC_DDR4_MCAS_N")
	)
	(segment
		(start 62.494922 -45.771308)
		(end 62.890146 -45.376084)
		(width 0.11684)
		(layer "F.Cu")
		(net "M_BMC_DDR4_MCAS_N")
	)
	(segment
		(start 84.8995 -48.237394)
		(end 84.17687 -48.237394)
		(width 0.11684)
		(layer "F.Cu")
		(net "M_BMC_DDR4_MCAS_N")
	)
	(via
		(at 78.270608 -44.72559)
		(size 0.4572)
		(drill 0.254)
		(layers "F.Cu" "B.Cu")
		(net "M_BMC_DDR4_MCAS_N")
	)
	(via
		(at 83.37931 -47.50943)
		(size 0.762)
		(drill 0.381)
		(layers "F.Cu" "B.Cu")
		(net "M_BMC_DDR4_MCAS_N")
	)
	(via
		(at 84.17687 -48.237394)
		(size 0.508)
		(drill 0.254)
		(layers "F.Cu" "B.Cu")
		(net "M_BMC_DDR4_MCAS_N")
	)
	(via
		(at 62.890146 -45.376084)
		(size 0.4572)
		(drill 0.254)
		(layers "F.Cu" "B.Cu")
		(net "M_BMC_DDR4_MCAS_N")
	)
	(arc
		(start 79.276448 -45.503846)
		(mid 79.066118 -45.461991)
		(end 78.887828 -45.34281)
		(width 0.11684)
		(layer "F.Cu")
		(net "M_BMC_DDR4_MCAS_N")
	)
	(arc
		(start 80.403954 -45.622972)
		(mid 80.272035 -45.534827)
		(end 80.116426 -45.503846)
		(width 0.11684)
		(layer "F.Cu")
		(net "M_BMC_DDR4_MCAS_N")
	)
	(segment
		(start 84.8995 -48.504094)
		(end 84.6328 -48.237394)
		(width 0.11684)
		(layer "B.Cu")
		(net "M_BMC_DDR4_MCAS_N")
	)
	(segment
		(start 84.6328 -48.237394)
		(end 84.17687 -48.237394)
		(width 0.11684)
		(layer "B.Cu")
		(net "M_BMC_DDR4_MCAS_N")
	)
	(segment
		(start 78.270608 -44.465494)
		(end 78.270608 -44.72559)
		(width 0.08382)
		(layer "In9.Cu")
		(net "M_BMC_DDR4_MCAS_N")
	)
	(segment
		(start 63.609474 -40.182546)
		(end 64.004952 -40.182546)
		(width 0.08382)
		(layer "In9.Cu")
		(net "M_BMC_DDR4_MCAS_N")
	)
	(segment
		(start 76.482702 -43.050968)
		(end 76.482702 -43.439842)
		(width 0.08382)
		(layer "In9.Cu")
		(net "M_BMC_DDR4_MCAS_N")
	)
	(segment
		(start 64.876934 -40.745156)
		(end 64.876934 -40.276526)
		(width 0.08382)
		(layer "In9.Cu")
		(net "M_BMC_DDR4_MCAS_N")
	)
	(segment
		(start 64.098932 -40.276526)
		(end 64.098932 -40.663622)
		(width 0.08382)
		(layer "In9.Cu")
		(net "M_BMC_DDR4_MCAS_N")
	)
	(segment
		(start 62.49162 -41.46042)
		(end 62.49162 -41.29532)
		(width 0.08382)
		(layer "In9.Cu")
		(net "M_BMC_DDR4_MCAS_N")
	)
	(segment
		(start 77.871066 -43.620182)
		(end 77.871066 -44.026836)
		(width 0.08382)
		(layer "In9.Cu")
		(net "M_BMC_DDR4_MCAS_N")
	)
	(segment
		(start 66.211704 -40.246554)
		(end 74.265028 -40.246554)
		(width 0.08382)
		(layer "In9.Cu")
		(net "M_BMC_DDR4_MCAS_N")
	)
	(segment
		(start 65.746122 -40.204644)
		(end 66.117978 -40.241982)
		(width 0.08382)
		(layer "In9.Cu")
		(net "M_BMC_DDR4_MCAS_N")
	)
	(segment
		(start 64.42329 -40.98798)
		(end 64.63411 -40.98798)
		(width 0.08382)
		(layer "In9.Cu")
		(net "M_BMC_DDR4_MCAS_N")
	)
	(segment
		(start 64.970914 -40.182546)
		(end 65.30467 -40.182546)
		(width 0.08382)
		(layer "In9.Cu")
		(net "M_BMC_DDR4_MCAS_N")
	)
	(segment
		(start 61.675772 -43.925236)
		(end 61.675772 -42.118788)
		(width 0.08382)
		(layer "In9.Cu")
		(net "M_BMC_DDR4_MCAS_N")
	)
	(segment
		(start 62.890146 -45.376084)
		(end 62.667642 -45.15358)
		(width 0.08382)
		(layer "In9.Cu")
		(net "M_BMC_DDR4_MCAS_N")
	)
	(segment
		(start 62.228476 -44.167298)
		(end 61.917834 -44.167298)
		(width 0.08382)
		(layer "In9.Cu")
		(net "M_BMC_DDR4_MCAS_N")
	)
	(segment
		(start 76.634594 -42.375328)
		(end 77.059282 -42.375328)
		(width 0.08382)
		(layer "In9.Cu")
		(net "M_BMC_DDR4_MCAS_N")
	)
	(segment
		(start 62.503558 -44.75734)
		(end 62.503558 -44.44238)
		(width 0.08382)
		(layer "In9.Cu")
		(net "M_BMC_DDR4_MCAS_N")
	)
	(segment
		(start 77.153262 -42.469308)
		(end 77.153262 -42.870628)
		(width 0.08382)
		(layer "In9.Cu")
		(net "M_BMC_DDR4_MCAS_N")
	)
	(segment
		(start 75.203812 -40.635428)
		(end 76.305918 -41.737534)
		(width 0.08382)
		(layer "In9.Cu")
		(net "M_BMC_DDR4_MCAS_N")
	)
	(segment
		(start 63.165482 -40.898318)
		(end 63.1952 -40.8686)
		(width 0.08382)
		(layer "In9.Cu")
		(net "M_BMC_DDR4_MCAS_N")
	)
	(segment
		(start 62.01156 -41.783)
		(end 62.16904 -41.783)
		(width 0.08382)
		(layer "In9.Cu")
		(net "M_BMC_DDR4_MCAS_N")
	)
	(segment
		(start 76.34097 -41.822116)
		(end 76.34097 -42.081704)
		(width 0.08382)
		(layer "In9.Cu")
		(net "M_BMC_DDR4_MCAS_N")
	)
	(segment
		(start 77.059282 -42.964608)
		(end 76.569062 -42.964608)
		(width 0.08382)
		(layer "In9.Cu")
		(net "M_BMC_DDR4_MCAS_N")
	)
	(segment
		(start 62.81674 -40.9702)
		(end 62.992 -40.9702)
		(width 0.08382)
		(layer "In9.Cu")
		(net "M_BMC_DDR4_MCAS_N")
	)
	(segment
		(start 76.569062 -43.526202)
		(end 77.777086 -43.526202)
		(width 0.08382)
		(layer "In9.Cu")
		(net "M_BMC_DDR4_MCAS_N")
	)
	(segment
		(start 77.898752 -44.093638)
		(end 78.270608 -44.465494)
		(width 0.08382)
		(layer "In9.Cu")
		(net "M_BMC_DDR4_MCAS_N")
	)
	(segment
		(start 63.2968 -40.623236)
		(end 63.2968 -40.49522)
		(width 0.08382)
		(layer "In9.Cu")
		(net "M_BMC_DDR4_MCAS_N")
	)
	(arc
		(start 77.059282 -42.375328)
		(mid 77.125736 -42.402854)
		(end 77.153262 -42.469308)
		(width 0.08382)
		(layer "In9.Cu")
		(net "M_BMC_DDR4_MCAS_N")
	)
	(arc
		(start 76.34097 -42.081704)
		(mid 76.42697 -42.289328)
		(end 76.634594 -42.375328)
		(width 0.08382)
		(layer "In9.Cu")
		(net "M_BMC_DDR4_MCAS_N")
	)
	(arc
		(start 64.63411 -40.98798)
		(mid 64.805812 -40.916858)
		(end 64.876934 -40.745156)
		(width 0.08382)
		(layer "In9.Cu")
		(net "M_BMC_DDR4_MCAS_N")
	)
	(arc
		(start 77.777086 -43.526202)
		(mid 77.84354 -43.553728)
		(end 77.871066 -43.620182)
		(width 0.08382)
		(layer "In9.Cu")
		(net "M_BMC_DDR4_MCAS_N")
	)
	(arc
		(start 77.871066 -44.026836)
		(mid 77.878258 -44.062995)
		(end 77.898752 -44.093638)
		(width 0.08382)
		(layer "In9.Cu")
		(net "M_BMC_DDR4_MCAS_N")
	)
	(arc
		(start 62.667642 -45.15358)
		(mid 62.546223 -44.971769)
		(end 62.503558 -44.75734)
		(width 0.08382)
		(layer "In9.Cu")
		(net "M_BMC_DDR4_MCAS_N")
	)
	(arc
		(start 62.992 -40.9702)
		(mid 63.085897 -40.951523)
		(end 63.165482 -40.898318)
		(width 0.08382)
		(layer "In9.Cu")
		(net "M_BMC_DDR4_MCAS_N")
	)
	(arc
		(start 65.30467 -40.182546)
		(mid 65.525672 -40.188076)
		(end 65.746122 -40.204644)
		(width 0.08382)
		(layer "In9.Cu")
		(net "M_BMC_DDR4_MCAS_N")
	)
	(arc
		(start 76.305918 -41.737534)
		(mid 76.331848 -41.776341)
		(end 76.34097 -41.822116)
		(width 0.08382)
		(layer "In9.Cu")
		(net "M_BMC_DDR4_MCAS_N")
	)
	(arc
		(start 64.004952 -40.182546)
		(mid 64.071406 -40.210072)
		(end 64.098932 -40.276526)
		(width 0.08382)
		(layer "In9.Cu")
		(net "M_BMC_DDR4_MCAS_N")
	)
	(arc
		(start 74.265028 -40.246554)
		(mid 74.773101 -40.347616)
		(end 75.203812 -40.635428)
		(width 0.08382)
		(layer "In9.Cu")
		(net "M_BMC_DDR4_MCAS_N")
	)
	(arc
		(start 64.098932 -40.663622)
		(mid 64.193934 -40.892978)
		(end 64.42329 -40.98798)
		(width 0.08382)
		(layer "In9.Cu")
		(net "M_BMC_DDR4_MCAS_N")
	)
	(arc
		(start 63.2968 -40.49522)
		(mid 63.38838 -40.274126)
		(end 63.609474 -40.182546)
		(width 0.08382)
		(layer "In9.Cu")
		(net "M_BMC_DDR4_MCAS_N")
	)
	(arc
		(start 61.917834 -44.167298)
		(mid 61.74667 -44.0964)
		(end 61.675772 -43.925236)
		(width 0.08382)
		(layer "In9.Cu")
		(net "M_BMC_DDR4_MCAS_N")
	)
	(arc
		(start 62.49162 -41.29532)
		(mid 62.586845 -41.065425)
		(end 62.81674 -40.9702)
		(width 0.08382)
		(layer "In9.Cu")
		(net "M_BMC_DDR4_MCAS_N")
	)
	(arc
		(start 62.503558 -44.44238)
		(mid 62.422988 -44.247868)
		(end 62.228476 -44.167298)
		(width 0.08382)
		(layer "In9.Cu")
		(net "M_BMC_DDR4_MCAS_N")
	)
	(arc
		(start 63.1952 -40.8686)
		(mid 63.27042 -40.756026)
		(end 63.2968 -40.623236)
		(width 0.08382)
		(layer "In9.Cu")
		(net "M_BMC_DDR4_MCAS_N")
	)
	(arc
		(start 66.117978 -40.241982)
		(mid 66.164784 -40.24544)
		(end 66.211704 -40.246554)
		(width 0.08382)
		(layer "In9.Cu")
		(net "M_BMC_DDR4_MCAS_N")
	)
	(arc
		(start 64.876934 -40.276526)
		(mid 64.90446 -40.210072)
		(end 64.970914 -40.182546)
		(width 0.08382)
		(layer "In9.Cu")
		(net "M_BMC_DDR4_MCAS_N")
	)
	(arc
		(start 61.675772 -42.118788)
		(mid 61.774122 -41.88135)
		(end 62.01156 -41.783)
		(width 0.08382)
		(layer "In9.Cu")
		(net "M_BMC_DDR4_MCAS_N")
	)
	(arc
		(start 62.16904 -41.783)
		(mid 62.397139 -41.688519)
		(end 62.49162 -41.46042)
		(width 0.08382)
		(layer "In9.Cu")
		(net "M_BMC_DDR4_MCAS_N")
	)
	(arc
		(start 76.482702 -43.439842)
		(mid 76.507996 -43.500908)
		(end 76.569062 -43.526202)
		(width 0.08382)
		(layer "In9.Cu")
		(net "M_BMC_DDR4_MCAS_N")
	)
	(arc
		(start 76.569062 -42.964608)
		(mid 76.507996 -42.989902)
		(end 76.482702 -43.050968)
		(width 0.08382)
		(layer "In9.Cu")
		(net "M_BMC_DDR4_MCAS_N")
	)
	(arc
		(start 77.153262 -42.870628)
		(mid 77.125736 -42.937082)
		(end 77.059282 -42.964608)
		(width 0.08382)
		(layer "In9.Cu")
		(net "M_BMC_DDR4_MCAS_N")
	)
	(segment
		(start 63.295022 -48.171354)
		(end 63.690246 -47.77613)
		(width 0.11684)
		(layer "F.Cu")
		(net "M_BMC_DDR4_MBG1")
	)
	(via
		(at 63.690246 -47.77613)
		(size 0.4572)
		(drill 0.254)
		(layers "F.Cu" "B.Cu")
		(net "M_BMC_DDR4_MBG1")
	)
	(via
		(at 68.048886 -47.014384)
		(size 0.6604)
		(drill 0.3302)
		(layers "F.Cu" "B.Cu")
		(net "M_BMC_DDR4_MBG1")
	)
	(segment
		(start 69.649086 -47.373032)
		(end 69.606414 -47.454566)
		(width 0.11684)
		(layer "B.Cu")
		(net "M_BMC_DDR4_MBG1")
	)
	(segment
		(start 70.215252 -46.08576)
		(end 69.486018 -46.316138)
		(width 0.11684)
		(layer "B.Cu")
		(net "M_BMC_DDR4_MBG1")
	)
	(segment
		(start 69.2531 -47.565056)
		(end 69.24294 -47.559722)
		(width 0.11684)
		(layer "B.Cu")
		(net "M_BMC_DDR4_MBG1")
	)
	(segment
		(start 81.78927 -46.586394)
		(end 81.729326 -46.586394)
		(width 0.11684)
		(layer "B.Cu")
		(net "M_BMC_DDR4_MBG1")
	)
	(segment
		(start 63.81877 -47.904654)
		(end 63.690246 -47.77613)
		(width 0.11684)
		(layer "B.Cu")
		(net "M_BMC_DDR4_MBG1")
	)
	(segment
		(start 68.048886 -47.014384)
		(end 67.785742 -47.277528)
		(width 0.11684)
		(layer "B.Cu")
		(net "M_BMC_DDR4_MBG1")
	)
	(segment
		(start 81.729326 -46.586394)
		(end 81.198974 -46.056042)
		(width 0.11684)
		(layer "B.Cu")
		(net "M_BMC_DDR4_MBG1")
	)
	(segment
		(start 65.96253 -48.07204)
		(end 64.222884 -48.07204)
		(width 0.11684)
		(layer "B.Cu")
		(net "M_BMC_DDR4_MBG1")
	)
	(segment
		(start 82.76717 -47.602394)
		(end 82.76717 -46.586394)
		(width 0.11684)
		(layer "B.Cu")
		(net "M_BMC_DDR4_MBG1")
	)
	(segment
		(start 80.066642 -45.512228)
		(end 79.901034 -45.512228)
		(width 0.11684)
		(layer "B.Cu")
		(net "M_BMC_DDR4_MBG1")
	)
	(segment
		(start 67.212718 -48.225964)
		(end 66.334132 -48.225964)
		(width 0.11684)
		(layer "B.Cu")
		(net "M_BMC_DDR4_MBG1")
	)
	(segment
		(start 69.411596 -46.459394)
		(end 69.660262 -47.245524)
		(width 0.11684)
		(layer "B.Cu")
		(net "M_BMC_DDR4_MBG1")
	)
	(segment
		(start 67.43319 -48.128682)
		(end 67.42303 -48.138842)
		(width 0.11684)
		(layer "B.Cu")
		(net "M_BMC_DDR4_MBG1")
	)
	(segment
		(start 80.71993 -45.735748)
		(end 80.28559 -45.555662)
		(width 0.11684)
		(layer "B.Cu")
		(net "M_BMC_DDR4_MBG1")
	)
	(segment
		(start 81.11236 -45.984922)
		(end 80.818482 -45.78858)
		(width 0.11684)
		(layer "B.Cu")
		(net "M_BMC_DDR4_MBG1")
	)
	(segment
		(start 69.066918 -47.350172)
		(end 68.906898 -46.843442)
		(width 0.11684)
		(layer "B.Cu")
		(net "M_BMC_DDR4_MBG1")
	)
	(segment
		(start 79.449168 -45.301408)
		(end 79.426562 -45.278802)
		(width 0.11684)
		(layer "B.Cu")
		(net "M_BMC_DDR4_MBG1")
	)
	(segment
		(start 82.76717 -46.586394)
		(end 81.78927 -46.586394)
		(width 0.11684)
		(layer "B.Cu")
		(net "M_BMC_DDR4_MBG1")
	)
	(segment
		(start 75.51293 -45.935392)
		(end 70.886828 -45.935392)
		(width 0.11684)
		(layer "B.Cu")
		(net "M_BMC_DDR4_MBG1")
	)
	(segment
		(start 79.065374 -45.129196)
		(end 77.484478 -45.129196)
		(width 0.11684)
		(layer "B.Cu")
		(net "M_BMC_DDR4_MBG1")
	)
	(segment
		(start 68.30695 -46.75632)
		(end 68.048886 -47.014384)
		(width 0.11684)
		(layer "B.Cu")
		(net "M_BMC_DDR4_MBG1")
	)
	(arc
		(start 79.426562 -45.278802)
		(mid 79.260848 -45.168075)
		(end 79.065374 -45.129196)
		(width 0.11684)
		(layer "B.Cu")
		(net "M_BMC_DDR4_MBG1")
	)
	(arc
		(start 67.42303 -48.138842)
		(mid 67.326538 -48.203316)
		(end 67.212718 -48.225964)
		(width 0.11684)
		(layer "B.Cu")
		(net "M_BMC_DDR4_MBG1")
	)
	(arc
		(start 77.484478 -45.129196)
		(mid 77.145914 -45.193985)
		(end 76.85532 -45.379386)
		(width 0.11684)
		(layer "B.Cu")
		(net "M_BMC_DDR4_MBG1")
	)
	(arc
		(start 66.334132 -48.225964)
		(mid 66.17686 -48.194681)
		(end 66.043556 -48.105568)
		(width 0.11684)
		(layer "B.Cu")
		(net "M_BMC_DDR4_MBG1")
	)
	(arc
		(start 70.780148 -45.945044)
		(mid 70.495515 -46.00663)
		(end 70.215252 -46.08576)
		(width 0.11684)
		(layer "B.Cu")
		(net "M_BMC_DDR4_MBG1")
	)
	(arc
		(start 64.222884 -48.07204)
		(mid 64.00418 -48.028537)
		(end 63.81877 -47.904654)
		(width 0.11684)
		(layer "B.Cu")
		(net "M_BMC_DDR4_MBG1")
	)
	(arc
		(start 67.572128 -47.793402)
		(mid 67.536015 -47.974863)
		(end 67.43319 -48.128682)
		(width 0.11684)
		(layer "B.Cu")
		(net "M_BMC_DDR4_MBG1")
	)
	(arc
		(start 80.28559 -45.555662)
		(mid 80.178256 -45.523151)
		(end 80.066642 -45.512228)
		(width 0.11684)
		(layer "B.Cu")
		(net "M_BMC_DDR4_MBG1")
	)
	(arc
		(start 67.785742 -47.277528)
		(mid 67.627594 -47.514213)
		(end 67.572128 -47.793402)
		(width 0.11684)
		(layer "B.Cu")
		(net "M_BMC_DDR4_MBG1")
	)
	(arc
		(start 80.818482 -45.78858)
		(mid 80.770504 -45.759741)
		(end 80.71993 -45.735748)
		(width 0.11684)
		(layer "B.Cu")
		(net "M_BMC_DDR4_MBG1")
	)
	(arc
		(start 68.847208 -46.742604)
		(mid 68.706123 -46.646658)
		(end 68.538344 -46.615604)
		(width 0.11684)
		(layer "B.Cu")
		(net "M_BMC_DDR4_MBG1")
	)
	(arc
		(start 66.043556 -48.105568)
		(mid 66.006381 -48.080728)
		(end 65.96253 -48.07204)
		(width 0.11684)
		(layer "B.Cu")
		(net "M_BMC_DDR4_MBG1")
	)
	(arc
		(start 69.606414 -47.454566)
		(mid 69.452585 -47.582897)
		(end 69.2531 -47.565056)
		(width 0.11684)
		(layer "B.Cu")
		(net "M_BMC_DDR4_MBG1")
	)
	(arc
		(start 81.198974 -46.056042)
		(mid 81.157416 -46.018352)
		(end 81.11236 -45.984922)
		(width 0.11684)
		(layer "B.Cu")
		(net "M_BMC_DDR4_MBG1")
	)
	(arc
		(start 79.787496 -45.497242)
		(mid 79.605473 -45.421533)
		(end 79.449168 -45.301408)
		(width 0.11684)
		(layer "B.Cu")
		(net "M_BMC_DDR4_MBG1")
	)
	(arc
		(start 70.886828 -45.935392)
		(mid 70.833269 -45.937792)
		(end 70.780148 -45.945044)
		(width 0.11684)
		(layer "B.Cu")
		(net "M_BMC_DDR4_MBG1")
	)
	(arc
		(start 76.85532 -45.379386)
		(mid 76.239426 -45.790913)
		(end 75.51293 -45.935392)
		(width 0.11684)
		(layer "B.Cu")
		(net "M_BMC_DDR4_MBG1")
	)
	(arc
		(start 69.660262 -47.245524)
		(mid 69.667388 -47.310391)
		(end 69.649086 -47.373032)
		(width 0.11684)
		(layer "B.Cu")
		(net "M_BMC_DDR4_MBG1")
	)
	(arc
		(start 68.538344 -46.615604)
		(mid 68.414211 -46.672083)
		(end 68.30695 -46.75632)
		(width 0.11684)
		(layer "B.Cu")
		(net "M_BMC_DDR4_MBG1")
	)
	(arc
		(start 79.901034 -45.512228)
		(mid 79.843766 -45.508506)
		(end 79.787496 -45.497242)
		(width 0.11684)
		(layer "B.Cu")
		(net "M_BMC_DDR4_MBG1")
	)
	(arc
		(start 69.24294 -47.559722)
		(mid 69.134075 -47.472456)
		(end 69.066918 -47.350172)
		(width 0.11684)
		(layer "B.Cu")
		(net "M_BMC_DDR4_MBG1")
	)
	(arc
		(start 69.486018 -46.316138)
		(mid 69.419134 -46.372333)
		(end 69.411596 -46.459394)
		(width 0.11684)
		(layer "B.Cu")
		(net "M_BMC_DDR4_MBG1")
	)
	(arc
		(start 68.906898 -46.843442)
		(mid 68.882891 -46.789567)
		(end 68.847208 -46.742604)
		(width 0.11684)
		(layer "B.Cu")
		(net "M_BMC_DDR4_MBG1")
	)
	(segment
		(start 63.295022 -44.171362)
		(end 63.690246 -43.776138)
		(width 0.11684)
		(layer "F.Cu")
		(net "M_BMC_DDR4_MBG0")
	)
	(segment
		(start 73.852278 -45.107352)
		(end 73.470516 -44.72559)
		(width 0.11684)
		(layer "F.Cu")
		(net "M_BMC_DDR4_MBG0")
	)
	(via
		(at 79.062326 -40.42791)
		(size 0.6604)
		(drill 0.3302)
		(layers "F.Cu" "B.Cu")
		(net "M_BMC_DDR4_MBG0")
	)
	(via
		(at 73.470516 -44.72559)
		(size 0.4572)
		(drill 0.254)
		(layers "F.Cu" "B.Cu")
		(net "M_BMC_DDR4_MBG0")
	)
	(via
		(at 63.690246 -43.776138)
		(size 0.4572)
		(drill 0.254)
		(layers "F.Cu" "B.Cu")
		(net "M_BMC_DDR4_MBG0")
	)
	(segment
		(start 75.416918 -44.280074)
		(end 75.374246 -44.322746)
		(width 0.11684)
		(layer "B.Cu")
		(net "M_BMC_DDR4_MBG0")
	)
	(segment
		(start 76.84897 -41.65981)
		(end 75.786996 -42.721784)
		(width 0.11684)
		(layer "B.Cu")
		(net "M_BMC_DDR4_MBG0")
	)
	(segment
		(start 75.055984 -44.454572)
		(end 74.880216 -44.454572)
		(width 0.11684)
		(layer "B.Cu")
		(net "M_BMC_DDR4_MBG0")
	)
	(segment
		(start 79.062326 -40.42791)
		(end 78.872334 -40.50665)
		(width 0.11684)
		(layer "B.Cu")
		(net "M_BMC_DDR4_MBG0")
	)
	(segment
		(start 75.55103 -43.131232)
		(end 75.55103 -43.956224)
		(width 0.11684)
		(layer "B.Cu")
		(net "M_BMC_DDR4_MBG0")
	)
	(segment
		(start 80.104234 -39.99611)
		(end 79.062326 -40.42791)
		(width 0.11684)
		(layer "B.Cu")
		(net "M_BMC_DDR4_MBG0")
	)
	(segment
		(start 80.761586 -39.942262)
		(end 80.729836 -39.974012)
		(width 0.11684)
		(layer "B.Cu")
		(net "M_BMC_DDR4_MBG0")
	)
	(segment
		(start 77.8891 -40.90162)
		(end 77.493114 -41.148254)
		(width 0.11684)
		(layer "B.Cu")
		(net "M_BMC_DDR4_MBG0")
	)
	(segment
		(start 74.398378 -44.329096)
		(end 73.982834 -44.329096)
		(width 0.11684)
		(layer "B.Cu")
		(net "M_BMC_DDR4_MBG0")
	)
	(segment
		(start 80.761586 -38.957758)
		(end 80.761586 -39.942262)
		(width 0.11684)
		(layer "B.Cu")
		(net "M_BMC_DDR4_MBG0")
	)
	(segment
		(start 74.714354 -44.421552)
		(end 74.575416 -44.364148)
		(width 0.11684)
		(layer "B.Cu")
		(net "M_BMC_DDR4_MBG0")
	)
	(segment
		(start 80.729836 -39.974012)
		(end 80.21574 -39.974012)
		(width 0.11684)
		(layer "B.Cu")
		(net "M_BMC_DDR4_MBG0")
	)
	(segment
		(start 73.784968 -44.411138)
		(end 73.470516 -44.72559)
		(width 0.11684)
		(layer "B.Cu")
		(net "M_BMC_DDR4_MBG0")
	)
	(arc
		(start 78.347824 -40.705786)
		(mid 78.116075 -40.798113)
		(end 77.8891 -40.90162)
		(width 0.11684)
		(layer "B.Cu")
		(net "M_BMC_DDR4_MBG0")
	)
	(arc
		(start 75.57389 -43.026838)
		(mid 75.55677 -43.07779)
		(end 75.55103 -43.131232)
		(width 0.11684)
		(layer "B.Cu")
		(net "M_BMC_DDR4_MBG0")
	)
	(arc
		(start 75.786996 -42.721784)
		(mid 75.666944 -42.864882)
		(end 75.57389 -43.026838)
		(width 0.11684)
		(layer "B.Cu")
		(net "M_BMC_DDR4_MBG0")
	)
	(arc
		(start 78.768194 -40.553894)
		(mid 78.609517 -40.622574)
		(end 78.444852 -40.675306)
		(width 0.11684)
		(layer "B.Cu")
		(net "M_BMC_DDR4_MBG0")
	)
	(arc
		(start 80.21574 -39.974012)
		(mid 80.158898 -39.979565)
		(end 80.104234 -39.99611)
		(width 0.11684)
		(layer "B.Cu")
		(net "M_BMC_DDR4_MBG0")
	)
	(arc
		(start 73.982834 -44.329096)
		(mid 73.875732 -44.350418)
		(end 73.784968 -44.411138)
		(width 0.11684)
		(layer "B.Cu")
		(net "M_BMC_DDR4_MBG0")
	)
	(arc
		(start 78.872334 -40.50665)
		(mid 78.819879 -40.529423)
		(end 78.768194 -40.553894)
		(width 0.11684)
		(layer "B.Cu")
		(net "M_BMC_DDR4_MBG0")
	)
	(arc
		(start 78.444852 -40.675306)
		(mid 78.395979 -40.689404)
		(end 78.347824 -40.705786)
		(width 0.11684)
		(layer "B.Cu")
		(net "M_BMC_DDR4_MBG0")
	)
	(arc
		(start 74.880216 -44.454572)
		(mid 74.795666 -44.446203)
		(end 74.714354 -44.421552)
		(width 0.11684)
		(layer "B.Cu")
		(net "M_BMC_DDR4_MBG0")
	)
	(arc
		(start 75.55103 -43.956224)
		(mid 75.516155 -44.131464)
		(end 75.416918 -44.280074)
		(width 0.11684)
		(layer "B.Cu")
		(net "M_BMC_DDR4_MBG0")
	)
	(arc
		(start 77.493114 -41.148254)
		(mid 77.156411 -41.38561)
		(end 76.84897 -41.65981)
		(width 0.11684)
		(layer "B.Cu")
		(net "M_BMC_DDR4_MBG0")
	)
	(arc
		(start 74.575416 -44.364148)
		(mid 74.488616 -44.337941)
		(end 74.398378 -44.329096)
		(width 0.11684)
		(layer "B.Cu")
		(net "M_BMC_DDR4_MBG0")
	)
	(arc
		(start 75.374246 -44.322746)
		(mid 75.22824 -44.420367)
		(end 75.055984 -44.454572)
		(width 0.11684)
		(layer "B.Cu")
		(net "M_BMC_DDR4_MBG0")
	)
	(segment
		(start 71.575676 -43.045634)
		(end 71.09714 -43.045634)
		(width 0.08382)
		(layer "In2.Cu")
		(net "M_BMC_DDR4_MBG0")
	)
	(segment
		(start 63.955422 -43.33367)
		(end 63.838328 -43.33367)
		(width 0.08382)
		(layer "In2.Cu")
		(net "M_BMC_DDR4_MBG0")
	)
	(segment
		(start 70.698868 -42.81297)
		(end 70.618858 -42.81297)
		(width 0.08382)
		(layer "In2.Cu")
		(net "M_BMC_DDR4_MBG0")
	)
	(segment
		(start 68.584318 -42.445178)
		(end 68.220082 -42.445178)
		(width 0.08382)
		(layer "In2.Cu")
		(net "M_BMC_DDR4_MBG0")
	)
	(segment
		(start 66.466212 -43.561508)
		(end 66.466212 -42.77741)
		(width 0.08382)
		(layer "In2.Cu")
		(net "M_BMC_DDR4_MBG0")
	)
	(segment
		(start 65.331594 -44.650152)
		(end 64.989202 -44.650152)
		(width 0.08382)
		(layer "In2.Cu")
		(net "M_BMC_DDR4_MBG0")
	)
	(segment
		(start 69.965316 -43.327828)
		(end 69.965316 -42.68978)
		(width 0.08382)
		(layer "In2.Cu")
		(net "M_BMC_DDR4_MBG0")
	)
	(segment
		(start 65.425574 -44.22648)
		(end 65.425574 -44.556172)
		(width 0.08382)
		(layer "In2.Cu")
		(net "M_BMC_DDR4_MBG0")
	)
	(segment
		(start 73.882758 -44.63161)
		(end 73.882758 -44.381166)
		(width 0.08382)
		(layer "In2.Cu")
		(net "M_BMC_DDR4_MBG0")
	)
	(segment
		(start 65.988692 -42.78503)
		(end 65.988692 -44.04614)
		(width 0.08382)
		(layer "In2.Cu")
		(net "M_BMC_DDR4_MBG0")
	)
	(segment
		(start 64.801242 -44.154852)
		(end 64.27978 -44.154852)
		(width 0.08382)
		(layer "In2.Cu")
		(net "M_BMC_DDR4_MBG0")
	)
	(segment
		(start 69.235574 -42.68978)
		(end 69.235574 -43.432222)
		(width 0.08382)
		(layer "In2.Cu")
		(net "M_BMC_DDR4_MBG0")
	)
	(segment
		(start 67.573906 -43.561508)
		(end 67.573906 -42.808398)
		(width 0.08382)
		(layer "In2.Cu")
		(net "M_BMC_DDR4_MBG0")
	)
	(segment
		(start 68.032122 -43.655488)
		(end 67.667886 -43.655488)
		(width 0.08382)
		(layer "In2.Cu")
		(net "M_BMC_DDR4_MBG0")
	)
	(segment
		(start 72.291956 -43.481244)
		(end 72.291956 -44.675298)
		(width 0.08382)
		(layer "In2.Cu")
		(net "M_BMC_DDR4_MBG0")
	)
	(segment
		(start 70.517258 -42.91457)
		(end 70.517258 -43.327828)
		(width 0.08382)
		(layer "In2.Cu")
		(net "M_BMC_DDR4_MBG0")
	)
	(segment
		(start 69.141594 -43.526202)
		(end 68.772278 -43.526202)
		(width 0.08382)
		(layer "In2.Cu")
		(net "M_BMC_DDR4_MBG0")
	)
	(segment
		(start 68.678298 -43.432222)
		(end 68.678298 -42.539158)
		(width 0.08382)
		(layer "In2.Cu")
		(net "M_BMC_DDR4_MBG0")
	)
	(segment
		(start 70.922388 -42.973244)
		(end 70.806818 -42.857674)
		(width 0.08382)
		(layer "In2.Cu")
		(net "M_BMC_DDR4_MBG0")
	)
	(segment
		(start 64.895222 -44.556172)
		(end 64.895222 -44.248832)
		(width 0.08382)
		(layer "In2.Cu")
		(net "M_BMC_DDR4_MBG0")
	)
	(segment
		(start 66.379852 -42.69105)
		(end 66.082672 -42.69105)
		(width 0.08382)
		(layer "In2.Cu")
		(net "M_BMC_DDR4_MBG0")
	)
	(segment
		(start 68.126102 -42.539158)
		(end 68.126102 -43.561508)
		(width 0.08382)
		(layer "In2.Cu")
		(net "M_BMC_DDR4_MBG0")
	)
	(segment
		(start 65.902332 -44.1325)
		(end 65.519554 -44.1325)
		(width 0.08382)
		(layer "In2.Cu")
		(net "M_BMC_DDR4_MBG0")
	)
	(segment
		(start 64.106298 -43.98137)
		(end 64.103504 -43.98137)
		(width 0.08382)
		(layer "In2.Cu")
		(net "M_BMC_DDR4_MBG0")
	)
	(segment
		(start 69.871336 -42.5958)
		(end 69.329554 -42.5958)
		(width 0.08382)
		(layer "In2.Cu")
		(net "M_BMC_DDR4_MBG0")
	)
	(segment
		(start 63.690246 -43.481752)
		(end 63.690246 -43.776138)
		(width 0.08382)
		(layer "In2.Cu")
		(net "M_BMC_DDR4_MBG0")
	)
	(segment
		(start 67.022726 -42.808398)
		(end 67.022726 -43.561508)
		(width 0.08382)
		(layer "In2.Cu")
		(net "M_BMC_DDR4_MBG0")
	)
	(segment
		(start 72.944482 -43.341798)
		(end 72.431402 -43.341798)
		(width 0.08382)
		(layer "In2.Cu")
		(net "M_BMC_DDR4_MBG0")
	)
	(segment
		(start 73.788778 -44.287186)
		(end 73.186036 -44.287186)
		(width 0.08382)
		(layer "In2.Cu")
		(net "M_BMC_DDR4_MBG0")
	)
	(segment
		(start 71.574914 -43.682666)
		(end 71.664576 -43.593004)
		(width 0.08382)
		(layer "In2.Cu")
		(net "M_BMC_DDR4_MBG0")
	)
	(segment
		(start 73.092056 -44.193206)
		(end 73.092056 -43.489372)
		(width 0.08382)
		(layer "In2.Cu")
		(net "M_BMC_DDR4_MBG0")
	)
	(segment
		(start 67.479926 -42.714418)
		(end 67.116706 -42.714418)
		(width 0.08382)
		(layer "In2.Cu")
		(net "M_BMC_DDR4_MBG0")
	)
	(segment
		(start 72.197976 -44.769278)
		(end 71.566278 -44.769278)
		(width 0.08382)
		(layer "In2.Cu")
		(net "M_BMC_DDR4_MBG0")
	)
	(segment
		(start 64.103504 -43.98137)
		(end 64.103504 -43.481752)
		(width 0.08382)
		(layer "In2.Cu")
		(net "M_BMC_DDR4_MBG0")
	)
	(segment
		(start 73.470516 -44.72559)
		(end 73.788778 -44.72559)
		(width 0.08382)
		(layer "In2.Cu")
		(net "M_BMC_DDR4_MBG0")
	)
	(segment
		(start 71.472298 -44.675298)
		(end 71.472298 -43.930316)
		(width 0.08382)
		(layer "In2.Cu")
		(net "M_BMC_DDR4_MBG0")
	)
	(segment
		(start 70.385432 -43.459654)
		(end 70.097142 -43.459654)
		(width 0.08382)
		(layer "In2.Cu")
		(net "M_BMC_DDR4_MBG0")
	)
	(segment
		(start 66.928746 -43.655488)
		(end 66.560192 -43.655488)
		(width 0.08382)
		(layer "In2.Cu")
		(net "M_BMC_DDR4_MBG0")
	)
	(segment
		(start 71.754238 -43.376596)
		(end 71.754238 -43.224196)
		(width 0.08382)
		(layer "In2.Cu")
		(net "M_BMC_DDR4_MBG0")
	)
	(arc
		(start 71.09714 -43.045634)
		(mid 71.002563 -43.026821)
		(end 70.922388 -42.973244)
		(width 0.08382)
		(layer "In2.Cu")
		(net "M_BMC_DDR4_MBG0")
	)
	(arc
		(start 69.235574 -43.432222)
		(mid 69.208048 -43.498676)
		(end 69.141594 -43.526202)
		(width 0.08382)
		(layer "In2.Cu")
		(net "M_BMC_DDR4_MBG0")
	)
	(arc
		(start 67.022726 -43.561508)
		(mid 66.9952 -43.627962)
		(end 66.928746 -43.655488)
		(width 0.08382)
		(layer "In2.Cu")
		(net "M_BMC_DDR4_MBG0")
	)
	(arc
		(start 71.754238 -43.224196)
		(mid 71.701938 -43.097934)
		(end 71.575676 -43.045634)
		(width 0.08382)
		(layer "In2.Cu")
		(net "M_BMC_DDR4_MBG0")
	)
	(arc
		(start 64.103504 -43.481752)
		(mid 64.060132 -43.377042)
		(end 63.955422 -43.33367)
		(width 0.08382)
		(layer "In2.Cu")
		(net "M_BMC_DDR4_MBG0")
	)
	(arc
		(start 71.566278 -44.769278)
		(mid 71.499824 -44.741752)
		(end 71.472298 -44.675298)
		(width 0.08382)
		(layer "In2.Cu")
		(net "M_BMC_DDR4_MBG0")
	)
	(arc
		(start 69.965316 -42.68978)
		(mid 69.93779 -42.623326)
		(end 69.871336 -42.5958)
		(width 0.08382)
		(layer "In2.Cu")
		(net "M_BMC_DDR4_MBG0")
	)
	(arc
		(start 70.618858 -42.81297)
		(mid 70.547016 -42.842728)
		(end 70.517258 -42.91457)
		(width 0.08382)
		(layer "In2.Cu")
		(net "M_BMC_DDR4_MBG0")
	)
	(arc
		(start 66.560192 -43.655488)
		(mid 66.493738 -43.627962)
		(end 66.466212 -43.561508)
		(width 0.08382)
		(layer "In2.Cu")
		(net "M_BMC_DDR4_MBG0")
	)
	(arc
		(start 73.788778 -44.72559)
		(mid 73.855232 -44.698064)
		(end 73.882758 -44.63161)
		(width 0.08382)
		(layer "In2.Cu")
		(net "M_BMC_DDR4_MBG0")
	)
	(arc
		(start 67.667886 -43.655488)
		(mid 67.601432 -43.627962)
		(end 67.573906 -43.561508)
		(width 0.08382)
		(layer "In2.Cu")
		(net "M_BMC_DDR4_MBG0")
	)
	(arc
		(start 73.092056 -43.489372)
		(mid 73.048833 -43.385021)
		(end 72.944482 -43.341798)
		(width 0.08382)
		(layer "In2.Cu")
		(net "M_BMC_DDR4_MBG0")
	)
	(arc
		(start 63.838328 -43.33367)
		(mid 63.733618 -43.377042)
		(end 63.690246 -43.481752)
		(width 0.08382)
		(layer "In2.Cu")
		(net "M_BMC_DDR4_MBG0")
	)
	(arc
		(start 70.097142 -43.459654)
		(mid 70.003927 -43.421043)
		(end 69.965316 -43.327828)
		(width 0.08382)
		(layer "In2.Cu")
		(net "M_BMC_DDR4_MBG0")
	)
	(arc
		(start 73.186036 -44.287186)
		(mid 73.119582 -44.25966)
		(end 73.092056 -44.193206)
		(width 0.08382)
		(layer "In2.Cu")
		(net "M_BMC_DDR4_MBG0")
	)
	(arc
		(start 68.678298 -42.539158)
		(mid 68.650772 -42.472704)
		(end 68.584318 -42.445178)
		(width 0.08382)
		(layer "In2.Cu")
		(net "M_BMC_DDR4_MBG0")
	)
	(arc
		(start 65.988692 -44.04614)
		(mid 65.963398 -44.107206)
		(end 65.902332 -44.1325)
		(width 0.08382)
		(layer "In2.Cu")
		(net "M_BMC_DDR4_MBG0")
	)
	(arc
		(start 71.664576 -43.593004)
		(mid 71.730919 -43.493715)
		(end 71.754238 -43.376596)
		(width 0.08382)
		(layer "In2.Cu")
		(net "M_BMC_DDR4_MBG0")
	)
	(arc
		(start 69.329554 -42.5958)
		(mid 69.2631 -42.623326)
		(end 69.235574 -42.68978)
		(width 0.08382)
		(layer "In2.Cu")
		(net "M_BMC_DDR4_MBG0")
	)
	(arc
		(start 68.126102 -43.561508)
		(mid 68.098576 -43.627962)
		(end 68.032122 -43.655488)
		(width 0.08382)
		(layer "In2.Cu")
		(net "M_BMC_DDR4_MBG0")
	)
	(arc
		(start 68.220082 -42.445178)
		(mid 68.153628 -42.472704)
		(end 68.126102 -42.539158)
		(width 0.08382)
		(layer "In2.Cu")
		(net "M_BMC_DDR4_MBG0")
	)
	(arc
		(start 66.466212 -42.77741)
		(mid 66.440918 -42.716344)
		(end 66.379852 -42.69105)
		(width 0.08382)
		(layer "In2.Cu")
		(net "M_BMC_DDR4_MBG0")
	)
	(arc
		(start 65.425574 -44.556172)
		(mid 65.398048 -44.622626)
		(end 65.331594 -44.650152)
		(width 0.08382)
		(layer "In2.Cu")
		(net "M_BMC_DDR4_MBG0")
	)
	(arc
		(start 70.806818 -42.857674)
		(mid 70.75729 -42.824581)
		(end 70.698868 -42.81297)
		(width 0.08382)
		(layer "In2.Cu")
		(net "M_BMC_DDR4_MBG0")
	)
	(arc
		(start 65.519554 -44.1325)
		(mid 65.4531 -44.160026)
		(end 65.425574 -44.22648)
		(width 0.08382)
		(layer "In2.Cu")
		(net "M_BMC_DDR4_MBG0")
	)
	(arc
		(start 64.895222 -44.248832)
		(mid 64.867696 -44.182378)
		(end 64.801242 -44.154852)
		(width 0.08382)
		(layer "In2.Cu")
		(net "M_BMC_DDR4_MBG0")
	)
	(arc
		(start 70.517258 -43.327828)
		(mid 70.478647 -43.421043)
		(end 70.385432 -43.459654)
		(width 0.08382)
		(layer "In2.Cu")
		(net "M_BMC_DDR4_MBG0")
	)
	(arc
		(start 64.27978 -44.154852)
		(mid 64.15711 -44.10404)
		(end 64.106298 -43.98137)
		(width 0.08382)
		(layer "In2.Cu")
		(net "M_BMC_DDR4_MBG0")
	)
	(arc
		(start 66.082672 -42.69105)
		(mid 66.016218 -42.718576)
		(end 65.988692 -42.78503)
		(width 0.08382)
		(layer "In2.Cu")
		(net "M_BMC_DDR4_MBG0")
	)
	(arc
		(start 71.472298 -43.930316)
		(mid 71.49896 -43.796275)
		(end 71.574914 -43.682666)
		(width 0.08382)
		(layer "In2.Cu")
		(net "M_BMC_DDR4_MBG0")
	)
	(arc
		(start 72.291956 -44.675298)
		(mid 72.26443 -44.741752)
		(end 72.197976 -44.769278)
		(width 0.08382)
		(layer "In2.Cu")
		(net "M_BMC_DDR4_MBG0")
	)
	(arc
		(start 67.116706 -42.714418)
		(mid 67.050252 -42.741944)
		(end 67.022726 -42.808398)
		(width 0.08382)
		(layer "In2.Cu")
		(net "M_BMC_DDR4_MBG0")
	)
	(arc
		(start 67.573906 -42.808398)
		(mid 67.54638 -42.741944)
		(end 67.479926 -42.714418)
		(width 0.08382)
		(layer "In2.Cu")
		(net "M_BMC_DDR4_MBG0")
	)
	(arc
		(start 73.882758 -44.381166)
		(mid 73.855232 -44.314712)
		(end 73.788778 -44.287186)
		(width 0.08382)
		(layer "In2.Cu")
		(net "M_BMC_DDR4_MBG0")
	)
	(arc
		(start 72.431402 -43.341798)
		(mid 72.332799 -43.382641)
		(end 72.291956 -43.481244)
		(width 0.08382)
		(layer "In2.Cu")
		(net "M_BMC_DDR4_MBG0")
	)
	(arc
		(start 68.772278 -43.526202)
		(mid 68.705824 -43.498676)
		(end 68.678298 -43.432222)
		(width 0.08382)
		(layer "In2.Cu")
		(net "M_BMC_DDR4_MBG0")
	)
	(arc
		(start 64.989202 -44.650152)
		(mid 64.922748 -44.622626)
		(end 64.895222 -44.556172)
		(width 0.08382)
		(layer "In2.Cu")
		(net "M_BMC_DDR4_MBG0")
	)
	(segment
		(start 82.493358 -46.238668)
		(end 81.81848 -46.238668)
		(width 0.11684)
		(layer "F.Cu")
		(net "M_BMC_DDR4_MBA1")
	)
	(segment
		(start 78.65237 -44.307506)
		(end 78.270608 -43.925744)
		(width 0.11684)
		(layer "F.Cu")
		(net "M_BMC_DDR4_MBA1")
	)
	(segment
		(start 80.287622 -44.70781)
		(end 79.489554 -44.70781)
		(width 0.11684)
		(layer "F.Cu")
		(net "M_BMC_DDR4_MBA1")
	)
	(segment
		(start 83.67268 -46.463204)
		(end 83.448144 -46.238668)
		(width 0.11684)
		(layer "F.Cu")
		(net "M_BMC_DDR4_MBA1")
	)
	(segment
		(start 83.448144 -46.238668)
		(end 82.493358 -46.238668)
		(width 0.11684)
		(layer "F.Cu")
		(net "M_BMC_DDR4_MBA1")
	)
	(segment
		(start 84.8995 -46.717204)
		(end 84.43087 -46.717204)
		(width 0.11684)
		(layer "F.Cu")
		(net "M_BMC_DDR4_MBA1")
	)
	(segment
		(start 81.81848 -46.238668)
		(end 80.287622 -44.70781)
		(width 0.11684)
		(layer "F.Cu")
		(net "M_BMC_DDR4_MBA1")
	)
	(segment
		(start 61.695076 -44.971208)
		(end 62.0903 -44.575984)
		(width 0.11684)
		(layer "F.Cu")
		(net "M_BMC_DDR4_MBA1")
	)
	(segment
		(start 84.17687 -46.463204)
		(end 83.67268 -46.463204)
		(width 0.11684)
		(layer "F.Cu")
		(net "M_BMC_DDR4_MBA1")
	)
	(segment
		(start 78.743556 -44.398692)
		(end 78.65237 -44.307506)
		(width 0.11684)
		(layer "F.Cu")
		(net "M_BMC_DDR4_MBA1")
	)
	(segment
		(start 84.43087 -46.717204)
		(end 84.17687 -46.463204)
		(width 0.11684)
		(layer "F.Cu")
		(net "M_BMC_DDR4_MBA1")
	)
	(via
		(at 84.17687 -46.463204)
		(size 0.508)
		(drill 0.254)
		(layers "F.Cu" "B.Cu")
		(net "M_BMC_DDR4_MBA1")
	)
	(via
		(at 62.0903 -44.575984)
		(size 0.4572)
		(drill 0.254)
		(layers "F.Cu" "B.Cu")
		(net "M_BMC_DDR4_MBA1")
	)
	(via
		(at 82.493358 -46.238668)
		(size 0.762)
		(drill 0.381)
		(layers "F.Cu" "B.Cu")
		(net "M_BMC_DDR4_MBA1")
	)
	(via
		(at 78.270608 -43.925744)
		(size 0.4572)
		(drill 0.254)
		(layers "F.Cu" "B.Cu")
		(net "M_BMC_DDR4_MBA1")
	)
	(arc
		(start 79.489554 -44.70781)
		(mid 79.085832 -44.627411)
		(end 78.743556 -44.398692)
		(width 0.11684)
		(layer "F.Cu")
		(net "M_BMC_DDR4_MBA1")
	)
	(segment
		(start 84.8995 -46.463204)
		(end 84.17687 -46.463204)
		(width 0.11684)
		(layer "B.Cu")
		(net "M_BMC_DDR4_MBA1")
	)
	(segment
		(start 62.175136 -39.348156)
		(end 61.901832 -39.372794)
		(width 0.08382)
		(layer "In2.Cu")
		(net "M_BMC_DDR4_MBA1")
	)
	(segment
		(start 77.849222 -43.157648)
		(end 77.849222 -40.183308)
		(width 0.08382)
		(layer "In2.Cu")
		(net "M_BMC_DDR4_MBA1")
	)
	(segment
		(start 77.083412 -39.453058)
		(end 66.840862 -39.453058)
		(width 0.08382)
		(layer "In2.Cu")
		(net "M_BMC_DDR4_MBA1")
	)
	(segment
		(start 78.270608 -43.659298)
		(end 77.906118 -43.294808)
		(width 0.08382)
		(layer "In2.Cu")
		(net "M_BMC_DDR4_MBA1")
	)
	(segment
		(start 61.582808 -44.253912)
		(end 62.0903 -44.575984)
		(width 0.08382)
		(layer "In2.Cu")
		(net "M_BMC_DDR4_MBA1")
	)
	(segment
		(start 78.270608 -43.925744)
		(end 78.270608 -43.659298)
		(width 0.08382)
		(layer "In2.Cu")
		(net "M_BMC_DDR4_MBA1")
	)
	(segment
		(start 64.483234 -39.4208)
		(end 63.872872 -39.348156)
		(width 0.08382)
		(layer "In2.Cu")
		(net "M_BMC_DDR4_MBA1")
	)
	(segment
		(start 63.872872 -39.348156)
		(end 62.175136 -39.348156)
		(width 0.08382)
		(layer "In2.Cu")
		(net "M_BMC_DDR4_MBA1")
	)
	(segment
		(start 61.249814 -44.189396)
		(end 61.360304 -44.189396)
		(width 0.08382)
		(layer "In2.Cu")
		(net "M_BMC_DDR4_MBA1")
	)
	(segment
		(start 61.831982 -39.419276)
		(end 60.923678 -40.32758)
		(width 0.08382)
		(layer "In2.Cu")
		(net "M_BMC_DDR4_MBA1")
	)
	(segment
		(start 77.6859 -39.7891)
		(end 77.538326 -39.641526)
		(width 0.08382)
		(layer "In2.Cu")
		(net "M_BMC_DDR4_MBA1")
	)
	(segment
		(start 66.644266 -39.4208)
		(end 64.483234 -39.4208)
		(width 0.08382)
		(layer "In2.Cu")
		(net "M_BMC_DDR4_MBA1")
	)
	(segment
		(start 60.86729 -40.463724)
		(end 60.86729 -43.806872)
		(width 0.08382)
		(layer "In2.Cu")
		(net "M_BMC_DDR4_MBA1")
	)
	(arc
		(start 66.840862 -39.453058)
		(mid 66.791066 -39.449042)
		(end 66.742564 -39.437056)
		(width 0.08382)
		(layer "In2.Cu")
		(net "M_BMC_DDR4_MBA1")
	)
	(arc
		(start 60.86729 -43.806872)
		(mid 60.979329 -44.077357)
		(end 61.249814 -44.189396)
		(width 0.08382)
		(layer "In2.Cu")
		(net "M_BMC_DDR4_MBA1")
	)
	(arc
		(start 77.538326 -39.641526)
		(mid 77.32961 -39.502066)
		(end 77.083412 -39.453058)
		(width 0.08382)
		(layer "In2.Cu")
		(net "M_BMC_DDR4_MBA1")
	)
	(arc
		(start 77.906118 -43.294808)
		(mid 77.864016 -43.231893)
		(end 77.849222 -43.157648)
		(width 0.08382)
		(layer "In2.Cu")
		(net "M_BMC_DDR4_MBA1")
	)
	(arc
		(start 60.923678 -40.32758)
		(mid 60.881941 -40.390043)
		(end 60.86729 -40.463724)
		(width 0.08382)
		(layer "In2.Cu")
		(net "M_BMC_DDR4_MBA1")
	)
	(arc
		(start 61.360304 -44.189396)
		(mid 61.476153 -44.205808)
		(end 61.582808 -44.253912)
		(width 0.08382)
		(layer "In2.Cu")
		(net "M_BMC_DDR4_MBA1")
	)
	(arc
		(start 66.742564 -39.437056)
		(mid 66.694076 -39.424941)
		(end 66.644266 -39.4208)
		(width 0.08382)
		(layer "In2.Cu")
		(net "M_BMC_DDR4_MBA1")
	)
	(arc
		(start 77.849222 -40.183308)
		(mid 77.806783 -39.969951)
		(end 77.6859 -39.7891)
		(width 0.08382)
		(layer "In2.Cu")
		(net "M_BMC_DDR4_MBA1")
	)
	(arc
		(start 61.901832 -39.372794)
		(mid 61.864544 -39.392485)
		(end 61.831982 -39.419276)
		(width 0.08382)
		(layer "In2.Cu")
		(net "M_BMC_DDR4_MBA1")
	)
	(segment
		(start 73.852278 -44.307506)
		(end 74.265536 -43.925744)
		(width 0.11684)
		(layer "F.Cu")
		(net "M_BMC_DDR4_MBA0")
	)
	(segment
		(start 62.494922 -44.171362)
		(end 62.890146 -43.776138)
		(width 0.11684)
		(layer "F.Cu")
		(net "M_BMC_DDR4_MBA0")
	)
	(via
		(at 74.265536 -43.925744)
		(size 0.4572)
		(drill 0.254)
		(layers "F.Cu" "B.Cu")
		(net "M_BMC_DDR4_MBA0")
	)
	(via
		(at 78.586076 -39.113206)
		(size 0.6604)
		(drill 0.3302)
		(layers "F.Cu" "B.Cu")
		(net "M_BMC_DDR4_MBA0")
	)
	(via
		(at 62.890146 -43.776138)
		(size 0.4572)
		(drill 0.254)
		(layers "F.Cu" "B.Cu")
		(net "M_BMC_DDR4_MBA0")
	)
	(segment
		(start 74.485754 -43.709082)
		(end 74.269092 -43.925744)
		(width 0.11684)
		(layer "B.Cu")
		(net "M_BMC_DDR4_MBA0")
	)
	(segment
		(start 76.906882 -40.240712)
		(end 76.839572 -40.28567)
		(width 0.11684)
		(layer "B.Cu")
		(net "M_BMC_DDR4_MBA0")
	)
	(segment
		(start 76.668122 -40.447976)
		(end 76.527152 -40.5892)
		(width 0.11684)
		(layer "B.Cu")
		(net "M_BMC_DDR4_MBA0")
	)
	(segment
		(start 76.527152 -40.590978)
		(end 76.396088 -40.715438)
		(width 0.11684)
		(layer "B.Cu")
		(net "M_BMC_DDR4_MBA0")
	)
	(segment
		(start 79.739744 -35.940238)
		(end 79.815944 -35.940238)
		(width 0.11684)
		(layer "B.Cu")
		(net "M_BMC_DDR4_MBA0")
	)
	(segment
		(start 79.815944 -35.940238)
		(end 80.123538 -36.247832)
		(width 0.11684)
		(layer "B.Cu")
		(net "M_BMC_DDR4_MBA0")
	)
	(segment
		(start 79.739744 -37.89299)
		(end 79.739744 -37.959538)
		(width 0.11684)
		(layer "B.Cu")
		(net "M_BMC_DDR4_MBA0")
	)
	(segment
		(start 80.259428 -36.576)
		(end 80.259428 -37.133276)
		(width 0.11684)
		(layer "B.Cu")
		(net "M_BMC_DDR4_MBA0")
	)
	(segment
		(start 80.089756 -37.542978)
		(end 79.739744 -37.89299)
		(width 0.11684)
		(layer "B.Cu")
		(net "M_BMC_DDR4_MBA0")
	)
	(segment
		(start 78.586076 -39.113206)
		(end 78.043278 -39.656004)
		(width 0.11684)
		(layer "B.Cu")
		(net "M_BMC_DDR4_MBA0")
	)
	(segment
		(start 76.396088 -40.715438)
		(end 75.517248 -41.594278)
		(width 0.11684)
		(layer "B.Cu")
		(net "M_BMC_DDR4_MBA0")
	)
	(segment
		(start 75.440286 -41.780206)
		(end 75.440286 -42.02303)
		(width 0.11684)
		(layer "B.Cu")
		(net "M_BMC_DDR4_MBA0")
	)
	(segment
		(start 74.269092 -43.925744)
		(end 74.265536 -43.925744)
		(width 0.11684)
		(layer "B.Cu")
		(net "M_BMC_DDR4_MBA0")
	)
	(segment
		(start 74.639424 -43.074844)
		(end 74.639424 -43.399202)
		(width 0.11684)
		(layer "B.Cu")
		(net "M_BMC_DDR4_MBA0")
	)
	(segment
		(start 77.174598 -40.12946)
		(end 77.124814 -40.150288)
		(width 0.11684)
		(layer "B.Cu")
		(net "M_BMC_DDR4_MBA0")
	)
	(segment
		(start 76.839572 -40.28567)
		(end 76.668122 -40.447976)
		(width 0.11684)
		(layer "B.Cu")
		(net "M_BMC_DDR4_MBA0")
	)
	(segment
		(start 75.362816 -42.23766)
		(end 74.719942 -42.880534)
		(width 0.11684)
		(layer "B.Cu")
		(net "M_BMC_DDR4_MBA0")
	)
	(segment
		(start 79.739744 -37.959538)
		(end 78.586076 -39.113206)
		(width 0.11684)
		(layer "B.Cu")
		(net "M_BMC_DDR4_MBA0")
	)
	(segment
		(start 77.124814 -40.150288)
		(end 76.906882 -40.240712)
		(width 0.11684)
		(layer "B.Cu")
		(net "M_BMC_DDR4_MBA0")
	)
	(segment
		(start 77.68844 -39.89324)
		(end 77.524102 -39.961312)
		(width 0.11684)
		(layer "B.Cu")
		(net "M_BMC_DDR4_MBA0")
	)
	(segment
		(start 76.527152 -40.5892)
		(end 76.527152 -40.590978)
		(width 0.11684)
		(layer "B.Cu")
		(net "M_BMC_DDR4_MBA0")
	)
	(segment
		(start 77.524102 -39.961312)
		(end 77.174598 -40.12946)
		(width 0.11684)
		(layer "B.Cu")
		(net "M_BMC_DDR4_MBA0")
	)
	(segment
		(start 80.123538 -36.247832)
		(end 80.259428 -36.576)
		(width 0.11684)
		(layer "B.Cu")
		(net "M_BMC_DDR4_MBA0")
	)
	(segment
		(start 80.259428 -37.133276)
		(end 80.089756 -37.542978)
		(width 0.11684)
		(layer "B.Cu")
		(net "M_BMC_DDR4_MBA0")
	)
	(arc
		(start 78.043278 -39.656004)
		(mid 77.877534 -39.792082)
		(end 77.68844 -39.89324)
		(width 0.11684)
		(layer "B.Cu")
		(net "M_BMC_DDR4_MBA0")
	)
	(arc
		(start 74.61758 -43.51147)
		(mid 74.561485 -43.616823)
		(end 74.485754 -43.709082)
		(width 0.11684)
		(layer "B.Cu")
		(net "M_BMC_DDR4_MBA0")
	)
	(arc
		(start 74.639424 -43.399202)
		(mid 74.633992 -43.456406)
		(end 74.61758 -43.51147)
		(width 0.11684)
		(layer "B.Cu")
		(net "M_BMC_DDR4_MBA0")
	)
	(arc
		(start 75.440286 -42.02303)
		(mid 75.435036 -42.085998)
		(end 75.419458 -42.147236)
		(width 0.11684)
		(layer "B.Cu")
		(net "M_BMC_DDR4_MBA0")
	)
	(arc
		(start 74.719942 -42.880534)
		(mid 74.660427 -42.969698)
		(end 74.639424 -43.074844)
		(width 0.11684)
		(layer "B.Cu")
		(net "M_BMC_DDR4_MBA0")
	)
	(arc
		(start 75.419458 -42.147236)
		(mid 75.396274 -42.195665)
		(end 75.362816 -42.23766)
		(width 0.11684)
		(layer "B.Cu")
		(net "M_BMC_DDR4_MBA0")
	)
	(arc
		(start 75.517248 -41.594278)
		(mid 75.460303 -41.679597)
		(end 75.440286 -41.780206)
		(width 0.11684)
		(layer "B.Cu")
		(net "M_BMC_DDR4_MBA0")
	)
	(segment
		(start 74.193146 -42.63009)
		(end 74.193146 -41.990518)
		(width 0.08382)
		(layer "In9.Cu")
		(net "M_BMC_DDR4_MBA0")
	)
	(segment
		(start 66.36131 -41.930574)
		(end 66.36131 -41.249854)
		(width 0.08382)
		(layer "In9.Cu")
		(net "M_BMC_DDR4_MBA0")
	)
	(segment
		(start 65.725548 -41.249854)
		(end 65.725548 -41.663874)
		(width 0.08382)
		(layer "In9.Cu")
		(net "M_BMC_DDR4_MBA0")
	)
	(segment
		(start 74.713084 -43.50893)
		(end 75.530456 -43.50893)
		(width 0.08382)
		(layer "In9.Cu")
		(net "M_BMC_DDR4_MBA0")
	)
	(segment
		(start 74.95921 -42.71645)
		(end 74.279506 -42.71645)
		(width 0.08382)
		(layer "In9.Cu")
		(net "M_BMC_DDR4_MBA0")
	)
	(segment
		(start 75.04557 -42.09034)
		(end 75.04557 -42.63009)
		(width 0.08382)
		(layer "In9.Cu")
		(net "M_BMC_DDR4_MBA0")
	)
	(segment
		(start 75.479148 -42.00398)
		(end 75.13193 -42.00398)
		(width 0.08382)
		(layer "In9.Cu")
		(net "M_BMC_DDR4_MBA0")
	)
	(segment
		(start 66.27495 -41.163494)
		(end 65.811908 -41.163494)
		(width 0.08382)
		(layer "In9.Cu")
		(net "M_BMC_DDR4_MBA0")
	)
	(segment
		(start 64.906398 -41.978072)
		(end 64.906398 -43.254168)
		(width 0.08382)
		(layer "In9.Cu")
		(net "M_BMC_DDR4_MBA0")
	)
	(segment
		(start 66.90487 -41.129458)
		(end 66.90487 -41.930574)
		(width 0.08382)
		(layer "In9.Cu")
		(net "M_BMC_DDR4_MBA0")
	)
	(segment
		(start 74.611738 -43.831764)
		(end 74.611738 -43.610276)
		(width 0.08382)
		(layer "In9.Cu")
		(net "M_BMC_DDR4_MBA0")
	)
	(segment
		(start 75.616816 -43.42257)
		(end 75.616816 -42.141648)
		(width 0.08382)
		(layer "In9.Cu")
		(net "M_BMC_DDR4_MBA0")
	)
	(segment
		(start 74.621644 -41.764204)
		(end 74.621644 -41.175686)
		(width 0.08382)
		(layer "In9.Cu")
		(net "M_BMC_DDR4_MBA0")
	)
	(segment
		(start 74.481436 -41.035478)
		(end 66.99885 -41.035478)
		(width 0.08382)
		(layer "In9.Cu")
		(net "M_BMC_DDR4_MBA0")
	)
	(segment
		(start 62.890146 -43.442382)
		(end 62.890146 -43.776138)
		(width 0.08382)
		(layer "In9.Cu")
		(net "M_BMC_DDR4_MBA0")
	)
	(segment
		(start 63.029846 -43.348402)
		(end 62.984126 -43.348402)
		(width 0.08382)
		(layer "In9.Cu")
		(net "M_BMC_DDR4_MBA0")
	)
	(segment
		(start 74.265536 -43.925744)
		(end 74.517758 -43.925744)
		(width 0.08382)
		(layer "In9.Cu")
		(net "M_BMC_DDR4_MBA0")
	)
	(segment
		(start 64.101218 -43.116754)
		(end 64.101218 -42.019982)
		(width 0.08382)
		(layer "In9.Cu")
		(net "M_BMC_DDR4_MBA0")
	)
	(segment
		(start 64.794892 -43.365674)
		(end 64.350138 -43.365674)
		(width 0.08382)
		(layer "In9.Cu")
		(net "M_BMC_DDR4_MBA0")
	)
	(segment
		(start 65.590928 -41.798494)
		(end 65.085976 -41.798494)
		(width 0.08382)
		(layer "In9.Cu")
		(net "M_BMC_DDR4_MBA0")
	)
	(segment
		(start 66.81089 -42.024554)
		(end 66.45529 -42.024554)
		(width 0.08382)
		(layer "In9.Cu")
		(net "M_BMC_DDR4_MBA0")
	)
	(segment
		(start 63.292736 -42.13098)
		(end 63.292736 -43.085512)
		(width 0.08382)
		(layer "In9.Cu")
		(net "M_BMC_DDR4_MBA0")
	)
	(segment
		(start 63.870332 -41.789096)
		(end 63.63462 -41.789096)
		(width 0.08382)
		(layer "In9.Cu")
		(net "M_BMC_DDR4_MBA0")
	)
	(segment
		(start 74.279506 -41.904158)
		(end 74.48169 -41.904158)
		(width 0.08382)
		(layer "In9.Cu")
		(net "M_BMC_DDR4_MBA0")
	)
	(arc
		(start 64.350138 -43.365674)
		(mid 64.174125 -43.292767)
		(end 64.101218 -43.116754)
		(width 0.08382)
		(layer "In9.Cu")
		(net "M_BMC_DDR4_MBA0")
	)
	(arc
		(start 62.984126 -43.348402)
		(mid 62.917672 -43.375928)
		(end 62.890146 -43.442382)
		(width 0.08382)
		(layer "In9.Cu")
		(net "M_BMC_DDR4_MBA0")
	)
	(arc
		(start 75.616816 -42.141648)
		(mid 75.576494 -42.044302)
		(end 75.479148 -42.00398)
		(width 0.08382)
		(layer "In9.Cu")
		(net "M_BMC_DDR4_MBA0")
	)
	(arc
		(start 64.906398 -43.254168)
		(mid 64.873739 -43.333015)
		(end 64.794892 -43.365674)
		(width 0.08382)
		(layer "In9.Cu")
		(net "M_BMC_DDR4_MBA0")
	)
	(arc
		(start 64.101218 -42.019982)
		(mid 64.033593 -41.856721)
		(end 63.870332 -41.789096)
		(width 0.08382)
		(layer "In9.Cu")
		(net "M_BMC_DDR4_MBA0")
	)
	(arc
		(start 75.13193 -42.00398)
		(mid 75.070864 -42.029274)
		(end 75.04557 -42.09034)
		(width 0.08382)
		(layer "In9.Cu")
		(net "M_BMC_DDR4_MBA0")
	)
	(arc
		(start 66.45529 -42.024554)
		(mid 66.388836 -41.997028)
		(end 66.36131 -41.930574)
		(width 0.08382)
		(layer "In9.Cu")
		(net "M_BMC_DDR4_MBA0")
	)
	(arc
		(start 75.530456 -43.50893)
		(mid 75.591522 -43.483636)
		(end 75.616816 -43.42257)
		(width 0.08382)
		(layer "In9.Cu")
		(net "M_BMC_DDR4_MBA0")
	)
	(arc
		(start 75.04557 -42.63009)
		(mid 75.020276 -42.691156)
		(end 74.95921 -42.71645)
		(width 0.08382)
		(layer "In9.Cu")
		(net "M_BMC_DDR4_MBA0")
	)
	(arc
		(start 74.621644 -41.175686)
		(mid 74.580578 -41.076544)
		(end 74.481436 -41.035478)
		(width 0.08382)
		(layer "In9.Cu")
		(net "M_BMC_DDR4_MBA0")
	)
	(arc
		(start 63.292736 -43.085512)
		(mid 63.215737 -43.271403)
		(end 63.029846 -43.348402)
		(width 0.08382)
		(layer "In9.Cu")
		(net "M_BMC_DDR4_MBA0")
	)
	(arc
		(start 74.611738 -43.610276)
		(mid 74.641422 -43.538614)
		(end 74.713084 -43.50893)
		(width 0.08382)
		(layer "In9.Cu")
		(net "M_BMC_DDR4_MBA0")
	)
	(arc
		(start 65.725548 -41.663874)
		(mid 65.686119 -41.759065)
		(end 65.590928 -41.798494)
		(width 0.08382)
		(layer "In9.Cu")
		(net "M_BMC_DDR4_MBA0")
	)
	(arc
		(start 74.193146 -41.990518)
		(mid 74.21844 -41.929452)
		(end 74.279506 -41.904158)
		(width 0.08382)
		(layer "In9.Cu")
		(net "M_BMC_DDR4_MBA0")
	)
	(arc
		(start 65.811908 -41.163494)
		(mid 65.750842 -41.188788)
		(end 65.725548 -41.249854)
		(width 0.08382)
		(layer "In9.Cu")
		(net "M_BMC_DDR4_MBA0")
	)
	(arc
		(start 66.99885 -41.035478)
		(mid 66.932396 -41.063004)
		(end 66.90487 -41.129458)
		(width 0.08382)
		(layer "In9.Cu")
		(net "M_BMC_DDR4_MBA0")
	)
	(arc
		(start 74.517758 -43.925744)
		(mid 74.584212 -43.898218)
		(end 74.611738 -43.831764)
		(width 0.08382)
		(layer "In9.Cu")
		(net "M_BMC_DDR4_MBA0")
	)
	(arc
		(start 65.085976 -41.798494)
		(mid 64.958995 -41.851091)
		(end 64.906398 -41.978072)
		(width 0.08382)
		(layer "In9.Cu")
		(net "M_BMC_DDR4_MBA0")
	)
	(arc
		(start 74.279506 -42.71645)
		(mid 74.21844 -42.691156)
		(end 74.193146 -42.63009)
		(width 0.08382)
		(layer "In9.Cu")
		(net "M_BMC_DDR4_MBA0")
	)
	(arc
		(start 66.90487 -41.930574)
		(mid 66.877344 -41.997028)
		(end 66.81089 -42.024554)
		(width 0.08382)
		(layer "In9.Cu")
		(net "M_BMC_DDR4_MBA0")
	)
	(arc
		(start 74.48169 -41.904158)
		(mid 74.580652 -41.863166)
		(end 74.621644 -41.764204)
		(width 0.08382)
		(layer "In9.Cu")
		(net "M_BMC_DDR4_MBA0")
	)
	(arc
		(start 66.36131 -41.249854)
		(mid 66.336016 -41.188788)
		(end 66.27495 -41.163494)
		(width 0.08382)
		(layer "In9.Cu")
		(net "M_BMC_DDR4_MBA0")
	)
	(arc
		(start 63.63462 -41.789096)
		(mid 63.392872 -41.889232)
		(end 63.292736 -42.13098)
		(width 0.08382)
		(layer "In9.Cu")
		(net "M_BMC_DDR4_MBA0")
	)
	(segment
		(start 69.984112 -41.607994)
		(end 68.932298 -41.607994)
		(width 0.11684)
		(layer "F.Cu")
		(net "M_BMC_DDR4_MACT_N")
	)
	(segment
		(start 71.538084 -41.607994)
		(end 69.984112 -41.607994)
		(width 0.11684)
		(layer "F.Cu")
		(net "M_BMC_DDR4_MACT_N")
	)
	(segment
		(start 70.562724 -42.39133)
		(end 70.562724 -42.391076)
		(width 0.11684)
		(layer "F.Cu")
		(net "M_BMC_DDR4_MACT_N")
	)
	(segment
		(start 70.72376 -42.300398)
		(end 71.538084 -42.300398)
		(width 0.11684)
		(layer "F.Cu")
		(net "M_BMC_DDR4_MACT_N")
	)
	(segment
		(start 67.003676 -40.199564)
		(end 66.44767 -40.199564)
		(width 0.11684)
		(layer "F.Cu")
		(net "M_BMC_DDR4_MACT_N")
	)
	(segment
		(start 71.652384 -42.186098)
		(end 71.652384 -41.722294)
		(width 0.11684)
		(layer "F.Cu")
		(net "M_BMC_DDR4_MACT_N")
	)
	(segment
		(start 64.894968 -44.970954)
		(end 64.894968 -44.971208)
		(width 0.11684)
		(layer "F.Cu")
		(net "M_BMC_DDR4_MACT_N")
	)
	(segment
		(start 67.194684 -41.238932)
		(end 67.194684 -40.390572)
		(width 0.11684)
		(layer "F.Cu")
		(net "M_BMC_DDR4_MACT_N")
	)
	(segment
		(start 70.197218 -44.565824)
		(end 70.197218 -44.436284)
		(width 0.11684)
		(layer "F.Cu")
		(net "M_BMC_DDR4_MACT_N")
	)
	(segment
		(start 65.707514 -43.430698)
		(end 65.707514 -43.76293)
		(width 0.11684)
		(layer "F.Cu")
		(net "M_BMC_DDR4_MACT_N")
	)
	(segment
		(start 68.709286 -41.430702)
		(end 67.386454 -41.430702)
		(width 0.11684)
		(layer "F.Cu")
		(net "M_BMC_DDR4_MACT_N")
	)
	(segment
		(start 70.5104 -44.123102)
		(end 70.5104 -42.557446)
		(width 0.11684)
		(layer "F.Cu")
		(net "M_BMC_DDR4_MACT_N")
	)
	(segment
		(start 69.658484 -44.718732)
		(end 70.04431 -44.718732)
		(width 0.11684)
		(layer "F.Cu")
		(net "M_BMC_DDR4_MACT_N")
	)
	(segment
		(start 69.505576 -44.263818)
		(end 69.505576 -44.565824)
		(width 0.11684)
		(layer "F.Cu")
		(net "M_BMC_DDR4_MACT_N")
	)
	(segment
		(start 75.03414 -45.52569)
		(end 74.652378 -45.907452)
		(width 0.11684)
		(layer "F.Cu")
		(net "M_BMC_DDR4_MACT_N")
	)
	(segment
		(start 66.1797 -42.702988)
		(end 65.888616 -42.994072)
		(width 0.11684)
		(layer "F.Cu")
		(net "M_BMC_DDR4_MACT_N")
	)
	(segment
		(start 66.2559 -40.391334)
		(end 66.2559 -42.519092)
		(width 0.11684)
		(layer "F.Cu")
		(net "M_BMC_DDR4_MACT_N")
	)
	(segment
		(start 65.42786 -44.438062)
		(end 64.894968 -44.970954)
		(width 0.11684)
		(layer "F.Cu")
		(net "M_BMC_DDR4_MACT_N")
	)
	(via
		(at 69.984112 -41.607994)
		(size 0.762)
		(drill 0.381)
		(layers "F.Cu" "B.Cu")
		(net "M_BMC_DDR4_MACT_N")
	)
	(via
		(at 75.03414 -45.52569)
		(size 0.4572)
		(drill 0.254)
		(layers "F.Cu" "B.Cu")
		(net "M_BMC_DDR4_MACT_N")
	)
	(via
		(at 69.505576 -44.263818)
		(size 0.4572)
		(drill 0.254)
		(layers "F.Cu" "B.Cu")
		(net "M_BMC_DDR4_MACT_N")
	)
	(arc
		(start 70.535038 -42.443146)
		(mid 70.548136 -42.41684)
		(end 70.562724 -42.39133)
		(width 0.11684)
		(layer "F.Cu")
		(net "M_BMC_DDR4_MACT_N")
	)
	(arc
		(start 65.707514 -43.76293)
		(mid 65.634835 -44.128311)
		(end 65.42786 -44.438062)
		(width 0.11684)
		(layer "F.Cu")
		(net "M_BMC_DDR4_MACT_N")
	)
	(arc
		(start 70.374256 -44.259246)
		(mid 70.470524 -44.21937)
		(end 70.5104 -44.123102)
		(width 0.11684)
		(layer "F.Cu")
		(net "M_BMC_DDR4_MACT_N")
	)
	(arc
		(start 71.652384 -41.722294)
		(mid 71.618906 -41.641472)
		(end 71.538084 -41.607994)
		(width 0.11684)
		(layer "F.Cu")
		(net "M_BMC_DDR4_MACT_N")
	)
	(arc
		(start 69.505576 -44.565824)
		(mid 69.550362 -44.673946)
		(end 69.658484 -44.718732)
		(width 0.11684)
		(layer "F.Cu")
		(net "M_BMC_DDR4_MACT_N")
	)
	(arc
		(start 67.386454 -41.430702)
		(mid 67.250852 -41.374534)
		(end 67.194684 -41.238932)
		(width 0.11684)
		(layer "F.Cu")
		(net "M_BMC_DDR4_MACT_N")
	)
	(arc
		(start 70.04431 -44.718732)
		(mid 70.152432 -44.673946)
		(end 70.197218 -44.565824)
		(width 0.11684)
		(layer "F.Cu")
		(net "M_BMC_DDR4_MACT_N")
	)
	(arc
		(start 70.5104 -42.557446)
		(mid 70.516535 -42.49896)
		(end 70.535038 -42.443146)
		(width 0.11684)
		(layer "F.Cu")
		(net "M_BMC_DDR4_MACT_N")
	)
	(arc
		(start 68.932298 -41.607994)
		(mid 68.860978 -41.583216)
		(end 68.820792 -41.519348)
		(width 0.11684)
		(layer "F.Cu")
		(net "M_BMC_DDR4_MACT_N")
	)
	(arc
		(start 68.820792 -41.519348)
		(mid 68.780486 -41.455616)
		(end 68.709286 -41.430702)
		(width 0.11684)
		(layer "F.Cu")
		(net "M_BMC_DDR4_MACT_N")
	)
	(arc
		(start 66.2559 -42.519092)
		(mid 66.236101 -42.618626)
		(end 66.1797 -42.702988)
		(width 0.11684)
		(layer "F.Cu")
		(net "M_BMC_DDR4_MACT_N")
	)
	(arc
		(start 70.197218 -44.436284)
		(mid 70.249071 -44.311099)
		(end 70.374256 -44.259246)
		(width 0.11684)
		(layer "F.Cu")
		(net "M_BMC_DDR4_MACT_N")
	)
	(arc
		(start 66.44767 -40.199564)
		(mid 66.312068 -40.255732)
		(end 66.2559 -40.391334)
		(width 0.11684)
		(layer "F.Cu")
		(net "M_BMC_DDR4_MACT_N")
	)
	(arc
		(start 70.562724 -42.391076)
		(mid 70.631371 -42.324672)
		(end 70.72376 -42.300398)
		(width 0.11684)
		(layer "F.Cu")
		(net "M_BMC_DDR4_MACT_N")
	)
	(arc
		(start 65.888616 -42.994072)
		(mid 65.754655 -43.194369)
		(end 65.707514 -43.430698)
		(width 0.11684)
		(layer "F.Cu")
		(net "M_BMC_DDR4_MACT_N")
	)
	(arc
		(start 71.538084 -42.300398)
		(mid 71.618906 -42.26692)
		(end 71.652384 -42.186098)
		(width 0.11684)
		(layer "F.Cu")
		(net "M_BMC_DDR4_MACT_N")
	)
	(arc
		(start 67.194684 -40.390572)
		(mid 67.138739 -40.255509)
		(end 67.003676 -40.199564)
		(width 0.11684)
		(layer "F.Cu")
		(net "M_BMC_DDR4_MACT_N")
	)
	(segment
		(start 80.798416 -40.990012)
		(end 80.729836 -40.990012)
		(width 0.11684)
		(layer "B.Cu")
		(net "M_BMC_DDR4_MACT_N")
	)
	(segment
		(start 78.431644 -42.71391)
		(end 78.395576 -42.71391)
		(width 0.11684)
		(layer "B.Cu")
		(net "M_BMC_DDR4_MACT_N")
	)
	(segment
		(start 79.850234 -41.919144)
		(end 79.843376 -41.919906)
		(width 0.11684)
		(layer "B.Cu")
		(net "M_BMC_DDR4_MACT_N")
	)
	(segment
		(start 78.395576 -42.71391)
		(end 78.395068 -42.714418)
		(width 0.11684)
		(layer "B.Cu")
		(net "M_BMC_DDR4_MACT_N")
	)
	(segment
		(start 77.244448 -42.78376)
		(end 77.06233 -42.965878)
		(width 0.11684)
		(layer "B.Cu")
		(net "M_BMC_DDR4_MACT_N")
	)
	(segment
		(start 80.283812 -41.63314)
		(end 80.131158 -41.785794)
		(width 0.11684)
		(layer "B.Cu")
		(net "M_BMC_DDR4_MACT_N")
	)
	(segment
		(start 81.143348 -41.334944)
		(end 80.798416 -40.990012)
		(width 0.11684)
		(layer "B.Cu")
		(net "M_BMC_DDR4_MACT_N")
	)
	(segment
		(start 80.423258 -41.29659)
		(end 80.283812 -41.63314)
		(width 0.11684)
		(layer "B.Cu")
		(net "M_BMC_DDR4_MACT_N")
	)
	(segment
		(start 78.395068 -42.714418)
		(end 78.072996 -42.714418)
		(width 0.11684)
		(layer "B.Cu")
		(net "M_BMC_DDR4_MACT_N")
	)
	(segment
		(start 79.44485 -42.090594)
		(end 79.097378 -42.438066)
		(width 0.11684)
		(layer "B.Cu")
		(net "M_BMC_DDR4_MACT_N")
	)
	(segment
		(start 76.655422 -44.702222)
		(end 76.151486 -45.206158)
		(width 0.11684)
		(layer "B.Cu")
		(net "M_BMC_DDR4_MACT_N")
	)
	(segment
		(start 82.76717 -41.506394)
		(end 81.557368 -41.506394)
		(width 0.11684)
		(layer "B.Cu")
		(net "M_BMC_DDR4_MACT_N")
	)
	(segment
		(start 81.557368 -41.506394)
		(end 81.143348 -41.334944)
		(width 0.11684)
		(layer "B.Cu")
		(net "M_BMC_DDR4_MACT_N")
	)
	(segment
		(start 76.962508 -43.20667)
		(end 76.962508 -43.96105)
		(width 0.11684)
		(layer "B.Cu")
		(net "M_BMC_DDR4_MACT_N")
	)
	(segment
		(start 78.072996 -42.714418)
		(end 78.072488 -42.71391)
		(width 0.11684)
		(layer "B.Cu")
		(net "M_BMC_DDR4_MACT_N")
	)
	(segment
		(start 78.072488 -42.71391)
		(end 77.413104 -42.71391)
		(width 0.11684)
		(layer "B.Cu")
		(net "M_BMC_DDR4_MACT_N")
	)
	(segment
		(start 80.729836 -40.990012)
		(end 80.423258 -41.29659)
		(width 0.11684)
		(layer "B.Cu")
		(net "M_BMC_DDR4_MACT_N")
	)
	(segment
		(start 75.380088 -45.52569)
		(end 75.03414 -45.52569)
		(width 0.11684)
		(layer "B.Cu")
		(net "M_BMC_DDR4_MACT_N")
	)
	(arc
		(start 76.151486 -45.206158)
		(mid 75.797566 -45.44264)
		(end 75.380088 -45.52569)
		(width 0.11684)
		(layer "B.Cu")
		(net "M_BMC_DDR4_MACT_N")
	)
	(arc
		(start 79.533496 -42.030904)
		(mid 79.486258 -42.056418)
		(end 79.44485 -42.090594)
		(width 0.11684)
		(layer "B.Cu")
		(net "M_BMC_DDR4_MACT_N")
	)
	(arc
		(start 76.962508 -43.96105)
		(mid 76.882699 -44.362187)
		(end 76.655422 -44.702222)
		(width 0.11684)
		(layer "B.Cu")
		(net "M_BMC_DDR4_MACT_N")
	)
	(arc
		(start 80.131158 -41.785794)
		(mid 80.002215 -41.87672)
		(end 79.850234 -41.919144)
		(width 0.11684)
		(layer "B.Cu")
		(net "M_BMC_DDR4_MACT_N")
	)
	(arc
		(start 77.06233 -42.965878)
		(mid 76.988458 -43.07634)
		(end 76.962508 -43.20667)
		(width 0.11684)
		(layer "B.Cu")
		(net "M_BMC_DDR4_MACT_N")
	)
	(arc
		(start 77.413104 -42.71391)
		(mid 77.321832 -42.732065)
		(end 77.244448 -42.78376)
		(width 0.11684)
		(layer "B.Cu")
		(net "M_BMC_DDR4_MACT_N")
	)
	(arc
		(start 79.843376 -41.919906)
		(mid 79.790497 -41.928943)
		(end 79.73949 -41.94556)
		(width 0.11684)
		(layer "B.Cu")
		(net "M_BMC_DDR4_MACT_N")
	)
	(arc
		(start 79.73949 -41.94556)
		(mid 79.636449 -41.988127)
		(end 79.533496 -42.030904)
		(width 0.11684)
		(layer "B.Cu")
		(net "M_BMC_DDR4_MACT_N")
	)
	(arc
		(start 79.097378 -42.438066)
		(mid 78.791951 -42.642209)
		(end 78.431644 -42.71391)
		(width 0.11684)
		(layer "B.Cu")
		(net "M_BMC_DDR4_MACT_N")
	)
	(segment
		(start 71.085456 -45.843698)
		(end 70.295516 -45.053758)
		(width 0.08382)
		(layer "In2.Cu")
		(net "M_BMC_DDR4_MACT_N")
	)
	(segment
		(start 75.0316 -45.52823)
		(end 75.0316 -46.285658)
		(width 0.08382)
		(layer "In2.Cu")
		(net "M_BMC_DDR4_MACT_N")
	)
	(segment
		(start 74.479912 -45.90288)
		(end 73.356216 -45.90288)
		(width 0.08382)
		(layer "In2.Cu")
		(net "M_BMC_DDR4_MACT_N")
	)
	(segment
		(start 70.02018 -44.263818)
		(end 69.505576 -44.263818)
		(width 0.08382)
		(layer "In2.Cu")
		(net "M_BMC_DDR4_MACT_N")
	)
	(segment
		(start 73.222104 -45.847254)
		(end 72.889364 -45.514514)
		(width 0.08382)
		(layer "In2.Cu")
		(net "M_BMC_DDR4_MACT_N")
	)
	(segment
		(start 71.790052 -45.927772)
		(end 71.288402 -45.927772)
		(width 0.08382)
		(layer "In2.Cu")
		(net "M_BMC_DDR4_MACT_N")
	)
	(segment
		(start 74.573892 -46.285658)
		(end 74.573892 -45.99686)
		(width 0.08382)
		(layer "In2.Cu")
		(net "M_BMC_DDR4_MACT_N")
	)
	(segment
		(start 74.93762 -46.379638)
		(end 74.667872 -46.379638)
		(width 0.08382)
		(layer "In2.Cu")
		(net "M_BMC_DDR4_MACT_N")
	)
	(segment
		(start 75.03414 -45.52569)
		(end 75.0316 -45.52823)
		(width 0.08382)
		(layer "In2.Cu")
		(net "M_BMC_DDR4_MACT_N")
	)
	(segment
		(start 70.139052 -44.67606)
		(end 70.139052 -44.38269)
		(width 0.08382)
		(layer "In2.Cu")
		(net "M_BMC_DDR4_MACT_N")
	)
	(segment
		(start 70.114414 -44.323254)
		(end 70.079616 -44.288456)
		(width 0.08382)
		(layer "In2.Cu")
		(net "M_BMC_DDR4_MACT_N")
	)
	(segment
		(start 71.941436 -45.598842)
		(end 71.941436 -45.776388)
		(width 0.08382)
		(layer "In2.Cu")
		(net "M_BMC_DDR4_MACT_N")
	)
	(segment
		(start 72.804782 -45.479462)
		(end 72.060816 -45.479462)
		(width 0.08382)
		(layer "In2.Cu")
		(net "M_BMC_DDR4_MACT_N")
	)
	(arc
		(start 74.573892 -45.99686)
		(mid 74.546366 -45.930406)
		(end 74.479912 -45.90288)
		(width 0.08382)
		(layer "In2.Cu")
		(net "M_BMC_DDR4_MACT_N")
	)
	(arc
		(start 74.667872 -46.379638)
		(mid 74.601418 -46.352112)
		(end 74.573892 -46.285658)
		(width 0.08382)
		(layer "In2.Cu")
		(net "M_BMC_DDR4_MACT_N")
	)
	(arc
		(start 71.288402 -45.927772)
		(mid 71.178564 -45.905924)
		(end 71.085456 -45.843698)
		(width 0.08382)
		(layer "In2.Cu")
		(net "M_BMC_DDR4_MACT_N")
	)
	(arc
		(start 72.889364 -45.514514)
		(mid 72.850557 -45.488584)
		(end 72.804782 -45.479462)
		(width 0.08382)
		(layer "In2.Cu")
		(net "M_BMC_DDR4_MACT_N")
	)
	(arc
		(start 75.0316 -46.285658)
		(mid 75.004074 -46.352112)
		(end 74.93762 -46.379638)
		(width 0.08382)
		(layer "In2.Cu")
		(net "M_BMC_DDR4_MACT_N")
	)
	(arc
		(start 70.139052 -44.38269)
		(mid 70.132652 -44.350516)
		(end 70.114414 -44.323254)
		(width 0.08382)
		(layer "In2.Cu")
		(net "M_BMC_DDR4_MACT_N")
	)
	(arc
		(start 72.060816 -45.479462)
		(mid 71.976402 -45.514428)
		(end 71.941436 -45.598842)
		(width 0.08382)
		(layer "In2.Cu")
		(net "M_BMC_DDR4_MACT_N")
	)
	(arc
		(start 70.079616 -44.288456)
		(mid 70.052347 -44.270235)
		(end 70.02018 -44.263818)
		(width 0.08382)
		(layer "In2.Cu")
		(net "M_BMC_DDR4_MACT_N")
	)
	(arc
		(start 73.356216 -45.90288)
		(mid 73.283621 -45.888422)
		(end 73.222104 -45.847254)
		(width 0.08382)
		(layer "In2.Cu")
		(net "M_BMC_DDR4_MACT_N")
	)
	(arc
		(start 70.295516 -45.053758)
		(mid 70.179728 -44.880469)
		(end 70.139052 -44.67606)
		(width 0.08382)
		(layer "In2.Cu")
		(net "M_BMC_DDR4_MACT_N")
	)
	(arc
		(start 71.941436 -45.776388)
		(mid 71.897097 -45.883433)
		(end 71.790052 -45.927772)
		(width 0.08382)
		(layer "In2.Cu")
		(net "M_BMC_DDR4_MACT_N")
	)
	(segment
		(start 83.885786 -43.157394)
		(end 83.74253 -43.014138)
		(width 0.11684)
		(layer "F.Cu")
		(net "M_BMC_DDR4_MA<9>")
	)
	(segment
		(start 84.17687 -43.157394)
		(end 83.885786 -43.157394)
		(width 0.11684)
		(layer "F.Cu")
		(net "M_BMC_DDR4_MA<9>")
	)
	(segment
		(start 83.155282 -43.014138)
		(end 82.676492 -42.535348)
		(width 0.11684)
		(layer "F.Cu")
		(net "M_BMC_DDR4_MA<9>")
	)
	(segment
		(start 80.946244 -42.310558)
		(end 78.249272 -42.310558)
		(width 0.11684)
		(layer "F.Cu")
		(net "M_BMC_DDR4_MA<9>")
	)
	(segment
		(start 82.676492 -42.535348)
		(end 81.171034 -42.535348)
		(width 0.11684)
		(layer "F.Cu")
		(net "M_BMC_DDR4_MA<9>")
	)
	(segment
		(start 83.74253 -43.014138)
		(end 83.155282 -43.014138)
		(width 0.11684)
		(layer "F.Cu")
		(net "M_BMC_DDR4_MA<9>")
	)
	(segment
		(start 64.894968 -48.9712)
		(end 65.290192 -48.575976)
		(width 0.11684)
		(layer "F.Cu")
		(net "M_BMC_DDR4_MA<9>")
	)
	(segment
		(start 81.171034 -42.535348)
		(end 80.946244 -42.310558)
		(width 0.11684)
		(layer "F.Cu")
		(net "M_BMC_DDR4_MA<9>")
	)
	(segment
		(start 84.8995 -43.157394)
		(end 84.17687 -43.157394)
		(width 0.11684)
		(layer "F.Cu")
		(net "M_BMC_DDR4_MA<9>")
	)
	(segment
		(start 78.234032 -42.325798)
		(end 77.85227 -42.70756)
		(width 0.11684)
		(layer "F.Cu")
		(net "M_BMC_DDR4_MA<9>")
	)
	(segment
		(start 78.249272 -42.310558)
		(end 78.234032 -42.325798)
		(width 0.11684)
		(layer "F.Cu")
		(net "M_BMC_DDR4_MA<9>")
	)
	(via
		(at 65.290192 -48.575976)
		(size 0.4572)
		(drill 0.254)
		(layers "F.Cu" "B.Cu")
		(net "M_BMC_DDR4_MA<9>")
	)
	(via
		(at 84.17687 -43.157394)
		(size 0.508)
		(drill 0.254)
		(layers "F.Cu" "B.Cu")
		(net "M_BMC_DDR4_MA<9>")
	)
	(via
		(at 78.234032 -42.325798)
		(size 0.4572)
		(drill 0.254)
		(layers "F.Cu" "B.Cu")
		(net "M_BMC_DDR4_MA<9>")
	)
	(segment
		(start 84.881212 -43.411394)
		(end 84.627212 -43.157394)
		(width 0.11684)
		(layer "B.Cu")
		(net "M_BMC_DDR4_MA<9>")
	)
	(segment
		(start 84.627212 -43.157394)
		(end 84.17687 -43.157394)
		(width 0.11684)
		(layer "B.Cu")
		(net "M_BMC_DDR4_MA<9>")
	)
	(segment
		(start 67.300348 -48.80356)
		(end 67.371976 -48.80356)
		(width 0.08382)
		(layer "In2.Cu")
		(net "M_BMC_DDR4_MA<9>")
	)
	(segment
		(start 75.013566 -48.98009)
		(end 75.013566 -48.688498)
		(width 0.08382)
		(layer "In2.Cu")
		(net "M_BMC_DDR4_MA<9>")
	)
	(segment
		(start 75.557126 -48.688498)
		(end 75.557126 -48.98009)
		(width 0.08382)
		(layer "In2.Cu")
		(net "M_BMC_DDR4_MA<9>")
	)
	(segment
		(start 80.307942 -42.325798)
		(end 78.234032 -42.325798)
		(width 0.08382)
		(layer "In2.Cu")
		(net "M_BMC_DDR4_MA<9>")
	)
	(segment
		(start 67.592702 -48.582834)
		(end 67.592702 -48.58258)
		(width 0.08382)
		(layer "In2.Cu")
		(net "M_BMC_DDR4_MA<9>")
	)
	(segment
		(start 68.105782 -48.58258)
		(end 68.105782 -48.648874)
		(width 0.08382)
		(layer "In2.Cu")
		(net "M_BMC_DDR4_MA<9>")
	)
	(segment
		(start 67.813428 -48.361854)
		(end 67.885056 -48.361854)
		(width 0.08382)
		(layer "In2.Cu")
		(net "M_BMC_DDR4_MA<9>")
	)
	(segment
		(start 72.06996 -49.06645)
		(end 74.927206 -49.06645)
		(width 0.08382)
		(layer "In2.Cu")
		(net "M_BMC_DDR4_MA<9>")
	)
	(segment
		(start 67.079622 -48.58258)
		(end 67.079622 -48.582834)
		(width 0.08382)
		(layer "In2.Cu")
		(net "M_BMC_DDR4_MA<9>")
	)
	(segment
		(start 66.787268 -48.361854)
		(end 66.858896 -48.361854)
		(width 0.08382)
		(layer "In2.Cu")
		(net "M_BMC_DDR4_MA<9>")
	)
	(segment
		(start 65.290192 -48.575976)
		(end 65.552574 -48.575976)
		(width 0.08382)
		(layer "In2.Cu")
		(net "M_BMC_DDR4_MA<9>")
	)
	(segment
		(start 65.736216 -48.652176)
		(end 65.793112 -48.709072)
		(width 0.08382)
		(layer "In2.Cu")
		(net "M_BMC_DDR4_MA<9>")
	)
	(segment
		(start 75.099926 -48.602138)
		(end 75.470766 -48.602138)
		(width 0.08382)
		(layer "In2.Cu")
		(net "M_BMC_DDR4_MA<9>")
	)
	(segment
		(start 68.363592 -48.918622)
		(end 71.508366 -48.918622)
		(width 0.08382)
		(layer "In2.Cu")
		(net "M_BMC_DDR4_MA<9>")
	)
	(segment
		(start 75.643486 -49.06645)
		(end 80.307942 -49.06645)
		(width 0.08382)
		(layer "In2.Cu")
		(net "M_BMC_DDR4_MA<9>")
	)
	(segment
		(start 80.394302 -48.98009)
		(end 80.394302 -42.412158)
		(width 0.08382)
		(layer "In2.Cu")
		(net "M_BMC_DDR4_MA<9>")
	)
	(segment
		(start 71.748396 -48.966374)
		(end 71.916544 -49.03597)
		(width 0.08382)
		(layer "In2.Cu")
		(net "M_BMC_DDR4_MA<9>")
	)
	(segment
		(start 66.566542 -48.582834)
		(end 66.566542 -48.58258)
		(width 0.08382)
		(layer "In2.Cu")
		(net "M_BMC_DDR4_MA<9>")
	)
	(segment
		(start 66.021204 -48.80356)
		(end 66.345816 -48.80356)
		(width 0.08382)
		(layer "In2.Cu")
		(net "M_BMC_DDR4_MA<9>")
	)
	(arc
		(start 67.079622 -48.582834)
		(mid 67.144271 -48.738911)
		(end 67.300348 -48.80356)
		(width 0.08382)
		(layer "In2.Cu")
		(net "M_BMC_DDR4_MA<9>")
	)
	(arc
		(start 66.858896 -48.361854)
		(mid 67.014973 -48.426503)
		(end 67.079622 -48.58258)
		(width 0.08382)
		(layer "In2.Cu")
		(net "M_BMC_DDR4_MA<9>")
	)
	(arc
		(start 71.916544 -49.03597)
		(mid 71.991751 -49.058772)
		(end 72.06996 -49.06645)
		(width 0.08382)
		(layer "In2.Cu")
		(net "M_BMC_DDR4_MA<9>")
	)
	(arc
		(start 65.793112 -48.709072)
		(mid 65.897761 -48.778997)
		(end 66.021204 -48.80356)
		(width 0.08382)
		(layer "In2.Cu")
		(net "M_BMC_DDR4_MA<9>")
	)
	(arc
		(start 80.394302 -42.412158)
		(mid 80.369008 -42.351092)
		(end 80.307942 -42.325798)
		(width 0.08382)
		(layer "In2.Cu")
		(net "M_BMC_DDR4_MA<9>")
	)
	(arc
		(start 67.592702 -48.58258)
		(mid 67.657351 -48.426503)
		(end 67.813428 -48.361854)
		(width 0.08382)
		(layer "In2.Cu")
		(net "M_BMC_DDR4_MA<9>")
	)
	(arc
		(start 66.566542 -48.58258)
		(mid 66.631191 -48.426503)
		(end 66.787268 -48.361854)
		(width 0.08382)
		(layer "In2.Cu")
		(net "M_BMC_DDR4_MA<9>")
	)
	(arc
		(start 66.345816 -48.80356)
		(mid 66.501893 -48.738911)
		(end 66.566542 -48.582834)
		(width 0.08382)
		(layer "In2.Cu")
		(net "M_BMC_DDR4_MA<9>")
	)
	(arc
		(start 65.552574 -48.575976)
		(mid 65.651958 -48.595838)
		(end 65.736216 -48.652176)
		(width 0.08382)
		(layer "In2.Cu")
		(net "M_BMC_DDR4_MA<9>")
	)
	(arc
		(start 71.508366 -48.918622)
		(mid 71.630733 -48.930676)
		(end 71.748396 -48.966374)
		(width 0.08382)
		(layer "In2.Cu")
		(net "M_BMC_DDR4_MA<9>")
	)
	(arc
		(start 75.470766 -48.602138)
		(mid 75.531832 -48.627432)
		(end 75.557126 -48.688498)
		(width 0.08382)
		(layer "In2.Cu")
		(net "M_BMC_DDR4_MA<9>")
	)
	(arc
		(start 68.271898 -48.90008)
		(mid 68.316817 -48.913942)
		(end 68.363592 -48.918622)
		(width 0.08382)
		(layer "In2.Cu")
		(net "M_BMC_DDR4_MA<9>")
	)
	(arc
		(start 74.927206 -49.06645)
		(mid 74.988272 -49.041156)
		(end 75.013566 -48.98009)
		(width 0.08382)
		(layer "In2.Cu")
		(net "M_BMC_DDR4_MA<9>")
	)
	(arc
		(start 67.885056 -48.361854)
		(mid 68.041133 -48.426503)
		(end 68.105782 -48.58258)
		(width 0.08382)
		(layer "In2.Cu")
		(net "M_BMC_DDR4_MA<9>")
	)
	(arc
		(start 80.307942 -49.06645)
		(mid 80.369008 -49.041156)
		(end 80.394302 -48.98009)
		(width 0.08382)
		(layer "In2.Cu")
		(net "M_BMC_DDR4_MA<9>")
	)
	(arc
		(start 75.013566 -48.688498)
		(mid 75.03886 -48.627432)
		(end 75.099926 -48.602138)
		(width 0.08382)
		(layer "In2.Cu")
		(net "M_BMC_DDR4_MA<9>")
	)
	(arc
		(start 68.105782 -48.648874)
		(mid 68.151062 -48.799464)
		(end 68.271898 -48.90008)
		(width 0.08382)
		(layer "In2.Cu")
		(net "M_BMC_DDR4_MA<9>")
	)
	(arc
		(start 67.371976 -48.80356)
		(mid 67.528053 -48.738911)
		(end 67.592702 -48.582834)
		(width 0.08382)
		(layer "In2.Cu")
		(net "M_BMC_DDR4_MA<9>")
	)
	(arc
		(start 75.557126 -48.98009)
		(mid 75.58242 -49.041156)
		(end 75.643486 -49.06645)
		(width 0.08382)
		(layer "In2.Cu")
		(net "M_BMC_DDR4_MA<9>")
	)
	(segment
		(start 71.914512 -45.449744)
		(end 72.176386 -45.711618)
		(width 0.11684)
		(layer "F.Cu")
		(net "M_BMC_DDR4_MA<8>")
	)
	(segment
		(start 74.23404 -43.089322)
		(end 74.225658 -43.097704)
		(width 0.11684)
		(layer "F.Cu")
		(net "M_BMC_DDR4_MA<8>")
	)
	(segment
		(start 69.54774 -47.64786)
		(end 71.745856 -45.449744)
		(width 0.11684)
		(layer "F.Cu")
		(net "M_BMC_DDR4_MA<8>")
	)
	(segment
		(start 68.139056 -48.934116)
		(end 67.977004 -48.934116)
		(width 0.11684)
		(layer "F.Cu")
		(net "M_BMC_DDR4_MA<8>")
	)
	(segment
		(start 71.837296 -46.35627)
		(end 72.242934 -46.761908)
		(width 0.11684)
		(layer "F.Cu")
		(net "M_BMC_DDR4_MA<8>")
	)
	(segment
		(start 73.852278 -42.70756)
		(end 74.23404 -43.089322)
		(width 0.11684)
		(layer "F.Cu")
		(net "M_BMC_DDR4_MA<8>")
	)
	(segment
		(start 69.105272 -47.413164)
		(end 69.339968 -47.64786)
		(width 0.11684)
		(layer "F.Cu")
		(net "M_BMC_DDR4_MA<8>")
	)
	(segment
		(start 69.826378 -45.834808)
		(end 70.079108 -46.087538)
		(width 0.11684)
		(layer "F.Cu")
		(net "M_BMC_DDR4_MA<8>")
	)
	(segment
		(start 68.705476 -46.76902)
		(end 69.639688 -45.834808)
		(width 0.11684)
		(layer "F.Cu")
		(net "M_BMC_DDR4_MA<8>")
	)
	(segment
		(start 69.396864 -45.22851)
		(end 68.29552 -46.329854)
		(width 0.11684)
		(layer "F.Cu")
		(net "M_BMC_DDR4_MA<8>")
	)
	(segment
		(start 69.817742 -48.241458)
		(end 69.80809 -48.241458)
		(width 0.11684)
		(layer "F.Cu")
		(net "M_BMC_DDR4_MA<8>")
	)
	(segment
		(start 71.475346 -43.369738)
		(end 71.475346 -44.729908)
		(width 0.11684)
		(layer "F.Cu")
		(net "M_BMC_DDR4_MA<8>")
	)
	(segment
		(start 71.238364 -46.820836)
		(end 69.817742 -48.241458)
		(width 0.11684)
		(layer "F.Cu")
		(net "M_BMC_DDR4_MA<8>")
	)
	(segment
		(start 66.17208 -48.895)
		(end 65.49644 -48.21936)
		(width 0.11684)
		(layer "F.Cu")
		(net "M_BMC_DDR4_MA<8>")
	)
	(segment
		(start 74.225658 -43.097704)
		(end 71.74738 -43.097704)
		(width 0.11684)
		(layer "F.Cu")
		(net "M_BMC_DDR4_MA<8>")
	)
	(segment
		(start 68.29552 -46.520608)
		(end 68.543932 -46.76902)
		(width 0.11684)
		(layer "F.Cu")
		(net "M_BMC_DDR4_MA<8>")
	)
	(segment
		(start 71.793862 -47.21098)
		(end 71.403464 -46.820836)
		(width 0.11684)
		(layer "F.Cu")
		(net "M_BMC_DDR4_MA<8>")
	)
	(segment
		(start 72.176386 -45.873162)
		(end 71.837296 -46.212252)
		(width 0.11684)
		(layer "F.Cu")
		(net "M_BMC_DDR4_MA<8>")
	)
	(segment
		(start 70.928992 -45.194982)
		(end 69.47789 -45.194982)
		(width 0.11684)
		(layer "F.Cu")
		(net "M_BMC_DDR4_MA<8>")
	)
	(segment
		(start 70.079108 -46.252892)
		(end 69.105272 -47.226728)
		(width 0.11684)
		(layer "F.Cu")
		(net "M_BMC_DDR4_MA<8>")
	)
	(segment
		(start 67.92976 -48.9458)
		(end 66.294762 -48.9458)
		(width 0.11684)
		(layer "F.Cu")
		(net "M_BMC_DDR4_MA<8>")
	)
	(segment
		(start 65.380616 -48.171354)
		(end 64.894968 -48.171354)
		(width 0.11684)
		(layer "F.Cu")
		(net "M_BMC_DDR4_MA<8>")
	)
	(segment
		(start 72.242934 -46.905672)
		(end 71.93788 -47.210726)
		(width 0.11684)
		(layer "F.Cu")
		(net "M_BMC_DDR4_MA<8>")
	)
	(segment
		(start 69.80809 -48.241458)
		(end 69.806312 -48.243236)
		(width 0.11684)
		(layer "F.Cu")
		(net "M_BMC_DDR4_MA<8>")
	)
	(via
		(at 69.80809 -48.241458)
		(size 0.762)
		(drill 0.381)
		(layers "F.Cu" "B.Cu")
		(net "M_BMC_DDR4_MA<8>")
	)
	(via
		(at 74.23404 -43.089322)
		(size 0.4572)
		(drill 0.254)
		(layers "F.Cu" "B.Cu")
		(net "M_BMC_DDR4_MA<8>")
	)
	(arc
		(start 69.47789 -45.194982)
		(mid 69.434052 -45.203702)
		(end 69.396864 -45.22851)
		(width 0.11684)
		(layer "F.Cu")
		(net "M_BMC_DDR4_MA<8>")
	)
	(arc
		(start 68.29552 -46.329854)
		(mid 68.255961 -46.425268)
		(end 68.29552 -46.520608)
		(width 0.11684)
		(layer "F.Cu")
		(net "M_BMC_DDR4_MA<8>")
	)
	(arc
		(start 71.745856 -45.449744)
		(mid 71.830184 -45.414814)
		(end 71.914512 -45.449744)
		(width 0.11684)
		(layer "F.Cu")
		(net "M_BMC_DDR4_MA<8>")
	)
	(arc
		(start 72.176386 -45.711618)
		(mid 72.209843 -45.79239)
		(end 72.176386 -45.873162)
		(width 0.11684)
		(layer "F.Cu")
		(net "M_BMC_DDR4_MA<8>")
	)
	(arc
		(start 70.079108 -46.087538)
		(mid 70.113481 -46.170252)
		(end 70.079108 -46.252892)
		(width 0.11684)
		(layer "F.Cu")
		(net "M_BMC_DDR4_MA<8>")
	)
	(arc
		(start 67.977004 -48.934116)
		(mid 67.954094 -48.942837)
		(end 67.92976 -48.9458)
		(width 0.11684)
		(layer "F.Cu")
		(net "M_BMC_DDR4_MA<8>")
	)
	(arc
		(start 72.242934 -46.761908)
		(mid 72.272708 -46.83379)
		(end 72.242934 -46.905672)
		(width 0.11684)
		(layer "F.Cu")
		(net "M_BMC_DDR4_MA<8>")
	)
	(arc
		(start 71.475346 -44.729908)
		(mid 71.467354 -44.796857)
		(end 71.443596 -44.859956)
		(width 0.11684)
		(layer "F.Cu")
		(net "M_BMC_DDR4_MA<8>")
	)
	(arc
		(start 66.294762 -48.9458)
		(mid 66.228373 -48.932594)
		(end 66.17208 -48.895)
		(width 0.11684)
		(layer "F.Cu")
		(net "M_BMC_DDR4_MA<8>")
	)
	(arc
		(start 69.339968 -47.64786)
		(mid 69.443854 -47.690891)
		(end 69.54774 -47.64786)
		(width 0.11684)
		(layer "F.Cu")
		(net "M_BMC_DDR4_MA<8>")
	)
	(arc
		(start 69.105272 -47.226728)
		(mid 69.06666 -47.319946)
		(end 69.105272 -47.413164)
		(width 0.11684)
		(layer "F.Cu")
		(net "M_BMC_DDR4_MA<8>")
	)
	(arc
		(start 68.543932 -46.76902)
		(mid 68.624704 -46.802477)
		(end 68.705476 -46.76902)
		(width 0.11684)
		(layer "F.Cu")
		(net "M_BMC_DDR4_MA<8>")
	)
	(arc
		(start 71.837296 -46.212252)
		(mid 71.807416 -46.284298)
		(end 71.837296 -46.35627)
		(width 0.11684)
		(layer "F.Cu")
		(net "M_BMC_DDR4_MA<8>")
	)
	(arc
		(start 65.49644 -48.21936)
		(mid 65.443299 -48.183853)
		(end 65.380616 -48.171354)
		(width 0.11684)
		(layer "F.Cu")
		(net "M_BMC_DDR4_MA<8>")
	)
	(arc
		(start 71.403464 -46.820836)
		(mid 71.320914 -46.786717)
		(end 71.238364 -46.820836)
		(width 0.11684)
		(layer "F.Cu")
		(net "M_BMC_DDR4_MA<8>")
	)
	(arc
		(start 71.443596 -44.859956)
		(mid 71.230053 -45.094678)
		(end 70.928992 -45.194982)
		(width 0.11684)
		(layer "F.Cu")
		(net "M_BMC_DDR4_MA<8>")
	)
	(arc
		(start 71.74738 -43.097704)
		(mid 71.555023 -43.177381)
		(end 71.475346 -43.369738)
		(width 0.11684)
		(layer "F.Cu")
		(net "M_BMC_DDR4_MA<8>")
	)
	(arc
		(start 71.93788 -47.210726)
		(mid 71.865924 -47.24068)
		(end 71.793862 -47.21098)
		(width 0.11684)
		(layer "F.Cu")
		(net "M_BMC_DDR4_MA<8>")
	)
	(arc
		(start 69.639688 -45.834808)
		(mid 69.73307 -45.796091)
		(end 69.826378 -45.834808)
		(width 0.11684)
		(layer "F.Cu")
		(net "M_BMC_DDR4_MA<8>")
	)
	(arc
		(start 69.806312 -48.243236)
		(mid 69.041411 -48.754516)
		(end 68.139056 -48.934116)
		(width 0.11684)
		(layer "F.Cu")
		(net "M_BMC_DDR4_MA<8>")
	)
	(segment
		(start 75.198986 -41.199562)
		(end 76.337668 -40.06088)
		(width 0.11684)
		(layer "B.Cu")
		(net "M_BMC_DDR4_MA<8>")
	)
	(segment
		(start 78.723744 -37.959538)
		(end 78.723744 -37.899086)
		(width 0.11684)
		(layer "B.Cu")
		(net "M_BMC_DDR4_MA<8>")
	)
	(segment
		(start 76.353416 -40.047926)
		(end 77.053694 -39.580058)
		(width 0.11684)
		(layer "B.Cu")
		(net "M_BMC_DDR4_MA<8>")
	)
	(segment
		(start 79.243428 -37.123878)
		(end 79.243428 -36.50996)
		(width 0.11684)
		(layer "B.Cu")
		(net "M_BMC_DDR4_MA<8>")
	)
	(segment
		(start 74.397616 -42.707814)
		(end 75.024234 -42.081196)
		(width 0.11684)
		(layer "B.Cu")
		(net "M_BMC_DDR4_MA<8>")
	)
	(segment
		(start 74.23404 -43.089322)
		(end 74.34326 -42.792904)
		(width 0.11684)
		(layer "B.Cu")
		(net "M_BMC_DDR4_MA<8>")
	)
	(segment
		(start 79.243428 -36.50996)
		(end 79.14767 -36.27882)
		(width 0.11684)
		(layer "B.Cu")
		(net "M_BMC_DDR4_MA<8>")
	)
	(segment
		(start 79.062834 -37.559996)
		(end 79.243428 -37.123878)
		(width 0.11684)
		(layer "B.Cu")
		(net "M_BMC_DDR4_MA<8>")
	)
	(segment
		(start 75.091544 -41.918636)
		(end 75.091544 -41.458896)
		(width 0.11684)
		(layer "B.Cu")
		(net "M_BMC_DDR4_MA<8>")
	)
	(segment
		(start 77.330808 -39.352474)
		(end 78.723744 -37.959538)
		(width 0.11684)
		(layer "B.Cu")
		(net "M_BMC_DDR4_MA<8>")
	)
	(segment
		(start 78.809088 -35.940238)
		(end 78.723744 -35.940238)
		(width 0.11684)
		(layer "B.Cu")
		(net "M_BMC_DDR4_MA<8>")
	)
	(segment
		(start 78.723744 -37.899086)
		(end 79.062834 -37.559996)
		(width 0.11684)
		(layer "B.Cu")
		(net "M_BMC_DDR4_MA<8>")
	)
	(segment
		(start 79.14767 -36.27882)
		(end 78.809088 -35.940238)
		(width 0.11684)
		(layer "B.Cu")
		(net "M_BMC_DDR4_MA<8>")
	)
	(arc
		(start 76.337668 -40.06088)
		(mid 76.34522 -40.054011)
		(end 76.353416 -40.047926)
		(width 0.11684)
		(layer "B.Cu")
		(net "M_BMC_DDR4_MA<8>")
	)
	(arc
		(start 77.053694 -39.580058)
		(mid 77.19783 -39.473061)
		(end 77.330808 -39.352474)
		(width 0.11684)
		(layer "B.Cu")
		(net "M_BMC_DDR4_MA<8>")
	)
	(arc
		(start 75.024234 -42.081196)
		(mid 75.074069 -42.006613)
		(end 75.091544 -41.918636)
		(width 0.11684)
		(layer "B.Cu")
		(net "M_BMC_DDR4_MA<8>")
	)
	(arc
		(start 75.091544 -41.458896)
		(mid 75.119463 -41.318537)
		(end 75.198986 -41.199562)
		(width 0.11684)
		(layer "B.Cu")
		(net "M_BMC_DDR4_MA<8>")
	)
	(arc
		(start 74.34326 -42.792904)
		(mid 74.365825 -42.747415)
		(end 74.397616 -42.707814)
		(width 0.11684)
		(layer "B.Cu")
		(net "M_BMC_DDR4_MA<8>")
	)
	(segment
		(start 67.385184 -48.376332)
		(end 66.742818 -48.376332)
		(width 0.11684)
		(layer "F.Cu")
		(net "M_BMC_DDR4_MA<7>")
	)
	(segment
		(start 65.947798 -47.77613)
		(end 64.532256 -47.77613)
		(width 0.11684)
		(layer "F.Cu")
		(net "M_BMC_DDR4_MA<7>")
	)
	(segment
		(start 83.704938 -44.298362)
		(end 83.26882 -44.298362)
		(width 0.11684)
		(layer "F.Cu")
		(net "M_BMC_DDR4_MA<7>")
	)
	(segment
		(start 66.582544 -48.310038)
		(end 66.12001 -47.847504)
		(width 0.11684)
		(layer "F.Cu")
		(net "M_BMC_DDR4_MA<7>")
	)
	(segment
		(start 79.07909 -43.100244)
		(end 79.034132 -43.089322)
		(width 0.11684)
		(layer "F.Cu")
		(net "M_BMC_DDR4_MA<7>")
	)
	(segment
		(start 67.086226 -47.776384)
		(end 67.399916 -47.776384)
		(width 0.11684)
		(layer "F.Cu")
		(net "M_BMC_DDR4_MA<7>")
	)
	(segment
		(start 83.83397 -44.427394)
		(end 83.704938 -44.298362)
		(width 0.11684)
		(layer "F.Cu")
		(net "M_BMC_DDR4_MA<7>")
	)
	(segment
		(start 67.085972 -47.77613)
		(end 67.086226 -47.776384)
		(width 0.11684)
		(layer "F.Cu")
		(net "M_BMC_DDR4_MA<7>")
	)
	(segment
		(start 67.501516 -47.877984)
		(end 67.501516 -48.26)
		(width 0.11684)
		(layer "F.Cu")
		(net "M_BMC_DDR4_MA<7>")
	)
	(segment
		(start 81.514696 -43.540426)
		(end 81.074514 -43.100244)
		(width 0.11684)
		(layer "F.Cu")
		(net "M_BMC_DDR4_MA<7>")
	)
	(segment
		(start 79.034132 -43.089322)
		(end 78.65237 -42.70756)
		(width 0.11684)
		(layer "F.Cu")
		(net "M_BMC_DDR4_MA<7>")
	)
	(segment
		(start 64.46012 -47.806102)
		(end 64.094868 -48.171354)
		(width 0.11684)
		(layer "F.Cu")
		(net "M_BMC_DDR4_MA<7>")
	)
	(segment
		(start 84.8995 -44.427394)
		(end 84.17687 -44.427394)
		(width 0.11684)
		(layer "F.Cu")
		(net "M_BMC_DDR4_MA<7>")
	)
	(segment
		(start 83.26882 -44.298362)
		(end 82.510884 -43.540426)
		(width 0.11684)
		(layer "F.Cu")
		(net "M_BMC_DDR4_MA<7>")
	)
	(segment
		(start 84.17687 -44.427394)
		(end 83.83397 -44.427394)
		(width 0.11684)
		(layer "F.Cu")
		(net "M_BMC_DDR4_MA<7>")
	)
	(segment
		(start 81.074514 -43.100244)
		(end 79.07909 -43.100244)
		(width 0.11684)
		(layer "F.Cu")
		(net "M_BMC_DDR4_MA<7>")
	)
	(segment
		(start 82.510884 -43.540426)
		(end 81.514696 -43.540426)
		(width 0.11684)
		(layer "F.Cu")
		(net "M_BMC_DDR4_MA<7>")
	)
	(via
		(at 83.26882 -44.298362)
		(size 0.762)
		(drill 0.381)
		(layers "F.Cu" "B.Cu")
		(net "M_BMC_DDR4_MA<7>")
	)
	(via
		(at 67.085972 -47.77613)
		(size 0.4572)
		(drill 0.254)
		(layers "F.Cu" "B.Cu")
		(net "M_BMC_DDR4_MA<7>")
	)
	(via
		(at 79.034132 -43.089322)
		(size 0.4572)
		(drill 0.254)
		(layers "F.Cu" "B.Cu")
		(net "M_BMC_DDR4_MA<7>")
	)
	(via
		(at 84.17687 -44.427394)
		(size 0.508)
		(drill 0.254)
		(layers "F.Cu" "B.Cu")
		(net "M_BMC_DDR4_MA<7>")
	)
	(arc
		(start 67.501516 -48.26)
		(mid 67.467443 -48.342259)
		(end 67.385184 -48.376332)
		(width 0.11684)
		(layer "F.Cu")
		(net "M_BMC_DDR4_MA<7>")
	)
	(arc
		(start 64.532256 -47.77613)
		(mid 64.493195 -47.783918)
		(end 64.46012 -47.806102)
		(width 0.11684)
		(layer "F.Cu")
		(net "M_BMC_DDR4_MA<7>")
	)
	(arc
		(start 67.399916 -47.776384)
		(mid 67.471758 -47.806142)
		(end 67.501516 -47.877984)
		(width 0.11684)
		(layer "F.Cu")
		(net "M_BMC_DDR4_MA<7>")
	)
	(arc
		(start 66.742818 -48.376332)
		(mid 66.656086 -48.359116)
		(end 66.582544 -48.310038)
		(width 0.11684)
		(layer "F.Cu")
		(net "M_BMC_DDR4_MA<7>")
	)
	(arc
		(start 66.12001 -47.847504)
		(mid 66.041013 -47.794656)
		(end 65.947798 -47.77613)
		(width 0.11684)
		(layer "F.Cu")
		(net "M_BMC_DDR4_MA<7>")
	)
	(segment
		(start 84.881212 -44.427394)
		(end 84.17687 -44.427394)
		(width 0.11684)
		(layer "B.Cu")
		(net "M_BMC_DDR4_MA<7>")
	)
	(segment
		(start 79.393034 -45.355002)
		(end 79.393034 -44.834302)
		(width 0.08382)
		(layer "In9.Cu")
		(net "M_BMC_DDR4_MA<7>")
	)
	(segment
		(start 70.134988 -45.750226)
		(end 70.724776 -45.750226)
		(width 0.08382)
		(layer "In9.Cu")
		(net "M_BMC_DDR4_MA<7>")
	)
	(segment
		(start 74.151236 -45.912278)
		(end 76.972414 -45.912278)
		(width 0.08382)
		(layer "In9.Cu")
		(net "M_BMC_DDR4_MA<7>")
	)
	(segment
		(start 69.638164 -46.15434)
		(end 69.976746 -45.815758)
		(width 0.08382)
		(layer "In9.Cu")
		(net "M_BMC_DDR4_MA<7>")
	)
	(segment
		(start 73.869042 -45.70984)
		(end 74.015092 -45.85589)
		(width 0.08382)
		(layer "In9.Cu")
		(net "M_BMC_DDR4_MA<7>")
	)
	(segment
		(start 70.8025 -45.717968)
		(end 71.152258 -45.36821)
		(width 0.08382)
		(layer "In9.Cu")
		(net "M_BMC_DDR4_MA<7>")
	)
	(segment
		(start 80.377284 -46.229016)
		(end 80.377284 -45.59554)
		(width 0.08382)
		(layer "In9.Cu")
		(net "M_BMC_DDR4_MA<7>")
	)
	(segment
		(start 79.539592 -44.687744)
		(end 80.287622 -44.687744)
		(width 0.08382)
		(layer "In9.Cu")
		(net "M_BMC_DDR4_MA<7>")
	)
	(segment
		(start 79.346298 -45.995336)
		(end 79.646272 -46.29531)
		(width 0.08382)
		(layer "In9.Cu")
		(net "M_BMC_DDR4_MA<7>")
	)
	(segment
		(start 73.66254 -45.157898)
		(end 73.81367 -45.309028)
		(width 0.08382)
		(layer "In9.Cu")
		(net "M_BMC_DDR4_MA<7>")
	)
	(segment
		(start 68.67144 -46.240192)
		(end 69.4309 -46.240192)
		(width 0.08382)
		(layer "In9.Cu")
		(net "M_BMC_DDR4_MA<7>")
	)
	(segment
		(start 71.784972 -45.106082)
		(end 73.537572 -45.106082)
		(width 0.08382)
		(layer "In9.Cu")
		(net "M_BMC_DDR4_MA<7>")
	)
	(segment
		(start 78.018132 -45.943266)
		(end 79.220568 -45.943266)
		(width 0.08382)
		(layer "In9.Cu")
		(net "M_BMC_DDR4_MA<7>")
	)
	(segment
		(start 80.381602 -44.593764)
		(end 80.381602 -44.008294)
		(width 0.08382)
		(layer "In9.Cu")
		(net "M_BMC_DDR4_MA<7>")
	)
	(segment
		(start 77.893164 -45.21835)
		(end 77.893164 -45.818298)
		(width 0.08382)
		(layer "In9.Cu")
		(net "M_BMC_DDR4_MA<7>")
	)
	(segment
		(start 77.066394 -45.818298)
		(end 77.066394 -45.21835)
		(width 0.08382)
		(layer "In9.Cu")
		(net "M_BMC_DDR4_MA<7>")
	)
	(segment
		(start 73.841356 -45.37583)
		(end 73.841356 -45.643038)
		(width 0.08382)
		(layer "In9.Cu")
		(net "M_BMC_DDR4_MA<7>")
	)
	(segment
		(start 80.283304 -45.50156)
		(end 79.539592 -45.50156)
		(width 0.08382)
		(layer "In9.Cu")
		(net "M_BMC_DDR4_MA<7>")
	)
	(segment
		(start 80.287622 -43.914314)
		(end 79.128112 -43.914314)
		(width 0.08382)
		(layer "In9.Cu")
		(net "M_BMC_DDR4_MA<7>")
	)
	(segment
		(start 67.085972 -47.77613)
		(end 67.249548 -47.612554)
		(width 0.08382)
		(layer "In9.Cu")
		(net "M_BMC_DDR4_MA<7>")
	)
	(segment
		(start 79.713074 -46.322996)
		(end 80.283304 -46.322996)
		(width 0.08382)
		(layer "In9.Cu")
		(net "M_BMC_DDR4_MA<7>")
	)
	(segment
		(start 67.30238 -47.511716)
		(end 68.504816 -46.30928)
		(width 0.08382)
		(layer "In9.Cu")
		(net "M_BMC_DDR4_MA<7>")
	)
	(segment
		(start 77.152754 -45.13199)
		(end 77.806804 -45.13199)
		(width 0.08382)
		(layer "In9.Cu")
		(net "M_BMC_DDR4_MA<7>")
	)
	(segment
		(start 79.034132 -43.820334)
		(end 79.034132 -43.089322)
		(width 0.08382)
		(layer "In9.Cu")
		(net "M_BMC_DDR4_MA<7>")
	)
	(arc
		(start 67.276218 -47.5615)
		(mid 67.285474 -47.534595)
		(end 67.30238 -47.511716)
		(width 0.08382)
		(layer "In9.Cu")
		(net "M_BMC_DDR4_MA<7>")
	)
	(arc
		(start 79.646272 -46.29531)
		(mid 79.676921 -46.315789)
		(end 79.713074 -46.322996)
		(width 0.08382)
		(layer "In9.Cu")
		(net "M_BMC_DDR4_MA<7>")
	)
	(arc
		(start 70.724776 -45.750226)
		(mid 70.766864 -45.741854)
		(end 70.8025 -45.717968)
		(width 0.08382)
		(layer "In9.Cu")
		(net "M_BMC_DDR4_MA<7>")
	)
	(arc
		(start 67.249548 -47.612554)
		(mid 67.266813 -47.589073)
		(end 67.276218 -47.5615)
		(width 0.08382)
		(layer "In9.Cu")
		(net "M_BMC_DDR4_MA<7>")
	)
	(arc
		(start 69.976746 -45.815758)
		(mid 70.049348 -45.767247)
		(end 70.134988 -45.750226)
		(width 0.08382)
		(layer "In9.Cu")
		(net "M_BMC_DDR4_MA<7>")
	)
	(arc
		(start 79.393034 -44.834302)
		(mid 79.43596 -44.73067)
		(end 79.539592 -44.687744)
		(width 0.08382)
		(layer "In9.Cu")
		(net "M_BMC_DDR4_MA<7>")
	)
	(arc
		(start 77.893164 -45.818298)
		(mid 77.929766 -45.906664)
		(end 78.018132 -45.943266)
		(width 0.08382)
		(layer "In9.Cu")
		(net "M_BMC_DDR4_MA<7>")
	)
	(arc
		(start 76.972414 -45.912278)
		(mid 77.038868 -45.884752)
		(end 77.066394 -45.818298)
		(width 0.08382)
		(layer "In9.Cu")
		(net "M_BMC_DDR4_MA<7>")
	)
	(arc
		(start 80.283304 -46.322996)
		(mid 80.349758 -46.29547)
		(end 80.377284 -46.229016)
		(width 0.08382)
		(layer "In9.Cu")
		(net "M_BMC_DDR4_MA<7>")
	)
	(arc
		(start 79.128112 -43.914314)
		(mid 79.061658 -43.886788)
		(end 79.034132 -43.820334)
		(width 0.08382)
		(layer "In9.Cu")
		(net "M_BMC_DDR4_MA<7>")
	)
	(arc
		(start 69.4309 -46.240192)
		(mid 69.543071 -46.21788)
		(end 69.638164 -46.15434)
		(width 0.08382)
		(layer "In9.Cu")
		(net "M_BMC_DDR4_MA<7>")
	)
	(arc
		(start 74.015092 -45.85589)
		(mid 74.077555 -45.897627)
		(end 74.151236 -45.912278)
		(width 0.08382)
		(layer "In9.Cu")
		(net "M_BMC_DDR4_MA<7>")
	)
	(arc
		(start 77.066394 -45.21835)
		(mid 77.091688 -45.157284)
		(end 77.152754 -45.13199)
		(width 0.08382)
		(layer "In9.Cu")
		(net "M_BMC_DDR4_MA<7>")
	)
	(arc
		(start 73.81367 -45.309028)
		(mid 73.834149 -45.339677)
		(end 73.841356 -45.37583)
		(width 0.08382)
		(layer "In9.Cu")
		(net "M_BMC_DDR4_MA<7>")
	)
	(arc
		(start 68.504816 -46.30928)
		(mid 68.581249 -46.258146)
		(end 68.67144 -46.240192)
		(width 0.08382)
		(layer "In9.Cu")
		(net "M_BMC_DDR4_MA<7>")
	)
	(arc
		(start 80.381602 -44.008294)
		(mid 80.354076 -43.94184)
		(end 80.287622 -43.914314)
		(width 0.08382)
		(layer "In9.Cu")
		(net "M_BMC_DDR4_MA<7>")
	)
	(arc
		(start 80.377284 -45.59554)
		(mid 80.349758 -45.529086)
		(end 80.283304 -45.50156)
		(width 0.08382)
		(layer "In9.Cu")
		(net "M_BMC_DDR4_MA<7>")
	)
	(arc
		(start 77.806804 -45.13199)
		(mid 77.86787 -45.157284)
		(end 77.893164 -45.21835)
		(width 0.08382)
		(layer "In9.Cu")
		(net "M_BMC_DDR4_MA<7>")
	)
	(arc
		(start 73.841356 -45.643038)
		(mid 73.848548 -45.679197)
		(end 73.869042 -45.70984)
		(width 0.08382)
		(layer "In9.Cu")
		(net "M_BMC_DDR4_MA<7>")
	)
	(arc
		(start 79.220568 -45.943266)
		(mid 79.288609 -45.9568)
		(end 79.346298 -45.995336)
		(width 0.08382)
		(layer "In9.Cu")
		(net "M_BMC_DDR4_MA<7>")
	)
	(arc
		(start 80.287622 -44.687744)
		(mid 80.354076 -44.660218)
		(end 80.381602 -44.593764)
		(width 0.08382)
		(layer "In9.Cu")
		(net "M_BMC_DDR4_MA<7>")
	)
	(arc
		(start 79.539592 -45.50156)
		(mid 79.43596 -45.458634)
		(end 79.393034 -45.355002)
		(width 0.08382)
		(layer "In9.Cu")
		(net "M_BMC_DDR4_MA<7>")
	)
	(arc
		(start 73.537572 -45.106082)
		(mid 73.605224 -45.119539)
		(end 73.66254 -45.157898)
		(width 0.08382)
		(layer "In9.Cu")
		(net "M_BMC_DDR4_MA<7>")
	)
	(arc
		(start 71.152258 -45.36821)
		(mid 71.442563 -45.174268)
		(end 71.784972 -45.106082)
		(width 0.08382)
		(layer "In9.Cu")
		(net "M_BMC_DDR4_MA<7>")
	)
	(segment
		(start 61.695076 -48.171354)
		(end 62.0903 -47.77613)
		(width 0.11684)
		(layer "F.Cu")
		(net "M_BMC_DDR4_MA<6>")
	)
	(segment
		(start 73.852278 -43.507406)
		(end 73.470516 -43.889168)
		(width 0.11684)
		(layer "F.Cu")
		(net "M_BMC_DDR4_MA<6>")
	)
	(via
		(at 76.408026 -39.259256)
		(size 0.6604)
		(drill 0.3302)
		(layers "F.Cu" "B.Cu")
		(net "M_BMC_DDR4_MA<6>")
	)
	(via
		(at 73.470516 -43.889168)
		(size 0.4572)
		(drill 0.254)
		(layers "F.Cu" "B.Cu")
		(net "M_BMC_DDR4_MA<6>")
	)
	(via
		(at 62.0903 -47.77613)
		(size 0.4572)
		(drill 0.254)
		(layers "F.Cu" "B.Cu")
		(net "M_BMC_DDR4_MA<6>")
	)
	(segment
		(start 78.050644 -37.555678)
		(end 78.227428 -37.128958)
		(width 0.11684)
		(layer "B.Cu")
		(net "M_BMC_DDR4_MA<6>")
	)
	(segment
		(start 78.227428 -37.128958)
		(end 78.227428 -36.535106)
		(width 0.11684)
		(layer "B.Cu")
		(net "M_BMC_DDR4_MA<6>")
	)
	(segment
		(start 77.707744 -37.959538)
		(end 76.408026 -39.259256)
		(width 0.11684)
		(layer "B.Cu")
		(net "M_BMC_DDR4_MA<6>")
	)
	(segment
		(start 78.227428 -36.535106)
		(end 78.129384 -36.298378)
		(width 0.11684)
		(layer "B.Cu")
		(net "M_BMC_DDR4_MA<6>")
	)
	(segment
		(start 73.842118 -43.396154)
		(end 73.842118 -43.030902)
		(width 0.11684)
		(layer "B.Cu")
		(net "M_BMC_DDR4_MA<6>")
	)
	(segment
		(start 78.129384 -36.298378)
		(end 77.771244 -35.940238)
		(width 0.11684)
		(layer "B.Cu")
		(net "M_BMC_DDR4_MA<6>")
	)
	(segment
		(start 74.239374 -42.071798)
		(end 74.646028 -41.665144)
		(width 0.11684)
		(layer "B.Cu")
		(net "M_BMC_DDR4_MA<6>")
	)
	(segment
		(start 77.707744 -37.898578)
		(end 78.050644 -37.555678)
		(width 0.11684)
		(layer "B.Cu")
		(net "M_BMC_DDR4_MA<6>")
	)
	(segment
		(start 77.707744 -37.959538)
		(end 77.707744 -37.898578)
		(width 0.11684)
		(layer "B.Cu")
		(net "M_BMC_DDR4_MA<6>")
	)
	(segment
		(start 74.904854 -40.762428)
		(end 76.408026 -39.259256)
		(width 0.11684)
		(layer "B.Cu")
		(net "M_BMC_DDR4_MA<6>")
	)
	(segment
		(start 77.771244 -35.940238)
		(end 77.707744 -35.940238)
		(width 0.11684)
		(layer "B.Cu")
		(net "M_BMC_DDR4_MA<6>")
	)
	(segment
		(start 74.744834 -41.426638)
		(end 74.744834 -41.148762)
		(width 0.11684)
		(layer "B.Cu")
		(net "M_BMC_DDR4_MA<6>")
	)
	(segment
		(start 73.470516 -43.889168)
		(end 73.737978 -43.621706)
		(width 0.11684)
		(layer "B.Cu")
		(net "M_BMC_DDR4_MA<6>")
	)
	(arc
		(start 74.744834 -41.148762)
		(mid 74.786423 -40.939681)
		(end 74.904854 -40.762428)
		(width 0.11684)
		(layer "B.Cu")
		(net "M_BMC_DDR4_MA<6>")
	)
	(arc
		(start 73.820528 -43.500802)
		(mid 73.836736 -43.449593)
		(end 73.842118 -43.396154)
		(width 0.11684)
		(layer "B.Cu")
		(net "M_BMC_DDR4_MA<6>")
	)
	(arc
		(start 73.842118 -43.030902)
		(mid 73.945365 -42.511845)
		(end 74.239374 -42.071798)
		(width 0.11684)
		(layer "B.Cu")
		(net "M_BMC_DDR4_MA<6>")
	)
	(arc
		(start 73.737978 -43.621706)
		(mid 73.784925 -43.565128)
		(end 73.820528 -43.500802)
		(width 0.11684)
		(layer "B.Cu")
		(net "M_BMC_DDR4_MA<6>")
	)
	(arc
		(start 74.646028 -41.665144)
		(mid 74.719145 -41.555717)
		(end 74.744834 -41.426638)
		(width 0.11684)
		(layer "B.Cu")
		(net "M_BMC_DDR4_MA<6>")
	)
	(segment
		(start 67.211956 -46.07814)
		(end 67.638422 -46.504606)
		(width 0.08382)
		(layer "In9.Cu")
		(net "M_BMC_DDR4_MA<6>")
	)
	(segment
		(start 60.75172 -49.61128)
		(end 60.75172 -49.076102)
		(width 0.08382)
		(layer "In9.Cu")
		(net "M_BMC_DDR4_MA<6>")
	)
	(segment
		(start 67.475862 -45.681138)
		(end 67.211956 -45.945044)
		(width 0.08382)
		(layer "In9.Cu")
		(net "M_BMC_DDR4_MA<6>")
	)
	(segment
		(start 65.298574 -47.343822)
		(end 64.962786 -47.343822)
		(width 0.08382)
		(layer "In9.Cu")
		(net "M_BMC_DDR4_MA<6>")
	)
	(segment
		(start 60.83808 -48.989742)
		(end 61.585856 -48.989742)
		(width 0.08382)
		(layer "In9.Cu")
		(net "M_BMC_DDR4_MA<6>")
	)
	(segment
		(start 60.838588 -47.373794)
		(end 61.31052 -47.373794)
		(width 0.08382)
		(layer "In9.Cu")
		(net "M_BMC_DDR4_MA<6>")
	)
	(segment
		(start 73.470516 -43.889168)
		(end 73.470516 -44.248324)
		(width 0.08382)
		(layer "In9.Cu")
		(net "M_BMC_DDR4_MA<6>")
	)
	(segment
		(start 64.876426 -47.257462)
		(end 64.876426 -46.19371)
		(width 0.08382)
		(layer "In9.Cu")
		(net "M_BMC_DDR4_MA<6>")
	)
	(segment
		(start 71.7042 -44.72813)
		(end 71.7042 -44.7294)
		(width 0.08382)
		(layer "In9.Cu")
		(net "M_BMC_DDR4_MA<6>")
	)
	(segment
		(start 67.91325 -45.98543)
		(end 67.608958 -45.681138)
		(width 0.08382)
		(layer "In9.Cu")
		(net "M_BMC_DDR4_MA<6>")
	)
	(segment
		(start 68.682362 -45.61205)
		(end 68.308982 -45.98543)
		(width 0.08382)
		(layer "In9.Cu")
		(net "M_BMC_DDR4_MA<6>")
	)
	(segment
		(start 69.4055 -45.834554)
		(end 69.045074 -45.834554)
		(width 0.08382)
		(layer "In9.Cu")
		(net "M_BMC_DDR4_MA<6>")
	)
	(segment
		(start 71.7042 -44.7294)
		(end 71.583804 -44.7294)
		(width 0.08382)
		(layer "In9.Cu")
		(net "M_BMC_DDR4_MA<6>")
	)
	(segment
		(start 72.202294 -44.436284)
		(end 72.202294 -44.63415)
		(width 0.08382)
		(layer "In9.Cu")
		(net "M_BMC_DDR4_MA<6>")
	)
	(segment
		(start 61.524896 -47.462694)
		(end 61.838332 -47.77613)
		(width 0.08382)
		(layer "In9.Cu")
		(net "M_BMC_DDR4_MA<6>")
	)
	(segment
		(start 62.47511 -48.290226)
		(end 62.47511 -49.61128)
		(width 0.08382)
		(layer "In9.Cu")
		(net "M_BMC_DDR4_MA<6>")
	)
	(segment
		(start 64.790066 -46.10735)
		(end 64.172592 -46.10735)
		(width 0.08382)
		(layer "In9.Cu")
		(net "M_BMC_DDR4_MA<6>")
	)
	(segment
		(start 63.29934 -47.467266)
		(end 63.29934 -47.924466)
		(width 0.08382)
		(layer "In9.Cu")
		(net "M_BMC_DDR4_MA<6>")
	)
	(segment
		(start 64.086232 -46.19371)
		(end 64.086232 -47.270416)
		(width 0.08382)
		(layer "In9.Cu")
		(net "M_BMC_DDR4_MA<6>")
	)
	(segment
		(start 67.638422 -46.627034)
		(end 67.09664 -47.168816)
		(width 0.08382)
		(layer "In9.Cu")
		(net "M_BMC_DDR4_MA<6>")
	)
	(segment
		(start 70.52437 -45.401484)
		(end 69.58584 -45.401484)
		(width 0.08382)
		(layer "In9.Cu")
		(net "M_BMC_DDR4_MA<6>")
	)
	(segment
		(start 61.838332 -47.77613)
		(end 62.0903 -47.77613)
		(width 0.08382)
		(layer "In9.Cu")
		(net "M_BMC_DDR4_MA<6>")
	)
	(segment
		(start 63.270892 -47.993046)
		(end 63.095378 -48.16856)
		(width 0.08382)
		(layer "In9.Cu")
		(net "M_BMC_DDR4_MA<6>")
	)
	(segment
		(start 63.028576 -48.196246)
		(end 62.56909 -48.196246)
		(width 0.08382)
		(layer "In9.Cu")
		(net "M_BMC_DDR4_MA<6>")
	)
	(segment
		(start 61.673486 -48.902112)
		(end 61.673486 -48.284892)
		(width 0.08382)
		(layer "In9.Cu")
		(net "M_BMC_DDR4_MA<6>")
	)
	(segment
		(start 68.857114 -45.579792)
		(end 68.760086 -45.579792)
		(width 0.08382)
		(layer "In9.Cu")
		(net "M_BMC_DDR4_MA<6>")
	)
	(segment
		(start 61.56071 -48.172116)
		(end 60.838588 -48.172116)
		(width 0.08382)
		(layer "In9.Cu")
		(net "M_BMC_DDR4_MA<6>")
	)
	(segment
		(start 73.376536 -44.342304)
		(end 72.296274 -44.342304)
		(width 0.08382)
		(layer "In9.Cu")
		(net "M_BMC_DDR4_MA<6>")
	)
	(segment
		(start 71.085202 -44.935902)
		(end 70.68693 -45.334174)
		(width 0.08382)
		(layer "In9.Cu")
		(net "M_BMC_DDR4_MA<6>")
	)
	(segment
		(start 65.803018 -46.550072)
		(end 65.471294 -46.550072)
		(width 0.08382)
		(layer "In9.Cu")
		(net "M_BMC_DDR4_MA<6>")
	)
	(segment
		(start 72.108314 -44.72813)
		(end 71.7042 -44.72813)
		(width 0.08382)
		(layer "In9.Cu")
		(net "M_BMC_DDR4_MA<6>")
	)
	(segment
		(start 68.951094 -45.740574)
		(end 68.951094 -45.673772)
		(width 0.08382)
		(layer "In9.Cu")
		(net "M_BMC_DDR4_MA<6>")
	)
	(segment
		(start 62.38875 -49.69764)
		(end 60.83808 -49.69764)
		(width 0.08382)
		(layer "In9.Cu")
		(net "M_BMC_DDR4_MA<6>")
	)
	(segment
		(start 65.384934 -46.636432)
		(end 65.384934 -47.257462)
		(width 0.08382)
		(layer "In9.Cu")
		(net "M_BMC_DDR4_MA<6>")
	)
	(segment
		(start 60.752228 -48.085756)
		(end 60.752228 -47.460154)
		(width 0.08382)
		(layer "In9.Cu")
		(net "M_BMC_DDR4_MA<6>")
	)
	(segment
		(start 69.49948 -45.487844)
		(end 69.49948 -45.740574)
		(width 0.08382)
		(layer "In9.Cu")
		(net "M_BMC_DDR4_MA<6>")
	)
	(segment
		(start 63.983362 -47.373286)
		(end 63.39332 -47.373286)
		(width 0.08382)
		(layer "In9.Cu")
		(net "M_BMC_DDR4_MA<6>")
	)
	(segment
		(start 67.018916 -47.201074)
		(end 65.975738 -47.201074)
		(width 0.08382)
		(layer "In9.Cu")
		(net "M_BMC_DDR4_MA<6>")
	)
	(segment
		(start 65.889378 -47.114714)
		(end 65.889378 -46.636432)
		(width 0.08382)
		(layer "In9.Cu")
		(net "M_BMC_DDR4_MA<6>")
	)
	(arc
		(start 71.583804 -44.7294)
		(mid 71.313972 -44.783073)
		(end 71.085202 -44.935902)
		(width 0.08382)
		(layer "In9.Cu")
		(net "M_BMC_DDR4_MA<6>")
	)
	(arc
		(start 68.308982 -45.98543)
		(mid 68.111116 -46.067389)
		(end 67.91325 -45.98543)
		(width 0.08382)
		(layer "In9.Cu")
		(net "M_BMC_DDR4_MA<6>")
	)
	(arc
		(start 60.838588 -48.172116)
		(mid 60.777522 -48.146822)
		(end 60.752228 -48.085756)
		(width 0.08382)
		(layer "In9.Cu")
		(net "M_BMC_DDR4_MA<6>")
	)
	(arc
		(start 68.951094 -45.673772)
		(mid 68.923568 -45.607318)
		(end 68.857114 -45.579792)
		(width 0.08382)
		(layer "In9.Cu")
		(net "M_BMC_DDR4_MA<6>")
	)
	(arc
		(start 67.608958 -45.681138)
		(mid 67.54241 -45.653573)
		(end 67.475862 -45.681138)
		(width 0.08382)
		(layer "In9.Cu")
		(net "M_BMC_DDR4_MA<6>")
	)
	(arc
		(start 69.045074 -45.834554)
		(mid 68.97862 -45.807028)
		(end 68.951094 -45.740574)
		(width 0.08382)
		(layer "In9.Cu")
		(net "M_BMC_DDR4_MA<6>")
	)
	(arc
		(start 72.202294 -44.63415)
		(mid 72.174768 -44.700604)
		(end 72.108314 -44.72813)
		(width 0.08382)
		(layer "In9.Cu")
		(net "M_BMC_DDR4_MA<6>")
	)
	(arc
		(start 60.83808 -49.69764)
		(mid 60.777014 -49.672346)
		(end 60.75172 -49.61128)
		(width 0.08382)
		(layer "In9.Cu")
		(net "M_BMC_DDR4_MA<6>")
	)
	(arc
		(start 64.086232 -47.270416)
		(mid 64.056102 -47.343156)
		(end 63.983362 -47.373286)
		(width 0.08382)
		(layer "In9.Cu")
		(net "M_BMC_DDR4_MA<6>")
	)
	(arc
		(start 61.585856 -48.989742)
		(mid 61.64782 -48.964076)
		(end 61.673486 -48.902112)
		(width 0.08382)
		(layer "In9.Cu")
		(net "M_BMC_DDR4_MA<6>")
	)
	(arc
		(start 69.49948 -45.740574)
		(mid 69.471954 -45.807028)
		(end 69.4055 -45.834554)
		(width 0.08382)
		(layer "In9.Cu")
		(net "M_BMC_DDR4_MA<6>")
	)
	(arc
		(start 60.75172 -49.076102)
		(mid 60.777014 -49.015036)
		(end 60.83808 -48.989742)
		(width 0.08382)
		(layer "In9.Cu")
		(net "M_BMC_DDR4_MA<6>")
	)
	(arc
		(start 62.56909 -48.196246)
		(mid 62.502636 -48.223772)
		(end 62.47511 -48.290226)
		(width 0.08382)
		(layer "In9.Cu")
		(net "M_BMC_DDR4_MA<6>")
	)
	(arc
		(start 67.638422 -46.504606)
		(mid 67.663778 -46.56582)
		(end 67.638422 -46.627034)
		(width 0.08382)
		(layer "In9.Cu")
		(net "M_BMC_DDR4_MA<6>")
	)
	(arc
		(start 60.752228 -47.460154)
		(mid 60.777522 -47.399088)
		(end 60.838588 -47.373794)
		(width 0.08382)
		(layer "In9.Cu")
		(net "M_BMC_DDR4_MA<6>")
	)
	(arc
		(start 61.31052 -47.373794)
		(mid 61.426564 -47.396895)
		(end 61.524896 -47.462694)
		(width 0.08382)
		(layer "In9.Cu")
		(net "M_BMC_DDR4_MA<6>")
	)
	(arc
		(start 63.29934 -47.924466)
		(mid 63.291939 -47.961583)
		(end 63.270892 -47.993046)
		(width 0.08382)
		(layer "In9.Cu")
		(net "M_BMC_DDR4_MA<6>")
	)
	(arc
		(start 64.172592 -46.10735)
		(mid 64.111526 -46.132644)
		(end 64.086232 -46.19371)
		(width 0.08382)
		(layer "In9.Cu")
		(net "M_BMC_DDR4_MA<6>")
	)
	(arc
		(start 70.68693 -45.334174)
		(mid 70.612347 -45.384009)
		(end 70.52437 -45.401484)
		(width 0.08382)
		(layer "In9.Cu")
		(net "M_BMC_DDR4_MA<6>")
	)
	(arc
		(start 68.760086 -45.579792)
		(mid 68.717998 -45.588164)
		(end 68.682362 -45.61205)
		(width 0.08382)
		(layer "In9.Cu")
		(net "M_BMC_DDR4_MA<6>")
	)
	(arc
		(start 65.975738 -47.201074)
		(mid 65.914672 -47.17578)
		(end 65.889378 -47.114714)
		(width 0.08382)
		(layer "In9.Cu")
		(net "M_BMC_DDR4_MA<6>")
	)
	(arc
		(start 61.673486 -48.284892)
		(mid 61.640455 -48.205147)
		(end 61.56071 -48.172116)
		(width 0.08382)
		(layer "In9.Cu")
		(net "M_BMC_DDR4_MA<6>")
	)
	(arc
		(start 72.296274 -44.342304)
		(mid 72.262549 -44.348546)
		(end 72.233282 -44.366434)
		(width 0.08382)
		(layer "In9.Cu")
		(net "M_BMC_DDR4_MA<6>")
	)
	(arc
		(start 62.47511 -49.61128)
		(mid 62.449816 -49.672346)
		(end 62.38875 -49.69764)
		(width 0.08382)
		(layer "In9.Cu")
		(net "M_BMC_DDR4_MA<6>")
	)
	(arc
		(start 65.384934 -47.257462)
		(mid 65.35964 -47.318528)
		(end 65.298574 -47.343822)
		(width 0.08382)
		(layer "In9.Cu")
		(net "M_BMC_DDR4_MA<6>")
	)
	(arc
		(start 73.470516 -44.248324)
		(mid 73.44299 -44.314778)
		(end 73.376536 -44.342304)
		(width 0.08382)
		(layer "In9.Cu")
		(net "M_BMC_DDR4_MA<6>")
	)
	(arc
		(start 67.09664 -47.168816)
		(mid 67.06098 -47.192643)
		(end 67.018916 -47.201074)
		(width 0.08382)
		(layer "In9.Cu")
		(net "M_BMC_DDR4_MA<6>")
	)
	(arc
		(start 67.211956 -45.945044)
		(mid 67.184391 -46.011592)
		(end 67.211956 -46.07814)
		(width 0.08382)
		(layer "In9.Cu")
		(net "M_BMC_DDR4_MA<6>")
	)
	(arc
		(start 65.889378 -46.636432)
		(mid 65.864084 -46.575366)
		(end 65.803018 -46.550072)
		(width 0.08382)
		(layer "In9.Cu")
		(net "M_BMC_DDR4_MA<6>")
	)
	(arc
		(start 72.233282 -44.366434)
		(mid 72.210392 -44.398077)
		(end 72.202294 -44.436284)
		(width 0.08382)
		(layer "In9.Cu")
		(net "M_BMC_DDR4_MA<6>")
	)
	(arc
		(start 65.471294 -46.550072)
		(mid 65.410228 -46.575366)
		(end 65.384934 -46.636432)
		(width 0.08382)
		(layer "In9.Cu")
		(net "M_BMC_DDR4_MA<6>")
	)
	(arc
		(start 64.962786 -47.343822)
		(mid 64.90172 -47.318528)
		(end 64.876426 -47.257462)
		(width 0.08382)
		(layer "In9.Cu")
		(net "M_BMC_DDR4_MA<6>")
	)
	(arc
		(start 69.58584 -45.401484)
		(mid 69.524774 -45.426778)
		(end 69.49948 -45.487844)
		(width 0.08382)
		(layer "In9.Cu")
		(net "M_BMC_DDR4_MA<6>")
	)
	(arc
		(start 63.095378 -48.16856)
		(mid 63.064729 -48.189039)
		(end 63.028576 -48.196246)
		(width 0.08382)
		(layer "In9.Cu")
		(net "M_BMC_DDR4_MA<6>")
	)
	(arc
		(start 64.876426 -46.19371)
		(mid 64.851132 -46.132644)
		(end 64.790066 -46.10735)
		(width 0.08382)
		(layer "In9.Cu")
		(net "M_BMC_DDR4_MA<6>")
	)
	(arc
		(start 63.39332 -47.373286)
		(mid 63.326866 -47.400812)
		(end 63.29934 -47.467266)
		(width 0.08382)
		(layer "In9.Cu")
		(net "M_BMC_DDR4_MA<6>")
	)
	(segment
		(start 78.65237 -43.507406)
		(end 78.270608 -43.125644)
		(width 0.11684)
		(layer "F.Cu")
		(net "M_BMC_DDR4_MA<5>")
	)
	(segment
		(start 81.15046 -44.552362)
		(end 80.5053 -43.907202)
		(width 0.11684)
		(layer "F.Cu")
		(net "M_BMC_DDR4_MA<5>")
	)
	(segment
		(start 67.045078 -47.188882)
		(end 65.141602 -47.188882)
		(width 0.11684)
		(layer "F.Cu")
		(net "M_BMC_DDR4_MA<5>")
	)
	(segment
		(start 83.682078 -45.697394)
		(end 82.537046 -44.552362)
		(width 0.11684)
		(layer "F.Cu")
		(net "M_BMC_DDR4_MA<5>")
	)
	(segment
		(start 78.858618 -43.713654)
		(end 78.65237 -43.507406)
		(width 0.11684)
		(layer "F.Cu")
		(net "M_BMC_DDR4_MA<5>")
	)
	(segment
		(start 82.537046 -44.552362)
		(end 81.15046 -44.552362)
		(width 0.11684)
		(layer "F.Cu")
		(net "M_BMC_DDR4_MA<5>")
	)
	(segment
		(start 64.899032 -47.371254)
		(end 64.894968 -47.371254)
		(width 0.11684)
		(layer "F.Cu")
		(net "M_BMC_DDR4_MA<5>")
	)
	(segment
		(start 80.5053 -43.907202)
		(end 79.325978 -43.907202)
		(width 0.11684)
		(layer "F.Cu")
		(net "M_BMC_DDR4_MA<5>")
	)
	(segment
		(start 68.094606 -47.235618)
		(end 67.869816 -47.133764)
		(width 0.11684)
		(layer "F.Cu")
		(net "M_BMC_DDR4_MA<5>")
	)
	(segment
		(start 67.868038 -47.135542)
		(end 67.224148 -47.135542)
		(width 0.11684)
		(layer "F.Cu")
		(net "M_BMC_DDR4_MA<5>")
	)
	(segment
		(start 67.869816 -47.133764)
		(end 67.868038 -47.135542)
		(width 0.11684)
		(layer "F.Cu")
		(net "M_BMC_DDR4_MA<5>")
	)
	(segment
		(start 67.144138 -47.157894)
		(end 67.134486 -47.163736)
		(width 0.11684)
		(layer "F.Cu")
		(net "M_BMC_DDR4_MA<5>")
	)
	(segment
		(start 84.8995 -45.697394)
		(end 84.17687 -45.697394)
		(width 0.11684)
		(layer "F.Cu")
		(net "M_BMC_DDR4_MA<5>")
	)
	(segment
		(start 65.038732 -47.231554)
		(end 64.899032 -47.371254)
		(width 0.11684)
		(layer "F.Cu")
		(net "M_BMC_DDR4_MA<5>")
	)
	(segment
		(start 84.17687 -45.697394)
		(end 83.682078 -45.697394)
		(width 0.11684)
		(layer "F.Cu")
		(net "M_BMC_DDR4_MA<5>")
	)
	(segment
		(start 68.699888 -47.875952)
		(end 68.51523 -47.595282)
		(width 0.11684)
		(layer "F.Cu")
		(net "M_BMC_DDR4_MA<5>")
	)
	(via
		(at 78.270608 -43.125644)
		(size 0.4572)
		(drill 0.254)
		(layers "F.Cu" "B.Cu")
		(net "M_BMC_DDR4_MA<5>")
	)
	(via
		(at 84.17687 -45.697394)
		(size 0.508)
		(drill 0.254)
		(layers "F.Cu" "B.Cu")
		(net "M_BMC_DDR4_MA<5>")
	)
	(via
		(at 68.699888 -47.875952)
		(size 0.4572)
		(drill 0.254)
		(layers "F.Cu" "B.Cu")
		(net "M_BMC_DDR4_MA<5>")
	)
	(via
		(at 67.869816 -47.133764)
		(size 0.762)
		(drill 0.381)
		(layers "F.Cu" "B.Cu")
		(net "M_BMC_DDR4_MA<5>")
	)
	(arc
		(start 65.141602 -47.188882)
		(mid 65.085905 -47.199961)
		(end 65.038732 -47.231554)
		(width 0.11684)
		(layer "F.Cu")
		(net "M_BMC_DDR4_MA<5>")
	)
	(arc
		(start 68.51523 -47.595282)
		(mid 68.330438 -47.385599)
		(end 68.094606 -47.235618)
		(width 0.11684)
		(layer "F.Cu")
		(net "M_BMC_DDR4_MA<5>")
	)
	(arc
		(start 67.134486 -47.163736)
		(mid 67.091518 -47.182483)
		(end 67.045078 -47.188882)
		(width 0.11684)
		(layer "F.Cu")
		(net "M_BMC_DDR4_MA<5>")
	)
	(arc
		(start 67.224148 -47.135542)
		(mid 67.18261 -47.141233)
		(end 67.144138 -47.157894)
		(width 0.11684)
		(layer "F.Cu")
		(net "M_BMC_DDR4_MA<5>")
	)
	(arc
		(start 79.325978 -43.907202)
		(mid 79.073045 -43.856908)
		(end 78.858618 -43.713654)
		(width 0.11684)
		(layer "F.Cu")
		(net "M_BMC_DDR4_MA<5>")
	)
	(segment
		(start 84.6455 -45.697394)
		(end 84.17687 -45.697394)
		(width 0.11684)
		(layer "B.Cu")
		(net "M_BMC_DDR4_MA<5>")
	)
	(segment
		(start 84.8995 -45.443394)
		(end 84.6455 -45.697394)
		(width 0.11684)
		(layer "B.Cu")
		(net "M_BMC_DDR4_MA<5>")
	)
	(segment
		(start 78.822804 -43.47718)
		(end 79.518256 -43.47718)
		(width 0.08382)
		(layer "In2.Cu")
		(net "M_BMC_DDR4_MA<5>")
	)
	(segment
		(start 72.39508 -48.684688)
		(end 72.747886 -48.684688)
		(width 0.08382)
		(layer "In2.Cu")
		(net "M_BMC_DDR4_MA<5>")
	)
	(segment
		(start 71.76262 -48.52416)
		(end 71.924418 -48.591216)
		(width 0.08382)
		(layer "In2.Cu")
		(net "M_BMC_DDR4_MA<5>")
	)
	(segment
		(start 79.604616 -43.39082)
		(end 79.604616 -42.797222)
		(width 0.08382)
		(layer "In2.Cu")
		(net "M_BMC_DDR4_MA<5>")
	)
	(segment
		(start 77.272642 -47.912528)
		(end 77.272642 -48.58893)
		(width 0.08382)
		(layer "In2.Cu")
		(net "M_BMC_DDR4_MA<5>")
	)
	(segment
		(start 73.307194 -48.283114)
		(end 76.160122 -48.283114)
		(width 0.08382)
		(layer "In2.Cu")
		(net "M_BMC_DDR4_MA<5>")
	)
	(segment
		(start 77.366622 -48.68291)
		(end 77.691742 -48.68291)
		(width 0.08382)
		(layer "In2.Cu")
		(net "M_BMC_DDR4_MA<5>")
	)
	(segment
		(start 79.518256 -42.710862)
		(end 78.356968 -42.710862)
		(width 0.08382)
		(layer "In2.Cu")
		(net "M_BMC_DDR4_MA<5>")
	)
	(segment
		(start 76.845922 -47.826168)
		(end 77.186282 -47.826168)
		(width 0.08382)
		(layer "In2.Cu")
		(net "M_BMC_DDR4_MA<5>")
	)
	(segment
		(start 76.340462 -48.686974)
		(end 76.665582 -48.686974)
		(width 0.08382)
		(layer "In2.Cu")
		(net "M_BMC_DDR4_MA<5>")
	)
	(segment
		(start 68.699888 -47.875952)
		(end 69.19976 -48.375824)
		(width 0.08382)
		(layer "In2.Cu")
		(net "M_BMC_DDR4_MA<5>")
	)
	(segment
		(start 69.428868 -48.47082)
		(end 71.494904 -48.47082)
		(width 0.08382)
		(layer "In2.Cu")
		(net "M_BMC_DDR4_MA<5>")
	)
	(segment
		(start 78.736444 -43.920918)
		(end 78.736444 -43.56354)
		(width 0.08382)
		(layer "In2.Cu")
		(net "M_BMC_DDR4_MA<5>")
	)
	(segment
		(start 76.759562 -48.592994)
		(end 76.759562 -47.912528)
		(width 0.08382)
		(layer "In2.Cu")
		(net "M_BMC_DDR4_MA<5>")
	)
	(segment
		(start 76.246482 -48.369474)
		(end 76.246482 -48.592994)
		(width 0.08382)
		(layer "In2.Cu")
		(net "M_BMC_DDR4_MA<5>")
	)
	(segment
		(start 79.45247 -48.064166)
		(end 79.45247 -46.650148)
		(width 0.08382)
		(layer "In2.Cu")
		(net "M_BMC_DDR4_MA<5>")
	)
	(segment
		(start 79.604616 -46.478444)
		(end 79.604616 -44.093638)
		(width 0.08382)
		(layer "In2.Cu")
		(net "M_BMC_DDR4_MA<5>")
	)
	(segment
		(start 78.270608 -42.797222)
		(end 78.270608 -43.125644)
		(width 0.08382)
		(layer "In2.Cu")
		(net "M_BMC_DDR4_MA<5>")
	)
	(segment
		(start 72.814688 -48.657002)
		(end 73.11136 -48.36033)
		(width 0.08382)
		(layer "In2.Cu")
		(net "M_BMC_DDR4_MA<5>")
	)
	(segment
		(start 79.518256 -44.007278)
		(end 78.822804 -44.007278)
		(width 0.08382)
		(layer "In2.Cu")
		(net "M_BMC_DDR4_MA<5>")
	)
	(segment
		(start 77.785722 -48.58893)
		(end 77.785722 -48.379126)
		(width 0.08382)
		(layer "In2.Cu")
		(net "M_BMC_DDR4_MA<5>")
	)
	(segment
		(start 77.879702 -48.285146)
		(end 79.255112 -48.285146)
		(width 0.08382)
		(layer "In2.Cu")
		(net "M_BMC_DDR4_MA<5>")
	)
	(arc
		(start 79.604616 -42.797222)
		(mid 79.579322 -42.736156)
		(end 79.518256 -42.710862)
		(width 0.08382)
		(layer "In2.Cu")
		(net "M_BMC_DDR4_MA<5>")
	)
	(arc
		(start 78.822804 -44.007278)
		(mid 78.761738 -43.981984)
		(end 78.736444 -43.920918)
		(width 0.08382)
		(layer "In2.Cu")
		(net "M_BMC_DDR4_MA<5>")
	)
	(arc
		(start 76.160122 -48.283114)
		(mid 76.221188 -48.308408)
		(end 76.246482 -48.369474)
		(width 0.08382)
		(layer "In2.Cu")
		(net "M_BMC_DDR4_MA<5>")
	)
	(arc
		(start 79.604616 -44.093638)
		(mid 79.579322 -44.032572)
		(end 79.518256 -44.007278)
		(width 0.08382)
		(layer "In2.Cu")
		(net "M_BMC_DDR4_MA<5>")
	)
	(arc
		(start 76.665582 -48.686974)
		(mid 76.732036 -48.659448)
		(end 76.759562 -48.592994)
		(width 0.08382)
		(layer "In2.Cu")
		(net "M_BMC_DDR4_MA<5>")
	)
	(arc
		(start 78.736444 -43.56354)
		(mid 78.761738 -43.502474)
		(end 78.822804 -43.47718)
		(width 0.08382)
		(layer "In2.Cu")
		(net "M_BMC_DDR4_MA<5>")
	)
	(arc
		(start 79.518256 -43.47718)
		(mid 79.579322 -43.451886)
		(end 79.604616 -43.39082)
		(width 0.08382)
		(layer "In2.Cu")
		(net "M_BMC_DDR4_MA<5>")
	)
	(arc
		(start 71.494904 -48.47082)
		(mid 71.631393 -48.484285)
		(end 71.76262 -48.52416)
		(width 0.08382)
		(layer "In2.Cu")
		(net "M_BMC_DDR4_MA<5>")
	)
	(arc
		(start 77.186282 -47.826168)
		(mid 77.247348 -47.851462)
		(end 77.272642 -47.912528)
		(width 0.08382)
		(layer "In2.Cu")
		(net "M_BMC_DDR4_MA<5>")
	)
	(arc
		(start 77.691742 -48.68291)
		(mid 77.758196 -48.655384)
		(end 77.785722 -48.58893)
		(width 0.08382)
		(layer "In2.Cu")
		(net "M_BMC_DDR4_MA<5>")
	)
	(arc
		(start 76.759562 -47.912528)
		(mid 76.784856 -47.851462)
		(end 76.845922 -47.826168)
		(width 0.08382)
		(layer "In2.Cu")
		(net "M_BMC_DDR4_MA<5>")
	)
	(arc
		(start 71.924418 -48.591216)
		(mid 72.155147 -48.661117)
		(end 72.39508 -48.684688)
		(width 0.08382)
		(layer "In2.Cu")
		(net "M_BMC_DDR4_MA<5>")
	)
	(arc
		(start 73.11136 -48.36033)
		(mid 73.162222 -48.320739)
		(end 73.221342 -48.295052)
		(width 0.08382)
		(layer "In2.Cu")
		(net "M_BMC_DDR4_MA<5>")
	)
	(arc
		(start 79.255112 -48.285146)
		(mid 79.349732 -48.259751)
		(end 79.418942 -48.190404)
		(width 0.08382)
		(layer "In2.Cu")
		(net "M_BMC_DDR4_MA<5>")
	)
	(arc
		(start 79.418942 -48.190404)
		(mid 79.443936 -48.129472)
		(end 79.45247 -48.064166)
		(width 0.08382)
		(layer "In2.Cu")
		(net "M_BMC_DDR4_MA<5>")
	)
	(arc
		(start 78.356968 -42.710862)
		(mid 78.295902 -42.736156)
		(end 78.270608 -42.797222)
		(width 0.08382)
		(layer "In2.Cu")
		(net "M_BMC_DDR4_MA<5>")
	)
	(arc
		(start 79.45247 -46.650148)
		(mid 79.474181 -46.592635)
		(end 79.52867 -46.564296)
		(width 0.08382)
		(layer "In2.Cu")
		(net "M_BMC_DDR4_MA<5>")
	)
	(arc
		(start 77.785722 -48.379126)
		(mid 77.813248 -48.312672)
		(end 77.879702 -48.285146)
		(width 0.08382)
		(layer "In2.Cu")
		(net "M_BMC_DDR4_MA<5>")
	)
	(arc
		(start 77.272642 -48.58893)
		(mid 77.300168 -48.655384)
		(end 77.366622 -48.68291)
		(width 0.08382)
		(layer "In2.Cu")
		(net "M_BMC_DDR4_MA<5>")
	)
	(arc
		(start 79.52867 -46.564296)
		(mid 79.582838 -46.535722)
		(end 79.604616 -46.478444)
		(width 0.08382)
		(layer "In2.Cu")
		(net "M_BMC_DDR4_MA<5>")
	)
	(arc
		(start 72.747886 -48.684688)
		(mid 72.784045 -48.677496)
		(end 72.814688 -48.657002)
		(width 0.08382)
		(layer "In2.Cu")
		(net "M_BMC_DDR4_MA<5>")
	)
	(arc
		(start 69.19976 -48.375824)
		(mid 69.304876 -48.44606)
		(end 69.428868 -48.47082)
		(width 0.08382)
		(layer "In2.Cu")
		(net "M_BMC_DDR4_MA<5>")
	)
	(arc
		(start 73.221342 -48.295052)
		(mid 73.263847 -48.286063)
		(end 73.307194 -48.283114)
		(width 0.08382)
		(layer "In2.Cu")
		(net "M_BMC_DDR4_MA<5>")
	)
	(arc
		(start 76.246482 -48.592994)
		(mid 76.274008 -48.659448)
		(end 76.340462 -48.686974)
		(width 0.08382)
		(layer "In2.Cu")
		(net "M_BMC_DDR4_MA<5>")
	)
	(segment
		(start 75.62342 -41.53535)
		(end 75.62342 -42.73169)
		(width 0.11684)
		(layer "F.Cu")
		(net "M_BMC_DDR4_MA<4>")
	)
	(segment
		(start 77.7621 -35.927538)
		(end 78.20279 -36.368228)
		(width 0.11684)
		(layer "F.Cu")
		(net "M_BMC_DDR4_MA<4>")
	)
	(segment
		(start 63.295022 -45.771308)
		(end 63.690246 -45.376084)
		(width 0.11684)
		(layer "F.Cu")
		(net "M_BMC_DDR4_MA<4>")
	)
	(segment
		(start 78.20279 -37.4015)
		(end 77.707744 -37.896546)
		(width 0.11684)
		(layer "F.Cu")
		(net "M_BMC_DDR4_MA<4>")
	)
	(segment
		(start 75.190096 -43.769788)
		(end 75.03414 -43.925744)
		(width 0.11684)
		(layer "F.Cu")
		(net "M_BMC_DDR4_MA<4>")
	)
	(segment
		(start 77.707744 -37.959538)
		(end 76.678028 -38.989254)
		(width 0.11684)
		(layer "F.Cu")
		(net "M_BMC_DDR4_MA<4>")
	)
	(segment
		(start 77.707744 -37.896546)
		(end 77.707744 -37.959538)
		(width 0.11684)
		(layer "F.Cu")
		(net "M_BMC_DDR4_MA<4>")
	)
	(segment
		(start 75.193398 -43.769788)
		(end 75.190096 -43.769788)
		(width 0.11684)
		(layer "F.Cu")
		(net "M_BMC_DDR4_MA<4>")
	)
	(segment
		(start 77.707744 -35.927538)
		(end 77.7621 -35.927538)
		(width 0.11684)
		(layer "F.Cu")
		(net "M_BMC_DDR4_MA<4>")
	)
	(segment
		(start 75.03414 -43.925744)
		(end 74.652378 -44.307506)
		(width 0.11684)
		(layer "F.Cu")
		(net "M_BMC_DDR4_MA<4>")
	)
	(segment
		(start 78.20279 -36.368228)
		(end 78.20279 -37.4015)
		(width 0.11684)
		(layer "F.Cu")
		(net "M_BMC_DDR4_MA<4>")
	)
	(via
		(at 75.03414 -43.925744)
		(size 0.4572)
		(drill 0.254)
		(layers "F.Cu" "B.Cu")
		(net "M_BMC_DDR4_MA<4>")
	)
	(via
		(at 63.690246 -45.376084)
		(size 0.4572)
		(drill 0.254)
		(layers "F.Cu" "B.Cu")
		(net "M_BMC_DDR4_MA<4>")
	)
	(arc
		(start 75.62342 -42.73169)
		(mid 75.511666 -43.293515)
		(end 75.193398 -43.769788)
		(width 0.11684)
		(layer "F.Cu")
		(net "M_BMC_DDR4_MA<4>")
	)
	(arc
		(start 76.678028 -38.989254)
		(mid 75.897489 -40.157413)
		(end 75.62342 -41.53535)
		(width 0.11684)
		(layer "F.Cu")
		(net "M_BMC_DDR4_MA<4>")
	)
	(segment
		(start 74.94016 -44.322238)
		(end 73.935336 -44.322238)
		(width 0.08382)
		(layer "In9.Cu")
		(net "M_BMC_DDR4_MA<4>")
	)
	(segment
		(start 63.819786 -43.386502)
		(end 63.507366 -43.386502)
		(width 0.08382)
		(layer "In9.Cu")
		(net "M_BMC_DDR4_MA<4>")
	)
	(segment
		(start 66.791586 -43.06824)
		(end 66.791586 -42.864278)
		(width 0.08382)
		(layer "In9.Cu")
		(net "M_BMC_DDR4_MA<4>")
	)
	(segment
		(start 64.878458 -44.254928)
		(end 64.878458 -44.875704)
		(width 0.08382)
		(layer "In9.Cu")
		(net "M_BMC_DDR4_MA<4>")
	)
	(segment
		(start 73.299066 -42.248328)
		(end 73.299066 -43.367198)
		(width 0.08382)
		(layer "In9.Cu")
		(net "M_BMC_DDR4_MA<4>")
	)
	(segment
		(start 70.948804 -42.972482)
		(end 70.948804 -42.83456)
		(width 0.08382)
		(layer "In9.Cu")
		(net "M_BMC_DDR4_MA<4>")
	)
	(segment
		(start 71.464424 -43.058842)
		(end 71.035164 -43.058842)
		(width 0.08382)
		(layer "In9.Cu")
		(net "M_BMC_DDR4_MA<4>")
	)
	(segment
		(start 66.14668 -43.255692)
		(end 65.778126 -43.255692)
		(width 0.08382)
		(layer "In9.Cu")
		(net "M_BMC_DDR4_MA<4>")
	)
	(segment
		(start 67.89166 -43.22064)
		(end 67.89166 -42.86631)
		(width 0.08382)
		(layer "In9.Cu")
		(net "M_BMC_DDR4_MA<4>")
	)
	(segment
		(start 68.981828 -43.67784)
		(end 68.981828 -42.865802)
		(width 0.08382)
		(layer "In9.Cu")
		(net "M_BMC_DDR4_MA<4>")
	)
	(segment
		(start 66.24066 -42.864278)
		(end 66.24066 -43.161712)
		(width 0.08382)
		(layer "In9.Cu")
		(net "M_BMC_DDR4_MA<4>")
	)
	(segment
		(start 71.592694 -43.374818)
		(end 71.592694 -43.187112)
		(width 0.08382)
		(layer "In9.Cu")
		(net "M_BMC_DDR4_MA<4>")
	)
	(segment
		(start 66.665856 -42.738548)
		(end 66.36639 -42.738548)
		(width 0.08382)
		(layer "In9.Cu")
		(net "M_BMC_DDR4_MA<4>")
	)
	(segment
		(start 67.252342 -43.1546)
		(end 66.877946 -43.1546)
		(width 0.08382)
		(layer "In9.Cu")
		(net "M_BMC_DDR4_MA<4>")
	)
	(segment
		(start 63.313056 -43.580812)
		(end 63.313056 -45.279818)
		(width 0.08382)
		(layer "In9.Cu")
		(net "M_BMC_DDR4_MA<4>")
	)
	(segment
		(start 75.03414 -43.925744)
		(end 75.03414 -44.228258)
		(width 0.08382)
		(layer "In9.Cu")
		(net "M_BMC_DDR4_MA<4>")
	)
	(segment
		(start 65.590166 -44.160948)
		(end 64.972438 -44.160948)
		(width 0.08382)
		(layer "In9.Cu")
		(net "M_BMC_DDR4_MA<4>")
	)
	(segment
		(start 64.072262 -44.875704)
		(end 64.072262 -43.638978)
		(width 0.08382)
		(layer "In9.Cu")
		(net "M_BMC_DDR4_MA<4>")
	)
	(segment
		(start 70.815962 -42.701718)
		(end 69.648324 -42.701718)
		(width 0.08382)
		(layer "In9.Cu")
		(net "M_BMC_DDR4_MA<4>")
	)
	(segment
		(start 73.848976 -44.235878)
		(end 73.848976 -42.248328)
		(width 0.08382)
		(layer "In9.Cu")
		(net "M_BMC_DDR4_MA<4>")
	)
	(segment
		(start 64.784478 -44.969684)
		(end 64.166242 -44.969684)
		(width 0.08382)
		(layer "In9.Cu")
		(net "M_BMC_DDR4_MA<4>")
	)
	(segment
		(start 68.43776 -42.864532)
		(end 68.43776 -43.22064)
		(width 0.08382)
		(layer "In9.Cu")
		(net "M_BMC_DDR4_MA<4>")
	)
	(segment
		(start 68.3514 -43.307)
		(end 67.97802 -43.307)
		(width 0.08382)
		(layer "In9.Cu")
		(net "M_BMC_DDR4_MA<4>")
	)
	(segment
		(start 69.533008 -42.817034)
		(end 69.533008 -43.67784)
		(width 0.08382)
		(layer "In9.Cu")
		(net "M_BMC_DDR4_MA<4>")
	)
	(segment
		(start 63.409322 -45.376084)
		(end 63.690246 -45.376084)
		(width 0.08382)
		(layer "In9.Cu")
		(net "M_BMC_DDR4_MA<4>")
	)
	(segment
		(start 67.338702 -42.86631)
		(end 67.338702 -43.06824)
		(width 0.08382)
		(layer "In9.Cu")
		(net "M_BMC_DDR4_MA<4>")
	)
	(segment
		(start 73.762616 -42.161968)
		(end 73.385426 -42.161968)
		(width 0.08382)
		(layer "In9.Cu")
		(net "M_BMC_DDR4_MA<4>")
	)
	(segment
		(start 68.886578 -42.770552)
		(end 68.53174 -42.770552)
		(width 0.08382)
		(layer "In9.Cu")
		(net "M_BMC_DDR4_MA<4>")
	)
	(segment
		(start 69.446648 -43.7642)
		(end 69.068188 -43.7642)
		(width 0.08382)
		(layer "In9.Cu")
		(net "M_BMC_DDR4_MA<4>")
	)
	(segment
		(start 65.684146 -43.349672)
		(end 65.684146 -44.066968)
		(width 0.08382)
		(layer "In9.Cu")
		(net "M_BMC_DDR4_MA<4>")
	)
	(segment
		(start 67.79768 -42.77233)
		(end 67.432682 -42.77233)
		(width 0.08382)
		(layer "In9.Cu")
		(net "M_BMC_DDR4_MA<4>")
	)
	(segment
		(start 73.127616 -43.538648)
		(end 71.756524 -43.538648)
		(width 0.08382)
		(layer "In9.Cu")
		(net "M_BMC_DDR4_MA<4>")
	)
	(arc
		(start 68.981828 -42.865802)
		(mid 68.95393 -42.79845)
		(end 68.886578 -42.770552)
		(width 0.08382)
		(layer "In9.Cu")
		(net "M_BMC_DDR4_MA<4>")
	)
	(arc
		(start 64.072262 -43.638978)
		(mid 63.998313 -43.460451)
		(end 63.819786 -43.386502)
		(width 0.08382)
		(layer "In9.Cu")
		(net "M_BMC_DDR4_MA<4>")
	)
	(arc
		(start 67.338702 -43.06824)
		(mid 67.313408 -43.129306)
		(end 67.252342 -43.1546)
		(width 0.08382)
		(layer "In9.Cu")
		(net "M_BMC_DDR4_MA<4>")
	)
	(arc
		(start 63.313056 -45.279818)
		(mid 63.341252 -45.347888)
		(end 63.409322 -45.376084)
		(width 0.08382)
		(layer "In9.Cu")
		(net "M_BMC_DDR4_MA<4>")
	)
	(arc
		(start 64.972438 -44.160948)
		(mid 64.905984 -44.188474)
		(end 64.878458 -44.254928)
		(width 0.08382)
		(layer "In9.Cu")
		(net "M_BMC_DDR4_MA<4>")
	)
	(arc
		(start 71.756524 -43.538648)
		(mid 71.640679 -43.490663)
		(end 71.592694 -43.374818)
		(width 0.08382)
		(layer "In9.Cu")
		(net "M_BMC_DDR4_MA<4>")
	)
	(arc
		(start 65.778126 -43.255692)
		(mid 65.711672 -43.283218)
		(end 65.684146 -43.349672)
		(width 0.08382)
		(layer "In9.Cu")
		(net "M_BMC_DDR4_MA<4>")
	)
	(arc
		(start 71.592694 -43.187112)
		(mid 71.555125 -43.096411)
		(end 71.464424 -43.058842)
		(width 0.08382)
		(layer "In9.Cu")
		(net "M_BMC_DDR4_MA<4>")
	)
	(arc
		(start 73.848976 -42.248328)
		(mid 73.823682 -42.187262)
		(end 73.762616 -42.161968)
		(width 0.08382)
		(layer "In9.Cu")
		(net "M_BMC_DDR4_MA<4>")
	)
	(arc
		(start 66.36639 -42.738548)
		(mid 66.277485 -42.775373)
		(end 66.24066 -42.864278)
		(width 0.08382)
		(layer "In9.Cu")
		(net "M_BMC_DDR4_MA<4>")
	)
	(arc
		(start 68.43776 -43.22064)
		(mid 68.412466 -43.281706)
		(end 68.3514 -43.307)
		(width 0.08382)
		(layer "In9.Cu")
		(net "M_BMC_DDR4_MA<4>")
	)
	(arc
		(start 70.948804 -42.83456)
		(mid 70.909895 -42.740627)
		(end 70.815962 -42.701718)
		(width 0.08382)
		(layer "In9.Cu")
		(net "M_BMC_DDR4_MA<4>")
	)
	(arc
		(start 73.299066 -43.367198)
		(mid 73.248849 -43.488431)
		(end 73.127616 -43.538648)
		(width 0.08382)
		(layer "In9.Cu")
		(net "M_BMC_DDR4_MA<4>")
	)
	(arc
		(start 68.53174 -42.770552)
		(mid 68.465286 -42.798078)
		(end 68.43776 -42.864532)
		(width 0.08382)
		(layer "In9.Cu")
		(net "M_BMC_DDR4_MA<4>")
	)
	(arc
		(start 67.97802 -43.307)
		(mid 67.916954 -43.281706)
		(end 67.89166 -43.22064)
		(width 0.08382)
		(layer "In9.Cu")
		(net "M_BMC_DDR4_MA<4>")
	)
	(arc
		(start 69.648324 -42.701718)
		(mid 69.566783 -42.735493)
		(end 69.533008 -42.817034)
		(width 0.08382)
		(layer "In9.Cu")
		(net "M_BMC_DDR4_MA<4>")
	)
	(arc
		(start 73.935336 -44.322238)
		(mid 73.87427 -44.296944)
		(end 73.848976 -44.235878)
		(width 0.08382)
		(layer "In9.Cu")
		(net "M_BMC_DDR4_MA<4>")
	)
	(arc
		(start 67.89166 -42.86631)
		(mid 67.864134 -42.799856)
		(end 67.79768 -42.77233)
		(width 0.08382)
		(layer "In9.Cu")
		(net "M_BMC_DDR4_MA<4>")
	)
	(arc
		(start 71.035164 -43.058842)
		(mid 70.974098 -43.033548)
		(end 70.948804 -42.972482)
		(width 0.08382)
		(layer "In9.Cu")
		(net "M_BMC_DDR4_MA<4>")
	)
	(arc
		(start 75.03414 -44.228258)
		(mid 75.006614 -44.294712)
		(end 74.94016 -44.322238)
		(width 0.08382)
		(layer "In9.Cu")
		(net "M_BMC_DDR4_MA<4>")
	)
	(arc
		(start 64.878458 -44.875704)
		(mid 64.850932 -44.942158)
		(end 64.784478 -44.969684)
		(width 0.08382)
		(layer "In9.Cu")
		(net "M_BMC_DDR4_MA<4>")
	)
	(arc
		(start 66.877946 -43.1546)
		(mid 66.81688 -43.129306)
		(end 66.791586 -43.06824)
		(width 0.08382)
		(layer "In9.Cu")
		(net "M_BMC_DDR4_MA<4>")
	)
	(arc
		(start 69.533008 -43.67784)
		(mid 69.507714 -43.738906)
		(end 69.446648 -43.7642)
		(width 0.08382)
		(layer "In9.Cu")
		(net "M_BMC_DDR4_MA<4>")
	)
	(arc
		(start 63.507366 -43.386502)
		(mid 63.369968 -43.443414)
		(end 63.313056 -43.580812)
		(width 0.08382)
		(layer "In9.Cu")
		(net "M_BMC_DDR4_MA<4>")
	)
	(arc
		(start 64.166242 -44.969684)
		(mid 64.099788 -44.942158)
		(end 64.072262 -44.875704)
		(width 0.08382)
		(layer "In9.Cu")
		(net "M_BMC_DDR4_MA<4>")
	)
	(arc
		(start 65.684146 -44.066968)
		(mid 65.65662 -44.133422)
		(end 65.590166 -44.160948)
		(width 0.08382)
		(layer "In9.Cu")
		(net "M_BMC_DDR4_MA<4>")
	)
	(arc
		(start 67.432682 -42.77233)
		(mid 67.366228 -42.799856)
		(end 67.338702 -42.86631)
		(width 0.08382)
		(layer "In9.Cu")
		(net "M_BMC_DDR4_MA<4>")
	)
	(arc
		(start 66.24066 -43.161712)
		(mid 66.213134 -43.228166)
		(end 66.14668 -43.255692)
		(width 0.08382)
		(layer "In9.Cu")
		(net "M_BMC_DDR4_MA<4>")
	)
	(arc
		(start 69.068188 -43.7642)
		(mid 69.007122 -43.738906)
		(end 68.981828 -43.67784)
		(width 0.08382)
		(layer "In9.Cu")
		(net "M_BMC_DDR4_MA<4>")
	)
	(arc
		(start 66.791586 -42.864278)
		(mid 66.754761 -42.775373)
		(end 66.665856 -42.738548)
		(width 0.08382)
		(layer "In9.Cu")
		(net "M_BMC_DDR4_MA<4>")
	)
	(arc
		(start 73.385426 -42.161968)
		(mid 73.32436 -42.187262)
		(end 73.299066 -42.248328)
		(width 0.08382)
		(layer "In9.Cu")
		(net "M_BMC_DDR4_MA<4>")
	)
	(segment
		(start 77.85227 -44.307506)
		(end 77.470508 -43.925744)
		(width 0.11684)
		(layer "F.Cu")
		(net "M_BMC_DDR4_MA<3>")
	)
	(segment
		(start 63.295022 -44.971208)
		(end 63.690246 -44.575984)
		(width 0.11684)
		(layer "F.Cu")
		(net "M_BMC_DDR4_MA<3>")
	)
	(via
		(at 77.470508 -43.925744)
		(size 0.4572)
		(drill 0.254)
		(layers "F.Cu" "B.Cu")
		(net "M_BMC_DDR4_MA<3>")
	)
	(via
		(at 63.690246 -44.575984)
		(size 0.4572)
		(drill 0.254)
		(layers "F.Cu" "B.Cu")
		(net "M_BMC_DDR4_MA<3>")
	)
	(segment
		(start 79.572358 -42.803572)
		(end 79.572358 -43.024298)
		(width 0.11684)
		(layer "B.Cu")
		(net "M_BMC_DDR4_MA<3>")
	)
	(segment
		(start 81.13903 -42.361358)
		(end 80.783684 -42.006012)
		(width 0.11684)
		(layer "B.Cu")
		(net "M_BMC_DDR4_MA<3>")
	)
	(segment
		(start 82.76717 -42.522394)
		(end 81.527904 -42.522394)
		(width 0.11684)
		(layer "B.Cu")
		(net "M_BMC_DDR4_MA<3>")
	)
	(segment
		(start 78.412086 -43.515026)
		(end 78.117446 -43.515026)
		(width 0.11684)
		(layer "B.Cu")
		(net "M_BMC_DDR4_MA<3>")
	)
	(segment
		(start 80.477614 -42.258234)
		(end 79.968852 -42.258234)
		(width 0.11684)
		(layer "B.Cu")
		(net "M_BMC_DDR4_MA<3>")
	)
	(segment
		(start 79.004668 -43.591988)
		(end 78.802484 -43.591988)
		(width 0.11684)
		(layer "B.Cu")
		(net "M_BMC_DDR4_MA<3>")
	)
	(segment
		(start 80.783684 -42.006012)
		(end 80.729836 -42.006012)
		(width 0.11684)
		(layer "B.Cu")
		(net "M_BMC_DDR4_MA<3>")
	)
	(segment
		(start 80.729836 -42.006012)
		(end 80.477614 -42.258234)
		(width 0.11684)
		(layer "B.Cu")
		(net "M_BMC_DDR4_MA<3>")
	)
	(segment
		(start 81.527904 -42.522394)
		(end 81.13903 -42.361358)
		(width 0.11684)
		(layer "B.Cu")
		(net "M_BMC_DDR4_MA<3>")
	)
	(segment
		(start 79.968852 -42.258234)
		(end 79.862426 -42.310812)
		(width 0.11684)
		(layer "B.Cu")
		(net "M_BMC_DDR4_MA<3>")
	)
	(segment
		(start 77.680566 -43.715686)
		(end 77.470508 -43.925744)
		(width 0.11684)
		(layer "B.Cu")
		(net "M_BMC_DDR4_MA<3>")
	)
	(segment
		(start 79.775558 -42.362628)
		(end 79.740506 -42.39768)
		(width 0.11684)
		(layer "B.Cu")
		(net "M_BMC_DDR4_MA<3>")
	)
	(arc
		(start 78.117446 -43.515026)
		(mid 78.064089 -43.518247)
		(end 78.011528 -43.52798)
		(width 0.11684)
		(layer "B.Cu")
		(net "M_BMC_DDR4_MA<3>")
	)
	(arc
		(start 78.518004 -43.529504)
		(mid 78.46554 -43.518641)
		(end 78.412086 -43.515026)
		(width 0.11684)
		(layer "B.Cu")
		(net "M_BMC_DDR4_MA<3>")
	)
	(arc
		(start 78.576424 -43.549062)
		(mid 78.547458 -43.538555)
		(end 78.518004 -43.529504)
		(width 0.11684)
		(layer "B.Cu")
		(net "M_BMC_DDR4_MA<3>")
	)
	(arc
		(start 79.862426 -42.310812)
		(mid 79.817975 -42.335015)
		(end 79.775558 -42.362628)
		(width 0.11684)
		(layer "B.Cu")
		(net "M_BMC_DDR4_MA<3>")
	)
	(arc
		(start 79.572358 -43.024298)
		(mid 79.406085 -43.425715)
		(end 79.004668 -43.591988)
		(width 0.11684)
		(layer "B.Cu")
		(net "M_BMC_DDR4_MA<3>")
	)
	(arc
		(start 79.740506 -42.39768)
		(mid 79.616075 -42.583905)
		(end 79.572358 -42.803572)
		(width 0.11684)
		(layer "B.Cu")
		(net "M_BMC_DDR4_MA<3>")
	)
	(arc
		(start 78.011528 -43.52798)
		(mid 77.833312 -43.599379)
		(end 77.680566 -43.715686)
		(width 0.11684)
		(layer "B.Cu")
		(net "M_BMC_DDR4_MA<3>")
	)
	(arc
		(start 78.802484 -43.591988)
		(mid 78.687441 -43.581121)
		(end 78.576424 -43.549062)
		(width 0.11684)
		(layer "B.Cu")
		(net "M_BMC_DDR4_MA<3>")
	)
	(segment
		(start 76.720446 -41.814496)
		(end 76.991464 -42.085514)
		(width 0.08382)
		(layer "In2.Cu")
		(net "M_BMC_DDR4_MA<3>")
	)
	(segment
		(start 65.574926 -40.226742)
		(end 75.097894 -40.226742)
		(width 0.08382)
		(layer "In2.Cu")
		(net "M_BMC_DDR4_MA<3>")
	)
	(segment
		(start 77.016102 -42.14495)
		(end 77.016102 -43.422062)
		(width 0.08382)
		(layer "In2.Cu")
		(net "M_BMC_DDR4_MA<3>")
	)
	(segment
		(start 63.269368 -44.482004)
		(end 63.269368 -44.417742)
		(width 0.08382)
		(layer "In2.Cu")
		(net "M_BMC_DDR4_MA<3>")
	)
	(segment
		(start 77.102462 -43.508422)
		(end 77.718666 -43.508422)
		(width 0.08382)
		(layer "In2.Cu")
		(net "M_BMC_DDR4_MA<3>")
	)
	(segment
		(start 62.917324 -40.1828)
		(end 65.40119 -40.1828)
		(width 0.08382)
		(layer "In2.Cu")
		(net "M_BMC_DDR4_MA<3>")
	)
	(segment
		(start 62.512956 -43.858942)
		(end 62.512956 -40.587168)
		(width 0.08382)
		(layer "In2.Cu")
		(net "M_BMC_DDR4_MA<3>")
	)
	(segment
		(start 75.518772 -40.49395)
		(end 75.777852 -40.23487)
		(width 0.08382)
		(layer "In2.Cu")
		(net "M_BMC_DDR4_MA<3>")
	)
	(segment
		(start 76.979526 -41.436544)
		(end 76.720446 -41.695624)
		(width 0.08382)
		(layer "In2.Cu")
		(net "M_BMC_DDR4_MA<3>")
	)
	(segment
		(start 77.812646 -43.602402)
		(end 77.812646 -43.839384)
		(width 0.08382)
		(layer "In2.Cu")
		(net "M_BMC_DDR4_MA<3>")
	)
	(segment
		(start 75.15733 -40.25138)
		(end 75.3999 -40.49395)
		(width 0.08382)
		(layer "In2.Cu")
		(net "M_BMC_DDR4_MA<3>")
	)
	(segment
		(start 63.690246 -44.575984)
		(end 63.363348 -44.575984)
		(width 0.08382)
		(layer "In2.Cu")
		(net "M_BMC_DDR4_MA<3>")
	)
	(segment
		(start 63.01867 -44.167044)
		(end 62.821058 -44.167044)
		(width 0.08382)
		(layer "In2.Cu")
		(net "M_BMC_DDR4_MA<3>")
	)
	(segment
		(start 76.69784 -41.035986)
		(end 76.979526 -41.317672)
		(width 0.08382)
		(layer "In2.Cu")
		(net "M_BMC_DDR4_MA<3>")
	)
	(segment
		(start 76.319888 -41.295066)
		(end 76.578968 -41.035986)
		(width 0.08382)
		(layer "In2.Cu")
		(net "M_BMC_DDR4_MA<3>")
	)
	(segment
		(start 75.896724 -40.23487)
		(end 76.17841 -40.516556)
		(width 0.08382)
		(layer "In2.Cu")
		(net "M_BMC_DDR4_MA<3>")
	)
	(segment
		(start 75.920346 -41.014396)
		(end 76.201016 -41.295066)
		(width 0.08382)
		(layer "In2.Cu")
		(net "M_BMC_DDR4_MA<3>")
	)
	(segment
		(start 77.726286 -43.925744)
		(end 77.470508 -43.925744)
		(width 0.08382)
		(layer "In2.Cu")
		(net "M_BMC_DDR4_MA<3>")
	)
	(segment
		(start 76.17841 -40.635428)
		(end 75.920346 -40.893492)
		(width 0.08382)
		(layer "In2.Cu")
		(net "M_BMC_DDR4_MA<3>")
	)
	(arc
		(start 76.578968 -41.035986)
		(mid 76.638404 -41.011367)
		(end 76.69784 -41.035986)
		(width 0.08382)
		(layer "In2.Cu")
		(net "M_BMC_DDR4_MA<3>")
	)
	(arc
		(start 75.097894 -40.226742)
		(mid 75.130068 -40.233142)
		(end 75.15733 -40.25138)
		(width 0.08382)
		(layer "In2.Cu")
		(net "M_BMC_DDR4_MA<3>")
	)
	(arc
		(start 62.512956 -40.587168)
		(mid 62.631393 -40.301237)
		(end 62.917324 -40.1828)
		(width 0.08382)
		(layer "In2.Cu")
		(net "M_BMC_DDR4_MA<3>")
	)
	(arc
		(start 75.920346 -40.893492)
		(mid 75.895306 -40.953944)
		(end 75.920346 -41.014396)
		(width 0.08382)
		(layer "In2.Cu")
		(net "M_BMC_DDR4_MA<3>")
	)
	(arc
		(start 77.016102 -43.422062)
		(mid 77.041396 -43.483128)
		(end 77.102462 -43.508422)
		(width 0.08382)
		(layer "In2.Cu")
		(net "M_BMC_DDR4_MA<3>")
	)
	(arc
		(start 75.777852 -40.23487)
		(mid 75.837288 -40.210251)
		(end 75.896724 -40.23487)
		(width 0.08382)
		(layer "In2.Cu")
		(net "M_BMC_DDR4_MA<3>")
	)
	(arc
		(start 76.17841 -40.516556)
		(mid 76.203029 -40.575992)
		(end 76.17841 -40.635428)
		(width 0.08382)
		(layer "In2.Cu")
		(net "M_BMC_DDR4_MA<3>")
	)
	(arc
		(start 63.269368 -44.417742)
		(mid 63.19594 -44.240472)
		(end 63.01867 -44.167044)
		(width 0.08382)
		(layer "In2.Cu")
		(net "M_BMC_DDR4_MA<3>")
	)
	(arc
		(start 65.40119 -40.1828)
		(mid 65.446263 -40.188377)
		(end 65.488566 -40.204898)
		(width 0.08382)
		(layer "In2.Cu")
		(net "M_BMC_DDR4_MA<3>")
	)
	(arc
		(start 76.979526 -41.317672)
		(mid 77.004145 -41.377108)
		(end 76.979526 -41.436544)
		(width 0.08382)
		(layer "In2.Cu")
		(net "M_BMC_DDR4_MA<3>")
	)
	(arc
		(start 77.812646 -43.839384)
		(mid 77.787352 -43.90045)
		(end 77.726286 -43.925744)
		(width 0.08382)
		(layer "In2.Cu")
		(net "M_BMC_DDR4_MA<3>")
	)
	(arc
		(start 62.821058 -44.167044)
		(mid 62.603197 -44.076803)
		(end 62.512956 -43.858942)
		(width 0.08382)
		(layer "In2.Cu")
		(net "M_BMC_DDR4_MA<3>")
	)
	(arc
		(start 77.718666 -43.508422)
		(mid 77.78512 -43.535948)
		(end 77.812646 -43.602402)
		(width 0.08382)
		(layer "In2.Cu")
		(net "M_BMC_DDR4_MA<3>")
	)
	(arc
		(start 76.720446 -41.695624)
		(mid 76.695827 -41.75506)
		(end 76.720446 -41.814496)
		(width 0.08382)
		(layer "In2.Cu")
		(net "M_BMC_DDR4_MA<3>")
	)
	(arc
		(start 63.363348 -44.575984)
		(mid 63.296894 -44.548458)
		(end 63.269368 -44.482004)
		(width 0.08382)
		(layer "In2.Cu")
		(net "M_BMC_DDR4_MA<3>")
	)
	(arc
		(start 75.3999 -40.49395)
		(mid 75.459336 -40.518569)
		(end 75.518772 -40.49395)
		(width 0.08382)
		(layer "In2.Cu")
		(net "M_BMC_DDR4_MA<3>")
	)
	(arc
		(start 76.991464 -42.085514)
		(mid 77.009685 -42.112783)
		(end 77.016102 -42.14495)
		(width 0.08382)
		(layer "In2.Cu")
		(net "M_BMC_DDR4_MA<3>")
	)
	(arc
		(start 76.201016 -41.295066)
		(mid 76.260452 -41.319685)
		(end 76.319888 -41.295066)
		(width 0.08382)
		(layer "In2.Cu")
		(net "M_BMC_DDR4_MA<3>")
	)
	(arc
		(start 65.488566 -40.204898)
		(mid 65.530382 -40.221208)
		(end 65.574926 -40.226742)
		(width 0.08382)
		(layer "In2.Cu")
		(net "M_BMC_DDR4_MA<3>")
	)
	(segment
		(start 67.9831 -40.23741)
		(end 72.622664 -40.23741)
		(width 0.11684)
		(layer "F.Cu")
		(net "M_BMC_DDR4_MA<2>")
	)
	(segment
		(start 76.691744 -35.902138)
		(end 76.7334 -35.902138)
		(width 0.11684)
		(layer "F.Cu")
		(net "M_BMC_DDR4_MA<2>")
	)
	(segment
		(start 74.912474 -42.447464)
		(end 74.652378 -42.70756)
		(width 0.11684)
		(layer "F.Cu")
		(net "M_BMC_DDR4_MA<2>")
	)
	(segment
		(start 76.691744 -37.959538)
		(end 76.592176 -38.059106)
		(width 0.11684)
		(layer "F.Cu")
		(net "M_BMC_DDR4_MA<2>")
	)
	(segment
		(start 72.736964 -40.12311)
		(end 72.736964 -39.74846)
		(width 0.11684)
		(layer "F.Cu")
		(net "M_BMC_DDR4_MA<2>")
	)
	(segment
		(start 65.656206 -42.610024)
		(end 64.894968 -43.371262)
		(width 0.11684)
		(layer "F.Cu")
		(net "M_BMC_DDR4_MA<2>")
	)
	(segment
		(start 77.18679 -36.355528)
		(end 77.18679 -37.392356)
		(width 0.11684)
		(layer "F.Cu")
		(net "M_BMC_DDR4_MA<2>")
	)
	(segment
		(start 67.8688 -40.726868)
		(end 67.8688 -40.35171)
		(width 0.11684)
		(layer "F.Cu")
		(net "M_BMC_DDR4_MA<2>")
	)
	(segment
		(start 76.691744 -37.887402)
		(end 76.691744 -37.959538)
		(width 0.11684)
		(layer "F.Cu")
		(net "M_BMC_DDR4_MA<2>")
	)
	(segment
		(start 74.652378 -42.70756)
		(end 74.444352 -42.70756)
		(width 0.11684)
		(layer "F.Cu")
		(net "M_BMC_DDR4_MA<2>")
	)
	(segment
		(start 77.18679 -37.392356)
		(end 76.691744 -37.887402)
		(width 0.11684)
		(layer "F.Cu")
		(net "M_BMC_DDR4_MA<2>")
	)
	(segment
		(start 72.249792 -42.186098)
		(end 72.249792 -41.20134)
		(width 0.11684)
		(layer "F.Cu")
		(net "M_BMC_DDR4_MA<2>")
	)
	(segment
		(start 75.0316 -41.510712)
		(end 75.0316 -42.159936)
		(width 0.11684)
		(layer "F.Cu")
		(net "M_BMC_DDR4_MA<2>")
	)
	(segment
		(start 73.91527 -42.308272)
		(end 72.371966 -42.308272)
		(width 0.11684)
		(layer "F.Cu")
		(net "M_BMC_DDR4_MA<2>")
	)
	(segment
		(start 76.7334 -35.902138)
		(end 77.18679 -36.355528)
		(width 0.11684)
		(layer "F.Cu")
		(net "M_BMC_DDR4_MA<2>")
	)
	(segment
		(start 65.725548 -40.22217)
		(end 65.725548 -42.442638)
		(width 0.11684)
		(layer "F.Cu")
		(net "M_BMC_DDR4_MA<2>")
	)
	(segment
		(start 72.622664 -39.63416)
		(end 66.313558 -39.63416)
		(width 0.11684)
		(layer "F.Cu")
		(net "M_BMC_DDR4_MA<2>")
	)
	(segment
		(start 71.88962 -40.841168)
		(end 67.9831 -40.841168)
		(width 0.11684)
		(layer "F.Cu")
		(net "M_BMC_DDR4_MA<2>")
	)
	(segment
		(start 74.328528 -42.659554)
		(end 74.021188 -42.352214)
		(width 0.11684)
		(layer "F.Cu")
		(net "M_BMC_DDR4_MA<2>")
	)
	(arc
		(start 76.592176 -38.059106)
		(mid 75.497125 -39.642595)
		(end 75.0316 -41.510712)
		(width 0.11684)
		(layer "F.Cu")
		(net "M_BMC_DDR4_MA<2>")
	)
	(arc
		(start 74.444352 -42.70756)
		(mid 74.381657 -42.695089)
		(end 74.328528 -42.659554)
		(width 0.11684)
		(layer "F.Cu")
		(net "M_BMC_DDR4_MA<2>")
	)
	(arc
		(start 72.736964 -39.74846)
		(mid 72.703486 -39.667638)
		(end 72.622664 -39.63416)
		(width 0.11684)
		(layer "F.Cu")
		(net "M_BMC_DDR4_MA<2>")
	)
	(arc
		(start 72.249792 -41.20134)
		(mid 72.1443 -40.94666)
		(end 71.88962 -40.841168)
		(width 0.11684)
		(layer "F.Cu")
		(net "M_BMC_DDR4_MA<2>")
	)
	(arc
		(start 67.9831 -40.841168)
		(mid 67.902278 -40.80769)
		(end 67.8688 -40.726868)
		(width 0.11684)
		(layer "F.Cu")
		(net "M_BMC_DDR4_MA<2>")
	)
	(arc
		(start 65.725548 -42.442638)
		(mid 65.707528 -42.53323)
		(end 65.656206 -42.610024)
		(width 0.11684)
		(layer "F.Cu")
		(net "M_BMC_DDR4_MA<2>")
	)
	(arc
		(start 74.021188 -42.352214)
		(mid 73.972607 -42.31969)
		(end 73.91527 -42.308272)
		(width 0.11684)
		(layer "F.Cu")
		(net "M_BMC_DDR4_MA<2>")
	)
	(arc
		(start 72.371966 -42.308272)
		(mid 72.285576 -42.272488)
		(end 72.249792 -42.186098)
		(width 0.11684)
		(layer "F.Cu")
		(net "M_BMC_DDR4_MA<2>")
	)
	(arc
		(start 66.313558 -39.63416)
		(mid 65.897772 -39.806384)
		(end 65.725548 -40.22217)
		(width 0.11684)
		(layer "F.Cu")
		(net "M_BMC_DDR4_MA<2>")
	)
	(arc
		(start 72.622664 -40.23741)
		(mid 72.703486 -40.203932)
		(end 72.736964 -40.12311)
		(width 0.11684)
		(layer "F.Cu")
		(net "M_BMC_DDR4_MA<2>")
	)
	(arc
		(start 75.0316 -42.159936)
		(mid 75.00063 -42.315542)
		(end 74.912474 -42.447464)
		(width 0.11684)
		(layer "F.Cu")
		(net "M_BMC_DDR4_MA<2>")
	)
	(arc
		(start 67.8688 -40.35171)
		(mid 67.902278 -40.270888)
		(end 67.9831 -40.23741)
		(width 0.11684)
		(layer "F.Cu")
		(net "M_BMC_DDR4_MA<2>")
	)
	(segment
		(start 82.797904 -40.617394)
		(end 82.644742 -40.464232)
		(width 0.11684)
		(layer "F.Cu")
		(net "M_BMC_DDR4_MA<1>")
	)
	(segment
		(start 61.695076 -46.571154)
		(end 62.0903 -46.17593)
		(width 0.11684)
		(layer "F.Cu")
		(net "M_BMC_DDR4_MA<1>")
	)
	(segment
		(start 77.801216 -41.241218)
		(end 77.559408 -41.483026)
		(width 0.11684)
		(layer "F.Cu")
		(net "M_BMC_DDR4_MA<1>")
	)
	(segment
		(start 77.470508 -41.697402)
		(end 77.470508 -43.125644)
		(width 0.11684)
		(layer "F.Cu")
		(net "M_BMC_DDR4_MA<1>")
	)
	(segment
		(start 84.8995 -40.617394)
		(end 84.17687 -40.617394)
		(width 0.11684)
		(layer "F.Cu")
		(net "M_BMC_DDR4_MA<1>")
	)
	(segment
		(start 77.470508 -43.125644)
		(end 77.85227 -43.507406)
		(width 0.11684)
		(layer "F.Cu")
		(net "M_BMC_DDR4_MA<1>")
	)
	(segment
		(start 84.17687 -40.617394)
		(end 82.797904 -40.617394)
		(width 0.11684)
		(layer "F.Cu")
		(net "M_BMC_DDR4_MA<1>")
	)
	(segment
		(start 82.644742 -40.464232)
		(end 79.677006 -40.464232)
		(width 0.11684)
		(layer "F.Cu")
		(net "M_BMC_DDR4_MA<1>")
	)
	(via
		(at 62.0903 -46.17593)
		(size 0.4572)
		(drill 0.254)
		(layers "F.Cu" "B.Cu")
		(net "M_BMC_DDR4_MA<1>")
	)
	(via
		(at 84.17687 -40.617394)
		(size 0.508)
		(drill 0.254)
		(layers "F.Cu" "B.Cu")
		(net "M_BMC_DDR4_MA<1>")
	)
	(via
		(at 77.470508 -43.125644)
		(size 0.4572)
		(drill 0.254)
		(layers "F.Cu" "B.Cu")
		(net "M_BMC_DDR4_MA<1>")
	)
	(arc
		(start 77.559408 -41.483026)
		(mid 77.493635 -41.581368)
		(end 77.470508 -41.697402)
		(width 0.11684)
		(layer "F.Cu")
		(net "M_BMC_DDR4_MA<1>")
	)
	(arc
		(start 79.677006 -40.464232)
		(mid 78.661833 -40.666163)
		(end 77.801216 -41.241218)
		(width 0.11684)
		(layer "F.Cu")
		(net "M_BMC_DDR4_MA<1>")
	)
	(segment
		(start 84.8995 -40.363394)
		(end 84.6455 -40.617394)
		(width 0.11684)
		(layer "B.Cu")
		(net "M_BMC_DDR4_MA<1>")
	)
	(segment
		(start 84.6455 -40.617394)
		(end 84.17687 -40.617394)
		(width 0.11684)
		(layer "B.Cu")
		(net "M_BMC_DDR4_MA<1>")
	)
	(segment
		(start 61.69914 -40.515286)
		(end 61.69914 -43.804078)
		(width 0.08382)
		(layer "In2.Cu")
		(net "M_BMC_DDR4_MA<1>")
	)
	(segment
		(start 61.79947 -45.757084)
		(end 61.993526 -45.757084)
		(width 0.08382)
		(layer "In2.Cu")
		(net "M_BMC_DDR4_MA<1>")
	)
	(segment
		(start 77.470508 -43.125644)
		(end 77.470508 -40.223948)
		(width 0.08382)
		(layer "In2.Cu")
		(net "M_BMC_DDR4_MA<1>")
	)
	(segment
		(start 62.507876 -44.567602)
		(end 62.507876 -44.867322)
		(width 0.08382)
		(layer "In2.Cu")
		(net "M_BMC_DDR4_MA<1>")
	)
	(segment
		(start 61.780166 -43.999658)
		(end 61.951616 -44.171108)
		(width 0.08382)
		(layer "In2.Cu")
		(net "M_BMC_DDR4_MA<1>")
	)
	(segment
		(start 62.27445 -44.22648)
		(end 62.431676 -44.383706)
		(width 0.08382)
		(layer "In2.Cu")
		(net "M_BMC_DDR4_MA<1>")
	)
	(segment
		(start 74.577956 -39.839138)
		(end 62.919356 -39.839138)
		(width 0.08382)
		(layer "In2.Cu")
		(net "M_BMC_DDR4_MA<1>")
	)
	(segment
		(start 62.091062 -46.175168)
		(end 62.0903 -46.17593)
		(width 0.08382)
		(layer "In2.Cu")
		(net "M_BMC_DDR4_MA<1>")
	)
	(segment
		(start 62.091062 -45.85462)
		(end 62.091062 -46.175168)
		(width 0.08382)
		(layer "In2.Cu")
		(net "M_BMC_DDR4_MA<1>")
	)
	(segment
		(start 77.042264 -39.831772)
		(end 74.585322 -39.831772)
		(width 0.08382)
		(layer "In2.Cu")
		(net "M_BMC_DDR4_MA<1>")
	)
	(segment
		(start 74.585322 -39.831772)
		(end 74.577956 -39.839138)
		(width 0.08382)
		(layer "In2.Cu")
		(net "M_BMC_DDR4_MA<1>")
	)
	(segment
		(start 62.413896 -44.961302)
		(end 61.80709 -44.961302)
		(width 0.08382)
		(layer "In2.Cu")
		(net "M_BMC_DDR4_MA<1>")
	)
	(segment
		(start 77.389482 -40.028368)
		(end 77.299566 -39.938452)
		(width 0.08382)
		(layer "In2.Cu")
		(net "M_BMC_DDR4_MA<1>")
	)
	(segment
		(start 61.70549 -45.062902)
		(end 61.70549 -45.663104)
		(width 0.08382)
		(layer "In2.Cu")
		(net "M_BMC_DDR4_MA<1>")
	)
	(segment
		(start 62.018418 -44.198794)
		(end 62.207648 -44.198794)
		(width 0.08382)
		(layer "In2.Cu")
		(net "M_BMC_DDR4_MA<1>")
	)
	(arc
		(start 77.299566 -39.938452)
		(mid 77.181529 -39.859519)
		(end 77.042264 -39.831772)
		(width 0.08382)
		(layer "In2.Cu")
		(net "M_BMC_DDR4_MA<1>")
	)
	(arc
		(start 62.462664 -40.00373)
		(mid 62.267472 -40.118784)
		(end 62.046104 -40.167052)
		(width 0.08382)
		(layer "In2.Cu")
		(net "M_BMC_DDR4_MA<1>")
	)
	(arc
		(start 61.70549 -45.663104)
		(mid 61.733016 -45.729558)
		(end 61.79947 -45.757084)
		(width 0.08382)
		(layer "In2.Cu")
		(net "M_BMC_DDR4_MA<1>")
	)
	(arc
		(start 62.507876 -44.867322)
		(mid 62.48035 -44.933776)
		(end 62.413896 -44.961302)
		(width 0.08382)
		(layer "In2.Cu")
		(net "M_BMC_DDR4_MA<1>")
	)
	(arc
		(start 61.993526 -45.757084)
		(mid 62.062494 -45.785652)
		(end 62.091062 -45.85462)
		(width 0.08382)
		(layer "In2.Cu")
		(net "M_BMC_DDR4_MA<1>")
	)
	(arc
		(start 62.919356 -39.839138)
		(mid 62.676627 -39.881535)
		(end 62.462664 -40.00373)
		(width 0.08382)
		(layer "In2.Cu")
		(net "M_BMC_DDR4_MA<1>")
	)
	(arc
		(start 77.470508 -40.223948)
		(mid 77.449453 -40.118095)
		(end 77.389482 -40.028368)
		(width 0.08382)
		(layer "In2.Cu")
		(net "M_BMC_DDR4_MA<1>")
	)
	(arc
		(start 62.046104 -40.167052)
		(mid 61.807517 -40.276325)
		(end 61.69914 -40.515286)
		(width 0.08382)
		(layer "In2.Cu")
		(net "M_BMC_DDR4_MA<1>")
	)
	(arc
		(start 61.951616 -44.171108)
		(mid 61.982265 -44.191587)
		(end 62.018418 -44.198794)
		(width 0.08382)
		(layer "In2.Cu")
		(net "M_BMC_DDR4_MA<1>")
	)
	(arc
		(start 61.69914 -43.804078)
		(mid 61.720195 -43.909931)
		(end 61.780166 -43.999658)
		(width 0.08382)
		(layer "In2.Cu")
		(net "M_BMC_DDR4_MA<1>")
	)
	(arc
		(start 62.207648 -44.198794)
		(mid 62.243807 -44.205986)
		(end 62.27445 -44.22648)
		(width 0.08382)
		(layer "In2.Cu")
		(net "M_BMC_DDR4_MA<1>")
	)
	(arc
		(start 62.431676 -44.383706)
		(mid 62.488052 -44.468078)
		(end 62.507876 -44.567602)
		(width 0.08382)
		(layer "In2.Cu")
		(net "M_BMC_DDR4_MA<1>")
	)
	(arc
		(start 61.80709 -44.961302)
		(mid 61.735248 -44.99106)
		(end 61.70549 -45.062902)
		(width 0.08382)
		(layer "In2.Cu")
		(net "M_BMC_DDR4_MA<1>")
	)
	(segment
		(start 83.155282 -41.744138)
		(end 82.80781 -41.744138)
		(width 0.11684)
		(layer "F.Cu")
		(net "M_BMC_DDR4_MA<13>")
	)
	(segment
		(start 83.590892 -41.744138)
		(end 83.155282 -41.744138)
		(width 0.11684)
		(layer "F.Cu")
		(net "M_BMC_DDR4_MA<13>")
	)
	(segment
		(start 79.034132 -41.525698)
		(end 78.65237 -41.90746)
		(width 0.11684)
		(layer "F.Cu")
		(net "M_BMC_DDR4_MA<13>")
	)
	(segment
		(start 84.17687 -41.887394)
		(end 83.91398 -41.887394)
		(width 0.11684)
		(layer "F.Cu")
		(net "M_BMC_DDR4_MA<13>")
	)
	(segment
		(start 82.27568 -41.514268)
		(end 81.78038 -41.514268)
		(width 0.11684)
		(layer "F.Cu")
		(net "M_BMC_DDR4_MA<13>")
	)
	(segment
		(start 79.23276 -41.32707)
		(end 79.034132 -41.525698)
		(width 0.11684)
		(layer "F.Cu")
		(net "M_BMC_DDR4_MA<13>")
	)
	(segment
		(start 83.76031 -41.82364)
		(end 83.744562 -41.807892)
		(width 0.11684)
		(layer "F.Cu")
		(net "M_BMC_DDR4_MA<13>")
	)
	(segment
		(start 63.295022 -46.571154)
		(end 63.690246 -46.17593)
		(width 0.11684)
		(layer "F.Cu")
		(net "M_BMC_DDR4_MA<13>")
	)
	(segment
		(start 81.376012 -41.346628)
		(end 81.32953 -41.300146)
		(width 0.11684)
		(layer "F.Cu")
		(net "M_BMC_DDR4_MA<13>")
	)
	(segment
		(start 84.8995 -41.887394)
		(end 84.17687 -41.887394)
		(width 0.11684)
		(layer "F.Cu")
		(net "M_BMC_DDR4_MA<13>")
	)
	(segment
		(start 80.925162 -41.132506)
		(end 79.702406 -41.132506)
		(width 0.11684)
		(layer "F.Cu")
		(net "M_BMC_DDR4_MA<13>")
	)
	(segment
		(start 82.549746 -41.637204)
		(end 82.533744 -41.621202)
		(width 0.11684)
		(layer "F.Cu")
		(net "M_BMC_DDR4_MA<13>")
	)
	(via
		(at 79.034132 -41.525698)
		(size 0.4572)
		(drill 0.254)
		(layers "F.Cu" "B.Cu")
		(net "M_BMC_DDR4_MA<13>")
	)
	(via
		(at 83.155282 -41.744138)
		(size 0.762)
		(drill 0.381)
		(layers "F.Cu" "B.Cu")
		(net "M_BMC_DDR4_MA<13>")
	)
	(via
		(at 84.17687 -41.887394)
		(size 0.508)
		(drill 0.254)
		(layers "F.Cu" "B.Cu")
		(net "M_BMC_DDR4_MA<13>")
	)
	(via
		(at 63.690246 -46.17593)
		(size 0.4572)
		(drill 0.254)
		(layers "F.Cu" "B.Cu")
		(net "M_BMC_DDR4_MA<13>")
	)
	(arc
		(start 79.702406 -41.132506)
		(mid 79.448224 -41.183066)
		(end 79.23276 -41.32707)
		(width 0.11684)
		(layer "F.Cu")
		(net "M_BMC_DDR4_MA<13>")
	)
	(arc
		(start 81.78038 -41.514268)
		(mid 81.561536 -41.470644)
		(end 81.376012 -41.346628)
		(width 0.11684)
		(layer "F.Cu")
		(net "M_BMC_DDR4_MA<13>")
	)
	(arc
		(start 81.32953 -41.300146)
		(mid 81.144019 -41.176099)
		(end 80.925162 -41.132506)
		(width 0.11684)
		(layer "F.Cu")
		(net "M_BMC_DDR4_MA<13>")
	)
	(arc
		(start 83.744562 -41.807892)
		(mid 83.674072 -41.760729)
		(end 83.590892 -41.744138)
		(width 0.11684)
		(layer "F.Cu")
		(net "M_BMC_DDR4_MA<13>")
	)
	(arc
		(start 83.91398 -41.887394)
		(mid 83.83079 -41.870829)
		(end 83.76031 -41.82364)
		(width 0.11684)
		(layer "F.Cu")
		(net "M_BMC_DDR4_MA<13>")
	)
	(arc
		(start 82.80781 -41.744138)
		(mid 82.668146 -41.716339)
		(end 82.549746 -41.637204)
		(width 0.11684)
		(layer "F.Cu")
		(net "M_BMC_DDR4_MA<13>")
	)
	(arc
		(start 82.533744 -41.621202)
		(mid 82.415357 -41.542035)
		(end 82.27568 -41.514268)
		(width 0.11684)
		(layer "F.Cu")
		(net "M_BMC_DDR4_MA<13>")
	)
	(segment
		(start 65.543176 -45.219112)
		(end 65.543176 -47.347886)
		(width 0.11684)
		(layer "B.Cu")
		(net "M_BMC_DDR4_MA<13>")
	)
	(segment
		(start 66.46926 -47.538894)
		(end 66.4464 -47.538894)
		(width 0.11684)
		(layer "B.Cu")
		(net "M_BMC_DDR4_MA<13>")
	)
	(segment
		(start 66.761106 -46.50994)
		(end 66.761106 -47.247048)
		(width 0.11684)
		(layer "B.Cu")
		(net "M_BMC_DDR4_MA<13>")
	)
	(segment
		(start 64.926972 -47.347886)
		(end 64.926972 -46.74743)
		(width 0.11684)
		(layer "B.Cu")
		(net "M_BMC_DDR4_MA<13>")
	)
	(segment
		(start 65.860168 -44.924726)
		(end 65.837562 -44.924726)
		(width 0.11684)
		(layer "B.Cu")
		(net "M_BMC_DDR4_MA<13>")
	)
	(segment
		(start 79.034132 -41.525698)
		(end 78.813152 -41.304718)
		(width 0.11684)
		(layer "B.Cu")
		(net "M_BMC_DDR4_MA<13>")
	)
	(segment
		(start 73.166986 -45.217588)
		(end 73.092056 -45.292518)
		(width 0.11684)
		(layer "B.Cu")
		(net "M_BMC_DDR4_MA<13>")
	)
	(segment
		(start 75.178412 -44.786296)
		(end 75.009248 -44.786296)
		(width 0.11684)
		(layer "B.Cu")
		(net "M_BMC_DDR4_MA<13>")
	)
	(segment
		(start 70.10146 -45.164248)
		(end 70.10146 -44.845478)
		(width 0.11684)
		(layer "B.Cu")
		(net "M_BMC_DDR4_MA<13>")
	)
	(segment
		(start 75.955652 -43.487594)
		(end 75.955652 -43.817794)
		(width 0.11684)
		(layer "B.Cu")
		(net "M_BMC_DDR4_MA<13>")
	)
	(segment
		(start 66.154554 -47.247048)
		(end 66.154554 -45.219112)
		(width 0.11684)
		(layer "B.Cu")
		(net "M_BMC_DDR4_MA<13>")
	)
	(segment
		(start 84.615782 -41.379394)
		(end 84.17687 -41.818306)
		(width 0.11684)
		(layer "B.Cu")
		(net "M_BMC_DDR4_MA<13>")
	)
	(segment
		(start 75.652884 -44.548552)
		(end 75.58278 -44.618656)
		(width 0.11684)
		(layer "B.Cu")
		(net "M_BMC_DDR4_MA<13>")
	)
	(segment
		(start 69.086222 -45.93844)
		(end 67.332606 -45.93844)
		(width 0.11684)
		(layer "B.Cu")
		(net "M_BMC_DDR4_MA<13>")
	)
	(segment
		(start 84.17687 -41.818306)
		(end 84.17687 -41.887394)
		(width 0.11684)
		(layer "B.Cu")
		(net "M_BMC_DDR4_MA<13>")
	)
	(segment
		(start 78.408784 -41.137078)
		(end 78.230476 -41.137078)
		(width 0.11684)
		(layer "B.Cu")
		(net "M_BMC_DDR4_MA<13>")
	)
	(segment
		(start 64.355472 -46.17593)
		(end 63.690246 -46.17593)
		(width 0.11684)
		(layer "B.Cu")
		(net "M_BMC_DDR4_MA<13>")
	)
	(segment
		(start 69.504306 -44.908216)
		(end 69.504306 -45.551598)
		(width 0.11684)
		(layer "B.Cu")
		(net "M_BMC_DDR4_MA<13>")
	)
	(segment
		(start 74.61504 -44.949618)
		(end 74.599292 -44.965366)
		(width 0.11684)
		(layer "B.Cu")
		(net "M_BMC_DDR4_MA<13>")
	)
	(segment
		(start 69.567298 -44.778422)
		(end 69.55155 -44.79417)
		(width 0.11684)
		(layer "B.Cu")
		(net "M_BMC_DDR4_MA<13>")
	)
	(segment
		(start 69.98716 -44.731178)
		(end 69.68109 -44.731178)
		(width 0.11684)
		(layer "B.Cu")
		(net "M_BMC_DDR4_MA<13>")
	)
	(segment
		(start 77.955394 -41.251124)
		(end 76.123292 -43.083226)
		(width 0.11684)
		(layer "B.Cu")
		(net "M_BMC_DDR4_MA<13>")
	)
	(segment
		(start 74.205084 -45.128688)
		(end 73.381616 -45.128688)
		(width 0.11684)
		(layer "B.Cu")
		(net "M_BMC_DDR4_MA<13>")
	)
	(segment
		(start 72.968104 -45.343826)
		(end 70.281038 -45.343826)
		(width 0.11684)
		(layer "B.Cu")
		(net "M_BMC_DDR4_MA<13>")
	)
	(segment
		(start 65.246504 -47.644558)
		(end 65.223644 -47.644558)
		(width 0.11684)
		(layer "B.Cu")
		(net "M_BMC_DDR4_MA<13>")
	)
	(segment
		(start 84.8995 -41.379394)
		(end 84.615782 -41.379394)
		(width 0.11684)
		(layer "B.Cu")
		(net "M_BMC_DDR4_MA<13>")
	)
	(arc
		(start 66.154554 -45.219112)
		(mid 66.06833 -45.01095)
		(end 65.860168 -44.924726)
		(width 0.11684)
		(layer "B.Cu")
		(net "M_BMC_DDR4_MA<13>")
	)
	(arc
		(start 66.761106 -47.247048)
		(mid 66.675626 -47.453414)
		(end 66.46926 -47.538894)
		(width 0.11684)
		(layer "B.Cu")
		(net "M_BMC_DDR4_MA<13>")
	)
	(arc
		(start 74.599292 -44.965366)
		(mid 74.418428 -45.086216)
		(end 74.205084 -45.128688)
		(width 0.11684)
		(layer "B.Cu")
		(net "M_BMC_DDR4_MA<13>")
	)
	(arc
		(start 78.230476 -41.137078)
		(mid 78.081577 -41.166714)
		(end 77.955394 -41.251124)
		(width 0.11684)
		(layer "B.Cu")
		(net "M_BMC_DDR4_MA<13>")
	)
	(arc
		(start 73.381616 -45.128688)
		(mid 73.26546 -45.151793)
		(end 73.166986 -45.217588)
		(width 0.11684)
		(layer "B.Cu")
		(net "M_BMC_DDR4_MA<13>")
	)
	(arc
		(start 67.332606 -45.93844)
		(mid 66.928494 -46.105828)
		(end 66.761106 -46.50994)
		(width 0.11684)
		(layer "B.Cu")
		(net "M_BMC_DDR4_MA<13>")
	)
	(arc
		(start 70.281038 -45.343826)
		(mid 70.154057 -45.291229)
		(end 70.10146 -45.164248)
		(width 0.11684)
		(layer "B.Cu")
		(net "M_BMC_DDR4_MA<13>")
	)
	(arc
		(start 66.4464 -47.538894)
		(mid 66.240034 -47.453414)
		(end 66.154554 -47.247048)
		(width 0.11684)
		(layer "B.Cu")
		(net "M_BMC_DDR4_MA<13>")
	)
	(arc
		(start 76.123292 -43.083226)
		(mid 75.999245 -43.268737)
		(end 75.955652 -43.487594)
		(width 0.11684)
		(layer "B.Cu")
		(net "M_BMC_DDR4_MA<13>")
	)
	(arc
		(start 73.092056 -45.292518)
		(mid 73.035186 -45.330517)
		(end 72.968104 -45.343826)
		(width 0.11684)
		(layer "B.Cu")
		(net "M_BMC_DDR4_MA<13>")
	)
	(arc
		(start 75.58278 -44.618656)
		(mid 75.397269 -44.742703)
		(end 75.178412 -44.786296)
		(width 0.11684)
		(layer "B.Cu")
		(net "M_BMC_DDR4_MA<13>")
	)
	(arc
		(start 78.813152 -41.304718)
		(mid 78.627641 -41.180671)
		(end 78.408784 -41.137078)
		(width 0.11684)
		(layer "B.Cu")
		(net "M_BMC_DDR4_MA<13>")
	)
	(arc
		(start 70.10146 -44.845478)
		(mid 70.067982 -44.764656)
		(end 69.98716 -44.731178)
		(width 0.11684)
		(layer "B.Cu")
		(net "M_BMC_DDR4_MA<13>")
	)
	(arc
		(start 69.68109 -44.731178)
		(mid 69.619518 -44.743519)
		(end 69.567298 -44.778422)
		(width 0.11684)
		(layer "B.Cu")
		(net "M_BMC_DDR4_MA<13>")
	)
	(arc
		(start 65.837562 -44.924726)
		(mid 65.6294 -45.01095)
		(end 65.543176 -45.219112)
		(width 0.11684)
		(layer "B.Cu")
		(net "M_BMC_DDR4_MA<13>")
	)
	(arc
		(start 69.55155 -44.79417)
		(mid 69.516588 -44.846495)
		(end 69.504306 -44.908216)
		(width 0.11684)
		(layer "B.Cu")
		(net "M_BMC_DDR4_MA<13>")
	)
	(arc
		(start 65.223644 -47.644558)
		(mid 65.013865 -47.557665)
		(end 64.926972 -47.347886)
		(width 0.11684)
		(layer "B.Cu")
		(net "M_BMC_DDR4_MA<13>")
	)
	(arc
		(start 69.397372 -45.809154)
		(mid 69.254673 -45.904785)
		(end 69.086222 -45.93844)
		(width 0.11684)
		(layer "B.Cu")
		(net "M_BMC_DDR4_MA<13>")
	)
	(arc
		(start 65.543176 -47.347886)
		(mid 65.456283 -47.557665)
		(end 65.246504 -47.644558)
		(width 0.11684)
		(layer "B.Cu")
		(net "M_BMC_DDR4_MA<13>")
	)
	(arc
		(start 69.504306 -45.551598)
		(mid 69.476463 -45.691014)
		(end 69.397372 -45.809154)
		(width 0.11684)
		(layer "B.Cu")
		(net "M_BMC_DDR4_MA<13>")
	)
	(arc
		(start 64.926972 -46.74743)
		(mid 64.759584 -46.343318)
		(end 64.355472 -46.17593)
		(width 0.11684)
		(layer "B.Cu")
		(net "M_BMC_DDR4_MA<13>")
	)
	(arc
		(start 75.955652 -43.817794)
		(mid 75.876964 -44.213293)
		(end 75.652884 -44.548552)
		(width 0.11684)
		(layer "B.Cu")
		(net "M_BMC_DDR4_MA<13>")
	)
	(arc
		(start 75.009248 -44.786296)
		(mid 74.795891 -44.828735)
		(end 74.61504 -44.949618)
		(width 0.11684)
		(layer "B.Cu")
		(net "M_BMC_DDR4_MA<13>")
	)
	(segment
		(start 77.85227 -45.107352)
		(end 77.470508 -44.72559)
		(width 0.11684)
		(layer "F.Cu")
		(net "M_BMC_DDR4_MA<12>")
	)
	(segment
		(start 62.494922 -47.371254)
		(end 62.890146 -46.97603)
		(width 0.11684)
		(layer "F.Cu")
		(net "M_BMC_DDR4_MA<12>")
	)
	(via
		(at 62.890146 -46.97603)
		(size 0.4572)
		(drill 0.254)
		(layers "F.Cu" "B.Cu")
		(net "M_BMC_DDR4_MA<12>")
	)
	(via
		(at 77.470508 -44.72559)
		(size 0.4572)
		(drill 0.254)
		(layers "F.Cu" "B.Cu")
		(net "M_BMC_DDR4_MA<12>")
	)
	(via
		(at 78.891892 -44.319952)
		(size 0.6604)
		(drill 0.3302)
		(layers "F.Cu" "B.Cu")
		(net "M_BMC_DDR4_MA<12>")
	)
	(segment
		(start 80.25384 -44.69765)
		(end 79.926688 -44.69765)
		(width 0.11684)
		(layer "B.Cu")
		(net "M_BMC_DDR4_MA<12>")
	)
	(segment
		(start 80.599788 -44.554394)
		(end 80.25384 -44.69765)
		(width 0.11684)
		(layer "B.Cu")
		(net "M_BMC_DDR4_MA<12>")
	)
	(segment
		(start 82.76717 -45.570394)
		(end 82.76717 -44.554394)
		(width 0.11684)
		(layer "B.Cu")
		(net "M_BMC_DDR4_MA<12>")
	)
	(segment
		(start 78.891892 -44.319952)
		(end 78.066138 -44.319952)
		(width 0.11684)
		(layer "B.Cu")
		(net "M_BMC_DDR4_MA<12>")
	)
	(segment
		(start 77.735684 -44.456858)
		(end 77.470508 -44.722034)
		(width 0.11684)
		(layer "B.Cu")
		(net "M_BMC_DDR4_MA<12>")
	)
	(segment
		(start 77.470508 -44.722034)
		(end 77.470508 -44.72559)
		(width 0.11684)
		(layer "B.Cu")
		(net "M_BMC_DDR4_MA<12>")
	)
	(segment
		(start 82.76717 -44.554394)
		(end 80.599788 -44.554394)
		(width 0.11684)
		(layer "B.Cu")
		(net "M_BMC_DDR4_MA<12>")
	)
	(arc
		(start 78.066138 -44.319952)
		(mid 77.887287 -44.355528)
		(end 77.735684 -44.456858)
		(width 0.11684)
		(layer "B.Cu")
		(net "M_BMC_DDR4_MA<12>")
	)
	(arc
		(start 79.926688 -44.69765)
		(mid 79.743079 -44.665168)
		(end 79.581756 -44.571666)
		(width 0.11684)
		(layer "B.Cu")
		(net "M_BMC_DDR4_MA<12>")
	)
	(arc
		(start 79.581756 -44.571666)
		(mid 79.259079 -44.384822)
		(end 78.891892 -44.319952)
		(width 0.11684)
		(layer "B.Cu")
		(net "M_BMC_DDR4_MA<12>")
	)
	(segment
		(start 64.657224 -40.972994)
		(end 63.54572 -40.972994)
		(width 0.08382)
		(layer "In2.Cu")
		(net "M_BMC_DDR4_MA<12>")
	)
	(segment
		(start 77.470508 -44.46143)
		(end 77.02042 -44.011342)
		(width 0.08382)
		(layer "In2.Cu")
		(net "M_BMC_DDR4_MA<12>")
	)
	(segment
		(start 76.6318 -43.266614)
		(end 76.6318 -42.311574)
		(width 0.08382)
		(layer "In2.Cu")
		(net "M_BMC_DDR4_MA<12>")
	)
	(segment
		(start 63.270638 -45.111924)
		(end 63.270638 -46.459902)
		(width 0.08382)
		(layer "In2.Cu")
		(net "M_BMC_DDR4_MA<12>")
	)
	(segment
		(start 63.978282 -44.99737)
		(end 63.385192 -44.99737)
		(width 0.08382)
		(layer "In2.Cu")
		(net "M_BMC_DDR4_MA<12>")
	)
	(segment
		(start 62.890146 -46.651164)
		(end 62.890146 -46.97603)
		(width 0.08382)
		(layer "In2.Cu")
		(net "M_BMC_DDR4_MA<12>")
	)
	(segment
		(start 76.953618 -43.983656)
		(end 75.941682 -43.983656)
		(width 0.08382)
		(layer "In2.Cu")
		(net "M_BMC_DDR4_MA<12>")
	)
	(segment
		(start 75.218798 -41.79062)
		(end 75.218798 -41.459404)
		(width 0.08382)
		(layer "In2.Cu")
		(net "M_BMC_DDR4_MA<12>")
	)
	(segment
		(start 63.184278 -46.546262)
		(end 62.995048 -46.546262)
		(width 0.08382)
		(layer "In2.Cu")
		(net "M_BMC_DDR4_MA<12>")
	)
	(segment
		(start 63.297562 -41.221152)
		(end 63.297562 -43.839384)
		(width 0.08382)
		(layer "In2.Cu")
		(net "M_BMC_DDR4_MA<12>")
	)
	(segment
		(start 64.845438 -40.7924)
		(end 64.845438 -40.793924)
		(width 0.08382)
		(layer "In2.Cu")
		(net "M_BMC_DDR4_MA<12>")
	)
	(segment
		(start 75.941682 -43.45813)
		(end 76.440284 -43.45813)
		(width 0.08382)
		(layer "In2.Cu")
		(net "M_BMC_DDR4_MA<12>")
	)
	(segment
		(start 77.470508 -44.72559)
		(end 77.470508 -44.46143)
		(width 0.08382)
		(layer "In2.Cu")
		(net "M_BMC_DDR4_MA<12>")
	)
	(segment
		(start 76.197206 -41.87698)
		(end 75.305158 -41.87698)
		(width 0.08382)
		(layer "In2.Cu")
		(net "M_BMC_DDR4_MA<12>")
	)
	(segment
		(start 74.340212 -40.580818)
		(end 65.06718 -40.580818)
		(width 0.08382)
		(layer "In2.Cu")
		(net "M_BMC_DDR4_MA<12>")
	)
	(segment
		(start 63.644526 -44.186348)
		(end 63.812928 -44.186348)
		(width 0.08382)
		(layer "In2.Cu")
		(net "M_BMC_DDR4_MA<12>")
	)
	(segment
		(start 75.855322 -43.897296)
		(end 75.855322 -43.54449)
		(width 0.08382)
		(layer "In2.Cu")
		(net "M_BMC_DDR4_MA<12>")
	)
	(segment
		(start 64.1096 -44.48302)
		(end 64.1096 -44.866052)
		(width 0.08382)
		(layer "In2.Cu")
		(net "M_BMC_DDR4_MA<12>")
	)
	(arc
		(start 75.305158 -41.87698)
		(mid 75.244092 -41.851686)
		(end 75.218798 -41.79062)
		(width 0.08382)
		(layer "In2.Cu")
		(net "M_BMC_DDR4_MA<12>")
	)
	(arc
		(start 62.995048 -46.546262)
		(mid 62.920871 -46.576987)
		(end 62.890146 -46.651164)
		(width 0.08382)
		(layer "In2.Cu")
		(net "M_BMC_DDR4_MA<12>")
	)
	(arc
		(start 63.297562 -43.839384)
		(mid 63.399185 -44.084725)
		(end 63.644526 -44.186348)
		(width 0.08382)
		(layer "In2.Cu")
		(net "M_BMC_DDR4_MA<12>")
	)
	(arc
		(start 63.385192 -44.99737)
		(mid 63.30419 -45.030922)
		(end 63.270638 -45.111924)
		(width 0.08382)
		(layer "In2.Cu")
		(net "M_BMC_DDR4_MA<12>")
	)
	(arc
		(start 75.855322 -43.54449)
		(mid 75.880616 -43.483424)
		(end 75.941682 -43.45813)
		(width 0.08382)
		(layer "In2.Cu")
		(net "M_BMC_DDR4_MA<12>")
	)
	(arc
		(start 65.06718 -40.580818)
		(mid 64.913931 -40.642199)
		(end 64.845438 -40.7924)
		(width 0.08382)
		(layer "In2.Cu")
		(net "M_BMC_DDR4_MA<12>")
	)
	(arc
		(start 75.218798 -41.459404)
		(mid 74.961466 -40.83815)
		(end 74.340212 -40.580818)
		(width 0.08382)
		(layer "In2.Cu")
		(net "M_BMC_DDR4_MA<12>")
	)
	(arc
		(start 75.941682 -43.983656)
		(mid 75.880616 -43.958362)
		(end 75.855322 -43.897296)
		(width 0.08382)
		(layer "In2.Cu")
		(net "M_BMC_DDR4_MA<12>")
	)
	(arc
		(start 64.1096 -44.866052)
		(mid 64.071138 -44.958908)
		(end 63.978282 -44.99737)
		(width 0.08382)
		(layer "In2.Cu")
		(net "M_BMC_DDR4_MA<12>")
	)
	(arc
		(start 76.6318 -42.311574)
		(mid 76.50451 -42.00427)
		(end 76.197206 -41.87698)
		(width 0.08382)
		(layer "In2.Cu")
		(net "M_BMC_DDR4_MA<12>")
	)
	(arc
		(start 77.02042 -44.011342)
		(mid 76.989771 -43.990863)
		(end 76.953618 -43.983656)
		(width 0.08382)
		(layer "In2.Cu")
		(net "M_BMC_DDR4_MA<12>")
	)
	(arc
		(start 63.54572 -40.972994)
		(mid 63.370246 -41.045678)
		(end 63.297562 -41.221152)
		(width 0.08382)
		(layer "In2.Cu")
		(net "M_BMC_DDR4_MA<12>")
	)
	(arc
		(start 64.845438 -40.793924)
		(mid 64.787112 -40.921061)
		(end 64.657224 -40.972994)
		(width 0.08382)
		(layer "In2.Cu")
		(net "M_BMC_DDR4_MA<12>")
	)
	(arc
		(start 63.270638 -46.459902)
		(mid 63.245344 -46.520968)
		(end 63.184278 -46.546262)
		(width 0.08382)
		(layer "In2.Cu")
		(net "M_BMC_DDR4_MA<12>")
	)
	(arc
		(start 63.812928 -44.186348)
		(mid 64.022707 -44.273241)
		(end 64.1096 -44.48302)
		(width 0.08382)
		(layer "In2.Cu")
		(net "M_BMC_DDR4_MA<12>")
	)
	(arc
		(start 76.440284 -43.45813)
		(mid 76.575706 -43.402036)
		(end 76.6318 -43.266614)
		(width 0.08382)
		(layer "In2.Cu")
		(net "M_BMC_DDR4_MA<12>")
	)
	(segment
		(start 64.894968 -44.171362)
		(end 65.290192 -43.776138)
		(width 0.11684)
		(layer "F.Cu")
		(net "M_BMC_DDR4_MA<11>")
	)
	(segment
		(start 73.8378 -39.69385)
		(end 73.8378 -41.892982)
		(width 0.11684)
		(layer "F.Cu")
		(net "M_BMC_DDR4_MA<11>")
	)
	(segment
		(start 73.43394 -41.525698)
		(end 73.257918 -41.349676)
		(width 0.11684)
		(layer "F.Cu")
		(net "M_BMC_DDR4_MA<11>")
	)
	(segment
		(start 73.8378 -41.892982)
		(end 73.852278 -41.90746)
		(width 0.11684)
		(layer "F.Cu")
		(net "M_BMC_DDR4_MA<11>")
	)
	(segment
		(start 73.329546 -39.560246)
		(end 73.704196 -39.560246)
		(width 0.11684)
		(layer "F.Cu")
		(net "M_BMC_DDR4_MA<11>")
	)
	(segment
		(start 73.215246 -41.246806)
		(end 73.215246 -39.674546)
		(width 0.11684)
		(layer "F.Cu")
		(net "M_BMC_DDR4_MA<11>")
	)
	(via
		(at 65.290192 -43.776138)
		(size 0.4572)
		(drill 0.254)
		(layers "F.Cu" "B.Cu")
		(net "M_BMC_DDR4_MA<11>")
	)
	(via
		(at 74.313288 -40.64635)
		(size 0.6604)
		(drill 0.3302)
		(layers "F.Cu" "B.Cu")
		(net "M_BMC_DDR4_MA<11>")
	)
	(via
		(at 73.43394 -41.525698)
		(size 0.4572)
		(drill 0.254)
		(layers "F.Cu" "B.Cu")
		(net "M_BMC_DDR4_MA<11>")
	)
	(arc
		(start 73.215246 -39.674546)
		(mid 73.248724 -39.593724)
		(end 73.329546 -39.560246)
		(width 0.11684)
		(layer "F.Cu")
		(net "M_BMC_DDR4_MA<11>")
	)
	(arc
		(start 73.704196 -39.560246)
		(mid 73.798668 -39.599378)
		(end 73.8378 -39.69385)
		(width 0.11684)
		(layer "F.Cu")
		(net "M_BMC_DDR4_MA<11>")
	)
	(arc
		(start 73.257918 -41.349676)
		(mid 73.226382 -41.302479)
		(end 73.215246 -41.246806)
		(width 0.11684)
		(layer "F.Cu")
		(net "M_BMC_DDR4_MA<11>")
	)
	(segment
		(start 76.391008 -38.260274)
		(end 76.691744 -37.959538)
		(width 0.11684)
		(layer "B.Cu")
		(net "M_BMC_DDR4_MA<11>")
	)
	(segment
		(start 77.211428 -37.191442)
		(end 77.076808 -37.516562)
		(width 0.11684)
		(layer "B.Cu")
		(net "M_BMC_DDR4_MA<11>")
	)
	(segment
		(start 76.691744 -37.901626)
		(end 76.691744 -37.959538)
		(width 0.11684)
		(layer "B.Cu")
		(net "M_BMC_DDR4_MA<11>")
	)
	(segment
		(start 74.313288 -40.64635)
		(end 73.43394 -41.525698)
		(width 0.11684)
		(layer "B.Cu")
		(net "M_BMC_DDR4_MA<11>")
	)
	(segment
		(start 75.981052 -38.872922)
		(end 76.391008 -38.260274)
		(width 0.11684)
		(layer "B.Cu")
		(net "M_BMC_DDR4_MA<11>")
	)
	(segment
		(start 76.691744 -35.940238)
		(end 76.76642 -35.940238)
		(width 0.11684)
		(layer "B.Cu")
		(net "M_BMC_DDR4_MA<11>")
	)
	(segment
		(start 74.313288 -40.64635)
		(end 75.494388 -39.46525)
		(width 0.11684)
		(layer "B.Cu")
		(net "M_BMC_DDR4_MA<11>")
	)
	(segment
		(start 77.076808 -37.516562)
		(end 76.691744 -37.901626)
		(width 0.11684)
		(layer "B.Cu")
		(net "M_BMC_DDR4_MA<11>")
	)
	(segment
		(start 77.07122 -36.245038)
		(end 77.211428 -36.58362)
		(width 0.11684)
		(layer "B.Cu")
		(net "M_BMC_DDR4_MA<11>")
	)
	(segment
		(start 77.211428 -36.58362)
		(end 77.211428 -37.191442)
		(width 0.11684)
		(layer "B.Cu")
		(net "M_BMC_DDR4_MA<11>")
	)
	(segment
		(start 76.76642 -35.940238)
		(end 77.07122 -36.245038)
		(width 0.11684)
		(layer "B.Cu")
		(net "M_BMC_DDR4_MA<11>")
	)
	(arc
		(start 75.494388 -39.46525)
		(mid 75.752268 -39.181039)
		(end 75.981052 -38.872922)
		(width 0.11684)
		(layer "B.Cu")
		(net "M_BMC_DDR4_MA<11>")
	)
	(segment
		(start 73.34758 -41.8592)
		(end 72.999092 -41.8592)
		(width 0.08382)
		(layer "In9.Cu")
		(net "M_BMC_DDR4_MA<11>")
	)
	(segment
		(start 73.43394 -41.525698)
		(end 73.43394 -41.77284)
		(width 0.08382)
		(layer "In9.Cu")
		(net "M_BMC_DDR4_MA<11>")
	)
	(segment
		(start 70.449186 -41.476168)
		(end 70.449186 -42.263568)
		(width 0.08382)
		(layer "In9.Cu")
		(net "M_BMC_DDR4_MA<11>")
	)
	(segment
		(start 72.171052 -41.382696)
		(end 71.681594 -41.382696)
		(width 0.08382)
		(layer "In9.Cu")
		(net "M_BMC_DDR4_MA<11>")
	)
	(segment
		(start 67.742816 -42.38117)
		(end 65.425828 -42.38117)
		(width 0.08382)
		(layer "In9.Cu")
		(net "M_BMC_DDR4_MA<11>")
	)
	(segment
		(start 67.836796 -41.5163)
		(end 67.836796 -42.28719)
		(width 0.08382)
		(layer "In9.Cu")
		(net "M_BMC_DDR4_MA<11>")
	)
	(segment
		(start 71.508874 -42.413428)
		(end 71.131938 -42.413428)
		(width 0.08382)
		(layer "In9.Cu")
		(net "M_BMC_DDR4_MA<11>")
	)
	(segment
		(start 72.257412 -42.260012)
		(end 72.257412 -41.469056)
		(width 0.08382)
		(layer "In9.Cu")
		(net "M_BMC_DDR4_MA<11>")
	)
	(segment
		(start 68.684902 -41.42232)
		(end 67.930776 -41.42232)
		(width 0.08382)
		(layer "In9.Cu")
		(net "M_BMC_DDR4_MA<11>")
	)
	(segment
		(start 71.595234 -41.469056)
		(end 71.595234 -42.327068)
		(width 0.08382)
		(layer "In9.Cu")
		(net "M_BMC_DDR4_MA<11>")
	)
	(segment
		(start 72.901048 -41.957244)
		(end 72.901048 -43.155616)
		(width 0.08382)
		(layer "In9.Cu")
		(net "M_BMC_DDR4_MA<11>")
	)
	(segment
		(start 65.28943 -43.696636)
		(end 65.290192 -43.776138)
		(width 0.08382)
		(layer "In9.Cu")
		(net "M_BMC_DDR4_MA<11>")
	)
	(segment
		(start 65.28943 -42.517568)
		(end 65.28943 -43.696636)
		(width 0.08382)
		(layer "In9.Cu")
		(net "M_BMC_DDR4_MA<11>")
	)
	(segment
		(start 72.134222 -43.163236)
		(end 72.134222 -42.42562)
		(width 0.08382)
		(layer "In9.Cu")
		(net "M_BMC_DDR4_MA<11>")
	)
	(segment
		(start 70.952106 -41.389808)
		(end 70.535546 -41.389808)
		(width 0.08382)
		(layer "In9.Cu")
		(net "M_BMC_DDR4_MA<11>")
	)
	(segment
		(start 71.045578 -42.327068)
		(end 71.045578 -41.48328)
		(width 0.08382)
		(layer "In9.Cu")
		(net "M_BMC_DDR4_MA<11>")
	)
	(segment
		(start 65.366392 -42.405808)
		(end 65.314068 -42.458132)
		(width 0.08382)
		(layer "In9.Cu")
		(net "M_BMC_DDR4_MA<11>")
	)
	(segment
		(start 69.807836 -41.42232)
		(end 69.451474 -41.42232)
		(width 0.08382)
		(layer "In9.Cu")
		(net "M_BMC_DDR4_MA<11>")
	)
	(segment
		(start 69.901816 -42.263568)
		(end 69.901816 -41.5163)
		(width 0.08382)
		(layer "In9.Cu")
		(net "M_BMC_DDR4_MA<11>")
	)
	(segment
		(start 69.263514 -42.395902)
		(end 68.907152 -42.395902)
		(width 0.08382)
		(layer "In9.Cu")
		(net "M_BMC_DDR4_MA<11>")
	)
	(segment
		(start 69.357494 -41.5163)
		(end 69.357494 -42.301922)
		(width 0.08382)
		(layer "In9.Cu")
		(net "M_BMC_DDR4_MA<11>")
	)
	(segment
		(start 72.807068 -43.249596)
		(end 72.220582 -43.249596)
		(width 0.08382)
		(layer "In9.Cu")
		(net "M_BMC_DDR4_MA<11>")
	)
	(segment
		(start 70.362826 -42.349928)
		(end 69.988176 -42.349928)
		(width 0.08382)
		(layer "In9.Cu")
		(net "M_BMC_DDR4_MA<11>")
	)
	(segment
		(start 68.813172 -42.301922)
		(end 68.813172 -41.55059)
		(width 0.08382)
		(layer "In9.Cu")
		(net "M_BMC_DDR4_MA<11>")
	)
	(arc
		(start 71.131938 -42.413428)
		(mid 71.070872 -42.388134)
		(end 71.045578 -42.327068)
		(width 0.08382)
		(layer "In9.Cu")
		(net "M_BMC_DDR4_MA<11>")
	)
	(arc
		(start 72.999092 -41.8592)
		(mid 72.929764 -41.887916)
		(end 72.901048 -41.957244)
		(width 0.08382)
		(layer "In9.Cu")
		(net "M_BMC_DDR4_MA<11>")
	)
	(arc
		(start 72.220582 -43.249596)
		(mid 72.159516 -43.224302)
		(end 72.134222 -43.163236)
		(width 0.08382)
		(layer "In9.Cu")
		(net "M_BMC_DDR4_MA<11>")
	)
	(arc
		(start 69.901816 -41.5163)
		(mid 69.87429 -41.449846)
		(end 69.807836 -41.42232)
		(width 0.08382)
		(layer "In9.Cu")
		(net "M_BMC_DDR4_MA<11>")
	)
	(arc
		(start 68.907152 -42.395902)
		(mid 68.840698 -42.368376)
		(end 68.813172 -42.301922)
		(width 0.08382)
		(layer "In9.Cu")
		(net "M_BMC_DDR4_MA<11>")
	)
	(arc
		(start 70.535546 -41.389808)
		(mid 70.47448 -41.415102)
		(end 70.449186 -41.476168)
		(width 0.08382)
		(layer "In9.Cu")
		(net "M_BMC_DDR4_MA<11>")
	)
	(arc
		(start 73.43394 -41.77284)
		(mid 73.408646 -41.833906)
		(end 73.34758 -41.8592)
		(width 0.08382)
		(layer "In9.Cu")
		(net "M_BMC_DDR4_MA<11>")
	)
	(arc
		(start 72.134222 -42.42562)
		(mid 72.151354 -42.373991)
		(end 72.195944 -42.342816)
		(width 0.08382)
		(layer "In9.Cu")
		(net "M_BMC_DDR4_MA<11>")
	)
	(arc
		(start 67.930776 -41.42232)
		(mid 67.864322 -41.449846)
		(end 67.836796 -41.5163)
		(width 0.08382)
		(layer "In9.Cu")
		(net "M_BMC_DDR4_MA<11>")
	)
	(arc
		(start 72.257412 -41.469056)
		(mid 72.232118 -41.40799)
		(end 72.171052 -41.382696)
		(width 0.08382)
		(layer "In9.Cu")
		(net "M_BMC_DDR4_MA<11>")
	)
	(arc
		(start 70.449186 -42.263568)
		(mid 70.423892 -42.324634)
		(end 70.362826 -42.349928)
		(width 0.08382)
		(layer "In9.Cu")
		(net "M_BMC_DDR4_MA<11>")
	)
	(arc
		(start 72.901048 -43.155616)
		(mid 72.873522 -43.22207)
		(end 72.807068 -43.249596)
		(width 0.08382)
		(layer "In9.Cu")
		(net "M_BMC_DDR4_MA<11>")
	)
	(arc
		(start 69.988176 -42.349928)
		(mid 69.92711 -42.324634)
		(end 69.901816 -42.263568)
		(width 0.08382)
		(layer "In9.Cu")
		(net "M_BMC_DDR4_MA<11>")
	)
	(arc
		(start 69.451474 -41.42232)
		(mid 69.38502 -41.449846)
		(end 69.357494 -41.5163)
		(width 0.08382)
		(layer "In9.Cu")
		(net "M_BMC_DDR4_MA<11>")
	)
	(arc
		(start 71.045578 -41.48328)
		(mid 71.018201 -41.417185)
		(end 70.952106 -41.389808)
		(width 0.08382)
		(layer "In9.Cu")
		(net "M_BMC_DDR4_MA<11>")
	)
	(arc
		(start 68.813172 -41.55059)
		(mid 68.775603 -41.459889)
		(end 68.684902 -41.42232)
		(width 0.08382)
		(layer "In9.Cu")
		(net "M_BMC_DDR4_MA<11>")
	)
	(arc
		(start 69.357494 -42.301922)
		(mid 69.329968 -42.368376)
		(end 69.263514 -42.395902)
		(width 0.08382)
		(layer "In9.Cu")
		(net "M_BMC_DDR4_MA<11>")
	)
	(arc
		(start 65.314068 -42.458132)
		(mid 65.295847 -42.485401)
		(end 65.28943 -42.517568)
		(width 0.08382)
		(layer "In9.Cu")
		(net "M_BMC_DDR4_MA<11>")
	)
	(arc
		(start 72.195944 -42.342816)
		(mid 72.240314 -42.311552)
		(end 72.257412 -42.260012)
		(width 0.08382)
		(layer "In9.Cu")
		(net "M_BMC_DDR4_MA<11>")
	)
	(arc
		(start 65.425828 -42.38117)
		(mid 65.393654 -42.38757)
		(end 65.366392 -42.405808)
		(width 0.08382)
		(layer "In9.Cu")
		(net "M_BMC_DDR4_MA<11>")
	)
	(arc
		(start 71.595234 -42.327068)
		(mid 71.56994 -42.388134)
		(end 71.508874 -42.413428)
		(width 0.08382)
		(layer "In9.Cu")
		(net "M_BMC_DDR4_MA<11>")
	)
	(arc
		(start 71.681594 -41.382696)
		(mid 71.620528 -41.40799)
		(end 71.595234 -41.469056)
		(width 0.08382)
		(layer "In9.Cu")
		(net "M_BMC_DDR4_MA<11>")
	)
	(arc
		(start 67.836796 -42.28719)
		(mid 67.80927 -42.353644)
		(end 67.742816 -42.38117)
		(width 0.08382)
		(layer "In9.Cu")
		(net "M_BMC_DDR4_MA<11>")
	)
	(segment
		(start 76.150978 -41.510966)
		(end 76.150978 -42.5958)
		(width 0.11684)
		(layer "F.Cu")
		(net "M_BMC_DDR4_MA<10>")
	)
	(segment
		(start 78.7781 -35.927538)
		(end 79.21879 -36.368228)
		(width 0.11684)
		(layer "F.Cu")
		(net "M_BMC_DDR4_MA<10>")
	)
	(segment
		(start 78.723744 -37.959538)
		(end 76.842874 -39.840408)
		(width 0.11684)
		(layer "F.Cu")
		(net "M_BMC_DDR4_MA<10>")
	)
	(segment
		(start 79.21879 -36.368228)
		(end 79.21879 -37.392864)
		(width 0.11684)
		(layer "F.Cu")
		(net "M_BMC_DDR4_MA<10>")
	)
	(segment
		(start 78.723744 -35.927538)
		(end 78.7781 -35.927538)
		(width 0.11684)
		(layer "F.Cu")
		(net "M_BMC_DDR4_MA<10>")
	)
	(segment
		(start 74.270616 -44.72559)
		(end 74.652378 -45.107352)
		(width 0.11684)
		(layer "F.Cu")
		(net "M_BMC_DDR4_MA<10>")
	)
	(segment
		(start 78.723744 -37.88791)
		(end 78.723744 -37.959538)
		(width 0.11684)
		(layer "F.Cu")
		(net "M_BMC_DDR4_MA<10>")
	)
	(segment
		(start 75.434698 -44.325032)
		(end 74.652378 -45.107352)
		(width 0.11684)
		(layer "F.Cu")
		(net "M_BMC_DDR4_MA<10>")
	)
	(segment
		(start 64.094868 -43.371262)
		(end 64.490092 -42.976038)
		(width 0.11684)
		(layer "F.Cu")
		(net "M_BMC_DDR4_MA<10>")
	)
	(segment
		(start 79.21879 -37.392864)
		(end 78.723744 -37.88791)
		(width 0.11684)
		(layer "F.Cu")
		(net "M_BMC_DDR4_MA<10>")
	)
	(via
		(at 64.490092 -42.976038)
		(size 0.4572)
		(drill 0.254)
		(layers "F.Cu" "B.Cu")
		(net "M_BMC_DDR4_MA<10>")
	)
	(via
		(at 74.270616 -44.72559)
		(size 0.4572)
		(drill 0.254)
		(layers "F.Cu" "B.Cu")
		(net "M_BMC_DDR4_MA<10>")
	)
	(arc
		(start 76.842874 -39.840408)
		(mid 76.330796 -40.606881)
		(end 76.150978 -41.510966)
		(width 0.11684)
		(layer "F.Cu")
		(net "M_BMC_DDR4_MA<10>")
	)
	(arc
		(start 76.150978 -42.5958)
		(mid 75.964824 -43.531657)
		(end 75.434698 -44.325032)
		(width 0.11684)
		(layer "F.Cu")
		(net "M_BMC_DDR4_MA<10>")
	)
	(segment
		(start 65.913 -41.926002)
		(end 65.913 -42.324782)
		(width 0.08382)
		(layer "In2.Cu")
		(net "M_BMC_DDR4_MA<10>")
	)
	(segment
		(start 69.21627 -42.21734)
		(end 68.968366 -42.21734)
		(width 0.08382)
		(layer "In2.Cu")
		(net "M_BMC_DDR4_MA<10>")
	)
	(segment
		(start 74.648314 -44.22013)
		(end 74.648314 -43.62323)
		(width 0.08382)
		(layer "In2.Cu")
		(net "M_BMC_DDR4_MA<10>")
	)
	(segment
		(start 64.490092 -42.62882)
		(end 64.490092 -42.976038)
		(width 0.08382)
		(layer "In2.Cu")
		(net "M_BMC_DDR4_MA<10>")
	)
	(segment
		(start 65.527428 -41.40962)
		(end 65.527428 -41.758362)
		(width 0.08382)
		(layer "In2.Cu")
		(net "M_BMC_DDR4_MA<10>")
	)
	(segment
		(start 69.932804 -42.1894)
		(end 69.932804 -41.420034)
		(width 0.08382)
		(layer "In2.Cu")
		(net "M_BMC_DDR4_MA<10>")
	)
	(segment
		(start 65.82918 -42.408602)
		(end 65.611248 -42.408602)
		(width 0.08382)
		(layer "In2.Cu")
		(net "M_BMC_DDR4_MA<10>")
	)
	(segment
		(start 70.480174 -41.390316)
		(end 70.480174 -42.1894)
		(width 0.08382)
		(layer "In2.Cu")
		(net "M_BMC_DDR4_MA<10>")
	)
	(segment
		(start 65.527428 -42.492422)
		(end 65.527428 -43.29684)
		(width 0.08382)
		(layer "In2.Cu")
		(net "M_BMC_DDR4_MA<10>")
	)
	(segment
		(start 70.941946 -41.296336)
		(end 70.574154 -41.296336)
		(width 0.08382)
		(layer "In2.Cu")
		(net "M_BMC_DDR4_MA<10>")
	)
	(segment
		(start 68.721478 -41.290748)
		(end 67.955414 -41.290748)
		(width 0.08382)
		(layer "In2.Cu")
		(net "M_BMC_DDR4_MA<10>")
	)
	(segment
		(start 68.815458 -42.064432)
		(end 68.815458 -41.384728)
		(width 0.08382)
		(layer "In2.Cu")
		(net "M_BMC_DDR4_MA<10>")
	)
	(segment
		(start 71.995538 -42.69867)
		(end 71.206106 -42.69867)
		(width 0.08382)
		(layer "In2.Cu")
		(net "M_BMC_DDR4_MA<10>")
	)
	(segment
		(start 65.611248 -41.842182)
		(end 65.82918 -41.842182)
		(width 0.08382)
		(layer "In2.Cu")
		(net "M_BMC_DDR4_MA<10>")
	)
	(segment
		(start 72.119998 -43.000168)
		(end 72.119998 -42.82313)
		(width 0.08382)
		(layer "In2.Cu")
		(net "M_BMC_DDR4_MA<10>")
	)
	(segment
		(start 69.798184 -41.285414)
		(end 69.463158 -41.285414)
		(width 0.08382)
		(layer "In2.Cu")
		(net "M_BMC_DDR4_MA<10>")
	)
	(segment
		(start 66.830194 -41.3258)
		(end 65.611248 -41.3258)
		(width 0.08382)
		(layer "In2.Cu")
		(net "M_BMC_DDR4_MA<10>")
	)
	(segment
		(start 74.270616 -44.72559)
		(end 74.270616 -44.42968)
		(width 0.08382)
		(layer "In2.Cu")
		(net "M_BMC_DDR4_MA<10>")
	)
	(segment
		(start 66.914014 -42.252138)
		(end 66.914014 -41.40962)
		(width 0.08382)
		(layer "In2.Cu")
		(net "M_BMC_DDR4_MA<10>")
	)
	(segment
		(start 74.537062 -43.511978)
		(end 73.829164 -43.511978)
		(width 0.08382)
		(layer "In2.Cu")
		(net "M_BMC_DDR4_MA<10>")
	)
	(segment
		(start 64.840358 -42.545)
		(end 64.573912 -42.545)
		(width 0.08382)
		(layer "In2.Cu")
		(net "M_BMC_DDR4_MA<10>")
	)
	(segment
		(start 71.028306 -42.46626)
		(end 71.028306 -41.382696)
		(width 0.08382)
		(layer "In2.Cu")
		(net "M_BMC_DDR4_MA<10>")
	)
	(segment
		(start 72.9234 -42.30878)
		(end 72.9234 -42.937176)
		(width 0.08382)
		(layer "In2.Cu")
		(net "M_BMC_DDR4_MA<10>")
	)
	(segment
		(start 64.924178 -43.253914)
		(end 64.924178 -42.62882)
		(width 0.08382)
		(layer "In2.Cu")
		(net "M_BMC_DDR4_MA<10>")
	)
	(segment
		(start 70.393814 -42.27576)
		(end 70.019164 -42.27576)
		(width 0.08382)
		(layer "In2.Cu")
		(net "M_BMC_DDR4_MA<10>")
	)
	(segment
		(start 73.6092 -43.292014)
		(end 73.6092 -42.30878)
		(width 0.08382)
		(layer "In2.Cu")
		(net "M_BMC_DDR4_MA<10>")
	)
	(segment
		(start 67.705478 -42.35958)
		(end 67.021456 -42.35958)
		(width 0.08382)
		(layer "In2.Cu")
		(net "M_BMC_DDR4_MA<10>")
	)
	(segment
		(start 73.51522 -42.2148)
		(end 73.01738 -42.2148)
		(width 0.08382)
		(layer "In2.Cu")
		(net "M_BMC_DDR4_MA<10>")
	)
	(segment
		(start 72.766428 -43.094148)
		(end 72.213978 -43.094148)
		(width 0.08382)
		(layer "In2.Cu")
		(net "M_BMC_DDR4_MA<10>")
	)
	(segment
		(start 69.369178 -41.379394)
		(end 69.369178 -42.064432)
		(width 0.08382)
		(layer "In2.Cu")
		(net "M_BMC_DDR4_MA<10>")
	)
	(segment
		(start 67.830446 -41.39565)
		(end 67.830446 -42.234612)
		(width 0.08382)
		(layer "In2.Cu")
		(net "M_BMC_DDR4_MA<10>")
	)
	(segment
		(start 65.441068 -43.3832)
		(end 65.053464 -43.3832)
		(width 0.08382)
		(layer "In2.Cu")
		(net "M_BMC_DDR4_MA<10>")
	)
	(segment
		(start 74.393806 -44.30649)
		(end 74.561954 -44.30649)
		(width 0.08382)
		(layer "In2.Cu")
		(net "M_BMC_DDR4_MA<10>")
	)
	(arc
		(start 65.611248 -41.3258)
		(mid 65.551978 -41.35035)
		(end 65.527428 -41.40962)
		(width 0.08382)
		(layer "In2.Cu")
		(net "M_BMC_DDR4_MA<10>")
	)
	(arc
		(start 64.573912 -42.545)
		(mid 64.514642 -42.56955)
		(end 64.490092 -42.62882)
		(width 0.08382)
		(layer "In2.Cu")
		(net "M_BMC_DDR4_MA<10>")
	)
	(arc
		(start 67.866768 -41.321228)
		(mid 67.840034 -41.354251)
		(end 67.830446 -41.39565)
		(width 0.08382)
		(layer "In2.Cu")
		(net "M_BMC_DDR4_MA<10>")
	)
	(arc
		(start 67.955414 -41.290748)
		(mid 67.90854 -41.298575)
		(end 67.866768 -41.321228)
		(width 0.08382)
		(layer "In2.Cu")
		(net "M_BMC_DDR4_MA<10>")
	)
	(arc
		(start 69.932804 -41.420034)
		(mid 69.893375 -41.324843)
		(end 69.798184 -41.285414)
		(width 0.08382)
		(layer "In2.Cu")
		(net "M_BMC_DDR4_MA<10>")
	)
	(arc
		(start 73.6092 -42.30878)
		(mid 73.581674 -42.242326)
		(end 73.51522 -42.2148)
		(width 0.08382)
		(layer "In2.Cu")
		(net "M_BMC_DDR4_MA<10>")
	)
	(arc
		(start 72.9234 -42.937176)
		(mid 72.877424 -43.048172)
		(end 72.766428 -43.094148)
		(width 0.08382)
		(layer "In2.Cu")
		(net "M_BMC_DDR4_MA<10>")
	)
	(arc
		(start 67.021456 -42.35958)
		(mid 66.945483 -42.328111)
		(end 66.914014 -42.252138)
		(width 0.08382)
		(layer "In2.Cu")
		(net "M_BMC_DDR4_MA<10>")
	)
	(arc
		(start 66.914014 -41.40962)
		(mid 66.889464 -41.35035)
		(end 66.830194 -41.3258)
		(width 0.08382)
		(layer "In2.Cu")
		(net "M_BMC_DDR4_MA<10>")
	)
	(arc
		(start 74.648314 -43.62323)
		(mid 74.615729 -43.544563)
		(end 74.537062 -43.511978)
		(width 0.08382)
		(layer "In2.Cu")
		(net "M_BMC_DDR4_MA<10>")
	)
	(arc
		(start 70.019164 -42.27576)
		(mid 69.958098 -42.250466)
		(end 69.932804 -42.1894)
		(width 0.08382)
		(layer "In2.Cu")
		(net "M_BMC_DDR4_MA<10>")
	)
	(arc
		(start 67.830446 -42.234612)
		(mid 67.793844 -42.322978)
		(end 67.705478 -42.35958)
		(width 0.08382)
		(layer "In2.Cu")
		(net "M_BMC_DDR4_MA<10>")
	)
	(arc
		(start 71.206106 -42.69867)
		(mid 71.16228 -42.691107)
		(end 71.123556 -42.669206)
		(width 0.08382)
		(layer "In2.Cu")
		(net "M_BMC_DDR4_MA<10>")
	)
	(arc
		(start 68.815458 -41.384728)
		(mid 68.787932 -41.318274)
		(end 68.721478 -41.290748)
		(width 0.08382)
		(layer "In2.Cu")
		(net "M_BMC_DDR4_MA<10>")
	)
	(arc
		(start 72.213978 -43.094148)
		(mid 72.147524 -43.066622)
		(end 72.119998 -43.000168)
		(width 0.08382)
		(layer "In2.Cu")
		(net "M_BMC_DDR4_MA<10>")
	)
	(arc
		(start 68.968366 -42.21734)
		(mid 68.860244 -42.172554)
		(end 68.815458 -42.064432)
		(width 0.08382)
		(layer "In2.Cu")
		(net "M_BMC_DDR4_MA<10>")
	)
	(arc
		(start 64.924178 -42.62882)
		(mid 64.899628 -42.56955)
		(end 64.840358 -42.545)
		(width 0.08382)
		(layer "In2.Cu")
		(net "M_BMC_DDR4_MA<10>")
	)
	(arc
		(start 65.611248 -42.408602)
		(mid 65.551978 -42.433152)
		(end 65.527428 -42.492422)
		(width 0.08382)
		(layer "In2.Cu")
		(net "M_BMC_DDR4_MA<10>")
	)
	(arc
		(start 65.527428 -43.29684)
		(mid 65.502134 -43.357906)
		(end 65.441068 -43.3832)
		(width 0.08382)
		(layer "In2.Cu")
		(net "M_BMC_DDR4_MA<10>")
	)
	(arc
		(start 69.369178 -42.064432)
		(mid 69.324392 -42.172554)
		(end 69.21627 -42.21734)
		(width 0.08382)
		(layer "In2.Cu")
		(net "M_BMC_DDR4_MA<10>")
	)
	(arc
		(start 73.01738 -42.2148)
		(mid 72.950926 -42.242326)
		(end 72.9234 -42.30878)
		(width 0.08382)
		(layer "In2.Cu")
		(net "M_BMC_DDR4_MA<10>")
	)
	(arc
		(start 71.123556 -42.669206)
		(mid 71.053214 -42.578389)
		(end 71.028306 -42.46626)
		(width 0.08382)
		(layer "In2.Cu")
		(net "M_BMC_DDR4_MA<10>")
	)
	(arc
		(start 65.913 -42.324782)
		(mid 65.88845 -42.384052)
		(end 65.82918 -42.408602)
		(width 0.08382)
		(layer "In2.Cu")
		(net "M_BMC_DDR4_MA<10>")
	)
	(arc
		(start 71.028306 -41.382696)
		(mid 71.003012 -41.32163)
		(end 70.941946 -41.296336)
		(width 0.08382)
		(layer "In2.Cu")
		(net "M_BMC_DDR4_MA<10>")
	)
	(arc
		(start 74.270616 -44.42968)
		(mid 74.306698 -44.342572)
		(end 74.393806 -44.30649)
		(width 0.08382)
		(layer "In2.Cu")
		(net "M_BMC_DDR4_MA<10>")
	)
	(arc
		(start 74.561954 -44.30649)
		(mid 74.62302 -44.281196)
		(end 74.648314 -44.22013)
		(width 0.08382)
		(layer "In2.Cu")
		(net "M_BMC_DDR4_MA<10>")
	)
	(arc
		(start 72.119998 -42.82313)
		(mid 72.083545 -42.735123)
		(end 71.995538 -42.69867)
		(width 0.08382)
		(layer "In2.Cu")
		(net "M_BMC_DDR4_MA<10>")
	)
	(arc
		(start 65.82918 -41.842182)
		(mid 65.88845 -41.866732)
		(end 65.913 -41.926002)
		(width 0.08382)
		(layer "In2.Cu")
		(net "M_BMC_DDR4_MA<10>")
	)
	(arc
		(start 70.480174 -42.1894)
		(mid 70.45488 -42.250466)
		(end 70.393814 -42.27576)
		(width 0.08382)
		(layer "In2.Cu")
		(net "M_BMC_DDR4_MA<10>")
	)
	(arc
		(start 73.829164 -43.511978)
		(mid 73.673626 -43.447552)
		(end 73.6092 -43.292014)
		(width 0.08382)
		(layer "In2.Cu")
		(net "M_BMC_DDR4_MA<10>")
	)
	(arc
		(start 69.463158 -41.285414)
		(mid 69.396704 -41.31294)
		(end 69.369178 -41.379394)
		(width 0.08382)
		(layer "In2.Cu")
		(net "M_BMC_DDR4_MA<10>")
	)
	(arc
		(start 70.574154 -41.296336)
		(mid 70.5077 -41.323862)
		(end 70.480174 -41.390316)
		(width 0.08382)
		(layer "In2.Cu")
		(net "M_BMC_DDR4_MA<10>")
	)
	(arc
		(start 65.527428 -41.758362)
		(mid 65.551978 -41.817632)
		(end 65.611248 -41.842182)
		(width 0.08382)
		(layer "In2.Cu")
		(net "M_BMC_DDR4_MA<10>")
	)
	(arc
		(start 65.053464 -43.3832)
		(mid 64.962045 -43.345333)
		(end 64.924178 -43.253914)
		(width 0.08382)
		(layer "In2.Cu")
		(net "M_BMC_DDR4_MA<10>")
	)
	(segment
		(start 74.652378 -43.507406)
		(end 75.03414 -43.125644)
		(width 0.11684)
		(layer "F.Cu")
		(net "M_BMC_DDR4_MA<0>")
	)
	(segment
		(start 63.295022 -43.371262)
		(end 63.690246 -42.976038)
		(width 0.11684)
		(layer "F.Cu")
		(net "M_BMC_DDR4_MA<0>")
	)
	(via
		(at 63.690246 -42.976038)
		(size 0.4572)
		(drill 0.254)
		(layers "F.Cu" "B.Cu")
		(net "M_BMC_DDR4_MA<0>")
	)
	(via
		(at 75.03414 -43.125644)
		(size 0.4572)
		(drill 0.254)
		(layers "F.Cu" "B.Cu")
		(net "M_BMC_DDR4_MA<0>")
	)
	(segment
		(start 77.303884 -40.582088)
		(end 78.666594 -40.017192)
		(width 0.11684)
		(layer "B.Cu")
		(net "M_BMC_DDR4_MA<0>")
	)
	(segment
		(start 80.807052 -35.940238)
		(end 81.14792 -36.281106)
		(width 0.11684)
		(layer "B.Cu")
		(net "M_BMC_DDR4_MA<0>")
	)
	(segment
		(start 80.755744 -35.940238)
		(end 80.807052 -35.940238)
		(width 0.11684)
		(layer "B.Cu")
		(net "M_BMC_DDR4_MA<0>")
	)
	(segment
		(start 81.094834 -37.563552)
		(end 80.755744 -37.902642)
		(width 0.11684)
		(layer "B.Cu")
		(net "M_BMC_DDR4_MA<0>")
	)
	(segment
		(start 81.269078 -36.573714)
		(end 81.269078 -37.142674)
		(width 0.11684)
		(layer "B.Cu")
		(net "M_BMC_DDR4_MA<0>")
	)
	(segment
		(start 75.873864 -41.903142)
		(end 76.975462 -40.801544)
		(width 0.11684)
		(layer "B.Cu")
		(net "M_BMC_DDR4_MA<0>")
	)
	(segment
		(start 81.14792 -36.281106)
		(end 81.269078 -36.573714)
		(width 0.11684)
		(layer "B.Cu")
		(net "M_BMC_DDR4_MA<0>")
	)
	(segment
		(start 75.840336 -42.227246)
		(end 75.840336 -41.984168)
		(width 0.11684)
		(layer "B.Cu")
		(net "M_BMC_DDR4_MA<0>")
	)
	(segment
		(start 81.269078 -37.142674)
		(end 81.094834 -37.563552)
		(width 0.11684)
		(layer "B.Cu")
		(net "M_BMC_DDR4_MA<0>")
	)
	(segment
		(start 75.03668 -43.125644)
		(end 75.77328 -42.389044)
		(width 0.11684)
		(layer "B.Cu")
		(net "M_BMC_DDR4_MA<0>")
	)
	(segment
		(start 80.755744 -37.902642)
		(end 80.755744 -37.959538)
		(width 0.11684)
		(layer "B.Cu")
		(net "M_BMC_DDR4_MA<0>")
	)
	(segment
		(start 75.03414 -43.125644)
		(end 75.03668 -43.125644)
		(width 0.11684)
		(layer "B.Cu")
		(net "M_BMC_DDR4_MA<0>")
	)
	(segment
		(start 78.761082 -39.9542)
		(end 80.755744 -37.959538)
		(width 0.11684)
		(layer "B.Cu")
		(net "M_BMC_DDR4_MA<0>")
	)
	(arc
		(start 76.994512 -40.783002)
		(mid 77.139968 -40.668331)
		(end 77.303884 -40.582088)
		(width 0.11684)
		(layer "B.Cu")
		(net "M_BMC_DDR4_MA<0>")
	)
	(arc
		(start 75.840336 -41.984168)
		(mid 75.849056 -41.94033)
		(end 75.873864 -41.903142)
		(width 0.11684)
		(layer "B.Cu")
		(net "M_BMC_DDR4_MA<0>")
	)
	(arc
		(start 78.666594 -40.017192)
		(mid 78.716922 -39.990327)
		(end 78.761082 -39.9542)
		(width 0.11684)
		(layer "B.Cu")
		(net "M_BMC_DDR4_MA<0>")
	)
	(arc
		(start 75.77328 -42.389044)
		(mid 75.822935 -42.314825)
		(end 75.840336 -42.227246)
		(width 0.11684)
		(layer "B.Cu")
		(net "M_BMC_DDR4_MA<0>")
	)
	(arc
		(start 76.975462 -40.801544)
		(mid 76.984926 -40.79221)
		(end 76.994512 -40.783002)
		(width 0.11684)
		(layer "B.Cu")
		(net "M_BMC_DDR4_MA<0>")
	)
	(segment
		(start 75.003152 -42.615866)
		(end 75.003152 -42.323766)
		(width 0.08382)
		(layer "In2.Cu")
		(net "M_BMC_DDR4_MA<0>")
	)
	(segment
		(start 74.08418 -42.709846)
		(end 74.909172 -42.709846)
		(width 0.08382)
		(layer "In2.Cu")
		(net "M_BMC_DDR4_MA<0>")
	)
	(segment
		(start 65.041272 -41.56202)
		(end 65.041272 -41.22547)
		(width 0.08382)
		(layer "In2.Cu")
		(net "M_BMC_DDR4_MA<0>")
	)
	(segment
		(start 75.03414 -43.403774)
		(end 75.03414 -43.125644)
		(width 0.08382)
		(layer "In2.Cu")
		(net "M_BMC_DDR4_MA<0>")
	)
	(segment
		(start 74.81443 -41.33596)
		(end 74.81443 -41.835832)
		(width 0.08382)
		(layer "In2.Cu")
		(net "M_BMC_DDR4_MA<0>")
	)
	(segment
		(start 73.91019 -40.976042)
		(end 74.454512 -40.976042)
		(width 0.08382)
		(layer "In2.Cu")
		(net "M_BMC_DDR4_MA<0>")
	)
	(segment
		(start 71.410576 -41.13657)
		(end 71.410576 -42.218102)
		(width 0.08382)
		(layer "In2.Cu")
		(net "M_BMC_DDR4_MA<0>")
	)
	(segment
		(start 71.504556 -42.312082)
		(end 71.879206 -42.312082)
		(width 0.08382)
		(layer "In2.Cu")
		(net "M_BMC_DDR4_MA<0>")
	)
	(segment
		(start 72.067166 -40.941752)
		(end 72.95388 -40.941752)
		(width 0.08382)
		(layer "In2.Cu")
		(net "M_BMC_DDR4_MA<0>")
	)
	(segment
		(start 65.332864 -40.933878)
		(end 71.207884 -40.933878)
		(width 0.08382)
		(layer "In2.Cu")
		(net "M_BMC_DDR4_MA<0>")
	)
	(segment
		(start 73.04786 -41.035732)
		(end 73.04786 -41.827704)
		(width 0.08382)
		(layer "In2.Cu")
		(net "M_BMC_DDR4_MA<0>")
	)
	(segment
		(start 73.815956 -41.570148)
		(end 73.815956 -41.070276)
		(width 0.08382)
		(layer "In2.Cu")
		(net "M_BMC_DDR4_MA<0>")
	)
	(segment
		(start 76.204826 -42.398696)
		(end 76.204826 -42.956734)
		(width 0.08382)
		(layer "In2.Cu")
		(net "M_BMC_DDR4_MA<0>")
	)
	(segment
		(start 71.973186 -42.218102)
		(end 71.973186 -41.035732)
		(width 0.08382)
		(layer "In2.Cu")
		(net "M_BMC_DDR4_MA<0>")
	)
	(segment
		(start 75.097132 -42.229786)
		(end 76.035916 -42.229786)
		(width 0.08382)
		(layer "In2.Cu")
		(net "M_BMC_DDR4_MA<0>")
	)
	(segment
		(start 63.690246 -42.976038)
		(end 63.980568 -42.976038)
		(width 0.08382)
		(layer "In2.Cu")
		(net "M_BMC_DDR4_MA<0>")
	)
	(segment
		(start 73.9902 -42.02557)
		(end 73.9902 -42.615866)
		(width 0.08382)
		(layer "In2.Cu")
		(net "M_BMC_DDR4_MA<0>")
	)
	(segment
		(start 73.13422 -41.914064)
		(end 73.47204 -41.914064)
		(width 0.08382)
		(layer "In2.Cu")
		(net "M_BMC_DDR4_MA<0>")
	)
	(segment
		(start 75.59294 -43.294046)
		(end 75.59294 -43.41241)
		(width 0.08382)
		(layer "In2.Cu")
		(net "M_BMC_DDR4_MA<0>")
	)
	(segment
		(start 64.153288 -41.78427)
		(end 64.819022 -41.78427)
		(width 0.08382)
		(layer "In2.Cu")
		(net "M_BMC_DDR4_MA<0>")
	)
	(segment
		(start 75.464924 -43.540426)
		(end 75.170792 -43.540426)
		(width 0.08382)
		(layer "In2.Cu")
		(net "M_BMC_DDR4_MA<0>")
	)
	(segment
		(start 76.035916 -43.125644)
		(end 75.761342 -43.125644)
		(width 0.08382)
		(layer "In2.Cu")
		(net "M_BMC_DDR4_MA<0>")
	)
	(segment
		(start 64.066928 -42.889678)
		(end 64.066928 -41.87063)
		(width 0.08382)
		(layer "In2.Cu")
		(net "M_BMC_DDR4_MA<0>")
	)
	(segment
		(start 74.72045 -41.929812)
		(end 74.085958 -41.929812)
		(width 0.08382)
		(layer "In2.Cu")
		(net "M_BMC_DDR4_MA<0>")
	)
	(arc
		(start 71.973186 -41.035732)
		(mid 72.000712 -40.969278)
		(end 72.067166 -40.941752)
		(width 0.08382)
		(layer "In2.Cu")
		(net "M_BMC_DDR4_MA<0>")
	)
	(arc
		(start 76.035916 -42.229786)
		(mid 76.155353 -42.279259)
		(end 76.204826 -42.398696)
		(width 0.08382)
		(layer "In2.Cu")
		(net "M_BMC_DDR4_MA<0>")
	)
	(arc
		(start 73.47204 -41.914064)
		(mid 73.715225 -41.813333)
		(end 73.815956 -41.570148)
		(width 0.08382)
		(layer "In2.Cu")
		(net "M_BMC_DDR4_MA<0>")
	)
	(arc
		(start 71.207884 -40.933878)
		(mid 71.351209 -40.993245)
		(end 71.410576 -41.13657)
		(width 0.08382)
		(layer "In2.Cu")
		(net "M_BMC_DDR4_MA<0>")
	)
	(arc
		(start 74.81443 -41.835832)
		(mid 74.786904 -41.902286)
		(end 74.72045 -41.929812)
		(width 0.08382)
		(layer "In2.Cu")
		(net "M_BMC_DDR4_MA<0>")
	)
	(arc
		(start 75.003152 -42.323766)
		(mid 75.030678 -42.257312)
		(end 75.097132 -42.229786)
		(width 0.08382)
		(layer "In2.Cu")
		(net "M_BMC_DDR4_MA<0>")
	)
	(arc
		(start 71.879206 -42.312082)
		(mid 71.94566 -42.284556)
		(end 71.973186 -42.218102)
		(width 0.08382)
		(layer "In2.Cu")
		(net "M_BMC_DDR4_MA<0>")
	)
	(arc
		(start 76.204826 -42.956734)
		(mid 76.155353 -43.076171)
		(end 76.035916 -43.125644)
		(width 0.08382)
		(layer "In2.Cu")
		(net "M_BMC_DDR4_MA<0>")
	)
	(arc
		(start 74.085958 -41.929812)
		(mid 74.018247 -41.957859)
		(end 73.9902 -42.02557)
		(width 0.08382)
		(layer "In2.Cu")
		(net "M_BMC_DDR4_MA<0>")
	)
	(arc
		(start 71.410576 -42.218102)
		(mid 71.438102 -42.284556)
		(end 71.504556 -42.312082)
		(width 0.08382)
		(layer "In2.Cu")
		(net "M_BMC_DDR4_MA<0>")
	)
	(arc
		(start 74.454512 -40.976042)
		(mid 74.709012 -41.08146)
		(end 74.81443 -41.33596)
		(width 0.08382)
		(layer "In2.Cu")
		(net "M_BMC_DDR4_MA<0>")
	)
	(arc
		(start 64.066928 -41.87063)
		(mid 64.092222 -41.809564)
		(end 64.153288 -41.78427)
		(width 0.08382)
		(layer "In2.Cu")
		(net "M_BMC_DDR4_MA<0>")
	)
	(arc
		(start 72.95388 -40.941752)
		(mid 73.020334 -40.969278)
		(end 73.04786 -41.035732)
		(width 0.08382)
		(layer "In2.Cu")
		(net "M_BMC_DDR4_MA<0>")
	)
	(arc
		(start 75.59294 -43.41241)
		(mid 75.555445 -43.502931)
		(end 75.464924 -43.540426)
		(width 0.08382)
		(layer "In2.Cu")
		(net "M_BMC_DDR4_MA<0>")
	)
	(arc
		(start 75.761342 -43.125644)
		(mid 75.642264 -43.174968)
		(end 75.59294 -43.294046)
		(width 0.08382)
		(layer "In2.Cu")
		(net "M_BMC_DDR4_MA<0>")
	)
	(arc
		(start 65.041272 -41.22547)
		(mid 65.126677 -41.019283)
		(end 65.332864 -40.933878)
		(width 0.08382)
		(layer "In2.Cu")
		(net "M_BMC_DDR4_MA<0>")
	)
	(arc
		(start 73.04786 -41.827704)
		(mid 73.073154 -41.88877)
		(end 73.13422 -41.914064)
		(width 0.08382)
		(layer "In2.Cu")
		(net "M_BMC_DDR4_MA<0>")
	)
	(arc
		(start 74.909172 -42.709846)
		(mid 74.975626 -42.68232)
		(end 75.003152 -42.615866)
		(width 0.08382)
		(layer "In2.Cu")
		(net "M_BMC_DDR4_MA<0>")
	)
	(arc
		(start 63.980568 -42.976038)
		(mid 64.041634 -42.950744)
		(end 64.066928 -42.889678)
		(width 0.08382)
		(layer "In2.Cu")
		(net "M_BMC_DDR4_MA<0>")
	)
	(arc
		(start 75.170792 -43.540426)
		(mid 75.074164 -43.500402)
		(end 75.03414 -43.403774)
		(width 0.08382)
		(layer "In2.Cu")
		(net "M_BMC_DDR4_MA<0>")
	)
	(arc
		(start 64.819022 -41.78427)
		(mid 64.976176 -41.719174)
		(end 65.041272 -41.56202)
		(width 0.08382)
		(layer "In2.Cu")
		(net "M_BMC_DDR4_MA<0>")
	)
	(arc
		(start 73.815956 -41.070276)
		(mid 73.843556 -41.003642)
		(end 73.91019 -40.976042)
		(width 0.08382)
		(layer "In2.Cu")
		(net "M_BMC_DDR4_MA<0>")
	)
	(arc
		(start 73.9902 -42.615866)
		(mid 74.017726 -42.68232)
		(end 74.08418 -42.709846)
		(width 0.08382)
		(layer "In2.Cu")
		(net "M_BMC_DDR4_MA<0>")
	)
	(segment
		(start 70.623176 -53.65496)
		(end 70.771258 -53.65496)
		(width 0.1016)
		(layer "F.Cu")
		(net "M_BMC_DDR4_DQS1_P")
	)
	(segment
		(start 70.22973 -55.250842)
		(end 70.189852 -55.210964)
		(width 0.1016)
		(layer "F.Cu")
		(net "M_BMC_DDR4_DQS1_P")
	)
	(segment
		(start 69.375528 -55.37708)
		(end 69.355208 -55.37708)
		(width 0.1016)
		(layer "F.Cu")
		(net "M_BMC_DDR4_DQS1_P")
	)
	(segment
		(start 69.013578 -53.808376)
		(end 69.047106 -53.774848)
		(width 0.1016)
		(layer "F.Cu")
		(net "M_BMC_DDR4_DQS1_P")
	)
	(segment
		(start 70.77583 -55.37708)
		(end 70.53453 -55.37708)
		(width 0.1016)
		(layer "F.Cu")
		(net "M_BMC_DDR4_DQS1_P")
	)
	(segment
		(start 70.90791 -53.791866)
		(end 70.90791 -53.965856)
		(width 0.1016)
		(layer "F.Cu")
		(net "M_BMC_DDR4_DQS1_P")
	)
	(segment
		(start 68.750434 -53.90896)
		(end 68.770754 -53.90896)
		(width 0.1016)
		(layer "F.Cu")
		(net "M_BMC_DDR4_DQS1_P")
	)
	(segment
		(start 70.90791 -55.129684)
		(end 70.90791 -55.245)
		(width 0.1016)
		(layer "F.Cu")
		(net "M_BMC_DDR4_DQS1_P")
	)
	(segment
		(start 68.804028 -55.11038)
		(end 68.783708 -55.11038)
		(width 0.1016)
		(layer "F.Cu")
		(net "M_BMC_DDR4_DQS1_P")
	)
	(segment
		(start 68.191634 -53.65496)
		(end 68.211954 -53.65496)
		(width 0.1016)
		(layer "F.Cu")
		(net "M_BMC_DDR4_DQS1_P")
	)
	(segment
		(start 67.337178 -53.755544)
		(end 67.39001 -53.808376)
		(width 0.1016)
		(layer "F.Cu")
		(net "M_BMC_DDR4_DQS1_P")
	)
	(segment
		(start 70.861174 -53.692298)
		(end 70.870318 -53.701442)
		(width 0.1016)
		(layer "F.Cu")
		(net "M_BMC_DDR4_DQS1_P")
	)
	(segment
		(start 65.908174 -53.65496)
		(end 65.949322 -53.65496)
		(width 0.1016)
		(layer "F.Cu")
		(net "M_BMC_DDR4_DQS1_P")
	)
	(segment
		(start 67.58432 -55.085996)
		(end 67.58432 -54.802786)
		(width 0.1016)
		(layer "F.Cu")
		(net "M_BMC_DDR4_DQS1_P")
	)
	(segment
		(start 67.614292 -54.73065)
		(end 67.83832 -54.506622)
		(width 0.1016)
		(layer "F.Cu")
		(net "M_BMC_DDR4_DQS1_P")
	)
	(segment
		(start 68.201286 -55.372)
		(end 67.870324 -55.372)
		(width 0.1016)
		(layer "F.Cu")
		(net "M_BMC_DDR4_DQS1_P")
	)
	(segment
		(start 67.632834 -53.90896)
		(end 67.653154 -53.90896)
		(width 0.1016)
		(layer "F.Cu")
		(net "M_BMC_DDR4_DQS1_P")
	)
	(segment
		(start 69.732652 -53.781198)
		(end 69.77253 -53.821076)
		(width 0.1016)
		(layer "F.Cu")
		(net "M_BMC_DDR4_DQS1_P")
	)
	(segment
		(start 64.686434 -53.352192)
		(end 65.355724 -53.352192)
		(width 0.1016)
		(layer "F.Cu")
		(net "M_BMC_DDR4_DQS1_P")
	)
	(segment
		(start 69.683884 -55.210964)
		(end 69.618352 -55.276496)
		(width 0.1016)
		(layer "F.Cu")
		(net "M_BMC_DDR4_DQS1_P")
	)
	(segment
		(start 69.336666 -53.65496)
		(end 69.427852 -53.65496)
		(width 0.1016)
		(layer "F.Cu")
		(net "M_BMC_DDR4_DQS1_P")
	)
	(segment
		(start 65.404238 -53.362098)
		(end 65.546986 -53.504846)
		(width 0.1016)
		(layer "F.Cu")
		(net "M_BMC_DDR4_DQS1_P")
	)
	(segment
		(start 67.895978 -53.808376)
		(end 67.94881 -53.755544)
		(width 0.1016)
		(layer "F.Cu")
		(net "M_BMC_DDR4_DQS1_P")
	)
	(segment
		(start 77.85227 -53.107336)
		(end 77.470508 -53.489098)
		(width 0.1016)
		(layer "F.Cu")
		(net "M_BMC_DDR4_DQS1_P")
	)
	(segment
		(start 70.278498 -53.821076)
		(end 70.318376 -53.781198)
		(width 0.1016)
		(layer "F.Cu")
		(net "M_BMC_DDR4_DQS1_P")
	)
	(segment
		(start 69.947028 -55.11038)
		(end 69.926708 -55.11038)
		(width 0.1016)
		(layer "F.Cu")
		(net "M_BMC_DDR4_DQS1_P")
	)
	(segment
		(start 70.80377 -54.217062)
		(end 70.741794 -54.279038)
		(width 0.1016)
		(layer "F.Cu")
		(net "M_BMC_DDR4_DQS1_P")
	)
	(segment
		(start 66.238882 -53.774848)
		(end 66.27241 -53.808376)
		(width 0.1016)
		(layer "F.Cu")
		(net "M_BMC_DDR4_DQS1_P")
	)
	(segment
		(start 66.778378 -53.808376)
		(end 66.83121 -53.755544)
		(width 0.1016)
		(layer "F.Cu")
		(net "M_BMC_DDR4_DQS1_P")
	)
	(segment
		(start 64.094868 -52.971192)
		(end 64.327024 -53.203348)
		(width 0.1016)
		(layer "F.Cu")
		(net "M_BMC_DDR4_DQS1_P")
	)
	(segment
		(start 70.015354 -53.92166)
		(end 70.035674 -53.92166)
		(width 0.1016)
		(layer "F.Cu")
		(net "M_BMC_DDR4_DQS1_P")
	)
	(segment
		(start 67.074034 -53.65496)
		(end 67.094354 -53.65496)
		(width 0.1016)
		(layer "F.Cu")
		(net "M_BMC_DDR4_DQS1_P")
	)
	(segment
		(start 70.706742 -54.749954)
		(end 70.781672 -54.824884)
		(width 0.1016)
		(layer "F.Cu")
		(net "M_BMC_DDR4_DQS1_P")
	)
	(segment
		(start 70.64121 -54.521862)
		(end 70.64121 -54.591712)
		(width 0.1016)
		(layer "F.Cu")
		(net "M_BMC_DDR4_DQS1_P")
	)
	(segment
		(start 69.112384 -55.276496)
		(end 69.046852 -55.210964)
		(width 0.1016)
		(layer "F.Cu")
		(net "M_BMC_DDR4_DQS1_P")
	)
	(segment
		(start 68.454778 -53.755544)
		(end 68.50761 -53.808376)
		(width 0.1016)
		(layer "F.Cu")
		(net "M_BMC_DDR4_DQS1_P")
	)
	(segment
		(start 68.540884 -55.210964)
		(end 68.50634 -55.245508)
		(width 0.1016)
		(layer "F.Cu")
		(net "M_BMC_DDR4_DQS1_P")
	)
	(segment
		(start 66.515234 -53.90896)
		(end 66.535554 -53.90896)
		(width 0.1016)
		(layer "F.Cu")
		(net "M_BMC_DDR4_DQS1_P")
	)
	(segment
		(start 67.780408 -55.334662)
		(end 67.621658 -55.175912)
		(width 0.1016)
		(layer "F.Cu")
		(net "M_BMC_DDR4_DQS1_P")
	)
	(via
		(at 77.470508 -53.489098)
		(size 0.4572)
		(drill 0.254)
		(layers "F.Cu" "B.Cu")
		(net "M_BMC_DDR4_DQS1_P")
	)
	(via
		(at 67.83832 -54.506622)
		(size 0.4572)
		(drill 0.254)
		(layers "F.Cu" "B.Cu")
		(net "M_BMC_DDR4_DQS1_P")
	)
	(arc
		(start 68.50761 -53.808376)
		(mid 68.619019 -53.882817)
		(end 68.750434 -53.90896)
		(width 0.1016)
		(layer "F.Cu")
		(net "M_BMC_DDR4_DQS1_P")
	)
	(arc
		(start 65.546986 -53.504846)
		(mid 65.712656 -53.615793)
		(end 65.908174 -53.65496)
		(width 0.1016)
		(layer "F.Cu")
		(net "M_BMC_DDR4_DQS1_P")
	)
	(arc
		(start 70.035674 -53.92166)
		(mid 70.167091 -53.89552)
		(end 70.278498 -53.821076)
		(width 0.1016)
		(layer "F.Cu")
		(net "M_BMC_DDR4_DQS1_P")
	)
	(arc
		(start 67.621658 -55.175912)
		(mid 67.59401 -55.134673)
		(end 67.58432 -55.085996)
		(width 0.1016)
		(layer "F.Cu")
		(net "M_BMC_DDR4_DQS1_P")
	)
	(arc
		(start 70.741794 -54.279038)
		(mid 70.667353 -54.390447)
		(end 70.64121 -54.521862)
		(width 0.1016)
		(layer "F.Cu")
		(net "M_BMC_DDR4_DQS1_P")
	)
	(arc
		(start 68.783708 -55.11038)
		(mid 68.652291 -55.13652)
		(end 68.540884 -55.210964)
		(width 0.1016)
		(layer "F.Cu")
		(net "M_BMC_DDR4_DQS1_P")
	)
	(arc
		(start 69.926708 -55.11038)
		(mid 69.795291 -55.13652)
		(end 69.683884 -55.210964)
		(width 0.1016)
		(layer "F.Cu")
		(net "M_BMC_DDR4_DQS1_P")
	)
	(arc
		(start 69.427852 -53.65496)
		(mid 69.592803 -53.687771)
		(end 69.732652 -53.781198)
		(width 0.1016)
		(layer "F.Cu")
		(net "M_BMC_DDR4_DQS1_P")
	)
	(arc
		(start 70.64121 -54.591712)
		(mid 70.658244 -54.677347)
		(end 70.706742 -54.749954)
		(width 0.1016)
		(layer "F.Cu")
		(net "M_BMC_DDR4_DQS1_P")
	)
	(arc
		(start 70.870318 -53.701442)
		(mid 70.898122 -53.742914)
		(end 70.90791 -53.791866)
		(width 0.1016)
		(layer "F.Cu")
		(net "M_BMC_DDR4_DQS1_P")
	)
	(arc
		(start 66.27241 -53.808376)
		(mid 66.383819 -53.882817)
		(end 66.515234 -53.90896)
		(width 0.1016)
		(layer "F.Cu")
		(net "M_BMC_DDR4_DQS1_P")
	)
	(arc
		(start 70.90791 -55.245)
		(mid 70.869225 -55.338395)
		(end 70.77583 -55.37708)
		(width 0.1016)
		(layer "F.Cu")
		(net "M_BMC_DDR4_DQS1_P")
	)
	(arc
		(start 66.535554 -53.90896)
		(mid 66.666971 -53.88282)
		(end 66.778378 -53.808376)
		(width 0.1016)
		(layer "F.Cu")
		(net "M_BMC_DDR4_DQS1_P")
	)
	(arc
		(start 70.771258 -53.65496)
		(mid 70.819902 -53.66473)
		(end 70.861174 -53.692298)
		(width 0.1016)
		(layer "F.Cu")
		(net "M_BMC_DDR4_DQS1_P")
	)
	(arc
		(start 68.211954 -53.65496)
		(mid 68.343371 -53.6811)
		(end 68.454778 -53.755544)
		(width 0.1016)
		(layer "F.Cu")
		(net "M_BMC_DDR4_DQS1_P")
	)
	(arc
		(start 70.781672 -54.824884)
		(mid 70.875112 -54.964727)
		(end 70.90791 -55.129684)
		(width 0.1016)
		(layer "F.Cu")
		(net "M_BMC_DDR4_DQS1_P")
	)
	(arc
		(start 69.618352 -55.276496)
		(mid 69.506943 -55.350937)
		(end 69.375528 -55.37708)
		(width 0.1016)
		(layer "F.Cu")
		(net "M_BMC_DDR4_DQS1_P")
	)
	(arc
		(start 65.355724 -53.352192)
		(mid 65.380465 -53.354771)
		(end 65.404238 -53.362098)
		(width 0.1016)
		(layer "F.Cu")
		(net "M_BMC_DDR4_DQS1_P")
	)
	(arc
		(start 67.870324 -55.372)
		(mid 67.82168 -55.36223)
		(end 67.780408 -55.334662)
		(width 0.1016)
		(layer "F.Cu")
		(net "M_BMC_DDR4_DQS1_P")
	)
	(arc
		(start 70.318376 -53.781198)
		(mid 70.458219 -53.687758)
		(end 70.623176 -53.65496)
		(width 0.1016)
		(layer "F.Cu")
		(net "M_BMC_DDR4_DQS1_P")
	)
	(arc
		(start 69.355208 -55.37708)
		(mid 69.223791 -55.35094)
		(end 69.112384 -55.276496)
		(width 0.1016)
		(layer "F.Cu")
		(net "M_BMC_DDR4_DQS1_P")
	)
	(arc
		(start 65.949322 -53.65496)
		(mid 66.106025 -53.686112)
		(end 66.238882 -53.774848)
		(width 0.1016)
		(layer "F.Cu")
		(net "M_BMC_DDR4_DQS1_P")
	)
	(arc
		(start 70.189852 -55.210964)
		(mid 70.078443 -55.136523)
		(end 69.947028 -55.11038)
		(width 0.1016)
		(layer "F.Cu")
		(net "M_BMC_DDR4_DQS1_P")
	)
	(arc
		(start 69.047106 -53.774848)
		(mid 69.179971 -53.686133)
		(end 69.336666 -53.65496)
		(width 0.1016)
		(layer "F.Cu")
		(net "M_BMC_DDR4_DQS1_P")
	)
	(arc
		(start 64.327024 -53.203348)
		(mid 64.491923 -53.31353)
		(end 64.686434 -53.352192)
		(width 0.1016)
		(layer "F.Cu")
		(net "M_BMC_DDR4_DQS1_P")
	)
	(arc
		(start 67.94881 -53.755544)
		(mid 68.060219 -53.681103)
		(end 68.191634 -53.65496)
		(width 0.1016)
		(layer "F.Cu")
		(net "M_BMC_DDR4_DQS1_P")
	)
	(arc
		(start 70.90791 -53.965856)
		(mid 70.880846 -54.101827)
		(end 70.80377 -54.217062)
		(width 0.1016)
		(layer "F.Cu")
		(net "M_BMC_DDR4_DQS1_P")
	)
	(arc
		(start 67.39001 -53.808376)
		(mid 67.501419 -53.882817)
		(end 67.632834 -53.90896)
		(width 0.1016)
		(layer "F.Cu")
		(net "M_BMC_DDR4_DQS1_P")
	)
	(arc
		(start 67.653154 -53.90896)
		(mid 67.784571 -53.88282)
		(end 67.895978 -53.808376)
		(width 0.1016)
		(layer "F.Cu")
		(net "M_BMC_DDR4_DQS1_P")
	)
	(arc
		(start 67.094354 -53.65496)
		(mid 67.225771 -53.6811)
		(end 67.337178 -53.755544)
		(width 0.1016)
		(layer "F.Cu")
		(net "M_BMC_DDR4_DQS1_P")
	)
	(arc
		(start 68.770754 -53.90896)
		(mid 68.902171 -53.88282)
		(end 69.013578 -53.808376)
		(width 0.1016)
		(layer "F.Cu")
		(net "M_BMC_DDR4_DQS1_P")
	)
	(arc
		(start 67.58432 -54.802786)
		(mid 67.592108 -54.763725)
		(end 67.614292 -54.73065)
		(width 0.1016)
		(layer "F.Cu")
		(net "M_BMC_DDR4_DQS1_P")
	)
	(arc
		(start 70.53453 -55.37708)
		(mid 70.369579 -55.344269)
		(end 70.22973 -55.250842)
		(width 0.1016)
		(layer "F.Cu")
		(net "M_BMC_DDR4_DQS1_P")
	)
	(arc
		(start 69.77253 -53.821076)
		(mid 69.883939 -53.895517)
		(end 70.015354 -53.92166)
		(width 0.1016)
		(layer "F.Cu")
		(net "M_BMC_DDR4_DQS1_P")
	)
	(arc
		(start 69.046852 -55.210964)
		(mid 68.935443 -55.136523)
		(end 68.804028 -55.11038)
		(width 0.1016)
		(layer "F.Cu")
		(net "M_BMC_DDR4_DQS1_P")
	)
	(arc
		(start 66.83121 -53.755544)
		(mid 66.942619 -53.681103)
		(end 67.074034 -53.65496)
		(width 0.1016)
		(layer "F.Cu")
		(net "M_BMC_DDR4_DQS1_P")
	)
	(arc
		(start 68.50634 -55.245508)
		(mid 68.366395 -55.339109)
		(end 68.201286 -55.372)
		(width 0.1016)
		(layer "F.Cu")
		(net "M_BMC_DDR4_DQS1_P")
	)
	(segment
		(start 72.892158 -55.856378)
		(end 73.030842 -55.995062)
		(width 0.08636)
		(layer "In2.Cu")
		(net "M_BMC_DDR4_DQS1_P")
	)
	(segment
		(start 70.616318 -55.856378)
		(end 70.755002 -55.995062)
		(width 0.08636)
		(layer "In2.Cu")
		(net "M_BMC_DDR4_DQS1_P")
	)
	(segment
		(start 71.754238 -55.856378)
		(end 71.892922 -55.995062)
		(width 0.08636)
		(layer "In2.Cu")
		(net "M_BMC_DDR4_DQS1_P")
	)
	(segment
		(start 73.237344 -56.08066)
		(end 73.254616 -56.08066)
		(width 0.08636)
		(layer "In2.Cu")
		(net "M_BMC_DDR4_DQS1_P")
	)
	(segment
		(start 70.392544 -55.77078)
		(end 70.409816 -55.77078)
		(width 0.08636)
		(layer "In2.Cu")
		(net "M_BMC_DDR4_DQS1_P")
	)
	(segment
		(start 70.088252 -55.954168)
		(end 70.186042 -55.856378)
		(width 0.08636)
		(layer "In2.Cu")
		(net "M_BMC_DDR4_DQS1_P")
	)
	(segment
		(start 69.337936 -56.08066)
		(end 69.78269 -56.08066)
		(width 0.08636)
		(layer "In2.Cu")
		(net "M_BMC_DDR4_DQS1_P")
	)
	(segment
		(start 75.987148 -55.903114)
		(end 76.016866 -55.873142)
		(width 0.08636)
		(layer "In2.Cu")
		(net "M_BMC_DDR4_DQS1_P")
	)
	(segment
		(start 76.447396 -55.124858)
		(end 76.58608 -55.124858)
		(width 0.08636)
		(layer "In2.Cu")
		(net "M_BMC_DDR4_DQS1_P")
	)
	(segment
		(start 73.806304 -55.77078)
		(end 73.823576 -55.77078)
		(width 0.08636)
		(layer "In2.Cu")
		(net "M_BMC_DDR4_DQS1_P")
	)
	(segment
		(start 77.6732 -53.714142)
		(end 77.6732 -53.69179)
		(width 0.08636)
		(layer "In2.Cu")
		(net "M_BMC_DDR4_DQS1_P")
	)
	(segment
		(start 77.6732 -53.69179)
		(end 77.470508 -53.489098)
		(width 0.08636)
		(layer "In2.Cu")
		(net "M_BMC_DDR4_DQS1_P")
	)
	(segment
		(start 67.60464 -54.831742)
		(end 67.60464 -54.893972)
		(width 0.08636)
		(layer "In2.Cu")
		(net "M_BMC_DDR4_DQS1_P")
	)
	(segment
		(start 76.143358 -55.56758)
		(end 76.143358 -55.428896)
		(width 0.08636)
		(layer "In2.Cu")
		(net "M_BMC_DDR4_DQS1_P")
	)
	(segment
		(start 71.185278 -55.995062)
		(end 71.323962 -55.856378)
		(width 0.08636)
		(layer "In2.Cu")
		(net "M_BMC_DDR4_DQS1_P")
	)
	(segment
		(start 76.228956 -55.222394)
		(end 76.240894 -55.210456)
		(width 0.08636)
		(layer "In2.Cu")
		(net "M_BMC_DDR4_DQS1_P")
	)
	(segment
		(start 76.891642 -54.998366)
		(end 77.3176 -54.572408)
		(width 0.08636)
		(layer "In2.Cu")
		(net "M_BMC_DDR4_DQS1_P")
	)
	(segment
		(start 67.83832 -54.506622)
		(end 67.66941 -54.675532)
		(width 0.08636)
		(layer "In2.Cu")
		(net "M_BMC_DDR4_DQS1_P")
	)
	(segment
		(start 72.323198 -55.995062)
		(end 72.461882 -55.856378)
		(width 0.08636)
		(layer "In2.Cu")
		(net "M_BMC_DDR4_DQS1_P")
	)
	(segment
		(start 74.43343 -56.08066)
		(end 75.558904 -56.08066)
		(width 0.08636)
		(layer "In2.Cu")
		(net "M_BMC_DDR4_DQS1_P")
	)
	(segment
		(start 72.099424 -56.08066)
		(end 72.116696 -56.08066)
		(width 0.08636)
		(layer "In2.Cu")
		(net "M_BMC_DDR4_DQS1_P")
	)
	(segment
		(start 71.530464 -55.77078)
		(end 71.547736 -55.77078)
		(width 0.08636)
		(layer "In2.Cu")
		(net "M_BMC_DDR4_DQS1_P")
	)
	(segment
		(start 72.668384 -55.77078)
		(end 72.685656 -55.77078)
		(width 0.08636)
		(layer "In2.Cu")
		(net "M_BMC_DDR4_DQS1_P")
	)
	(segment
		(start 74.030078 -55.856378)
		(end 74.127868 -55.954168)
		(width 0.08636)
		(layer "In2.Cu")
		(net "M_BMC_DDR4_DQS1_P")
	)
	(segment
		(start 73.461118 -55.995062)
		(end 73.599802 -55.856378)
		(width 0.08636)
		(layer "In2.Cu")
		(net "M_BMC_DDR4_DQS1_P")
	)
	(segment
		(start 67.642994 -54.965854)
		(end 69.289676 -56.066182)
		(width 0.08636)
		(layer "In2.Cu")
		(net "M_BMC_DDR4_DQS1_P")
	)
	(segment
		(start 70.961504 -56.08066)
		(end 70.978776 -56.08066)
		(width 0.08636)
		(layer "In2.Cu")
		(net "M_BMC_DDR4_DQS1_P")
	)
	(arc
		(start 69.289676 -56.066182)
		(mid 69.312734 -56.076993)
		(end 69.337936 -56.08066)
		(width 0.08636)
		(layer "In2.Cu")
		(net "M_BMC_DDR4_DQS1_P")
	)
	(arc
		(start 73.030842 -55.995062)
		(mid 73.125572 -56.058422)
		(end 73.237344 -56.08066)
		(width 0.08636)
		(layer "In2.Cu")
		(net "M_BMC_DDR4_DQS1_P")
	)
	(arc
		(start 70.409816 -55.77078)
		(mid 70.521584 -55.79303)
		(end 70.616318 -55.856378)
		(width 0.08636)
		(layer "In2.Cu")
		(net "M_BMC_DDR4_DQS1_P")
	)
	(arc
		(start 67.66941 -54.675532)
		(mid 67.621468 -54.747188)
		(end 67.60464 -54.831742)
		(width 0.08636)
		(layer "In2.Cu")
		(net "M_BMC_DDR4_DQS1_P")
	)
	(arc
		(start 69.78269 -56.08066)
		(mid 69.948044 -56.047787)
		(end 70.088252 -55.954168)
		(width 0.08636)
		(layer "In2.Cu")
		(net "M_BMC_DDR4_DQS1_P")
	)
	(arc
		(start 70.755002 -55.995062)
		(mid 70.849732 -56.058422)
		(end 70.961504 -56.08066)
		(width 0.08636)
		(layer "In2.Cu")
		(net "M_BMC_DDR4_DQS1_P")
	)
	(arc
		(start 73.823576 -55.77078)
		(mid 73.935344 -55.79303)
		(end 74.030078 -55.856378)
		(width 0.08636)
		(layer "In2.Cu")
		(net "M_BMC_DDR4_DQS1_P")
	)
	(arc
		(start 76.143358 -55.428896)
		(mid 76.165608 -55.317128)
		(end 76.228956 -55.222394)
		(width 0.08636)
		(layer "In2.Cu")
		(net "M_BMC_DDR4_DQS1_P")
	)
	(arc
		(start 72.116696 -56.08066)
		(mid 72.228464 -56.05841)
		(end 72.323198 -55.995062)
		(width 0.08636)
		(layer "In2.Cu")
		(net "M_BMC_DDR4_DQS1_P")
	)
	(arc
		(start 73.254616 -56.08066)
		(mid 73.366384 -56.05841)
		(end 73.461118 -55.995062)
		(width 0.08636)
		(layer "In2.Cu")
		(net "M_BMC_DDR4_DQS1_P")
	)
	(arc
		(start 73.599802 -55.856378)
		(mid 73.694532 -55.793018)
		(end 73.806304 -55.77078)
		(width 0.08636)
		(layer "In2.Cu")
		(net "M_BMC_DDR4_DQS1_P")
	)
	(arc
		(start 76.240894 -55.210456)
		(mid 76.335624 -55.147096)
		(end 76.447396 -55.124858)
		(width 0.08636)
		(layer "In2.Cu")
		(net "M_BMC_DDR4_DQS1_P")
	)
	(arc
		(start 71.892922 -55.995062)
		(mid 71.987652 -56.058422)
		(end 72.099424 -56.08066)
		(width 0.08636)
		(layer "In2.Cu")
		(net "M_BMC_DDR4_DQS1_P")
	)
	(arc
		(start 71.323962 -55.856378)
		(mid 71.418692 -55.793018)
		(end 71.530464 -55.77078)
		(width 0.08636)
		(layer "In2.Cu")
		(net "M_BMC_DDR4_DQS1_P")
	)
	(arc
		(start 67.60464 -54.893972)
		(mid 67.614822 -54.934717)
		(end 67.642994 -54.965854)
		(width 0.08636)
		(layer "In2.Cu")
		(net "M_BMC_DDR4_DQS1_P")
	)
	(arc
		(start 72.461882 -55.856378)
		(mid 72.556612 -55.793018)
		(end 72.668384 -55.77078)
		(width 0.08636)
		(layer "In2.Cu")
		(net "M_BMC_DDR4_DQS1_P")
	)
	(arc
		(start 71.547736 -55.77078)
		(mid 71.659504 -55.79303)
		(end 71.754238 -55.856378)
		(width 0.08636)
		(layer "In2.Cu")
		(net "M_BMC_DDR4_DQS1_P")
	)
	(arc
		(start 70.186042 -55.856378)
		(mid 70.280772 -55.793018)
		(end 70.392544 -55.77078)
		(width 0.08636)
		(layer "In2.Cu")
		(net "M_BMC_DDR4_DQS1_P")
	)
	(arc
		(start 72.685656 -55.77078)
		(mid 72.797424 -55.79303)
		(end 72.892158 -55.856378)
		(width 0.08636)
		(layer "In2.Cu")
		(net "M_BMC_DDR4_DQS1_P")
	)
	(arc
		(start 77.3176 -54.572408)
		(mid 77.580766 -54.178646)
		(end 77.6732 -53.714142)
		(width 0.08636)
		(layer "In2.Cu")
		(net "M_BMC_DDR4_DQS1_P")
	)
	(arc
		(start 76.016866 -55.873142)
		(mid 76.110486 -55.732935)
		(end 76.143358 -55.56758)
		(width 0.08636)
		(layer "In2.Cu")
		(net "M_BMC_DDR4_DQS1_P")
	)
	(arc
		(start 76.58608 -55.124858)
		(mid 76.751434 -55.091985)
		(end 76.891642 -54.998366)
		(width 0.08636)
		(layer "In2.Cu")
		(net "M_BMC_DDR4_DQS1_P")
	)
	(arc
		(start 70.978776 -56.08066)
		(mid 71.090544 -56.05841)
		(end 71.185278 -55.995062)
		(width 0.08636)
		(layer "In2.Cu")
		(net "M_BMC_DDR4_DQS1_P")
	)
	(arc
		(start 74.127868 -55.954168)
		(mid 74.268075 -56.047788)
		(end 74.43343 -56.08066)
		(width 0.08636)
		(layer "In2.Cu")
		(net "M_BMC_DDR4_DQS1_P")
	)
	(arc
		(start 75.558904 -56.08066)
		(mid 75.790701 -56.034517)
		(end 75.987148 -55.903114)
		(width 0.08636)
		(layer "In2.Cu")
		(net "M_BMC_DDR4_DQS1_P")
	)
	(segment
		(start 71.28891 -53.791866)
		(end 71.28891 -55.245)
		(width 0.1016)
		(layer "F.Cu")
		(net "M_BMC_DDR4_DQS1_N")
	)
	(segment
		(start 77.85227 -53.907436)
		(end 78.234032 -53.525674)
		(width 0.1016)
		(layer "F.Cu")
		(net "M_BMC_DDR4_DQS1_N")
	)
	(segment
		(start 65.63868 -53.057552)
		(end 65.816734 -53.235606)
		(width 0.1016)
		(layer "F.Cu")
		(net "M_BMC_DDR4_DQS1_N")
	)
	(segment
		(start 68.20154 -55.753)
		(end 67.87007 -55.753)
		(width 0.1016)
		(layer "F.Cu")
		(net "M_BMC_DDR4_DQS1_N")
	)
	(segment
		(start 67.51066 -55.604156)
		(end 67.352164 -55.445406)
		(width 0.1016)
		(layer "F.Cu")
		(net "M_BMC_DDR4_DQS1_N")
	)
	(segment
		(start 65.908682 -53.27396)
		(end 70.771258 -53.27396)
		(width 0.1016)
		(layer "F.Cu")
		(net "M_BMC_DDR4_DQS1_N")
	)
	(segment
		(start 68.20662 -55.75808)
		(end 68.20154 -55.753)
		(width 0.1016)
		(layer "F.Cu")
		(net "M_BMC_DDR4_DQS1_N")
	)
	(segment
		(start 70.77583 -55.75808)
		(end 68.20662 -55.75808)
		(width 0.1016)
		(layer "F.Cu")
		(net "M_BMC_DDR4_DQS1_N")
	)
	(segment
		(start 67.083432 -54.640734)
		(end 66.94932 -54.506622)
		(width 0.1016)
		(layer "F.Cu")
		(net "M_BMC_DDR4_DQS1_N")
	)
	(segment
		(start 64.894968 -52.971192)
		(end 65.356232 -52.971192)
		(width 0.1016)
		(layer "F.Cu")
		(net "M_BMC_DDR4_DQS1_N")
	)
	(segment
		(start 71.130668 -53.422804)
		(end 71.139812 -53.431948)
		(width 0.1016)
		(layer "F.Cu")
		(net "M_BMC_DDR4_DQS1_N")
	)
	(segment
		(start 67.20332 -55.08625)
		(end 67.20332 -54.930294)
		(width 0.1016)
		(layer "F.Cu")
		(net "M_BMC_DDR4_DQS1_N")
	)
	(via
		(at 66.94932 -54.506622)
		(size 0.4572)
		(drill 0.254)
		(layers "F.Cu" "B.Cu")
		(net "M_BMC_DDR4_DQS1_N")
	)
	(via
		(at 78.234032 -53.525674)
		(size 0.4572)
		(drill 0.254)
		(layers "F.Cu" "B.Cu")
		(net "M_BMC_DDR4_DQS1_N")
	)
	(arc
		(start 65.356232 -52.971192)
		(mid 65.503862 -52.993414)
		(end 65.63868 -53.057552)
		(width 0.1016)
		(layer "F.Cu")
		(net "M_BMC_DDR4_DQS1_N")
	)
	(arc
		(start 67.352164 -55.445406)
		(mid 67.242031 -55.280625)
		(end 67.20332 -55.08625)
		(width 0.1016)
		(layer "F.Cu")
		(net "M_BMC_DDR4_DQS1_N")
	)
	(arc
		(start 71.139812 -53.431948)
		(mid 71.25015 -53.59708)
		(end 71.28891 -53.791866)
		(width 0.1016)
		(layer "F.Cu")
		(net "M_BMC_DDR4_DQS1_N")
	)
	(arc
		(start 71.28891 -55.245)
		(mid 71.138632 -55.607802)
		(end 70.77583 -55.75808)
		(width 0.1016)
		(layer "F.Cu")
		(net "M_BMC_DDR4_DQS1_N")
	)
	(arc
		(start 67.87007 -55.753)
		(mid 67.675555 -55.714326)
		(end 67.51066 -55.604156)
		(width 0.1016)
		(layer "F.Cu")
		(net "M_BMC_DDR4_DQS1_N")
	)
	(arc
		(start 70.771258 -53.27396)
		(mid 70.965758 -53.312649)
		(end 71.130668 -53.422804)
		(width 0.1016)
		(layer "F.Cu")
		(net "M_BMC_DDR4_DQS1_N")
	)
	(arc
		(start 67.20332 -54.930294)
		(mid 67.172168 -54.773591)
		(end 67.083432 -54.640734)
		(width 0.1016)
		(layer "F.Cu")
		(net "M_BMC_DDR4_DQS1_N")
	)
	(arc
		(start 65.816734 -53.235606)
		(mid 65.858891 -53.263931)
		(end 65.908682 -53.27396)
		(width 0.1016)
		(layer "F.Cu")
		(net "M_BMC_DDR4_DQS1_N")
	)
	(segment
		(start 67.182746 -54.89575)
		(end 67.183 -54.89575)
		(width 0.08636)
		(layer "In2.Cu")
		(net "M_BMC_DDR4_DQS1_N")
	)
	(segment
		(start 67.408552 -55.316374)
		(end 69.055488 -56.41721)
		(width 0.08636)
		(layer "In2.Cu")
		(net "M_BMC_DDR4_DQS1_N")
	)
	(segment
		(start 78.123796 -53.63591)
		(end 78.234032 -53.525674)
		(width 0.08636)
		(layer "In2.Cu")
		(net "M_BMC_DDR4_DQS1_N")
	)
	(segment
		(start 76.285344 -56.20131)
		(end 77.615796 -54.870604)
		(width 0.08636)
		(layer "In2.Cu")
		(net "M_BMC_DDR4_DQS1_N")
	)
	(segment
		(start 78.09484 -53.714142)
		(end 78.09484 -53.705506)
		(width 0.08636)
		(layer "In2.Cu")
		(net "M_BMC_DDR4_DQS1_N")
	)
	(segment
		(start 66.94932 -54.506622)
		(end 67.072256 -54.629558)
		(width 0.08636)
		(layer "In2.Cu")
		(net "M_BMC_DDR4_DQS1_N")
	)
	(segment
		(start 69.339206 -56.5023)
		(end 75.558904 -56.5023)
		(width 0.08636)
		(layer "In2.Cu")
		(net "M_BMC_DDR4_DQS1_N")
	)
	(arc
		(start 69.055488 -56.41721)
		(mid 69.191011 -56.480892)
		(end 69.339206 -56.5023)
		(width 0.08636)
		(layer "In2.Cu")
		(net "M_BMC_DDR4_DQS1_N")
	)
	(arc
		(start 78.09484 -53.705506)
		(mid 78.102425 -53.667845)
		(end 78.123796 -53.63591)
		(width 0.08636)
		(layer "In2.Cu")
		(net "M_BMC_DDR4_DQS1_N")
	)
	(arc
		(start 67.072256 -54.629558)
		(mid 67.15387 -54.751713)
		(end 67.182746 -54.89575)
		(width 0.08636)
		(layer "In2.Cu")
		(net "M_BMC_DDR4_DQS1_N")
	)
	(arc
		(start 75.558904 -56.5023)
		(mid 75.95207 -56.424077)
		(end 76.285344 -56.20131)
		(width 0.08636)
		(layer "In2.Cu")
		(net "M_BMC_DDR4_DQS1_N")
	)
	(arc
		(start 67.183 -54.89575)
		(mid 67.24334 -55.134177)
		(end 67.408552 -55.316374)
		(width 0.08636)
		(layer "In2.Cu")
		(net "M_BMC_DDR4_DQS1_N")
	)
	(arc
		(start 77.615796 -54.870604)
		(mid 77.970324 -54.340015)
		(end 78.09484 -53.714142)
		(width 0.08636)
		(layer "In2.Cu")
		(net "M_BMC_DDR4_DQS1_N")
	)
	(segment
		(start 64.094868 -51.371246)
		(end 64.327024 -51.603402)
		(width 0.1016)
		(layer "F.Cu")
		(net "M_BMC_DDR4_DQS0_P")
	)
	(segment
		(start 66.795904 -52.54371)
		(end 66.69532 -52.644548)
		(width 0.1016)
		(layer "F.Cu")
		(net "M_BMC_DDR4_DQS0_P")
	)
	(segment
		(start 70.067932 -50.86858)
		(end 70.067932 -51.36261)
		(width 0.1016)
		(layer "F.Cu")
		(net "M_BMC_DDR4_DQS0_P")
	)
	(segment
		(start 66.05524 -51.244246)
		(end 66.05524 -50.86858)
		(width 0.1016)
		(layer "F.Cu")
		(net "M_BMC_DDR4_DQS0_P")
	)
	(segment
		(start 69.940932 -51.48961)
		(end 67.432936 -51.48961)
		(width 0.1016)
		(layer "F.Cu")
		(net "M_BMC_DDR4_DQS0_P")
	)
	(segment
		(start 64.686434 -51.752246)
		(end 65.54724 -51.752246)
		(width 0.1016)
		(layer "F.Cu")
		(net "M_BMC_DDR4_DQS0_P")
	)
	(segment
		(start 74.652378 -49.107344)
		(end 75.03414 -49.489106)
		(width 0.1016)
		(layer "F.Cu")
		(net "M_BMC_DDR4_DQS0_P")
	)
	(segment
		(start 66.15684 -50.76698)
		(end 69.966332 -50.76698)
		(width 0.1016)
		(layer "F.Cu")
		(net "M_BMC_DDR4_DQS0_P")
	)
	(segment
		(start 66.882264 -52.040282)
		(end 66.882264 -52.334668)
		(width 0.1016)
		(layer "F.Cu")
		(net "M_BMC_DDR4_DQS0_P")
	)
	(via
		(at 66.69532 -52.644548)
		(size 0.4572)
		(drill 0.254)
		(layers "F.Cu" "B.Cu")
		(net "M_BMC_DDR4_DQS0_P")
	)
	(via
		(at 75.03414 -49.489106)
		(size 0.4572)
		(drill 0.254)
		(layers "F.Cu" "B.Cu")
		(net "M_BMC_DDR4_DQS0_P")
	)
	(arc
		(start 66.882264 -52.334668)
		(mid 66.859823 -52.447756)
		(end 66.795904 -52.54371)
		(width 0.1016)
		(layer "F.Cu")
		(net "M_BMC_DDR4_DQS0_P")
	)
	(arc
		(start 70.067932 -51.36261)
		(mid 70.030735 -51.452413)
		(end 69.940932 -51.48961)
		(width 0.1016)
		(layer "F.Cu")
		(net "M_BMC_DDR4_DQS0_P")
	)
	(arc
		(start 65.54724 -51.752246)
		(mid 65.90645 -51.603456)
		(end 66.05524 -51.244246)
		(width 0.1016)
		(layer "F.Cu")
		(net "M_BMC_DDR4_DQS0_P")
	)
	(arc
		(start 64.327024 -51.603402)
		(mid 64.491923 -51.713584)
		(end 64.686434 -51.752246)
		(width 0.1016)
		(layer "F.Cu")
		(net "M_BMC_DDR4_DQS0_P")
	)
	(arc
		(start 69.966332 -50.76698)
		(mid 70.038174 -50.796738)
		(end 70.067932 -50.86858)
		(width 0.1016)
		(layer "F.Cu")
		(net "M_BMC_DDR4_DQS0_P")
	)
	(arc
		(start 67.432936 -51.48961)
		(mid 67.043552 -51.650898)
		(end 66.882264 -52.040282)
		(width 0.1016)
		(layer "F.Cu")
		(net "M_BMC_DDR4_DQS0_P")
	)
	(arc
		(start 66.05524 -50.86858)
		(mid 66.084998 -50.796738)
		(end 66.15684 -50.76698)
		(width 0.1016)
		(layer "F.Cu")
		(net "M_BMC_DDR4_DQS0_P")
	)
	(segment
		(start 75.03414 -49.489106)
		(end 74.988166 -49.53508)
		(width 0.08636)
		(layer "In9.Cu")
		(net "M_BMC_DDR4_DQS0_P")
	)
	(segment
		(start 70.150228 -52.79644)
		(end 69.939408 -52.79644)
		(width 0.08636)
		(layer "In9.Cu")
		(net "M_BMC_DDR4_DQS0_P")
	)
	(segment
		(start 69.73824 -53.097684)
		(end 69.73824 -53.317394)
		(width 0.08636)
		(layer "In9.Cu")
		(net "M_BMC_DDR4_DQS0_P")
	)
	(segment
		(start 66.93027 -52.998116)
		(end 66.914014 -52.956714)
		(width 0.08636)
		(layer "In9.Cu")
		(net "M_BMC_DDR4_DQS0_P")
	)
	(segment
		(start 69.192394 -53.86324)
		(end 67.733164 -53.86324)
		(width 0.08636)
		(layer "In9.Cu")
		(net "M_BMC_DDR4_DQS0_P")
	)
	(segment
		(start 67.23253 -53.655722)
		(end 67.184524 -53.607716)
		(width 0.08636)
		(layer "In9.Cu")
		(net "M_BMC_DDR4_DQS0_P")
	)
	(segment
		(start 72.371966 -53.10124)
		(end 71.79564 -53.10124)
		(width 0.08636)
		(layer "In9.Cu")
		(net "M_BMC_DDR4_DQS0_P")
	)
	(segment
		(start 71.112888 -54.5338)
		(end 70.940168 -54.5338)
		(width 0.08636)
		(layer "In9.Cu")
		(net "M_BMC_DDR4_DQS0_P")
	)
	(segment
		(start 74.925682 -49.775618)
		(end 74.926444 -49.777904)
		(width 0.08636)
		(layer "In9.Cu")
		(net "M_BMC_DDR4_DQS0_P")
	)
	(segment
		(start 70.3072 -53.900832)
		(end 70.3072 -52.953412)
		(width 0.08636)
		(layer "In9.Cu")
		(net "M_BMC_DDR4_DQS0_P")
	)
	(segment
		(start 66.694558 -52.64912)
		(end 66.69532 -52.644548)
		(width 0.08636)
		(layer "In9.Cu")
		(net "M_BMC_DDR4_DQS0_P")
	)
	(segment
		(start 75.011534 -52.026058)
		(end 74.177906 -52.859686)
		(width 0.08636)
		(layer "In9.Cu")
		(net "M_BMC_DDR4_DQS0_P")
	)
	(segment
		(start 74.926444 -49.777904)
		(end 74.926444 -49.778412)
		(width 0.08636)
		(layer "In9.Cu")
		(net "M_BMC_DDR4_DQS0_P")
	)
	(segment
		(start 73.594722 -53.10124)
		(end 72.40778 -53.10124)
		(width 0.08636)
		(layer "In9.Cu")
		(net "M_BMC_DDR4_DQS0_P")
	)
	(segment
		(start 69.84746 -52.83454)
		(end 69.847206 -52.834794)
		(width 0.08636)
		(layer "In9.Cu")
		(net "M_BMC_DDR4_DQS0_P")
	)
	(segment
		(start 71.70928 -53.1876)
		(end 71.70928 -53.937408)
		(width 0.08636)
		(layer "In9.Cu")
		(net "M_BMC_DDR4_DQS0_P")
	)
	(segment
		(start 69.589396 -53.677058)
		(end 69.552058 -53.714396)
		(width 0.08636)
		(layer "In9.Cu")
		(net "M_BMC_DDR4_DQS0_P")
	)
	(segment
		(start 66.89979 -52.924964)
		(end 66.694558 -52.64912)
		(width 0.08636)
		(layer "In9.Cu")
		(net "M_BMC_DDR4_DQS0_P")
	)
	(segment
		(start 75.22464 -50.604166)
		(end 75.22464 -51.511708)
		(width 0.08636)
		(layer "In9.Cu")
		(net "M_BMC_DDR4_DQS0_P")
	)
	(arc
		(start 69.939408 -52.79644)
		(mid 69.889641 -52.806339)
		(end 69.84746 -52.83454)
		(width 0.08636)
		(layer "In9.Cu")
		(net "M_BMC_DDR4_DQS0_P")
	)
	(arc
		(start 67.733164 -53.86324)
		(mid 67.462205 -53.809267)
		(end 67.23253 -53.655722)
		(width 0.08636)
		(layer "In9.Cu")
		(net "M_BMC_DDR4_DQS0_P")
	)
	(arc
		(start 67.184524 -53.607716)
		(mid 67.156326 -53.578055)
		(end 67.12966 -53.54701)
		(width 0.08636)
		(layer "In9.Cu")
		(net "M_BMC_DDR4_DQS0_P")
	)
	(arc
		(start 69.73824 -53.317394)
		(mid 69.6996 -53.512031)
		(end 69.589396 -53.677058)
		(width 0.08636)
		(layer "In9.Cu")
		(net "M_BMC_DDR4_DQS0_P")
	)
	(arc
		(start 74.969116 -49.862486)
		(mid 75.158867 -50.211972)
		(end 75.22464 -50.604166)
		(width 0.08636)
		(layer "In9.Cu")
		(net "M_BMC_DDR4_DQS0_P")
	)
	(arc
		(start 67.12966 -53.54701)
		(mid 67.099889 -53.508118)
		(end 67.07251 -53.467508)
		(width 0.08636)
		(layer "In9.Cu")
		(net "M_BMC_DDR4_DQS0_P")
	)
	(arc
		(start 71.70928 -53.937408)
		(mid 71.664098 -54.164711)
		(end 71.535544 -54.357524)
		(width 0.08636)
		(layer "In9.Cu")
		(net "M_BMC_DDR4_DQS0_P")
	)
	(arc
		(start 69.847206 -52.834794)
		(mid 69.76656 -52.955395)
		(end 69.73824 -53.097684)
		(width 0.08636)
		(layer "In9.Cu")
		(net "M_BMC_DDR4_DQS0_P")
	)
	(arc
		(start 72.40778 -53.10124)
		(mid 72.407784 -53.100732)
		(end 72.40778 -53.100224)
		(width 0.08636)
		(layer "In9.Cu")
		(net "M_BMC_DDR4_DQS0_P")
	)
	(arc
		(start 74.926444 -49.778412)
		(mid 74.943755 -49.822492)
		(end 74.969116 -49.862486)
		(width 0.08636)
		(layer "In9.Cu")
		(net "M_BMC_DDR4_DQS0_P")
	)
	(arc
		(start 66.914014 -52.956714)
		(mid 66.906974 -52.940807)
		(end 66.89979 -52.924964)
		(width 0.08636)
		(layer "In9.Cu")
		(net "M_BMC_DDR4_DQS0_P")
	)
	(arc
		(start 74.177906 -52.859686)
		(mid 73.910339 -53.038469)
		(end 73.594722 -53.10124)
		(width 0.08636)
		(layer "In9.Cu")
		(net "M_BMC_DDR4_DQS0_P")
	)
	(arc
		(start 72.40778 -53.100224)
		(mid 72.389882 -53.101046)
		(end 72.371966 -53.10124)
		(width 0.08636)
		(layer "In9.Cu")
		(net "M_BMC_DDR4_DQS0_P")
	)
	(arc
		(start 71.79564 -53.10124)
		(mid 71.734574 -53.126534)
		(end 71.70928 -53.1876)
		(width 0.08636)
		(layer "In9.Cu")
		(net "M_BMC_DDR4_DQS0_P")
	)
	(arc
		(start 71.535544 -54.357524)
		(mid 71.341829 -54.487879)
		(end 71.112888 -54.5338)
		(width 0.08636)
		(layer "In9.Cu")
		(net "M_BMC_DDR4_DQS0_P")
	)
	(arc
		(start 69.552058 -53.714396)
		(mid 69.387042 -53.824626)
		(end 69.192394 -53.86324)
		(width 0.08636)
		(layer "In9.Cu")
		(net "M_BMC_DDR4_DQS0_P")
	)
	(arc
		(start 75.22464 -51.511708)
		(mid 75.169251 -51.790079)
		(end 75.011534 -52.026058)
		(width 0.08636)
		(layer "In9.Cu")
		(net "M_BMC_DDR4_DQS0_P")
	)
	(arc
		(start 70.940168 -54.5338)
		(mid 70.492592 -54.348408)
		(end 70.3072 -53.900832)
		(width 0.08636)
		(layer "In9.Cu")
		(net "M_BMC_DDR4_DQS0_P")
	)
	(arc
		(start 70.3072 -52.953412)
		(mid 70.261224 -52.842416)
		(end 70.150228 -52.79644)
		(width 0.08636)
		(layer "In9.Cu")
		(net "M_BMC_DDR4_DQS0_P")
	)
	(arc
		(start 66.951606 -53.180488)
		(mid 66.935585 -53.089928)
		(end 66.93027 -52.998116)
		(width 0.08636)
		(layer "In9.Cu")
		(net "M_BMC_DDR4_DQS0_P")
	)
	(arc
		(start 74.988166 -49.53508)
		(mid 74.92405 -49.646815)
		(end 74.925682 -49.775618)
		(width 0.08636)
		(layer "In9.Cu")
		(net "M_BMC_DDR4_DQS0_P")
	)
	(arc
		(start 67.07251 -53.467508)
		(mid 67.000202 -53.328993)
		(end 66.951606 -53.180488)
		(width 0.08636)
		(layer "In9.Cu")
		(net "M_BMC_DDR4_DQS0_P")
	)
	(segment
		(start 68.453254 -51.87061)
		(end 67.432936 -51.87061)
		(width 0.1016)
		(layer "F.Cu")
		(net "M_BMC_DDR4_DQS0_N")
	)
	(segment
		(start 68.320666 -50.219864)
		(end 68.360544 -50.259742)
		(width 0.1016)
		(layer "F.Cu")
		(net "M_BMC_DDR4_DQS0_N")
	)
	(segment
		(start 67.413632 -52.644548)
		(end 67.58432 -52.644548)
		(width 0.1016)
		(layer "F.Cu")
		(net "M_BMC_DDR4_DQS0_N")
	)
	(segment
		(start 66.87058 -50.11928)
		(end 66.8909 -50.11928)
		(width 0.1016)
		(layer "F.Cu")
		(net "M_BMC_DDR4_DQS0_N")
	)
	(segment
		(start 70.448932 -50.86858)
		(end 70.448932 -51.36261)
		(width 0.1016)
		(layer "F.Cu")
		(net "M_BMC_DDR4_DQS0_N")
	)
	(segment
		(start 69.061076 -52.13731)
		(end 69.040756 -52.13731)
		(width 0.1016)
		(layer "F.Cu")
		(net "M_BMC_DDR4_DQS0_N")
	)
	(segment
		(start 68.797932 -52.036726)
		(end 68.758054 -51.996848)
		(width 0.1016)
		(layer "F.Cu")
		(net "M_BMC_DDR4_DQS0_N")
	)
	(segment
		(start 69.379084 -50.11928)
		(end 69.399404 -50.11928)
		(width 0.1016)
		(layer "F.Cu")
		(net "M_BMC_DDR4_DQS0_N")
	)
	(segment
		(start 67.133724 -50.219864)
		(end 67.183508 -50.269648)
		(width 0.1016)
		(layer "F.Cu")
		(net "M_BMC_DDR4_DQS0_N")
	)
	(segment
		(start 69.642228 -50.219864)
		(end 69.703696 -50.281332)
		(width 0.1016)
		(layer "F.Cu")
		(net "M_BMC_DDR4_DQS0_N")
	)
	(segment
		(start 66.587878 -50.259742)
		(end 66.627756 -50.219864)
		(width 0.1016)
		(layer "F.Cu")
		(net "M_BMC_DDR4_DQS0_N")
	)
	(segment
		(start 74.652378 -49.907444)
		(end 74.270616 -49.525682)
		(width 0.1016)
		(layer "F.Cu")
		(net "M_BMC_DDR4_DQS0_N")
	)
	(segment
		(start 68.057522 -50.11928)
		(end 68.077842 -50.11928)
		(width 0.1016)
		(layer "F.Cu")
		(net "M_BMC_DDR4_DQS0_N")
	)
	(segment
		(start 69.940932 -51.87061)
		(end 69.648578 -51.87061)
		(width 0.1016)
		(layer "F.Cu")
		(net "M_BMC_DDR4_DQS0_N")
	)
	(segment
		(start 69.096382 -50.259742)
		(end 69.13626 -50.219864)
		(width 0.1016)
		(layer "F.Cu")
		(net "M_BMC_DDR4_DQS0_N")
	)
	(segment
		(start 67.263264 -52.040282)
		(end 67.263264 -52.49418)
		(width 0.1016)
		(layer "F.Cu")
		(net "M_BMC_DDR4_DQS0_N")
	)
	(segment
		(start 67.764914 -50.269648)
		(end 67.814698 -50.219864)
		(width 0.1016)
		(layer "F.Cu")
		(net "M_BMC_DDR4_DQS0_N")
	)
	(segment
		(start 67.464178 -50.38598)
		(end 67.484244 -50.38598)
		(width 0.1016)
		(layer "F.Cu")
		(net "M_BMC_DDR4_DQS0_N")
	)
	(segment
		(start 69.343778 -51.996848)
		(end 69.3039 -52.036726)
		(width 0.1016)
		(layer "F.Cu")
		(net "M_BMC_DDR4_DQS0_N")
	)
	(segment
		(start 68.665344 -50.38598)
		(end 68.791582 -50.38598)
		(width 0.1016)
		(layer "F.Cu")
		(net "M_BMC_DDR4_DQS0_N")
	)
	(segment
		(start 66.15684 -50.38598)
		(end 66.283078 -50.38598)
		(width 0.1016)
		(layer "F.Cu")
		(net "M_BMC_DDR4_DQS0_N")
	)
	(segment
		(start 64.894968 -51.371246)
		(end 65.54724 -51.371246)
		(width 0.1016)
		(layer "F.Cu")
		(net "M_BMC_DDR4_DQS0_N")
	)
	(segment
		(start 69.956172 -50.38598)
		(end 69.966332 -50.38598)
		(width 0.1016)
		(layer "F.Cu")
		(net "M_BMC_DDR4_DQS0_N")
	)
	(segment
		(start 65.67424 -51.244246)
		(end 65.67424 -50.86858)
		(width 0.1016)
		(layer "F.Cu")
		(net "M_BMC_DDR4_DQS0_N")
	)
	(via
		(at 74.270616 -49.525682)
		(size 0.4572)
		(drill 0.254)
		(layers "F.Cu" "B.Cu")
		(net "M_BMC_DDR4_DQS0_N")
	)
	(via
		(at 67.58432 -52.644548)
		(size 0.4572)
		(drill 0.254)
		(layers "F.Cu" "B.Cu")
		(net "M_BMC_DDR4_DQS0_N")
	)
	(arc
		(start 69.399404 -50.11928)
		(mid 69.530821 -50.14542)
		(end 69.642228 -50.219864)
		(width 0.1016)
		(layer "F.Cu")
		(net "M_BMC_DDR4_DQS0_N")
	)
	(arc
		(start 67.432936 -51.87061)
		(mid 67.31296 -51.920306)
		(end 67.263264 -52.040282)
		(width 0.1016)
		(layer "F.Cu")
		(net "M_BMC_DDR4_DQS0_N")
	)
	(arc
		(start 69.13626 -50.219864)
		(mid 69.247669 -50.145423)
		(end 69.379084 -50.11928)
		(width 0.1016)
		(layer "F.Cu")
		(net "M_BMC_DDR4_DQS0_N")
	)
	(arc
		(start 69.703696 -50.281332)
		(mid 69.819519 -50.358786)
		(end 69.956172 -50.38598)
		(width 0.1016)
		(layer "F.Cu")
		(net "M_BMC_DDR4_DQS0_N")
	)
	(arc
		(start 68.758054 -51.996848)
		(mid 68.618211 -51.903408)
		(end 68.453254 -51.87061)
		(width 0.1016)
		(layer "F.Cu")
		(net "M_BMC_DDR4_DQS0_N")
	)
	(arc
		(start 67.484244 -50.38598)
		(mid 67.636156 -50.355745)
		(end 67.764914 -50.269648)
		(width 0.1016)
		(layer "F.Cu")
		(net "M_BMC_DDR4_DQS0_N")
	)
	(arc
		(start 68.791582 -50.38598)
		(mid 68.956533 -50.353169)
		(end 69.096382 -50.259742)
		(width 0.1016)
		(layer "F.Cu")
		(net "M_BMC_DDR4_DQS0_N")
	)
	(arc
		(start 66.283078 -50.38598)
		(mid 66.448029 -50.353169)
		(end 66.587878 -50.259742)
		(width 0.1016)
		(layer "F.Cu")
		(net "M_BMC_DDR4_DQS0_N")
	)
	(arc
		(start 66.627756 -50.219864)
		(mid 66.739165 -50.145423)
		(end 66.87058 -50.11928)
		(width 0.1016)
		(layer "F.Cu")
		(net "M_BMC_DDR4_DQS0_N")
	)
	(arc
		(start 67.263264 -52.49418)
		(mid 67.307306 -52.600506)
		(end 67.413632 -52.644548)
		(width 0.1016)
		(layer "F.Cu")
		(net "M_BMC_DDR4_DQS0_N")
	)
	(arc
		(start 68.077842 -50.11928)
		(mid 68.209259 -50.14542)
		(end 68.320666 -50.219864)
		(width 0.1016)
		(layer "F.Cu")
		(net "M_BMC_DDR4_DQS0_N")
	)
	(arc
		(start 69.040756 -52.13731)
		(mid 68.909339 -52.11117)
		(end 68.797932 -52.036726)
		(width 0.1016)
		(layer "F.Cu")
		(net "M_BMC_DDR4_DQS0_N")
	)
	(arc
		(start 66.8909 -50.11928)
		(mid 67.022317 -50.14542)
		(end 67.133724 -50.219864)
		(width 0.1016)
		(layer "F.Cu")
		(net "M_BMC_DDR4_DQS0_N")
	)
	(arc
		(start 68.360544 -50.259742)
		(mid 68.500387 -50.353182)
		(end 68.665344 -50.38598)
		(width 0.1016)
		(layer "F.Cu")
		(net "M_BMC_DDR4_DQS0_N")
	)
	(arc
		(start 69.3039 -52.036726)
		(mid 69.192491 -52.111167)
		(end 69.061076 -52.13731)
		(width 0.1016)
		(layer "F.Cu")
		(net "M_BMC_DDR4_DQS0_N")
	)
	(arc
		(start 69.648578 -51.87061)
		(mid 69.483627 -51.903421)
		(end 69.343778 -51.996848)
		(width 0.1016)
		(layer "F.Cu")
		(net "M_BMC_DDR4_DQS0_N")
	)
	(arc
		(start 67.183508 -50.269648)
		(mid 67.312266 -50.355745)
		(end 67.464178 -50.38598)
		(width 0.1016)
		(layer "F.Cu")
		(net "M_BMC_DDR4_DQS0_N")
	)
	(arc
		(start 69.966332 -50.38598)
		(mid 70.307582 -50.52733)
		(end 70.448932 -50.86858)
		(width 0.1016)
		(layer "F.Cu")
		(net "M_BMC_DDR4_DQS0_N")
	)
	(arc
		(start 67.814698 -50.219864)
		(mid 67.926107 -50.145423)
		(end 68.057522 -50.11928)
		(width 0.1016)
		(layer "F.Cu")
		(net "M_BMC_DDR4_DQS0_N")
	)
	(arc
		(start 65.54724 -51.371246)
		(mid 65.637043 -51.334049)
		(end 65.67424 -51.244246)
		(width 0.1016)
		(layer "F.Cu")
		(net "M_BMC_DDR4_DQS0_N")
	)
	(arc
		(start 65.67424 -50.86858)
		(mid 65.81559 -50.52733)
		(end 66.15684 -50.38598)
		(width 0.1016)
		(layer "F.Cu")
		(net "M_BMC_DDR4_DQS0_N")
	)
	(arc
		(start 70.448932 -51.36261)
		(mid 70.300142 -51.72182)
		(end 69.940932 -51.87061)
		(width 0.1016)
		(layer "F.Cu")
		(net "M_BMC_DDR4_DQS0_N")
	)
	(segment
		(start 72.632062 -52.455318)
		(end 72.534272 -52.553108)
		(width 0.08636)
		(layer "In9.Cu")
		(net "M_BMC_DDR4_DQS0_N")
	)
	(segment
		(start 68.410836 -53.13172)
		(end 68.393564 -53.13172)
		(width 0.08636)
		(layer "In9.Cu")
		(net "M_BMC_DDR4_DQS0_N")
	)
	(segment
		(start 69.2912 -53.378608)
		(end 69.253608 -53.4162)
		(width 0.08636)
		(layer "In9.Cu")
		(net "M_BMC_DDR4_DQS0_N")
	)
	(segment
		(start 71.28764 -53.1876)
		(end 71.28764 -53.937154)
		(width 0.08636)
		(layer "In9.Cu")
		(net "M_BMC_DDR4_DQS0_N")
	)
	(segment
		(start 74.095864 -51.906932)
		(end 74.083926 -51.91887)
		(width 0.08636)
		(layer "In9.Cu")
		(net "M_BMC_DDR4_DQS0_N")
	)
	(segment
		(start 74.498962 -51.821334)
		(end 74.302366 -51.821334)
		(width 0.08636)
		(layer "In9.Cu")
		(net "M_BMC_DDR4_DQS0_N")
	)
	(segment
		(start 72.855836 -52.36972)
		(end 72.838564 -52.36972)
		(width 0.08636)
		(layer "In9.Cu")
		(net "M_BMC_DDR4_DQS0_N")
	)
	(segment
		(start 68.715128 -53.315108)
		(end 68.617338 -53.217318)
		(width 0.08636)
		(layer "In9.Cu")
		(net "M_BMC_DDR4_DQS0_N")
	)
	(segment
		(start 67.352164 -52.91836)
		(end 67.35064 -52.91455)
		(width 0.08636)
		(layer "In9.Cu")
		(net "M_BMC_DDR4_DQS0_N")
	)
	(segment
		(start 74.713338 -51.727862)
		(end 74.705464 -51.735736)
		(width 0.08636)
		(layer "In9.Cu")
		(net "M_BMC_DDR4_DQS0_N")
	)
	(segment
		(start 70.150228 -52.3748)
		(end 69.939408 -52.3748)
		(width 0.08636)
		(layer "In9.Cu")
		(net "M_BMC_DDR4_DQS0_N")
	)
	(segment
		(start 67.530726 -53.357526)
		(end 67.482974 -53.30952)
		(width 0.08636)
		(layer "In9.Cu")
		(net "M_BMC_DDR4_DQS0_N")
	)
	(segment
		(start 67.35064 -52.813966)
		(end 67.358006 -52.768246)
		(width 0.08636)
		(layer "In9.Cu")
		(net "M_BMC_DDR4_DQS0_N")
	)
	(segment
		(start 69.3166 -53.097684)
		(end 69.3166 -53.317394)
		(width 0.08636)
		(layer "In9.Cu")
		(net "M_BMC_DDR4_DQS0_N")
	)
	(segment
		(start 73.998328 -52.125372)
		(end 73.998328 -52.283868)
		(width 0.08636)
		(layer "In9.Cu")
		(net "M_BMC_DDR4_DQS0_N")
	)
	(segment
		(start 74.270616 -49.525682)
		(end 74.270616 -49.530762)
		(width 0.08636)
		(layer "In9.Cu")
		(net "M_BMC_DDR4_DQS0_N")
	)
	(segment
		(start 72.22871 -52.6796)
		(end 71.79564 -52.6796)
		(width 0.08636)
		(layer "In9.Cu")
		(net "M_BMC_DDR4_DQS0_N")
	)
	(segment
		(start 70.72884 -53.900832)
		(end 70.72884 -52.953412)
		(width 0.08636)
		(layer "In9.Cu")
		(net "M_BMC_DDR4_DQS0_N")
	)
	(segment
		(start 74.494136 -49.801526)
		(end 74.52106 -49.894998)
		(width 0.08636)
		(layer "In9.Cu")
		(net "M_BMC_DDR4_DQS0_N")
	)
	(segment
		(start 73.160128 -52.553108)
		(end 73.062338 -52.455318)
		(width 0.08636)
		(layer "In9.Cu")
		(net "M_BMC_DDR4_DQS0_N")
	)
	(segment
		(start 73.594722 -52.6796)
		(end 73.46569 -52.6796)
		(width 0.08636)
		(layer "In9.Cu")
		(net "M_BMC_DDR4_DQS0_N")
	)
	(segment
		(start 67.48399 -52.6415)
		(end 67.581272 -52.6415)
		(width 0.08636)
		(layer "In9.Cu")
		(net "M_BMC_DDR4_DQS0_N")
	)
	(segment
		(start 69.549264 -52.536344)
		(end 69.54901 -52.536598)
		(width 0.08636)
		(layer "In9.Cu")
		(net "M_BMC_DDR4_DQS0_N")
	)
	(segment
		(start 67.581272 -52.6415)
		(end 67.58432 -52.644548)
		(width 0.08636)
		(layer "In9.Cu")
		(net "M_BMC_DDR4_DQS0_N")
	)
	(segment
		(start 67.35064 -52.91455)
		(end 67.35064 -52.813966)
		(width 0.08636)
		(layer "In9.Cu")
		(net "M_BMC_DDR4_DQS0_N")
	)
	(segment
		(start 73.88606 -52.55514)
		(end 73.87971 -52.56149)
		(width 0.08636)
		(layer "In9.Cu")
		(net "M_BMC_DDR4_DQS0_N")
	)
	(segment
		(start 68.187062 -53.217318)
		(end 68.079874 -53.324506)
		(width 0.08636)
		(layer "In9.Cu")
		(net "M_BMC_DDR4_DQS0_N")
	)
	(segment
		(start 71.112634 -54.11216)
		(end 70.940168 -54.11216)
		(width 0.08636)
		(layer "In9.Cu")
		(net "M_BMC_DDR4_DQS0_N")
	)
	(segment
		(start 69.192394 -53.4416)
		(end 69.02069 -53.4416)
		(width 0.08636)
		(layer "In9.Cu")
		(net "M_BMC_DDR4_DQS0_N")
	)
	(segment
		(start 74.270616 -49.530762)
		(end 74.449178 -49.709324)
		(width 0.08636)
		(layer "In9.Cu")
		(net "M_BMC_DDR4_DQS0_N")
	)
	(segment
		(start 67.35191 -52.99837)
		(end 67.352164 -52.91836)
		(width 0.08636)
		(layer "In9.Cu")
		(net "M_BMC_DDR4_DQS0_N")
	)
	(segment
		(start 74.803 -50.60442)
		(end 74.803 -51.511708)
		(width 0.08636)
		(layer "In9.Cu")
		(net "M_BMC_DDR4_DQS0_N")
	)
	(segment
		(start 67.365626 -52.743862)
		(end 67.385946 -52.70246)
		(width 0.08636)
		(layer "In9.Cu")
		(net "M_BMC_DDR4_DQS0_N")
	)
	(segment
		(start 67.797426 -53.4416)
		(end 67.733418 -53.4416)
		(width 0.08636)
		(layer "In9.Cu")
		(net "M_BMC_DDR4_DQS0_N")
	)
	(arc
		(start 69.54901 -52.536598)
		(mid 69.377002 -52.794026)
		(end 69.3166 -53.097684)
		(width 0.08636)
		(layer "In9.Cu")
		(net "M_BMC_DDR4_DQS0_N")
	)
	(arc
		(start 74.52106 -49.894998)
		(mid 74.567965 -50.013953)
		(end 74.63663 -50.12182)
		(width 0.08636)
		(layer "In9.Cu")
		(net "M_BMC_DDR4_DQS0_N")
	)
	(arc
		(start 68.617338 -53.217318)
		(mid 68.522608 -53.153958)
		(end 68.410836 -53.13172)
		(width 0.08636)
		(layer "In9.Cu")
		(net "M_BMC_DDR4_DQS0_N")
	)
	(arc
		(start 74.63663 -50.12182)
		(mid 74.760161 -50.349211)
		(end 74.803 -50.60442)
		(width 0.08636)
		(layer "In9.Cu")
		(net "M_BMC_DDR4_DQS0_N")
	)
	(arc
		(start 73.062338 -52.455318)
		(mid 72.967608 -52.391958)
		(end 72.855836 -52.36972)
		(width 0.08636)
		(layer "In9.Cu")
		(net "M_BMC_DDR4_DQS0_N")
	)
	(arc
		(start 67.385946 -52.70246)
		(mid 67.42625 -52.657942)
		(end 67.48399 -52.6415)
		(width 0.08636)
		(layer "In9.Cu")
		(net "M_BMC_DDR4_DQS0_N")
	)
	(arc
		(start 67.456812 -53.28031)
		(mid 67.442388 -53.261552)
		(end 67.429126 -53.241956)
		(width 0.08636)
		(layer "In9.Cu")
		(net "M_BMC_DDR4_DQS0_N")
	)
	(arc
		(start 69.02069 -53.4416)
		(mid 68.855336 -53.408727)
		(end 68.715128 -53.315108)
		(width 0.08636)
		(layer "In9.Cu")
		(net "M_BMC_DDR4_DQS0_N")
	)
	(arc
		(start 74.803 -51.511708)
		(mid 74.779691 -51.62871)
		(end 74.713338 -51.727862)
		(width 0.08636)
		(layer "In9.Cu")
		(net "M_BMC_DDR4_DQS0_N")
	)
	(arc
		(start 73.46569 -52.6796)
		(mid 73.300336 -52.646727)
		(end 73.160128 -52.553108)
		(width 0.08636)
		(layer "In9.Cu")
		(net "M_BMC_DDR4_DQS0_N")
	)
	(arc
		(start 74.705464 -51.735736)
		(mid 74.610734 -51.799096)
		(end 74.498962 -51.821334)
		(width 0.08636)
		(layer "In9.Cu")
		(net "M_BMC_DDR4_DQS0_N")
	)
	(arc
		(start 69.253608 -53.4162)
		(mid 69.225537 -53.43502)
		(end 69.192394 -53.4416)
		(width 0.08636)
		(layer "In9.Cu")
		(net "M_BMC_DDR4_DQS0_N")
	)
	(arc
		(start 67.358006 -52.768246)
		(mid 67.360899 -52.755767)
		(end 67.365626 -52.743862)
		(width 0.08636)
		(layer "In9.Cu")
		(net "M_BMC_DDR4_DQS0_N")
	)
	(arc
		(start 74.083926 -51.91887)
		(mid 74.020566 -52.0136)
		(end 73.998328 -52.125372)
		(width 0.08636)
		(layer "In9.Cu")
		(net "M_BMC_DDR4_DQS0_N")
	)
	(arc
		(start 67.36207 -53.082698)
		(mid 67.354524 -53.040831)
		(end 67.35191 -52.99837)
		(width 0.08636)
		(layer "In9.Cu")
		(net "M_BMC_DDR4_DQS0_N")
	)
	(arc
		(start 72.534272 -52.553108)
		(mid 72.394065 -52.646728)
		(end 72.22871 -52.6796)
		(width 0.08636)
		(layer "In9.Cu")
		(net "M_BMC_DDR4_DQS0_N")
	)
	(arc
		(start 74.449178 -49.709324)
		(mid 74.475707 -49.75345)
		(end 74.494136 -49.801526)
		(width 0.08636)
		(layer "In9.Cu")
		(net "M_BMC_DDR4_DQS0_N")
	)
	(arc
		(start 67.733418 -53.4416)
		(mid 67.623731 -53.419688)
		(end 67.530726 -53.357526)
		(width 0.08636)
		(layer "In9.Cu")
		(net "M_BMC_DDR4_DQS0_N")
	)
	(arc
		(start 73.87971 -52.56149)
		(mid 73.748971 -52.64891)
		(end 73.594722 -52.6796)
		(width 0.08636)
		(layer "In9.Cu")
		(net "M_BMC_DDR4_DQS0_N")
	)
	(arc
		(start 68.079874 -53.324506)
		(mid 67.9503 -53.411148)
		(end 67.797426 -53.4416)
		(width 0.08636)
		(layer "In9.Cu")
		(net "M_BMC_DDR4_DQS0_N")
	)
	(arc
		(start 70.940168 -54.11216)
		(mid 70.790737 -54.050263)
		(end 70.72884 -53.900832)
		(width 0.08636)
		(layer "In9.Cu")
		(net "M_BMC_DDR4_DQS0_N")
	)
	(arc
		(start 69.3166 -53.317394)
		(mid 69.309992 -53.350525)
		(end 69.2912 -53.378608)
		(width 0.08636)
		(layer "In9.Cu")
		(net "M_BMC_DDR4_DQS0_N")
	)
	(arc
		(start 71.79564 -52.6796)
		(mid 71.43643 -52.82839)
		(end 71.28764 -53.1876)
		(width 0.08636)
		(layer "In9.Cu")
		(net "M_BMC_DDR4_DQS0_N")
	)
	(arc
		(start 70.72884 -52.953412)
		(mid 70.559368 -52.544272)
		(end 70.150228 -52.3748)
		(width 0.08636)
		(layer "In9.Cu")
		(net "M_BMC_DDR4_DQS0_N")
	)
	(arc
		(start 74.302366 -51.821334)
		(mid 74.190598 -51.843584)
		(end 74.095864 -51.906932)
		(width 0.08636)
		(layer "In9.Cu")
		(net "M_BMC_DDR4_DQS0_N")
	)
	(arc
		(start 68.393564 -53.13172)
		(mid 68.281796 -53.15397)
		(end 68.187062 -53.217318)
		(width 0.08636)
		(layer "In9.Cu")
		(net "M_BMC_DDR4_DQS0_N")
	)
	(arc
		(start 67.429126 -53.241956)
		(mid 67.389028 -53.165094)
		(end 67.36207 -53.082698)
		(width 0.08636)
		(layer "In9.Cu")
		(net "M_BMC_DDR4_DQS0_N")
	)
	(arc
		(start 73.998328 -52.283868)
		(mid 73.969148 -52.430657)
		(end 73.88606 -52.55514)
		(width 0.08636)
		(layer "In9.Cu")
		(net "M_BMC_DDR4_DQS0_N")
	)
	(arc
		(start 69.939408 -52.3748)
		(mid 69.728272 -52.41678)
		(end 69.549264 -52.536344)
		(width 0.08636)
		(layer "In9.Cu")
		(net "M_BMC_DDR4_DQS0_N")
	)
	(arc
		(start 71.28764 -53.937154)
		(mid 71.274175 -54.004015)
		(end 71.236078 -54.060598)
		(width 0.08636)
		(layer "In9.Cu")
		(net "M_BMC_DDR4_DQS0_N")
	)
	(arc
		(start 67.482974 -53.30952)
		(mid 67.469533 -53.295238)
		(end 67.456812 -53.28031)
		(width 0.08636)
		(layer "In9.Cu")
		(net "M_BMC_DDR4_DQS0_N")
	)
	(arc
		(start 72.838564 -52.36972)
		(mid 72.726796 -52.39197)
		(end 72.632062 -52.455318)
		(width 0.08636)
		(layer "In9.Cu")
		(net "M_BMC_DDR4_DQS0_N")
	)
	(arc
		(start 71.236078 -54.060598)
		(mid 71.179514 -54.09874)
		(end 71.112634 -54.11216)
		(width 0.08636)
		(layer "In9.Cu")
		(net "M_BMC_DDR4_DQS0_N")
	)
	(segment
		(start 63.295022 -52.971192)
		(end 63.690246 -53.366416)
		(width 0.11684)
		(layer "F.Cu")
		(net "M_BMC_DDR4_DQ<9>")
	)
	(segment
		(start 78.65237 -53.107336)
		(end 79.034132 -53.489098)
		(width 0.11684)
		(layer "F.Cu")
		(net "M_BMC_DDR4_DQ<9>")
	)
	(via
		(at 63.690246 -53.366416)
		(size 0.4572)
		(drill 0.254)
		(layers "F.Cu" "B.Cu")
		(net "M_BMC_DDR4_DQ<9>")
	)
	(via
		(at 79.034132 -53.489098)
		(size 0.4572)
		(drill 0.254)
		(layers "F.Cu" "B.Cu")
		(net "M_BMC_DDR4_DQ<9>")
	)
	(segment
		(start 74.143108 -52.663344)
		(end 74.477626 -52.328826)
		(width 0.08382)
		(layer "In2.Cu")
		(net "M_BMC_DDR4_DQ<9>")
	)
	(segment
		(start 69.632322 -51.74869)
		(end 69.734684 -51.851306)
		(width 0.08382)
		(layer "In2.Cu")
		(net "M_BMC_DDR4_DQ<9>")
	)
	(segment
		(start 80.411574 -51.597814)
		(end 80.411574 -52.184046)
		(width 0.08382)
		(layer "In2.Cu")
		(net "M_BMC_DDR4_DQ<9>")
	)
	(segment
		(start 75.456288 -52.310538)
		(end 78.560422 -52.310538)
		(width 0.08382)
		(layer "In2.Cu")
		(net "M_BMC_DDR4_DQ<9>")
	)
	(segment
		(start 66.12509 -51.708812)
		(end 69.536056 -51.708812)
		(width 0.08382)
		(layer "In2.Cu")
		(net "M_BMC_DDR4_DQ<9>")
	)
	(segment
		(start 80.354424 -53.8734)
		(end 79.159608 -53.8734)
		(width 0.08382)
		(layer "In2.Cu")
		(net "M_BMC_DDR4_DQ<9>")
	)
	(segment
		(start 78.654402 -52.216558)
		(end 78.654402 -51.58232)
		(width 0.08382)
		(layer "In2.Cu")
		(net "M_BMC_DDR4_DQ<9>")
	)
	(segment
		(start 64.077088 -52.853844)
		(end 64.077088 -52.476146)
		(width 0.08382)
		(layer "In2.Cu")
		(net "M_BMC_DDR4_DQ<9>")
	)
	(segment
		(start 78.748382 -51.48834)
		(end 80.3021 -51.48834)
		(width 0.08382)
		(layer "In2.Cu")
		(net "M_BMC_DDR4_DQ<9>")
	)
	(segment
		(start 74.70902 -52.233068)
		(end 75.105006 -52.233068)
		(width 0.08382)
		(layer "In2.Cu")
		(net "M_BMC_DDR4_DQ<9>")
	)
	(segment
		(start 63.690246 -53.366416)
		(end 63.373762 -53.366416)
		(width 0.08382)
		(layer "In2.Cu")
		(net "M_BMC_DDR4_DQ<9>")
	)
	(segment
		(start 63.381382 -52.947824)
		(end 63.983108 -52.947824)
		(width 0.08382)
		(layer "In2.Cu")
		(net "M_BMC_DDR4_DQ<9>")
	)
	(segment
		(start 71.873872 -51.96967)
		(end 71.873872 -52.471066)
		(width 0.08382)
		(layer "In2.Cu")
		(net "M_BMC_DDR4_DQ<9>")
	)
	(segment
		(start 64.46901 -51.77409)
		(end 65.774824 -51.77409)
		(width 0.08382)
		(layer "In2.Cu")
		(net "M_BMC_DDR4_DQ<9>")
	)
	(segment
		(start 80.440784 -53.232304)
		(end 80.440784 -53.78704)
		(width 0.08382)
		(layer "In2.Cu")
		(net "M_BMC_DDR4_DQ<9>")
	)
	(segment
		(start 64.37503 -52.092606)
		(end 64.37503 -51.86807)
		(width 0.08382)
		(layer "In2.Cu")
		(net "M_BMC_DDR4_DQ<9>")
	)
	(segment
		(start 79.034132 -53.747924)
		(end 79.034132 -53.489098)
		(width 0.08382)
		(layer "In2.Cu")
		(net "M_BMC_DDR4_DQ<9>")
	)
	(segment
		(start 64.110108 -52.396644)
		(end 64.347344 -52.159408)
		(width 0.08382)
		(layer "In2.Cu")
		(net "M_BMC_DDR4_DQ<9>")
	)
	(segment
		(start 80.325214 -52.270406)
		(end 79.422244 -52.270406)
		(width 0.08382)
		(layer "In2.Cu")
		(net "M_BMC_DDR4_DQ<9>")
	)
	(segment
		(start 72.093836 -52.69103)
		(end 74.076306 -52.69103)
		(width 0.08382)
		(layer "In2.Cu")
		(net "M_BMC_DDR4_DQ<9>")
	)
	(segment
		(start 79.335884 -52.356766)
		(end 79.335884 -53.026056)
		(width 0.08382)
		(layer "In2.Cu")
		(net "M_BMC_DDR4_DQ<9>")
	)
	(segment
		(start 69.796152 -51.876706)
		(end 71.780908 -51.876706)
		(width 0.08382)
		(layer "In2.Cu")
		(net "M_BMC_DDR4_DQ<9>")
	)
	(segment
		(start 63.287402 -53.280056)
		(end 63.287402 -53.041804)
		(width 0.08382)
		(layer "In2.Cu")
		(net "M_BMC_DDR4_DQ<9>")
	)
	(segment
		(start 79.422244 -53.112416)
		(end 80.320896 -53.112416)
		(width 0.08382)
		(layer "In2.Cu")
		(net "M_BMC_DDR4_DQ<9>")
	)
	(arc
		(start 65.774824 -51.77409)
		(mid 65.863955 -51.765931)
		(end 65.950084 -51.741578)
		(width 0.08382)
		(layer "In2.Cu")
		(net "M_BMC_DDR4_DQ<9>")
	)
	(arc
		(start 69.536056 -51.708812)
		(mid 69.588181 -51.719122)
		(end 69.632322 -51.74869)
		(width 0.08382)
		(layer "In2.Cu")
		(net "M_BMC_DDR4_DQ<9>")
	)
	(arc
		(start 65.950084 -51.741578)
		(mid 66.036073 -51.717112)
		(end 66.12509 -51.708812)
		(width 0.08382)
		(layer "In2.Cu")
		(net "M_BMC_DDR4_DQ<9>")
	)
	(arc
		(start 79.422244 -52.270406)
		(mid 79.361178 -52.2957)
		(end 79.335884 -52.356766)
		(width 0.08382)
		(layer "In2.Cu")
		(net "M_BMC_DDR4_DQ<9>")
	)
	(arc
		(start 63.287402 -53.041804)
		(mid 63.314928 -52.97535)
		(end 63.381382 -52.947824)
		(width 0.08382)
		(layer "In2.Cu")
		(net "M_BMC_DDR4_DQ<9>")
	)
	(arc
		(start 63.983108 -52.947824)
		(mid 64.049562 -52.920298)
		(end 64.077088 -52.853844)
		(width 0.08382)
		(layer "In2.Cu")
		(net "M_BMC_DDR4_DQ<9>")
	)
	(arc
		(start 64.37503 -51.86807)
		(mid 64.402556 -51.801616)
		(end 64.46901 -51.77409)
		(width 0.08382)
		(layer "In2.Cu")
		(net "M_BMC_DDR4_DQ<9>")
	)
	(arc
		(start 64.347344 -52.159408)
		(mid 64.367823 -52.128759)
		(end 64.37503 -52.092606)
		(width 0.08382)
		(layer "In2.Cu")
		(net "M_BMC_DDR4_DQ<9>")
	)
	(arc
		(start 74.477626 -52.328826)
		(mid 74.583805 -52.257943)
		(end 74.70902 -52.233068)
		(width 0.08382)
		(layer "In2.Cu")
		(net "M_BMC_DDR4_DQ<9>")
	)
	(arc
		(start 79.159608 -53.8734)
		(mid 79.070883 -53.836649)
		(end 79.034132 -53.747924)
		(width 0.08382)
		(layer "In2.Cu")
		(net "M_BMC_DDR4_DQ<9>")
	)
	(arc
		(start 75.257914 -52.26685)
		(mid 75.354722 -52.299489)
		(end 75.456288 -52.310538)
		(width 0.08382)
		(layer "In2.Cu")
		(net "M_BMC_DDR4_DQ<9>")
	)
	(arc
		(start 78.560422 -52.310538)
		(mid 78.626876 -52.283012)
		(end 78.654402 -52.216558)
		(width 0.08382)
		(layer "In2.Cu")
		(net "M_BMC_DDR4_DQ<9>")
	)
	(arc
		(start 71.780908 -51.876706)
		(mid 71.846643 -51.903935)
		(end 71.873872 -51.96967)
		(width 0.08382)
		(layer "In2.Cu")
		(net "M_BMC_DDR4_DQ<9>")
	)
	(arc
		(start 64.077088 -52.476146)
		(mid 64.085668 -52.4331)
		(end 64.110108 -52.396644)
		(width 0.08382)
		(layer "In2.Cu")
		(net "M_BMC_DDR4_DQ<9>")
	)
	(arc
		(start 80.411574 -52.184046)
		(mid 80.38628 -52.245112)
		(end 80.325214 -52.270406)
		(width 0.08382)
		(layer "In2.Cu")
		(net "M_BMC_DDR4_DQ<9>")
	)
	(arc
		(start 75.105006 -52.233068)
		(mid 75.183302 -52.241632)
		(end 75.257914 -52.26685)
		(width 0.08382)
		(layer "In2.Cu")
		(net "M_BMC_DDR4_DQ<9>")
	)
	(arc
		(start 71.873872 -52.471066)
		(mid 71.938298 -52.626604)
		(end 72.093836 -52.69103)
		(width 0.08382)
		(layer "In2.Cu")
		(net "M_BMC_DDR4_DQ<9>")
	)
	(arc
		(start 80.3021 -51.48834)
		(mid 80.37951 -51.520404)
		(end 80.411574 -51.597814)
		(width 0.08382)
		(layer "In2.Cu")
		(net "M_BMC_DDR4_DQ<9>")
	)
	(arc
		(start 80.440784 -53.78704)
		(mid 80.41549 -53.848106)
		(end 80.354424 -53.8734)
		(width 0.08382)
		(layer "In2.Cu")
		(net "M_BMC_DDR4_DQ<9>")
	)
	(arc
		(start 78.654402 -51.58232)
		(mid 78.681928 -51.515866)
		(end 78.748382 -51.48834)
		(width 0.08382)
		(layer "In2.Cu")
		(net "M_BMC_DDR4_DQ<9>")
	)
	(arc
		(start 80.320896 -53.112416)
		(mid 80.40567 -53.14753)
		(end 80.440784 -53.232304)
		(width 0.08382)
		(layer "In2.Cu")
		(net "M_BMC_DDR4_DQ<9>")
	)
	(arc
		(start 79.335884 -53.026056)
		(mid 79.361178 -53.087122)
		(end 79.422244 -53.112416)
		(width 0.08382)
		(layer "In2.Cu")
		(net "M_BMC_DDR4_DQ<9>")
	)
	(arc
		(start 74.076306 -52.69103)
		(mid 74.112465 -52.683838)
		(end 74.143108 -52.663344)
		(width 0.08382)
		(layer "In2.Cu")
		(net "M_BMC_DDR4_DQ<9>")
	)
	(arc
		(start 63.373762 -53.366416)
		(mid 63.312696 -53.341122)
		(end 63.287402 -53.280056)
		(width 0.08382)
		(layer "In2.Cu")
		(net "M_BMC_DDR4_DQ<9>")
	)
	(arc
		(start 69.734684 -51.851306)
		(mid 69.762901 -51.870067)
		(end 69.796152 -51.876706)
		(width 0.08382)
		(layer "In2.Cu")
		(net "M_BMC_DDR4_DQ<9>")
	)
	(segment
		(start 71.919338 -54.995318)
		(end 71.919338 -56.526938)
		(width 0.11684)
		(layer "F.Cu")
		(net "M_BMC_DDR4_DQ<8>")
	)
	(segment
		(start 72.033638 -56.641238)
		(end 75.58151 -56.641238)
		(width 0.11684)
		(layer "F.Cu")
		(net "M_BMC_DDR4_DQ<8>")
	)
	(segment
		(start 64.094868 -53.771292)
		(end 64.490092 -54.166516)
		(width 0.11684)
		(layer "F.Cu")
		(net "M_BMC_DDR4_DQ<8>")
	)
	(segment
		(start 75.58151 -56.018938)
		(end 72.650096 -56.018938)
		(width 0.11684)
		(layer "F.Cu")
		(net "M_BMC_DDR4_DQ<8>")
	)
	(segment
		(start 75.69581 -56.526938)
		(end 75.69581 -56.133238)
		(width 0.11684)
		(layer "F.Cu")
		(net "M_BMC_DDR4_DQ<8>")
	)
	(segment
		(start 72.650096 -55.396638)
		(end 74.525124 -55.396638)
		(width 0.11684)
		(layer "F.Cu")
		(net "M_BMC_DDR4_DQ<8>")
	)
	(segment
		(start 74.82332 -54.130702)
		(end 74.786236 -54.041294)
		(width 0.11684)
		(layer "F.Cu")
		(net "M_BMC_DDR4_DQ<8>")
	)
	(segment
		(start 74.098404 -54.7878)
		(end 72.126856 -54.7878)
		(width 0.11684)
		(layer "F.Cu")
		(net "M_BMC_DDR4_DQ<8>")
	)
	(segment
		(start 74.82332 -55.098442)
		(end 74.82332 -54.130702)
		(width 0.11684)
		(layer "F.Cu")
		(net "M_BMC_DDR4_DQ<8>")
	)
	(segment
		(start 74.270616 -54.289198)
		(end 74.270616 -54.596792)
		(width 0.11684)
		(layer "F.Cu")
		(net "M_BMC_DDR4_DQ<8>")
	)
	(segment
		(start 72.535796 -55.904638)
		(end 72.535796 -55.510938)
		(width 0.11684)
		(layer "F.Cu")
		(net "M_BMC_DDR4_DQ<8>")
	)
	(segment
		(start 74.786236 -54.041294)
		(end 74.652378 -53.907436)
		(width 0.11684)
		(layer "F.Cu")
		(net "M_BMC_DDR4_DQ<8>")
	)
	(via
		(at 64.490092 -54.166516)
		(size 0.4572)
		(drill 0.254)
		(layers "F.Cu" "B.Cu")
		(net "M_BMC_DDR4_DQ<8>")
	)
	(via
		(at 74.270616 -54.289198)
		(size 0.4572)
		(drill 0.254)
		(layers "F.Cu" "B.Cu")
		(net "M_BMC_DDR4_DQ<8>")
	)
	(arc
		(start 75.69581 -56.133238)
		(mid 75.662332 -56.052416)
		(end 75.58151 -56.018938)
		(width 0.11684)
		(layer "F.Cu")
		(net "M_BMC_DDR4_DQ<8>")
	)
	(arc
		(start 74.525124 -55.396638)
		(mid 74.73598 -55.309298)
		(end 74.82332 -55.098442)
		(width 0.11684)
		(layer "F.Cu")
		(net "M_BMC_DDR4_DQ<8>")
	)
	(arc
		(start 72.650096 -56.018938)
		(mid 72.569274 -55.98546)
		(end 72.535796 -55.904638)
		(width 0.11684)
		(layer "F.Cu")
		(net "M_BMC_DDR4_DQ<8>")
	)
	(arc
		(start 74.270616 -54.596792)
		(mid 74.253702 -54.678467)
		(end 74.205338 -54.746398)
		(width 0.11684)
		(layer "F.Cu")
		(net "M_BMC_DDR4_DQ<8>")
	)
	(arc
		(start 75.58151 -56.641238)
		(mid 75.662332 -56.60776)
		(end 75.69581 -56.526938)
		(width 0.11684)
		(layer "F.Cu")
		(net "M_BMC_DDR4_DQ<8>")
	)
	(arc
		(start 72.126856 -54.7878)
		(mid 71.980119 -54.848581)
		(end 71.919338 -54.995318)
		(width 0.11684)
		(layer "F.Cu")
		(net "M_BMC_DDR4_DQ<8>")
	)
	(arc
		(start 72.535796 -55.510938)
		(mid 72.569274 -55.430116)
		(end 72.650096 -55.396638)
		(width 0.11684)
		(layer "F.Cu")
		(net "M_BMC_DDR4_DQ<8>")
	)
	(arc
		(start 71.919338 -56.526938)
		(mid 71.952816 -56.60776)
		(end 72.033638 -56.641238)
		(width 0.11684)
		(layer "F.Cu")
		(net "M_BMC_DDR4_DQ<8>")
	)
	(arc
		(start 74.205338 -54.746398)
		(mid 74.155785 -54.777227)
		(end 74.098404 -54.7878)
		(width 0.11684)
		(layer "F.Cu")
		(net "M_BMC_DDR4_DQ<8>")
	)
	(segment
		(start 68.805806 -53.579268)
		(end 65.39357 -53.579268)
		(width 0.08382)
		(layer "In2.Cu")
		(net "M_BMC_DDR4_DQ<8>")
	)
	(segment
		(start 74.270616 -54.289198)
		(end 74.265536 -54.289198)
		(width 0.08382)
		(layer "In2.Cu")
		(net "M_BMC_DDR4_DQ<8>")
	)
	(segment
		(start 65.297812 -53.618892)
		(end 64.777874 -54.13883)
		(width 0.08382)
		(layer "In2.Cu")
		(net "M_BMC_DDR4_DQ<8>")
	)
	(segment
		(start 73.64349 -54.698138)
		(end 70.517258 -54.698138)
		(width 0.08382)
		(layer "In2.Cu")
		(net "M_BMC_DDR4_DQ<8>")
	)
	(segment
		(start 70.179438 -54.558184)
		(end 69.479668 -53.858414)
		(width 0.08382)
		(layer "In2.Cu")
		(net "M_BMC_DDR4_DQ<8>")
	)
	(segment
		(start 64.711072 -54.166516)
		(end 64.490092 -54.166516)
		(width 0.08382)
		(layer "In2.Cu")
		(net "M_BMC_DDR4_DQ<8>")
	)
	(segment
		(start 74.265536 -54.289198)
		(end 73.990962 -54.563772)
		(width 0.08382)
		(layer "In2.Cu")
		(net "M_BMC_DDR4_DQ<8>")
	)
	(arc
		(start 65.39357 -53.579268)
		(mid 65.341762 -53.589573)
		(end 65.297812 -53.618892)
		(width 0.08382)
		(layer "In2.Cu")
		(net "M_BMC_DDR4_DQ<8>")
	)
	(arc
		(start 73.923652 -54.61762)
		(mid 73.789251 -54.677643)
		(end 73.64349 -54.698138)
		(width 0.08382)
		(layer "In2.Cu")
		(net "M_BMC_DDR4_DQ<8>")
	)
	(arc
		(start 73.990962 -54.563772)
		(mid 73.958814 -54.592579)
		(end 73.923652 -54.61762)
		(width 0.08382)
		(layer "In2.Cu")
		(net "M_BMC_DDR4_DQ<8>")
	)
	(arc
		(start 64.777874 -54.13883)
		(mid 64.747225 -54.159309)
		(end 64.711072 -54.166516)
		(width 0.08382)
		(layer "In2.Cu")
		(net "M_BMC_DDR4_DQ<8>")
	)
	(arc
		(start 70.517258 -54.698138)
		(mid 70.334422 -54.66177)
		(end 70.179438 -54.558184)
		(width 0.08382)
		(layer "In2.Cu")
		(net "M_BMC_DDR4_DQ<8>")
	)
	(arc
		(start 69.479668 -53.858414)
		(mid 69.170497 -53.651833)
		(end 68.805806 -53.579268)
		(width 0.08382)
		(layer "In2.Cu")
		(net "M_BMC_DDR4_DQ<8>")
	)
	(segment
		(start 63.295022 -49.7713)
		(end 63.690246 -50.166524)
		(width 0.11684)
		(layer "F.Cu")
		(net "M_BMC_DDR4_DQ<7>")
	)
	(segment
		(start 77.85227 -47.507398)
		(end 78.234032 -47.88916)
		(width 0.11684)
		(layer "F.Cu")
		(net "M_BMC_DDR4_DQ<7>")
	)
	(via
		(at 63.690246 -50.166524)
		(size 0.4572)
		(drill 0.254)
		(layers "F.Cu" "B.Cu")
		(net "M_BMC_DDR4_DQ<7>")
	)
	(via
		(at 78.234032 -47.88916)
		(size 0.4572)
		(drill 0.254)
		(layers "F.Cu" "B.Cu")
		(net "M_BMC_DDR4_DQ<7>")
	)
	(segment
		(start 77.57795 -46.893226)
		(end 77.169772 -46.893226)
		(width 0.08382)
		(layer "In9.Cu")
		(net "M_BMC_DDR4_DQ<7>")
	)
	(segment
		(start 69.242178 -47.941738)
		(end 68.911216 -48.2727)
		(width 0.08382)
		(layer "In9.Cu")
		(net "M_BMC_DDR4_DQ<7>")
	)
	(segment
		(start 76.402438 -47.913544)
		(end 76.0349 -47.913544)
		(width 0.08382)
		(layer "In9.Cu")
		(net "M_BMC_DDR4_DQ<7>")
	)
	(segment
		(start 75.94854 -47.827184)
		(end 75.94854 -46.678596)
		(width 0.08382)
		(layer "In9.Cu")
		(net "M_BMC_DDR4_DQ<7>")
	)
	(segment
		(start 78.234032 -47.88916)
		(end 77.59954 -47.88916)
		(width 0.08382)
		(layer "In9.Cu")
		(net "M_BMC_DDR4_DQ<7>")
	)
	(segment
		(start 67.946524 -48.35779)
		(end 67.686936 -48.617378)
		(width 0.08382)
		(layer "In9.Cu")
		(net "M_BMC_DDR4_DQ<7>")
	)
	(segment
		(start 77.407008 -48.814736)
		(end 76.544932 -48.814736)
		(width 0.08382)
		(layer "In9.Cu")
		(net "M_BMC_DDR4_DQ<7>")
	)
	(segment
		(start 63.690246 -49.087024)
		(end 63.690246 -50.166524)
		(width 0.08382)
		(layer "In9.Cu")
		(net "M_BMC_DDR4_DQ<7>")
	)
	(segment
		(start 77.049376 -46.772576)
		(end 77.049376 -46.65218)
		(width 0.08382)
		(layer "In9.Cu")
		(net "M_BMC_DDR4_DQ<7>")
	)
	(segment
		(start 69.591936 -47.382938)
		(end 69.395594 -47.186596)
		(width 0.08382)
		(layer "In9.Cu")
		(net "M_BMC_DDR4_DQ<7>")
	)
	(segment
		(start 66.011552 -48.189642)
		(end 64.360806 -48.189642)
		(width 0.08382)
		(layer "In9.Cu")
		(net "M_BMC_DDR4_DQ<7>")
	)
	(segment
		(start 63.904622 -48.88611)
		(end 63.869824 -48.909224)
		(width 0.08382)
		(layer "In9.Cu")
		(net "M_BMC_DDR4_DQ<7>")
	)
	(segment
		(start 76.416916 -48.68672)
		(end 76.416916 -48.436276)
		(width 0.08382)
		(layer "In9.Cu")
		(net "M_BMC_DDR4_DQ<7>")
	)
	(segment
		(start 76.963016 -46.56582)
		(end 76.582778 -46.56582)
		(width 0.08382)
		(layer "In9.Cu")
		(net "M_BMC_DDR4_DQ<7>")
	)
	(segment
		(start 77.76083 -47.177706)
		(end 77.76083 -47.076106)
		(width 0.08382)
		(layer "In9.Cu")
		(net "M_BMC_DDR4_DQ<7>")
	)
	(segment
		(start 77.049376 -48.263556)
		(end 77.049376 -47.543466)
		(width 0.08382)
		(layer "In9.Cu")
		(net "M_BMC_DDR4_DQ<7>")
	)
	(segment
		(start 70.355714 -46.75251)
		(end 69.725286 -47.382938)
		(width 0.08382)
		(layer "In9.Cu")
		(net "M_BMC_DDR4_DQ<7>")
	)
	(segment
		(start 71.590916 -46.295818)
		(end 71.321168 -46.565566)
		(width 0.08382)
		(layer "In9.Cu")
		(net "M_BMC_DDR4_DQ<7>")
	)
	(segment
		(start 66.097912 -48.678846)
		(end 66.097912 -48.276002)
		(width 0.08382)
		(layer "In9.Cu")
		(net "M_BMC_DDR4_DQ<7>")
	)
	(segment
		(start 69.00799 -47.574454)
		(end 69.242178 -47.808642)
		(width 0.08382)
		(layer "In9.Cu")
		(net "M_BMC_DDR4_DQ<7>")
	)
	(segment
		(start 75.356974 -46.72711)
		(end 73.150222 -46.72711)
		(width 0.08382)
		(layer "In9.Cu")
		(net "M_BMC_DDR4_DQ<7>")
	)
	(segment
		(start 75.85456 -46.584616)
		(end 75.5396 -46.584616)
		(width 0.08382)
		(layer "In9.Cu")
		(net "M_BMC_DDR4_DQ<7>")
	)
	(segment
		(start 67.304666 -48.765206)
		(end 66.184272 -48.765206)
		(width 0.08382)
		(layer "In9.Cu")
		(net "M_BMC_DDR4_DQ<7>")
	)
	(segment
		(start 76.488798 -46.6598)
		(end 76.488798 -47.827184)
		(width 0.08382)
		(layer "In9.Cu")
		(net "M_BMC_DDR4_DQ<7>")
	)
	(segment
		(start 76.503276 -48.349916)
		(end 76.963016 -48.349916)
		(width 0.08382)
		(layer "In9.Cu")
		(net "M_BMC_DDR4_DQ<7>")
	)
	(segment
		(start 77.493368 -47.995332)
		(end 77.493368 -48.728376)
		(width 0.08382)
		(layer "In9.Cu")
		(net "M_BMC_DDR4_DQ<7>")
	)
	(segment
		(start 64.102996 -48.447452)
		(end 64.102996 -48.516286)
		(width 0.08382)
		(layer "In9.Cu")
		(net "M_BMC_DDR4_DQ<7>")
	)
	(segment
		(start 72.73544 -45.931074)
		(end 72.547988 -45.931074)
		(width 0.08382)
		(layer "In9.Cu")
		(net "M_BMC_DDR4_DQ<7>")
	)
	(segment
		(start 69.262498 -47.186596)
		(end 69.00799 -47.441104)
		(width 0.08382)
		(layer "In9.Cu")
		(net "M_BMC_DDR4_DQ<7>")
	)
	(segment
		(start 70.990714 -46.72711)
		(end 70.416928 -46.72711)
		(width 0.08382)
		(layer "In9.Cu")
		(net "M_BMC_DDR4_DQ<7>")
	)
	(segment
		(start 77.232256 -47.360586)
		(end 77.57795 -47.360586)
		(width 0.08382)
		(layer "In9.Cu")
		(net "M_BMC_DDR4_DQ<7>")
	)
	(segment
		(start 73.063862 -46.64075)
		(end 73.063862 -46.282356)
		(width 0.08382)
		(layer "In9.Cu")
		(net "M_BMC_DDR4_DQ<7>")
	)
	(segment
		(start 68.833492 -48.304958)
		(end 68.074032 -48.304958)
		(width 0.08382)
		(layer "In9.Cu")
		(net "M_BMC_DDR4_DQ<7>")
	)
	(arc
		(start 76.0349 -47.913544)
		(mid 75.973834 -47.88825)
		(end 75.94854 -47.827184)
		(width 0.08382)
		(layer "In9.Cu")
		(net "M_BMC_DDR4_DQ<7>")
	)
	(arc
		(start 67.686936 -48.617378)
		(mid 67.654846 -48.646449)
		(end 67.61988 -48.671988)
		(width 0.08382)
		(layer "In9.Cu")
		(net "M_BMC_DDR4_DQ<7>")
	)
	(arc
		(start 69.725286 -47.382938)
		(mid 69.658648 -47.410503)
		(end 69.591936 -47.382938)
		(width 0.08382)
		(layer "In9.Cu")
		(net "M_BMC_DDR4_DQ<7>")
	)
	(arc
		(start 69.242178 -47.808642)
		(mid 69.269743 -47.87519)
		(end 69.242178 -47.941738)
		(width 0.08382)
		(layer "In9.Cu")
		(net "M_BMC_DDR4_DQ<7>")
	)
	(arc
		(start 72.843136 -45.95241)
		(mid 72.790331 -45.936486)
		(end 72.73544 -45.931074)
		(width 0.08382)
		(layer "In9.Cu")
		(net "M_BMC_DDR4_DQ<7>")
	)
	(arc
		(start 69.00799 -47.441104)
		(mid 68.98032 -47.507816)
		(end 69.00799 -47.574454)
		(width 0.08382)
		(layer "In9.Cu")
		(net "M_BMC_DDR4_DQ<7>")
	)
	(arc
		(start 77.57795 -47.360586)
		(mid 77.707266 -47.307022)
		(end 77.76083 -47.177706)
		(width 0.08382)
		(layer "In9.Cu")
		(net "M_BMC_DDR4_DQ<7>")
	)
	(arc
		(start 76.488798 -47.827184)
		(mid 76.463504 -47.88825)
		(end 76.402438 -47.913544)
		(width 0.08382)
		(layer "In9.Cu")
		(net "M_BMC_DDR4_DQ<7>")
	)
	(arc
		(start 70.416928 -46.72711)
		(mid 70.383797 -46.733718)
		(end 70.355714 -46.75251)
		(width 0.08382)
		(layer "In9.Cu")
		(net "M_BMC_DDR4_DQ<7>")
	)
	(arc
		(start 72.188578 -46.040548)
		(mid 72.08262 -46.09343)
		(end 71.970138 -46.130464)
		(width 0.08382)
		(layer "In9.Cu")
		(net "M_BMC_DDR4_DQ<7>")
	)
	(arc
		(start 77.493368 -48.728376)
		(mid 77.468074 -48.789442)
		(end 77.407008 -48.814736)
		(width 0.08382)
		(layer "In9.Cu")
		(net "M_BMC_DDR4_DQ<7>")
	)
	(arc
		(start 71.66102 -46.245018)
		(mid 71.623914 -46.267582)
		(end 71.590916 -46.295818)
		(width 0.08382)
		(layer "In9.Cu")
		(net "M_BMC_DDR4_DQ<7>")
	)
	(arc
		(start 72.547988 -45.931074)
		(mid 72.504639 -45.932962)
		(end 72.461628 -45.938694)
		(width 0.08382)
		(layer "In9.Cu")
		(net "M_BMC_DDR4_DQ<7>")
	)
	(arc
		(start 71.076312 -46.714156)
		(mid 71.034008 -46.723915)
		(end 70.990714 -46.72711)
		(width 0.08382)
		(layer "In9.Cu")
		(net "M_BMC_DDR4_DQ<7>")
	)
	(arc
		(start 64.102996 -48.516286)
		(mid 64.050277 -48.726129)
		(end 63.904622 -48.88611)
		(width 0.08382)
		(layer "In9.Cu")
		(net "M_BMC_DDR4_DQ<7>")
	)
	(arc
		(start 63.869824 -48.909224)
		(mid 63.832117 -48.930679)
		(end 63.791846 -48.946816)
		(width 0.08382)
		(layer "In9.Cu")
		(net "M_BMC_DDR4_DQ<7>")
	)
	(arc
		(start 73.063862 -46.282356)
		(mid 73.003584 -46.083888)
		(end 72.843136 -45.95241)
		(width 0.08382)
		(layer "In9.Cu")
		(net "M_BMC_DDR4_DQ<7>")
	)
	(arc
		(start 68.911216 -48.2727)
		(mid 68.875556 -48.296527)
		(end 68.833492 -48.304958)
		(width 0.08382)
		(layer "In9.Cu")
		(net "M_BMC_DDR4_DQ<7>")
	)
	(arc
		(start 77.59954 -47.88916)
		(mid 77.524465 -47.920257)
		(end 77.493368 -47.995332)
		(width 0.08382)
		(layer "In9.Cu")
		(net "M_BMC_DDR4_DQ<7>")
	)
	(arc
		(start 66.097912 -48.276002)
		(mid 66.072618 -48.214936)
		(end 66.011552 -48.189642)
		(width 0.08382)
		(layer "In9.Cu")
		(net "M_BMC_DDR4_DQ<7>")
	)
	(arc
		(start 71.321168 -46.565566)
		(mid 71.207695 -46.654616)
		(end 71.076312 -46.714156)
		(width 0.08382)
		(layer "In9.Cu")
		(net "M_BMC_DDR4_DQ<7>")
	)
	(arc
		(start 67.61988 -48.671988)
		(mid 67.469029 -48.741422)
		(end 67.304666 -48.765206)
		(width 0.08382)
		(layer "In9.Cu")
		(net "M_BMC_DDR4_DQ<7>")
	)
	(arc
		(start 64.360806 -48.189642)
		(mid 64.178507 -48.265153)
		(end 64.102996 -48.447452)
		(width 0.08382)
		(layer "In9.Cu")
		(net "M_BMC_DDR4_DQ<7>")
	)
	(arc
		(start 77.169772 -46.893226)
		(mid 77.084624 -46.857799)
		(end 77.049376 -46.772576)
		(width 0.08382)
		(layer "In9.Cu")
		(net "M_BMC_DDR4_DQ<7>")
	)
	(arc
		(start 77.049376 -46.65218)
		(mid 77.024082 -46.591114)
		(end 76.963016 -46.56582)
		(width 0.08382)
		(layer "In9.Cu")
		(net "M_BMC_DDR4_DQ<7>")
	)
	(arc
		(start 77.76083 -47.076106)
		(mid 77.707266 -46.94679)
		(end 77.57795 -46.893226)
		(width 0.08382)
		(layer "In9.Cu")
		(net "M_BMC_DDR4_DQ<7>")
	)
	(arc
		(start 63.791846 -48.946816)
		(mid 63.71833 -49.000455)
		(end 63.690246 -49.087024)
		(width 0.08382)
		(layer "In9.Cu")
		(net "M_BMC_DDR4_DQ<7>")
	)
	(arc
		(start 69.395594 -47.186596)
		(mid 69.329046 -47.159031)
		(end 69.262498 -47.186596)
		(width 0.08382)
		(layer "In9.Cu")
		(net "M_BMC_DDR4_DQ<7>")
	)
	(arc
		(start 72.461628 -45.938694)
		(mid 72.320535 -45.977375)
		(end 72.188578 -46.040548)
		(width 0.08382)
		(layer "In9.Cu")
		(net "M_BMC_DDR4_DQ<7>")
	)
	(arc
		(start 76.582778 -46.56582)
		(mid 76.516324 -46.593346)
		(end 76.488798 -46.6598)
		(width 0.08382)
		(layer "In9.Cu")
		(net "M_BMC_DDR4_DQ<7>")
	)
	(arc
		(start 76.544932 -48.814736)
		(mid 76.454411 -48.777241)
		(end 76.416916 -48.68672)
		(width 0.08382)
		(layer "In9.Cu")
		(net "M_BMC_DDR4_DQ<7>")
	)
	(arc
		(start 76.416916 -48.436276)
		(mid 76.44221 -48.37521)
		(end 76.503276 -48.349916)
		(width 0.08382)
		(layer "In9.Cu")
		(net "M_BMC_DDR4_DQ<7>")
	)
	(arc
		(start 71.970138 -46.130464)
		(mid 71.812494 -46.179419)
		(end 71.66102 -46.245018)
		(width 0.08382)
		(layer "In9.Cu")
		(net "M_BMC_DDR4_DQ<7>")
	)
	(arc
		(start 77.049376 -47.543466)
		(mid 77.10294 -47.41415)
		(end 77.232256 -47.360586)
		(width 0.08382)
		(layer "In9.Cu")
		(net "M_BMC_DDR4_DQ<7>")
	)
	(arc
		(start 75.94854 -46.678596)
		(mid 75.921014 -46.612142)
		(end 75.85456 -46.584616)
		(width 0.08382)
		(layer "In9.Cu")
		(net "M_BMC_DDR4_DQ<7>")
	)
	(arc
		(start 75.5396 -46.584616)
		(mid 75.481634 -46.604423)
		(end 75.44816 -46.655736)
		(width 0.08382)
		(layer "In9.Cu")
		(net "M_BMC_DDR4_DQ<7>")
	)
	(arc
		(start 68.074032 -48.304958)
		(mid 68.005033 -48.318701)
		(end 67.946524 -48.35779)
		(width 0.08382)
		(layer "In9.Cu")
		(net "M_BMC_DDR4_DQ<7>")
	)
	(arc
		(start 76.963016 -48.349916)
		(mid 77.024082 -48.324622)
		(end 77.049376 -48.263556)
		(width 0.08382)
		(layer "In9.Cu")
		(net "M_BMC_DDR4_DQ<7>")
	)
	(arc
		(start 66.184272 -48.765206)
		(mid 66.123206 -48.739912)
		(end 66.097912 -48.678846)
		(width 0.08382)
		(layer "In9.Cu")
		(net "M_BMC_DDR4_DQ<7>")
	)
	(arc
		(start 75.44816 -46.655736)
		(mid 75.414863 -46.707122)
		(end 75.356974 -46.72711)
		(width 0.08382)
		(layer "In9.Cu")
		(net "M_BMC_DDR4_DQ<7>")
	)
	(arc
		(start 73.150222 -46.72711)
		(mid 73.089156 -46.701816)
		(end 73.063862 -46.64075)
		(width 0.08382)
		(layer "In9.Cu")
		(net "M_BMC_DDR4_DQ<7>")
	)
	(segment
		(start 64.094868 -49.7713)
		(end 64.490092 -50.166524)
		(width 0.11684)
		(layer "F.Cu")
		(net "M_BMC_DDR4_DQ<6>")
	)
	(segment
		(start 74.652378 -47.507398)
		(end 74.270616 -47.125636)
		(width 0.11684)
		(layer "F.Cu")
		(net "M_BMC_DDR4_DQ<6>")
	)
	(via
		(at 74.270616 -47.125636)
		(size 0.4572)
		(drill 0.254)
		(layers "F.Cu" "B.Cu")
		(net "M_BMC_DDR4_DQ<6>")
	)
	(via
		(at 64.490092 -50.166524)
		(size 0.4572)
		(drill 0.254)
		(layers "F.Cu" "B.Cu")
		(net "M_BMC_DDR4_DQ<6>")
	)
	(segment
		(start 72.275446 -47.52086)
		(end 72.275446 -46.741588)
		(width 0.08382)
		(layer "In9.Cu")
		(net "M_BMC_DDR4_DQ<6>")
	)
	(segment
		(start 70.141084 -47.579026)
		(end 70.779894 -48.217836)
		(width 0.08382)
		(layer "In9.Cu")
		(net "M_BMC_DDR4_DQ<6>")
	)
	(segment
		(start 74.270616 -47.125636)
		(end 74.489056 -47.125636)
		(width 0.08382)
		(layer "In9.Cu")
		(net "M_BMC_DDR4_DQ<6>")
	)
	(segment
		(start 71.687182 -47.96409)
		(end 71.313802 -47.96409)
		(width 0.08382)
		(layer "In9.Cu")
		(net "M_BMC_DDR4_DQ<6>")
	)
	(segment
		(start 66.330576 -49.24679)
		(end 66.330576 -49.620424)
		(width 0.08382)
		(layer "In9.Cu")
		(net "M_BMC_DDR4_DQ<6>")
	)
	(segment
		(start 67.96405 -49.16043)
		(end 66.416936 -49.16043)
		(width 0.08382)
		(layer "In9.Cu")
		(net "M_BMC_DDR4_DQ<6>")
	)
	(segment
		(start 64.671448 -49.752758)
		(end 64.671448 -49.039018)
		(width 0.08382)
		(layer "In9.Cu")
		(net "M_BMC_DDR4_DQ<6>")
	)
	(segment
		(start 67.848734 -49.793144)
		(end 67.848734 -50.168302)
		(width 0.08382)
		(layer "In9.Cu")
		(net "M_BMC_DDR4_DQ<6>")
	)
	(segment
		(start 68.091812 -49.08931)
		(end 68.091812 -49.089564)
		(width 0.08382)
		(layer "In9.Cu")
		(net "M_BMC_DDR4_DQ<6>")
	)
	(segment
		(start 69.386704 -48.410114)
		(end 69.768466 -48.791876)
		(width 0.08382)
		(layer "In9.Cu")
		(net "M_BMC_DDR4_DQ<6>")
	)
	(segment
		(start 65.70218 -49.734724)
		(end 65.70218 -49.0474)
		(width 0.08382)
		(layer "In9.Cu")
		(net "M_BMC_DDR4_DQ<6>")
	)
	(segment
		(start 69.645784 -48.028606)
		(end 69.386704 -48.287686)
		(width 0.08382)
		(layer "In9.Cu")
		(net "M_BMC_DDR4_DQ<6>")
	)
	(segment
		(start 74.46391 -47.60722)
		(end 72.361806 -47.60722)
		(width 0.08382)
		(layer "In9.Cu")
		(net "M_BMC_DDR4_DQ<6>")
	)
	(segment
		(start 64.22136 -50.166524)
		(end 64.490092 -50.166524)
		(width 0.08382)
		(layer "In9.Cu")
		(net "M_BMC_DDR4_DQ<6>")
	)
	(segment
		(start 67.762374 -50.254662)
		(end 66.282316 -50.254662)
		(width 0.08382)
		(layer "In9.Cu")
		(net "M_BMC_DDR4_DQ<6>")
	)
	(segment
		(start 69.768466 -48.942498)
		(end 69.66077 -49.050194)
		(width 0.08382)
		(layer "In9.Cu")
		(net "M_BMC_DDR4_DQ<6>")
	)
	(segment
		(start 66.069972 -50.166778)
		(end 65.747646 -49.844452)
		(width 0.08382)
		(layer "In9.Cu")
		(net "M_BMC_DDR4_DQ<6>")
	)
	(segment
		(start 71.773542 -46.741588)
		(end 71.773542 -47.87773)
		(width 0.08382)
		(layer "In9.Cu")
		(net "M_BMC_DDR4_DQ<6>")
	)
	(segment
		(start 72.189086 -46.655228)
		(end 71.859902 -46.655228)
		(width 0.08382)
		(layer "In9.Cu")
		(net "M_BMC_DDR4_DQ<6>")
	)
	(segment
		(start 74.613262 -47.249842)
		(end 74.613262 -47.457868)
		(width 0.08382)
		(layer "In9.Cu")
		(net "M_BMC_DDR4_DQ<6>")
	)
	(segment
		(start 70.779894 -48.43526)
		(end 70.542658 -48.672496)
		(width 0.08382)
		(layer "In9.Cu")
		(net "M_BMC_DDR4_DQ<6>")
	)
	(segment
		(start 69.48678 -49.122838)
		(end 68.81241 -49.122838)
		(width 0.08382)
		(layer "In9.Cu")
		(net "M_BMC_DDR4_DQ<6>")
	)
	(segment
		(start 65.072006 -49.846738)
		(end 64.765428 -49.846738)
		(width 0.08382)
		(layer "In9.Cu")
		(net "M_BMC_DDR4_DQ<6>")
	)
	(segment
		(start 68.67144 -48.981868)
		(end 68.67144 -48.73752)
		(width 0.08382)
		(layer "In9.Cu")
		(net "M_BMC_DDR4_DQ<6>")
	)
	(segment
		(start 68.104766 -48.73752)
		(end 68.104766 -49.043336)
		(width 0.08382)
		(layer "In9.Cu")
		(net "M_BMC_DDR4_DQ<6>")
	)
	(segment
		(start 66.416936 -49.706784)
		(end 67.762374 -49.706784)
		(width 0.08382)
		(layer "In9.Cu")
		(net "M_BMC_DDR4_DQ<6>")
	)
	(segment
		(start 71.133462 -47.076868)
		(end 70.571106 -47.076868)
		(width 0.08382)
		(layer "In9.Cu")
		(net "M_BMC_DDR4_DQ<6>")
	)
	(segment
		(start 68.58508 -48.65116)
		(end 68.191126 -48.65116)
		(width 0.08382)
		(layer "In9.Cu")
		(net "M_BMC_DDR4_DQ<6>")
	)
	(segment
		(start 70.42023 -48.672496)
		(end 69.77634 -48.028606)
		(width 0.08382)
		(layer "In9.Cu")
		(net "M_BMC_DDR4_DQ<6>")
	)
	(segment
		(start 65.165986 -49.0474)
		(end 65.165986 -49.752758)
		(width 0.08382)
		(layer "In9.Cu")
		(net "M_BMC_DDR4_DQ<6>")
	)
	(segment
		(start 64.135 -49.039018)
		(end 64.135 -50.080164)
		(width 0.08382)
		(layer "In9.Cu")
		(net "M_BMC_DDR4_DQ<6>")
	)
	(segment
		(start 71.227442 -47.87773)
		(end 71.227442 -47.170848)
		(width 0.08382)
		(layer "In9.Cu")
		(net "M_BMC_DDR4_DQ<6>")
	)
	(segment
		(start 70.485254 -47.112428)
		(end 70.141084 -47.456598)
		(width 0.08382)
		(layer "In9.Cu")
		(net "M_BMC_DDR4_DQ<6>")
	)
	(segment
		(start 64.585088 -48.952658)
		(end 64.22136 -48.952658)
		(width 0.08382)
		(layer "In9.Cu")
		(net "M_BMC_DDR4_DQ<6>")
	)
	(segment
		(start 65.61582 -48.96104)
		(end 65.252346 -48.96104)
		(width 0.08382)
		(layer "In9.Cu")
		(net "M_BMC_DDR4_DQ<6>")
	)
	(arc
		(start 71.227442 -47.170848)
		(mid 71.199916 -47.104394)
		(end 71.133462 -47.076868)
		(width 0.08382)
		(layer "In9.Cu")
		(net "M_BMC_DDR4_DQ<6>")
	)
	(arc
		(start 71.773542 -47.87773)
		(mid 71.748248 -47.938796)
		(end 71.687182 -47.96409)
		(width 0.08382)
		(layer "In9.Cu")
		(net "M_BMC_DDR4_DQ<6>")
	)
	(arc
		(start 68.67144 -48.73752)
		(mid 68.646146 -48.676454)
		(end 68.58508 -48.65116)
		(width 0.08382)
		(layer "In9.Cu")
		(net "M_BMC_DDR4_DQ<6>")
	)
	(arc
		(start 69.768466 -48.791876)
		(mid 69.799788 -48.867224)
		(end 69.768466 -48.942498)
		(width 0.08382)
		(layer "In9.Cu")
		(net "M_BMC_DDR4_DQ<6>")
	)
	(arc
		(start 68.104766 -49.043336)
		(mid 68.101547 -49.067245)
		(end 68.091812 -49.08931)
		(width 0.08382)
		(layer "In9.Cu")
		(net "M_BMC_DDR4_DQ<6>")
	)
	(arc
		(start 69.66077 -49.050194)
		(mid 69.581058 -49.103965)
		(end 69.48678 -49.122838)
		(width 0.08382)
		(layer "In9.Cu")
		(net "M_BMC_DDR4_DQ<6>")
	)
	(arc
		(start 68.191126 -48.65116)
		(mid 68.13006 -48.676454)
		(end 68.104766 -48.73752)
		(width 0.08382)
		(layer "In9.Cu")
		(net "M_BMC_DDR4_DQ<6>")
	)
	(arc
		(start 71.313802 -47.96409)
		(mid 71.252736 -47.938796)
		(end 71.227442 -47.87773)
		(width 0.08382)
		(layer "In9.Cu")
		(net "M_BMC_DDR4_DQ<6>")
	)
	(arc
		(start 70.779894 -48.217836)
		(mid 70.824924 -48.326548)
		(end 70.779894 -48.43526)
		(width 0.08382)
		(layer "In9.Cu")
		(net "M_BMC_DDR4_DQ<6>")
	)
	(arc
		(start 65.252346 -48.96104)
		(mid 65.19128 -48.986334)
		(end 65.165986 -49.0474)
		(width 0.08382)
		(layer "In9.Cu")
		(net "M_BMC_DDR4_DQ<6>")
	)
	(arc
		(start 66.416936 -49.16043)
		(mid 66.35587 -49.185724)
		(end 66.330576 -49.24679)
		(width 0.08382)
		(layer "In9.Cu")
		(net "M_BMC_DDR4_DQ<6>")
	)
	(arc
		(start 66.282316 -50.254662)
		(mid 66.167409 -50.231824)
		(end 66.069972 -50.166778)
		(width 0.08382)
		(layer "In9.Cu")
		(net "M_BMC_DDR4_DQ<6>")
	)
	(arc
		(start 68.091812 -49.089564)
		(mid 68.037098 -49.141521)
		(end 67.96405 -49.16043)
		(width 0.08382)
		(layer "In9.Cu")
		(net "M_BMC_DDR4_DQ<6>")
	)
	(arc
		(start 72.275446 -46.741588)
		(mid 72.250152 -46.680522)
		(end 72.189086 -46.655228)
		(width 0.08382)
		(layer "In9.Cu")
		(net "M_BMC_DDR4_DQ<6>")
	)
	(arc
		(start 64.22136 -48.952658)
		(mid 64.160294 -48.977952)
		(end 64.135 -49.039018)
		(width 0.08382)
		(layer "In9.Cu")
		(net "M_BMC_DDR4_DQ<6>")
	)
	(arc
		(start 69.77634 -48.028606)
		(mid 69.711062 -48.001567)
		(end 69.645784 -48.028606)
		(width 0.08382)
		(layer "In9.Cu")
		(net "M_BMC_DDR4_DQ<6>")
	)
	(arc
		(start 64.671448 -49.039018)
		(mid 64.646154 -48.977952)
		(end 64.585088 -48.952658)
		(width 0.08382)
		(layer "In9.Cu")
		(net "M_BMC_DDR4_DQ<6>")
	)
	(arc
		(start 74.489056 -47.125636)
		(mid 74.576883 -47.162015)
		(end 74.613262 -47.249842)
		(width 0.08382)
		(layer "In9.Cu")
		(net "M_BMC_DDR4_DQ<6>")
	)
	(arc
		(start 64.765428 -49.846738)
		(mid 64.698974 -49.819212)
		(end 64.671448 -49.752758)
		(width 0.08382)
		(layer "In9.Cu")
		(net "M_BMC_DDR4_DQ<6>")
	)
	(arc
		(start 69.386704 -48.287686)
		(mid 69.361348 -48.3489)
		(end 69.386704 -48.410114)
		(width 0.08382)
		(layer "In9.Cu")
		(net "M_BMC_DDR4_DQ<6>")
	)
	(arc
		(start 72.361806 -47.60722)
		(mid 72.30074 -47.581926)
		(end 72.275446 -47.52086)
		(width 0.08382)
		(layer "In9.Cu")
		(net "M_BMC_DDR4_DQ<6>")
	)
	(arc
		(start 70.141084 -47.456598)
		(mid 70.115728 -47.517812)
		(end 70.141084 -47.579026)
		(width 0.08382)
		(layer "In9.Cu")
		(net "M_BMC_DDR4_DQ<6>")
	)
	(arc
		(start 65.165986 -49.752758)
		(mid 65.13846 -49.819212)
		(end 65.072006 -49.846738)
		(width 0.08382)
		(layer "In9.Cu")
		(net "M_BMC_DDR4_DQ<6>")
	)
	(arc
		(start 67.848734 -50.168302)
		(mid 67.82344 -50.229368)
		(end 67.762374 -50.254662)
		(width 0.08382)
		(layer "In9.Cu")
		(net "M_BMC_DDR4_DQ<6>")
	)
	(arc
		(start 65.747646 -49.844452)
		(mid 65.714007 -49.794108)
		(end 65.70218 -49.734724)
		(width 0.08382)
		(layer "In9.Cu")
		(net "M_BMC_DDR4_DQ<6>")
	)
	(arc
		(start 64.135 -50.080164)
		(mid 64.160294 -50.14123)
		(end 64.22136 -50.166524)
		(width 0.08382)
		(layer "In9.Cu")
		(net "M_BMC_DDR4_DQ<6>")
	)
	(arc
		(start 71.859902 -46.655228)
		(mid 71.798836 -46.680522)
		(end 71.773542 -46.741588)
		(width 0.08382)
		(layer "In9.Cu")
		(net "M_BMC_DDR4_DQ<6>")
	)
	(arc
		(start 70.571106 -47.076868)
		(mid 70.524644 -47.08611)
		(end 70.485254 -47.112428)
		(width 0.08382)
		(layer "In9.Cu")
		(net "M_BMC_DDR4_DQ<6>")
	)
	(arc
		(start 68.81241 -49.122838)
		(mid 68.712729 -49.081549)
		(end 68.67144 -48.981868)
		(width 0.08382)
		(layer "In9.Cu")
		(net "M_BMC_DDR4_DQ<6>")
	)
	(arc
		(start 65.70218 -49.0474)
		(mid 65.676886 -48.986334)
		(end 65.61582 -48.96104)
		(width 0.08382)
		(layer "In9.Cu")
		(net "M_BMC_DDR4_DQ<6>")
	)
	(arc
		(start 74.613262 -47.457868)
		(mid 74.569518 -47.563476)
		(end 74.46391 -47.60722)
		(width 0.08382)
		(layer "In9.Cu")
		(net "M_BMC_DDR4_DQ<6>")
	)
	(arc
		(start 67.762374 -49.706784)
		(mid 67.82344 -49.732078)
		(end 67.848734 -49.793144)
		(width 0.08382)
		(layer "In9.Cu")
		(net "M_BMC_DDR4_DQ<6>")
	)
	(arc
		(start 70.542658 -48.672496)
		(mid 70.481444 -48.697852)
		(end 70.42023 -48.672496)
		(width 0.08382)
		(layer "In9.Cu")
		(net "M_BMC_DDR4_DQ<6>")
	)
	(arc
		(start 66.330576 -49.620424)
		(mid 66.35587 -49.68149)
		(end 66.416936 -49.706784)
		(width 0.08382)
		(layer "In9.Cu")
		(net "M_BMC_DDR4_DQ<6>")
	)
	(segment
		(start 64.894968 -49.7713)
		(end 65.290192 -50.166524)
		(width 0.11684)
		(layer "F.Cu")
		(net "M_BMC_DDR4_DQ<5>")
	)
	(segment
		(start 78.65237 -48.307498)
		(end 79.034132 -48.68926)
		(width 0.11684)
		(layer "F.Cu")
		(net "M_BMC_DDR4_DQ<5>")
	)
	(via
		(at 79.034132 -48.68926)
		(size 0.4572)
		(drill 0.254)
		(layers "F.Cu" "B.Cu")
		(net "M_BMC_DDR4_DQ<5>")
	)
	(via
		(at 65.290192 -50.166524)
		(size 0.4572)
		(drill 0.254)
		(layers "F.Cu" "B.Cu")
		(net "M_BMC_DDR4_DQ<5>")
	)
	(segment
		(start 65.290192 -50.166524)
		(end 65.516506 -50.166524)
		(width 0.08382)
		(layer "In9.Cu")
		(net "M_BMC_DDR4_DQ<5>")
	)
	(segment
		(start 75.7936 -48.295814)
		(end 75.7936 -49.046892)
		(width 0.08382)
		(layer "In9.Cu")
		(net "M_BMC_DDR4_DQ<5>")
	)
	(segment
		(start 70.07479 -49.342294)
		(end 70.07479 -49.133252)
		(width 0.08382)
		(layer "In9.Cu")
		(net "M_BMC_DDR4_DQ<5>")
	)
	(segment
		(start 68.200778 -50.528474)
		(end 68.200778 -49.5554)
		(width 0.08382)
		(layer "In9.Cu")
		(net "M_BMC_DDR4_DQ<5>")
	)
	(segment
		(start 77.069696 -49.308004)
		(end 77.069696 -49.477168)
		(width 0.08382)
		(layer "In9.Cu")
		(net "M_BMC_DDR4_DQ<5>")
	)
	(segment
		(start 80.129634 -51.4858)
		(end 79.50454 -51.4858)
		(width 0.08382)
		(layer "In9.Cu")
		(net "M_BMC_DDR4_DQ<5>")
	)
	(segment
		(start 80.215994 -48.37557)
		(end 80.215994 -51.39944)
		(width 0.08382)
		(layer "In9.Cu")
		(net "M_BMC_DDR4_DQ<5>")
	)
	(segment
		(start 75.921108 -49.1744)
		(end 76.936092 -49.1744)
		(width 0.08382)
		(layer "In9.Cu")
		(net "M_BMC_DDR4_DQ<5>")
	)
	(segment
		(start 70.16115 -49.046892)
		(end 70.483476 -49.046892)
		(width 0.08382)
		(layer "In9.Cu")
		(net "M_BMC_DDR4_DQ<5>")
	)
	(segment
		(start 77.84846 -49.477168)
		(end 77.84846 -48.476916)
		(width 0.08382)
		(layer "In9.Cu")
		(net "M_BMC_DDR4_DQ<5>")
	)
	(segment
		(start 77.187298 -49.59477)
		(end 77.730858 -49.59477)
		(width 0.08382)
		(layer "In9.Cu")
		(net "M_BMC_DDR4_DQ<5>")
	)
	(segment
		(start 79.3242 -48.68926)
		(end 79.034132 -48.68926)
		(width 0.08382)
		(layer "In9.Cu")
		(net "M_BMC_DDR4_DQ<5>")
	)
	(segment
		(start 65.59423 -50.198782)
		(end 65.846452 -50.451004)
		(width 0.08382)
		(layer "In9.Cu")
		(net "M_BMC_DDR4_DQ<5>")
	)
	(segment
		(start 79.41818 -51.39944)
		(end 79.41818 -48.78324)
		(width 0.08382)
		(layer "In9.Cu")
		(net "M_BMC_DDR4_DQ<5>")
	)
	(segment
		(start 78.043786 -48.28159)
		(end 80.122014 -48.28159)
		(width 0.08382)
		(layer "In9.Cu")
		(net "M_BMC_DDR4_DQ<5>")
	)
	(segment
		(start 71.40067 -48.34763)
		(end 72.026018 -48.34763)
		(width 0.08382)
		(layer "In9.Cu")
		(net "M_BMC_DDR4_DQ<5>")
	)
	(segment
		(start 68.287138 -49.46904)
		(end 69.948044 -49.46904)
		(width 0.08382)
		(layer "In9.Cu")
		(net "M_BMC_DDR4_DQ<5>")
	)
	(segment
		(start 66.24193 -50.614834)
		(end 68.114418 -50.614834)
		(width 0.08382)
		(layer "In9.Cu")
		(net "M_BMC_DDR4_DQ<5>")
	)
	(segment
		(start 70.794372 -48.918114)
		(end 71.339456 -48.37303)
		(width 0.08382)
		(layer "In9.Cu")
		(net "M_BMC_DDR4_DQ<5>")
	)
	(segment
		(start 72.21728 -47.898558)
		(end 75.396344 -47.898558)
		(width 0.08382)
		(layer "In9.Cu")
		(net "M_BMC_DDR4_DQ<5>")
	)
	(segment
		(start 72.119998 -48.25365)
		(end 72.119998 -47.99584)
		(width 0.08382)
		(layer "In9.Cu")
		(net "M_BMC_DDR4_DQ<5>")
	)
	(arc
		(start 70.483476 -49.046892)
		(mid 70.651732 -49.013424)
		(end 70.794372 -48.918114)
		(width 0.08382)
		(layer "In9.Cu")
		(net "M_BMC_DDR4_DQ<5>")
	)
	(arc
		(start 77.069696 -49.477168)
		(mid 77.104141 -49.560325)
		(end 77.187298 -49.59477)
		(width 0.08382)
		(layer "In9.Cu")
		(net "M_BMC_DDR4_DQ<5>")
	)
	(arc
		(start 71.339456 -48.37303)
		(mid 71.367527 -48.35421)
		(end 71.40067 -48.34763)
		(width 0.08382)
		(layer "In9.Cu")
		(net "M_BMC_DDR4_DQ<5>")
	)
	(arc
		(start 65.846452 -50.451004)
		(mid 66.027913 -50.572189)
		(end 66.24193 -50.614834)
		(width 0.08382)
		(layer "In9.Cu")
		(net "M_BMC_DDR4_DQ<5>")
	)
	(arc
		(start 80.215994 -51.39944)
		(mid 80.1907 -51.460506)
		(end 80.129634 -51.4858)
		(width 0.08382)
		(layer "In9.Cu")
		(net "M_BMC_DDR4_DQ<5>")
	)
	(arc
		(start 79.50454 -51.4858)
		(mid 79.443474 -51.460506)
		(end 79.41818 -51.39944)
		(width 0.08382)
		(layer "In9.Cu")
		(net "M_BMC_DDR4_DQ<5>")
	)
	(arc
		(start 75.7936 -49.046892)
		(mid 75.830946 -49.137054)
		(end 75.921108 -49.1744)
		(width 0.08382)
		(layer "In9.Cu")
		(net "M_BMC_DDR4_DQ<5>")
	)
	(arc
		(start 72.119998 -47.99584)
		(mid 72.148491 -47.927051)
		(end 72.21728 -47.898558)
		(width 0.08382)
		(layer "In9.Cu")
		(net "M_BMC_DDR4_DQ<5>")
	)
	(arc
		(start 70.07479 -49.133252)
		(mid 70.100084 -49.072186)
		(end 70.16115 -49.046892)
		(width 0.08382)
		(layer "In9.Cu")
		(net "M_BMC_DDR4_DQ<5>")
	)
	(arc
		(start 68.200778 -49.5554)
		(mid 68.226072 -49.494334)
		(end 68.287138 -49.46904)
		(width 0.08382)
		(layer "In9.Cu")
		(net "M_BMC_DDR4_DQ<5>")
	)
	(arc
		(start 75.396344 -47.898558)
		(mid 75.677246 -48.014912)
		(end 75.7936 -48.295814)
		(width 0.08382)
		(layer "In9.Cu")
		(net "M_BMC_DDR4_DQ<5>")
	)
	(arc
		(start 68.114418 -50.614834)
		(mid 68.175484 -50.58954)
		(end 68.200778 -50.528474)
		(width 0.08382)
		(layer "In9.Cu")
		(net "M_BMC_DDR4_DQ<5>")
	)
	(arc
		(start 69.948044 -49.46904)
		(mid 70.037667 -49.431917)
		(end 70.07479 -49.342294)
		(width 0.08382)
		(layer "In9.Cu")
		(net "M_BMC_DDR4_DQ<5>")
	)
	(arc
		(start 76.936092 -49.1744)
		(mid 77.030564 -49.213532)
		(end 77.069696 -49.308004)
		(width 0.08382)
		(layer "In9.Cu")
		(net "M_BMC_DDR4_DQ<5>")
	)
	(arc
		(start 79.41818 -48.78324)
		(mid 79.390654 -48.716786)
		(end 79.3242 -48.68926)
		(width 0.08382)
		(layer "In9.Cu")
		(net "M_BMC_DDR4_DQ<5>")
	)
	(arc
		(start 65.516506 -50.166524)
		(mid 65.558594 -50.174896)
		(end 65.59423 -50.198782)
		(width 0.08382)
		(layer "In9.Cu")
		(net "M_BMC_DDR4_DQ<5>")
	)
	(arc
		(start 77.730858 -49.59477)
		(mid 77.814015 -49.560325)
		(end 77.84846 -49.477168)
		(width 0.08382)
		(layer "In9.Cu")
		(net "M_BMC_DDR4_DQ<5>")
	)
	(arc
		(start 77.84846 -48.476916)
		(mid 77.90567 -48.3388)
		(end 78.043786 -48.28159)
		(width 0.08382)
		(layer "In9.Cu")
		(net "M_BMC_DDR4_DQ<5>")
	)
	(arc
		(start 72.026018 -48.34763)
		(mid 72.092472 -48.320104)
		(end 72.119998 -48.25365)
		(width 0.08382)
		(layer "In9.Cu")
		(net "M_BMC_DDR4_DQ<5>")
	)
	(arc
		(start 80.122014 -48.28159)
		(mid 80.188468 -48.309116)
		(end 80.215994 -48.37557)
		(width 0.08382)
		(layer "In9.Cu")
		(net "M_BMC_DDR4_DQ<5>")
	)
	(segment
		(start 70.217284 -49.511966)
		(end 70.217284 -49.25949)
		(width 0.11684)
		(layer "F.Cu")
		(net "M_BMC_DDR4_DQ<4>")
	)
	(segment
		(start 72.247506 -48.911002)
		(end 72.247506 -50.447194)
		(width 0.11684)
		(layer "F.Cu")
		(net "M_BMC_DDR4_DQ<4>")
	)
	(segment
		(start 71.489316 -50.447194)
		(end 71.489316 -49.798224)
		(width 0.11684)
		(layer "F.Cu")
		(net "M_BMC_DDR4_DQ<4>")
	)
	(segment
		(start 71.604378 -47.893478)
		(end 73.347072 -47.893478)
		(width 0.11684)
		(layer "F.Cu")
		(net "M_BMC_DDR4_DQ<4>")
	)
	(segment
		(start 72.133206 -50.561494)
		(end 71.603616 -50.561494)
		(width 0.11684)
		(layer "F.Cu")
		(net "M_BMC_DDR4_DQ<4>")
	)
	(segment
		(start 71.489316 -48.947324)
		(end 71.489316 -48.00854)
		(width 0.11684)
		(layer "F.Cu")
		(net "M_BMC_DDR4_DQ<4>")
	)
	(segment
		(start 64.894968 -50.571146)
		(end 65.290192 -50.96637)
		(width 0.11684)
		(layer "F.Cu")
		(net "M_BMC_DDR4_DQ<4>")
	)
	(segment
		(start 73.502774 -47.957994)
		(end 73.852278 -48.307498)
		(width 0.11684)
		(layer "F.Cu")
		(net "M_BMC_DDR4_DQ<4>")
	)
	(segment
		(start 70.41515 -49.061624)
		(end 71.375016 -49.061624)
		(width 0.11684)
		(layer "F.Cu")
		(net "M_BMC_DDR4_DQ<4>")
	)
	(segment
		(start 71.375016 -49.683924)
		(end 70.389242 -49.683924)
		(width 0.11684)
		(layer "F.Cu")
		(net "M_BMC_DDR4_DQ<4>")
	)
	(segment
		(start 73.470516 -48.68926)
		(end 73.46315 -48.696626)
		(width 0.11684)
		(layer "F.Cu")
		(net "M_BMC_DDR4_DQ<4>")
	)
	(segment
		(start 73.46315 -48.696626)
		(end 72.445626 -48.696626)
		(width 0.11684)
		(layer "F.Cu")
		(net "M_BMC_DDR4_DQ<4>")
	)
	(via
		(at 73.470516 -48.68926)
		(size 0.4572)
		(drill 0.254)
		(layers "F.Cu" "B.Cu")
		(net "M_BMC_DDR4_DQ<4>")
	)
	(via
		(at 65.290192 -50.96637)
		(size 0.4572)
		(drill 0.254)
		(layers "F.Cu" "B.Cu")
		(net "M_BMC_DDR4_DQ<4>")
	)
	(arc
		(start 72.247506 -50.447194)
		(mid 72.214028 -50.528016)
		(end 72.133206 -50.561494)
		(width 0.11684)
		(layer "F.Cu")
		(net "M_BMC_DDR4_DQ<4>")
	)
	(arc
		(start 72.343518 -48.728122)
		(mid 72.272927 -48.807702)
		(end 72.247506 -48.911002)
		(width 0.11684)
		(layer "F.Cu")
		(net "M_BMC_DDR4_DQ<4>")
	)
	(arc
		(start 70.389242 -49.683924)
		(mid 70.267649 -49.633559)
		(end 70.217284 -49.511966)
		(width 0.11684)
		(layer "F.Cu")
		(net "M_BMC_DDR4_DQ<4>")
	)
	(arc
		(start 71.603616 -50.561494)
		(mid 71.522794 -50.528016)
		(end 71.489316 -50.447194)
		(width 0.11684)
		(layer "F.Cu")
		(net "M_BMC_DDR4_DQ<4>")
	)
	(arc
		(start 71.375016 -49.061624)
		(mid 71.455838 -49.028146)
		(end 71.489316 -48.947324)
		(width 0.11684)
		(layer "F.Cu")
		(net "M_BMC_DDR4_DQ<4>")
	)
	(arc
		(start 73.347072 -47.893478)
		(mid 73.431346 -47.910241)
		(end 73.502774 -47.957994)
		(width 0.11684)
		(layer "F.Cu")
		(net "M_BMC_DDR4_DQ<4>")
	)
	(arc
		(start 71.489316 -48.00854)
		(mid 71.523017 -47.927179)
		(end 71.604378 -47.893478)
		(width 0.11684)
		(layer "F.Cu")
		(net "M_BMC_DDR4_DQ<4>")
	)
	(arc
		(start 71.489316 -49.798224)
		(mid 71.455838 -49.717402)
		(end 71.375016 -49.683924)
		(width 0.11684)
		(layer "F.Cu")
		(net "M_BMC_DDR4_DQ<4>")
	)
	(arc
		(start 72.445626 -48.696626)
		(mid 72.39217 -48.704597)
		(end 72.343518 -48.728122)
		(width 0.11684)
		(layer "F.Cu")
		(net "M_BMC_DDR4_DQ<4>")
	)
	(arc
		(start 70.217284 -49.25949)
		(mid 70.275238 -49.119578)
		(end 70.41515 -49.061624)
		(width 0.11684)
		(layer "F.Cu")
		(net "M_BMC_DDR4_DQ<4>")
	)
	(segment
		(start 68.996814 -50.271172)
		(end 68.996814 -51.232816)
		(width 0.08382)
		(layer "In9.Cu")
		(net "M_BMC_DDR4_DQ<4>")
	)
	(segment
		(start 72.207374 -50.375566)
		(end 71.33082 -50.375566)
		(width 0.08382)
		(layer "In9.Cu")
		(net "M_BMC_DDR4_DQ<4>")
	)
	(segment
		(start 71.711566 -49.147476)
		(end 71.711566 -49.605184)
		(width 0.08382)
		(layer "In9.Cu")
		(net "M_BMC_DDR4_DQ<4>")
	)
	(segment
		(start 70.098412 -50.461164)
		(end 70.098412 -51.034442)
		(width 0.08382)
		(layer "In9.Cu")
		(net "M_BMC_DDR4_DQ<4>")
	)
	(segment
		(start 71.24446 -50.289206)
		(end 71.24446 -49.93132)
		(width 0.08382)
		(layer "In9.Cu")
		(net "M_BMC_DDR4_DQ<4>")
	)
	(segment
		(start 64.87668 -51.347878)
		(end 64.87668 -51.05273)
		(width 0.08382)
		(layer "In9.Cu")
		(net "M_BMC_DDR4_DQ<4>")
	)
	(segment
		(start 72.788526 -49.043082)
		(end 72.515222 -49.043336)
		(width 0.08382)
		(layer "In9.Cu")
		(net "M_BMC_DDR4_DQ<4>")
	)
	(segment
		(start 64.96304 -50.96637)
		(end 65.290192 -50.96637)
		(width 0.08382)
		(layer "In9.Cu")
		(net "M_BMC_DDR4_DQ<4>")
	)
	(segment
		(start 69.468492 -50.184812)
		(end 69.083174 -50.184812)
		(width 0.08382)
		(layer "In9.Cu")
		(net "M_BMC_DDR4_DQ<4>")
	)
	(segment
		(start 70.69709 -49.93132)
		(end 70.69709 -50.288444)
		(width 0.08382)
		(layer "In9.Cu")
		(net "M_BMC_DDR4_DQ<4>")
	)
	(segment
		(start 71.797926 -49.691544)
		(end 72.207374 -49.691544)
		(width 0.08382)
		(layer "In9.Cu")
		(net "M_BMC_DDR4_DQ<4>")
	)
	(segment
		(start 68.910454 -51.319176)
		(end 65.612772 -51.319176)
		(width 0.08382)
		(layer "In9.Cu")
		(net "M_BMC_DDR4_DQ<4>")
	)
	(segment
		(start 69.554852 -51.034442)
		(end 69.554852 -50.271172)
		(width 0.08382)
		(layer "In9.Cu")
		(net "M_BMC_DDR4_DQ<4>")
	)
	(segment
		(start 65.367408 -51.434238)
		(end 64.96304 -51.434238)
		(width 0.08382)
		(layer "In9.Cu")
		(net "M_BMC_DDR4_DQ<4>")
	)
	(segment
		(start 70.61073 -50.374804)
		(end 70.184772 -50.374804)
		(width 0.08382)
		(layer "In9.Cu")
		(net "M_BMC_DDR4_DQ<4>")
	)
	(segment
		(start 72.992996 -48.77562)
		(end 72.992996 -48.841914)
		(width 0.08382)
		(layer "In9.Cu")
		(net "M_BMC_DDR4_DQ<4>")
	)
	(segment
		(start 73.470516 -48.68926)
		(end 73.079356 -48.68926)
		(width 0.08382)
		(layer "In9.Cu")
		(net "M_BMC_DDR4_DQ<4>")
	)
	(segment
		(start 71.1581 -49.84496)
		(end 70.78345 -49.84496)
		(width 0.08382)
		(layer "In9.Cu")
		(net "M_BMC_DDR4_DQ<4>")
	)
	(segment
		(start 72.515222 -49.043336)
		(end 71.815706 -49.043336)
		(width 0.08382)
		(layer "In9.Cu")
		(net "M_BMC_DDR4_DQ<4>")
	)
	(segment
		(start 70.012052 -51.120802)
		(end 69.641212 -51.120802)
		(width 0.08382)
		(layer "In9.Cu")
		(net "M_BMC_DDR4_DQ<4>")
	)
	(segment
		(start 72.293734 -49.777904)
		(end 72.293734 -50.289206)
		(width 0.08382)
		(layer "In9.Cu")
		(net "M_BMC_DDR4_DQ<4>")
	)
	(segment
		(start 65.52311 -51.350672)
		(end 65.45707 -51.402996)
		(width 0.08382)
		(layer "In9.Cu")
		(net "M_BMC_DDR4_DQ<4>")
	)
	(arc
		(start 70.78345 -49.84496)
		(mid 70.722384 -49.870254)
		(end 70.69709 -49.93132)
		(width 0.08382)
		(layer "In9.Cu")
		(net "M_BMC_DDR4_DQ<4>")
	)
	(arc
		(start 64.87668 -51.05273)
		(mid 64.901974 -50.991664)
		(end 64.96304 -50.96637)
		(width 0.08382)
		(layer "In9.Cu")
		(net "M_BMC_DDR4_DQ<4>")
	)
	(arc
		(start 68.996814 -51.232816)
		(mid 68.97152 -51.293882)
		(end 68.910454 -51.319176)
		(width 0.08382)
		(layer "In9.Cu")
		(net "M_BMC_DDR4_DQ<4>")
	)
	(arc
		(start 64.96304 -51.434238)
		(mid 64.901974 -51.408944)
		(end 64.87668 -51.347878)
		(width 0.08382)
		(layer "In9.Cu")
		(net "M_BMC_DDR4_DQ<4>")
	)
	(arc
		(start 71.711566 -49.605184)
		(mid 71.73686 -49.66625)
		(end 71.797926 -49.691544)
		(width 0.08382)
		(layer "In9.Cu")
		(net "M_BMC_DDR4_DQ<4>")
	)
	(arc
		(start 72.293734 -50.289206)
		(mid 72.26844 -50.350272)
		(end 72.207374 -50.375566)
		(width 0.08382)
		(layer "In9.Cu")
		(net "M_BMC_DDR4_DQ<4>")
	)
	(arc
		(start 69.083174 -50.184812)
		(mid 69.022108 -50.210106)
		(end 68.996814 -50.271172)
		(width 0.08382)
		(layer "In9.Cu")
		(net "M_BMC_DDR4_DQ<4>")
	)
	(arc
		(start 71.24446 -49.93132)
		(mid 71.219166 -49.870254)
		(end 71.1581 -49.84496)
		(width 0.08382)
		(layer "In9.Cu")
		(net "M_BMC_DDR4_DQ<4>")
	)
	(arc
		(start 65.45707 -51.402996)
		(mid 65.414883 -51.426205)
		(end 65.367408 -51.434238)
		(width 0.08382)
		(layer "In9.Cu")
		(net "M_BMC_DDR4_DQ<4>")
	)
	(arc
		(start 72.207374 -49.691544)
		(mid 72.26844 -49.716838)
		(end 72.293734 -49.777904)
		(width 0.08382)
		(layer "In9.Cu")
		(net "M_BMC_DDR4_DQ<4>")
	)
	(arc
		(start 71.33082 -50.375566)
		(mid 71.269754 -50.350272)
		(end 71.24446 -50.289206)
		(width 0.08382)
		(layer "In9.Cu")
		(net "M_BMC_DDR4_DQ<4>")
	)
	(arc
		(start 69.641212 -51.120802)
		(mid 69.580146 -51.095508)
		(end 69.554852 -51.034442)
		(width 0.08382)
		(layer "In9.Cu")
		(net "M_BMC_DDR4_DQ<4>")
	)
	(arc
		(start 70.184772 -50.374804)
		(mid 70.123706 -50.400098)
		(end 70.098412 -50.461164)
		(width 0.08382)
		(layer "In9.Cu")
		(net "M_BMC_DDR4_DQ<4>")
	)
	(arc
		(start 71.815706 -49.043336)
		(mid 71.742068 -49.073838)
		(end 71.711566 -49.147476)
		(width 0.08382)
		(layer "In9.Cu")
		(net "M_BMC_DDR4_DQ<4>")
	)
	(arc
		(start 72.992996 -48.841914)
		(mid 72.931883 -48.984304)
		(end 72.788526 -49.043082)
		(width 0.08382)
		(layer "In9.Cu")
		(net "M_BMC_DDR4_DQ<4>")
	)
	(arc
		(start 70.69709 -50.288444)
		(mid 70.671796 -50.34951)
		(end 70.61073 -50.374804)
		(width 0.08382)
		(layer "In9.Cu")
		(net "M_BMC_DDR4_DQ<4>")
	)
	(arc
		(start 65.612772 -51.319176)
		(mid 65.565263 -51.327311)
		(end 65.52311 -51.350672)
		(width 0.08382)
		(layer "In9.Cu")
		(net "M_BMC_DDR4_DQ<4>")
	)
	(arc
		(start 69.554852 -50.271172)
		(mid 69.529558 -50.210106)
		(end 69.468492 -50.184812)
		(width 0.08382)
		(layer "In9.Cu")
		(net "M_BMC_DDR4_DQ<4>")
	)
	(arc
		(start 70.098412 -51.034442)
		(mid 70.073118 -51.095508)
		(end 70.012052 -51.120802)
		(width 0.08382)
		(layer "In9.Cu")
		(net "M_BMC_DDR4_DQ<4>")
	)
	(arc
		(start 73.079356 -48.68926)
		(mid 73.01829 -48.714554)
		(end 72.992996 -48.77562)
		(width 0.08382)
		(layer "In9.Cu")
		(net "M_BMC_DDR4_DQ<4>")
	)
	(segment
		(start 77.85227 -48.307498)
		(end 78.234032 -48.68926)
		(width 0.11684)
		(layer "F.Cu")
		(net "M_BMC_DDR4_DQ<3>")
	)
	(segment
		(start 63.295022 -50.571146)
		(end 63.690246 -50.96637)
		(width 0.11684)
		(layer "F.Cu")
		(net "M_BMC_DDR4_DQ<3>")
	)
	(via
		(at 78.234032 -48.68926)
		(size 0.4572)
		(drill 0.254)
		(layers "F.Cu" "B.Cu")
		(net "M_BMC_DDR4_DQ<3>")
	)
	(via
		(at 63.690246 -50.96637)
		(size 0.4572)
		(drill 0.254)
		(layers "F.Cu" "B.Cu")
		(net "M_BMC_DDR4_DQ<3>")
	)
	(segment
		(start 76.157328 -53.738272)
		(end 75.642978 -54.073552)
		(width 0.08382)
		(layer "In9.Cu")
		(net "M_BMC_DDR4_DQ<3>")
	)
	(segment
		(start 71.912226 -55.46344)
		(end 66.02984 -55.46344)
		(width 0.08382)
		(layer "In9.Cu")
		(net "M_BMC_DDR4_DQ<3>")
	)
	(segment
		(start 77.50048 -51.241452)
		(end 77.276198 -51.465734)
		(width 0.08382)
		(layer "In9.Cu")
		(net "M_BMC_DDR4_DQ<3>")
	)
	(segment
		(start 61.63056 -51.178714)
		(end 61.667898 -51.088544)
		(width 0.08382)
		(layer "In9.Cu")
		(net "M_BMC_DDR4_DQ<3>")
	)
	(segment
		(start 78.646782 -49.606454)
		(end 78.646782 -50.271172)
		(width 0.08382)
		(layer "In9.Cu")
		(net "M_BMC_DDR4_DQ<3>")
	)
	(segment
		(start 62.479174 -54.260496)
		(end 62.479174 -54.003194)
		(width 0.08382)
		(layer "In9.Cu")
		(net "M_BMC_DDR4_DQ<3>")
	)
	(segment
		(start 61.52896 -52.313332)
		(end 61.477144 -51.816508)
		(width 0.08382)
		(layer "In9.Cu")
		(net "M_BMC_DDR4_DQ<3>")
	)
	(segment
		(start 63.121032 -50.66157)
		(end 63.227204 -50.767742)
		(width 0.08382)
		(layer "In9.Cu")
		(net "M_BMC_DDR4_DQ<3>")
	)
	(segment
		(start 63.31077 -55.05577)
		(end 63.31077 -54.916324)
		(width 0.08382)
		(layer "In9.Cu")
		(net "M_BMC_DDR4_DQ<3>")
	)
	(segment
		(start 78.519782 -50.577496)
		(end 78.4225 -50.674778)
		(width 0.08382)
		(layer "In9.Cu")
		(net "M_BMC_DDR4_DQ<3>")
	)
	(segment
		(start 62.096904 -50.56632)
		(end 62.891162 -50.56632)
		(width 0.08382)
		(layer "In9.Cu")
		(net "M_BMC_DDR4_DQ<3>")
	)
	(segment
		(start 73.381108 -54.935374)
		(end 72.129142 -55.4228)
		(width 0.08382)
		(layer "In9.Cu")
		(net "M_BMC_DDR4_DQ<3>")
	)
	(segment
		(start 61.811408 -52.958492)
		(end 61.55182 -52.39639)
		(width 0.08382)
		(layer "In9.Cu")
		(net "M_BMC_DDR4_DQ<3>")
	)
	(segment
		(start 62.975998 -54.581552)
		(end 62.80023 -54.581552)
		(width 0.08382)
		(layer "In9.Cu")
		(net "M_BMC_DDR4_DQ<3>")
	)
	(segment
		(start 65.764918 -55.377334)
		(end 65.764664 -55.37708)
		(width 0.08382)
		(layer "In9.Cu")
		(net "M_BMC_DDR4_DQ<3>")
	)
	(segment
		(start 78.234032 -48.68926)
		(end 78.289912 -48.74514)
		(width 0.08382)
		(layer "In9.Cu")
		(net "M_BMC_DDR4_DQ<3>")
	)
	(segment
		(start 63.227204 -50.767742)
		(end 63.690246 -50.96637)
		(width 0.08382)
		(layer "In9.Cu")
		(net "M_BMC_DDR4_DQ<3>")
	)
	(segment
		(start 77.025754 -51.831494)
		(end 76.2127 -53.673248)
		(width 0.08382)
		(layer "In9.Cu")
		(net "M_BMC_DDR4_DQ<3>")
	)
	(segment
		(start 65.71361 -55.36057)
		(end 63.530226 -55.36057)
		(width 0.08382)
		(layer "In9.Cu")
		(net "M_BMC_DDR4_DQ<3>")
	)
	(arc
		(start 78.057248 -50.88128)
		(mid 77.759789 -51.03188)
		(end 77.50048 -51.241452)
		(width 0.08382)
		(layer "In9.Cu")
		(net "M_BMC_DDR4_DQ<3>")
	)
	(arc
		(start 62.390528 -53.789326)
		(mid 62.065928 -53.398333)
		(end 61.811408 -52.958492)
		(width 0.08382)
		(layer "In9.Cu")
		(net "M_BMC_DDR4_DQ<3>")
	)
	(arc
		(start 75.280266 -54.243986)
		(mid 75.068936 -54.328343)
		(end 74.873358 -54.444646)
		(width 0.08382)
		(layer "In9.Cu")
		(net "M_BMC_DDR4_DQ<3>")
	)
	(arc
		(start 75.642978 -54.073552)
		(mid 75.467529 -54.171341)
		(end 75.280266 -54.243986)
		(width 0.08382)
		(layer "In9.Cu")
		(net "M_BMC_DDR4_DQ<3>")
	)
	(arc
		(start 62.479174 -54.003194)
		(mid 62.456131 -53.887441)
		(end 62.390528 -53.789326)
		(width 0.08382)
		(layer "In9.Cu")
		(net "M_BMC_DDR4_DQ<3>")
	)
	(arc
		(start 74.805794 -54.49824)
		(mid 74.775101 -54.522933)
		(end 74.742802 -54.545484)
		(width 0.08382)
		(layer "In9.Cu")
		(net "M_BMC_DDR4_DQ<3>")
	)
	(arc
		(start 65.764664 -55.37708)
		(mid 65.740438 -55.364826)
		(end 65.71361 -55.36057)
		(width 0.08382)
		(layer "In9.Cu")
		(net "M_BMC_DDR4_DQ<3>")
	)
	(arc
		(start 78.646782 -50.271172)
		(mid 78.613714 -50.436944)
		(end 78.519782 -50.577496)
		(width 0.08382)
		(layer "In9.Cu")
		(net "M_BMC_DDR4_DQ<3>")
	)
	(arc
		(start 61.55182 -52.39639)
		(mid 61.536951 -52.355806)
		(end 61.52896 -52.313332)
		(width 0.08382)
		(layer "In9.Cu")
		(net "M_BMC_DDR4_DQ<3>")
	)
	(arc
		(start 63.448184 -55.333138)
		(mid 63.347036 -55.210531)
		(end 63.31077 -55.05577)
		(width 0.08382)
		(layer "In9.Cu")
		(net "M_BMC_DDR4_DQ<3>")
	)
	(arc
		(start 78.349348 -50.73396)
		(mid 78.207118 -50.815195)
		(end 78.057248 -50.88128)
		(width 0.08382)
		(layer "In9.Cu")
		(net "M_BMC_DDR4_DQ<3>")
	)
	(arc
		(start 62.891162 -50.56632)
		(mid 63.015566 -50.591083)
		(end 63.121032 -50.66157)
		(width 0.08382)
		(layer "In9.Cu")
		(net "M_BMC_DDR4_DQ<3>")
	)
	(arc
		(start 78.4225 -50.674778)
		(mid 78.387511 -50.706331)
		(end 78.349348 -50.73396)
		(width 0.08382)
		(layer "In9.Cu")
		(net "M_BMC_DDR4_DQ<3>")
	)
	(arc
		(start 61.477144 -51.816508)
		(mid 61.47518 -51.773152)
		(end 61.478668 -51.729894)
		(width 0.08382)
		(layer "In9.Cu")
		(net "M_BMC_DDR4_DQ<3>")
	)
	(arc
		(start 61.704982 -50.930556)
		(mid 61.829371 -50.671416)
		(end 62.096904 -50.56632)
		(width 0.08382)
		(layer "In9.Cu")
		(net "M_BMC_DDR4_DQ<3>")
	)
	(arc
		(start 72.129142 -55.4228)
		(mid 72.022575 -55.453213)
		(end 71.912226 -55.46344)
		(width 0.08382)
		(layer "In9.Cu")
		(net "M_BMC_DDR4_DQ<3>")
	)
	(arc
		(start 77.276198 -51.465734)
		(mid 77.134023 -51.637006)
		(end 77.025754 -51.831494)
		(width 0.08382)
		(layer "In9.Cu")
		(net "M_BMC_DDR4_DQ<3>")
	)
	(arc
		(start 61.478668 -51.729894)
		(mid 61.537548 -51.4496)
		(end 61.63056 -51.178714)
		(width 0.08382)
		(layer "In9.Cu")
		(net "M_BMC_DDR4_DQ<3>")
	)
	(arc
		(start 63.530226 -55.36057)
		(mid 63.486968 -55.353559)
		(end 63.448184 -55.333138)
		(width 0.08382)
		(layer "In9.Cu")
		(net "M_BMC_DDR4_DQ<3>")
	)
	(arc
		(start 63.31077 -54.916324)
		(mid 63.212718 -54.679604)
		(end 62.975998 -54.581552)
		(width 0.08382)
		(layer "In9.Cu")
		(net "M_BMC_DDR4_DQ<3>")
	)
	(arc
		(start 62.80023 -54.581552)
		(mid 62.573209 -54.487517)
		(end 62.479174 -54.260496)
		(width 0.08382)
		(layer "In9.Cu")
		(net "M_BMC_DDR4_DQ<3>")
	)
	(arc
		(start 78.289912 -48.74514)
		(mid 78.554013 -49.1403)
		(end 78.646782 -49.606454)
		(width 0.08382)
		(layer "In9.Cu")
		(net "M_BMC_DDR4_DQ<3>")
	)
	(arc
		(start 61.667898 -51.088544)
		(mid 61.692865 -51.011057)
		(end 61.704982 -50.930556)
		(width 0.08382)
		(layer "In9.Cu")
		(net "M_BMC_DDR4_DQ<3>")
	)
	(arc
		(start 66.02984 -55.46344)
		(mid 65.890565 -55.441363)
		(end 65.764918 -55.377334)
		(width 0.08382)
		(layer "In9.Cu")
		(net "M_BMC_DDR4_DQ<3>")
	)
	(arc
		(start 76.2127 -53.673248)
		(mid 76.189758 -53.709801)
		(end 76.157328 -53.738272)
		(width 0.08382)
		(layer "In9.Cu")
		(net "M_BMC_DDR4_DQ<3>")
	)
	(arc
		(start 74.178414 -54.713124)
		(mid 73.99982 -54.727964)
		(end 73.826116 -54.772052)
		(width 0.08382)
		(layer "In9.Cu")
		(net "M_BMC_DDR4_DQ<3>")
	)
	(arc
		(start 74.742802 -54.545484)
		(mid 74.472796 -54.670339)
		(end 74.178414 -54.713124)
		(width 0.08382)
		(layer "In9.Cu")
		(net "M_BMC_DDR4_DQ<3>")
	)
	(arc
		(start 74.873358 -54.444646)
		(mid 74.838907 -54.4706)
		(end 74.805794 -54.49824)
		(width 0.08382)
		(layer "In9.Cu")
		(net "M_BMC_DDR4_DQ<3>")
	)
	(arc
		(start 73.826116 -54.772052)
		(mid 73.602821 -54.851558)
		(end 73.381108 -54.935374)
		(width 0.08382)
		(layer "In9.Cu")
		(net "M_BMC_DDR4_DQ<3>")
	)
	(segment
		(start 64.894968 -52.171346)
		(end 65.290192 -52.56657)
		(width 0.11684)
		(layer "F.Cu")
		(net "M_BMC_DDR4_DQ<2>")
	)
	(segment
		(start 76.032868 -47.994062)
		(end 76.032868 -48.987456)
		(width 0.11684)
		(layer "F.Cu")
		(net "M_BMC_DDR4_DQ<2>")
	)
	(segment
		(start 74.416412 -47.879762)
		(end 75.918568 -47.879762)
		(width 0.11684)
		(layer "F.Cu")
		(net "M_BMC_DDR4_DQ<2>")
	)
	(segment
		(start 74.270616 -48.68926)
		(end 74.270616 -48.025558)
		(width 0.11684)
		(layer "F.Cu")
		(net "M_BMC_DDR4_DQ<2>")
	)
	(segment
		(start 75.042776 -48.97501)
		(end 75.042776 -48.455072)
		(width 0.11684)
		(layer "F.Cu")
		(net "M_BMC_DDR4_DQ<2>")
	)
	(segment
		(start 74.895202 -48.307498)
		(end 74.652378 -48.307498)
		(width 0.11684)
		(layer "F.Cu")
		(net "M_BMC_DDR4_DQ<2>")
	)
	(segment
		(start 75.918568 -49.101756)
		(end 75.169522 -49.101756)
		(width 0.11684)
		(layer "F.Cu")
		(net "M_BMC_DDR4_DQ<2>")
	)
	(via
		(at 74.270616 -48.68926)
		(size 0.4572)
		(drill 0.254)
		(layers "F.Cu" "B.Cu")
		(net "M_BMC_DDR4_DQ<2>")
	)
	(via
		(at 65.290192 -52.56657)
		(size 0.4572)
		(drill 0.254)
		(layers "F.Cu" "B.Cu")
		(net "M_BMC_DDR4_DQ<2>")
	)
	(arc
		(start 75.169522 -49.101756)
		(mid 75.079899 -49.064633)
		(end 75.042776 -48.97501)
		(width 0.11684)
		(layer "F.Cu")
		(net "M_BMC_DDR4_DQ<2>")
	)
	(arc
		(start 76.032868 -48.987456)
		(mid 75.99939 -49.068278)
		(end 75.918568 -49.101756)
		(width 0.11684)
		(layer "F.Cu")
		(net "M_BMC_DDR4_DQ<2>")
	)
	(arc
		(start 74.270616 -48.025558)
		(mid 74.313319 -47.922465)
		(end 74.416412 -47.879762)
		(width 0.11684)
		(layer "F.Cu")
		(net "M_BMC_DDR4_DQ<2>")
	)
	(arc
		(start 75.918568 -47.879762)
		(mid 75.99939 -47.91324)
		(end 76.032868 -47.994062)
		(width 0.11684)
		(layer "F.Cu")
		(net "M_BMC_DDR4_DQ<2>")
	)
	(arc
		(start 75.042776 -48.455072)
		(mid 74.999553 -48.350721)
		(end 74.895202 -48.307498)
		(width 0.11684)
		(layer "F.Cu")
		(net "M_BMC_DDR4_DQ<2>")
	)
	(segment
		(start 65.675764 -52.11699)
		(end 65.675764 -53.13807)
		(width 0.08382)
		(layer "In9.Cu")
		(net "M_BMC_DDR4_DQ<2>")
	)
	(segment
		(start 71.259954 -51.080924)
		(end 70.887844 -51.080924)
		(width 0.08382)
		(layer "In9.Cu")
		(net "M_BMC_DDR4_DQ<2>")
	)
	(segment
		(start 65.29197 -52.56657)
		(end 65.290192 -52.56657)
		(width 0.08382)
		(layer "In9.Cu")
		(net "M_BMC_DDR4_DQ<2>")
	)
	(segment
		(start 75.164442 -48.77562)
		(end 75.164442 -48.981614)
		(width 0.08382)
		(layer "In9.Cu")
		(net "M_BMC_DDR4_DQ<2>")
	)
	(segment
		(start 69.172328 -52.03063)
		(end 65.762124 -52.03063)
		(width 0.08382)
		(layer "In9.Cu")
		(net "M_BMC_DDR4_DQ<2>")
	)
	(segment
		(start 65.29197 -53.692806)
		(end 65.29197 -52.56657)
		(width 0.08382)
		(layer "In9.Cu")
		(net "M_BMC_DDR4_DQ<2>")
	)
	(segment
		(start 73.793096 -51.496976)
		(end 72.634348 -51.496976)
		(width 0.08382)
		(layer "In9.Cu")
		(net "M_BMC_DDR4_DQ<2>")
	)
	(segment
		(start 65.738248 -54.01183)
		(end 65.738248 -53.869844)
		(width 0.08382)
		(layer "In9.Cu")
		(net "M_BMC_DDR4_DQ<2>")
	)
	(segment
		(start 73.879456 -49.154334)
		(end 73.879456 -51.410616)
		(width 0.08382)
		(layer "In9.Cu")
		(net "M_BMC_DDR4_DQ<2>")
	)
	(segment
		(start 65.651888 -53.783484)
		(end 65.382648 -53.783484)
		(width 0.08382)
		(layer "In9.Cu")
		(net "M_BMC_DDR4_DQ<2>")
	)
	(segment
		(start 74.270616 -48.68926)
		(end 75.078082 -48.68926)
		(width 0.08382)
		(layer "In9.Cu")
		(net "M_BMC_DDR4_DQ<2>")
	)
	(segment
		(start 66.277744 -54.09819)
		(end 65.824608 -54.09819)
		(width 0.08382)
		(layer "In9.Cu")
		(net "M_BMC_DDR4_DQ<2>")
	)
	(segment
		(start 65.790064 -53.25237)
		(end 66.277744 -53.25237)
		(width 0.08382)
		(layer "In9.Cu")
		(net "M_BMC_DDR4_DQ<2>")
	)
	(segment
		(start 71.346314 -52.036472)
		(end 71.346314 -51.167284)
		(width 0.08382)
		(layer "In9.Cu")
		(net "M_BMC_DDR4_DQ<2>")
	)
	(segment
		(start 70.715124 -51.820318)
		(end 69.5706 -51.820318)
		(width 0.08382)
		(layer "In9.Cu")
		(net "M_BMC_DDR4_DQ<2>")
	)
	(segment
		(start 66.364104 -53.33873)
		(end 66.364104 -54.01183)
		(width 0.08382)
		(layer "In9.Cu")
		(net "M_BMC_DDR4_DQ<2>")
	)
	(segment
		(start 75.078082 -49.067974)
		(end 73.965816 -49.067974)
		(width 0.08382)
		(layer "In9.Cu")
		(net "M_BMC_DDR4_DQ<2>")
	)
	(segment
		(start 72.270874 -51.86045)
		(end 72.270874 -52.026058)
		(width 0.08382)
		(layer "In9.Cu")
		(net "M_BMC_DDR4_DQ<2>")
	)
	(segment
		(start 70.801484 -51.167284)
		(end 70.801484 -51.733958)
		(width 0.08382)
		(layer "In9.Cu")
		(net "M_BMC_DDR4_DQ<2>")
	)
	(segment
		(start 72.1741 -52.122832)
		(end 71.432674 -52.122832)
		(width 0.08382)
		(layer "In9.Cu")
		(net "M_BMC_DDR4_DQ<2>")
	)
	(arc
		(start 73.965816 -49.067974)
		(mid 73.90475 -49.093268)
		(end 73.879456 -49.154334)
		(width 0.08382)
		(layer "In9.Cu")
		(net "M_BMC_DDR4_DQ<2>")
	)
	(arc
		(start 70.887844 -51.080924)
		(mid 70.826778 -51.106218)
		(end 70.801484 -51.167284)
		(width 0.08382)
		(layer "In9.Cu")
		(net "M_BMC_DDR4_DQ<2>")
	)
	(arc
		(start 65.382648 -53.783484)
		(mid 65.318529 -53.756925)
		(end 65.29197 -53.692806)
		(width 0.08382)
		(layer "In9.Cu")
		(net "M_BMC_DDR4_DQ<2>")
	)
	(arc
		(start 65.762124 -52.03063)
		(mid 65.701058 -52.055924)
		(end 65.675764 -52.11699)
		(width 0.08382)
		(layer "In9.Cu")
		(net "M_BMC_DDR4_DQ<2>")
	)
	(arc
		(start 70.801484 -51.733958)
		(mid 70.77619 -51.795024)
		(end 70.715124 -51.820318)
		(width 0.08382)
		(layer "In9.Cu")
		(net "M_BMC_DDR4_DQ<2>")
	)
	(arc
		(start 72.270874 -52.026058)
		(mid 72.24253 -52.094488)
		(end 72.1741 -52.122832)
		(width 0.08382)
		(layer "In9.Cu")
		(net "M_BMC_DDR4_DQ<2>")
	)
	(arc
		(start 75.164442 -48.981614)
		(mid 75.139148 -49.04268)
		(end 75.078082 -49.067974)
		(width 0.08382)
		(layer "In9.Cu")
		(net "M_BMC_DDR4_DQ<2>")
	)
	(arc
		(start 71.432674 -52.122832)
		(mid 71.371608 -52.097538)
		(end 71.346314 -52.036472)
		(width 0.08382)
		(layer "In9.Cu")
		(net "M_BMC_DDR4_DQ<2>")
	)
	(arc
		(start 65.738248 -53.869844)
		(mid 65.712954 -53.808778)
		(end 65.651888 -53.783484)
		(width 0.08382)
		(layer "In9.Cu")
		(net "M_BMC_DDR4_DQ<2>")
	)
	(arc
		(start 72.634348 -51.496976)
		(mid 72.377333 -51.603435)
		(end 72.270874 -51.86045)
		(width 0.08382)
		(layer "In9.Cu")
		(net "M_BMC_DDR4_DQ<2>")
	)
	(arc
		(start 66.277744 -53.25237)
		(mid 66.33881 -53.277664)
		(end 66.364104 -53.33873)
		(width 0.08382)
		(layer "In9.Cu")
		(net "M_BMC_DDR4_DQ<2>")
	)
	(arc
		(start 75.078082 -48.68926)
		(mid 75.139148 -48.714554)
		(end 75.164442 -48.77562)
		(width 0.08382)
		(layer "In9.Cu")
		(net "M_BMC_DDR4_DQ<2>")
	)
	(arc
		(start 66.364104 -54.01183)
		(mid 66.33881 -54.072896)
		(end 66.277744 -54.09819)
		(width 0.08382)
		(layer "In9.Cu")
		(net "M_BMC_DDR4_DQ<2>")
	)
	(arc
		(start 65.824608 -54.09819)
		(mid 65.763542 -54.072896)
		(end 65.738248 -54.01183)
		(width 0.08382)
		(layer "In9.Cu")
		(net "M_BMC_DDR4_DQ<2>")
	)
	(arc
		(start 69.371972 -51.925474)
		(mid 69.285154 -52.002744)
		(end 69.172328 -52.03063)
		(width 0.08382)
		(layer "In9.Cu")
		(net "M_BMC_DDR4_DQ<2>")
	)
	(arc
		(start 69.5706 -51.820318)
		(mid 69.458215 -51.84822)
		(end 69.371972 -51.925474)
		(width 0.08382)
		(layer "In9.Cu")
		(net "M_BMC_DDR4_DQ<2>")
	)
	(arc
		(start 65.675764 -53.13807)
		(mid 65.709242 -53.218892)
		(end 65.790064 -53.25237)
		(width 0.08382)
		(layer "In9.Cu")
		(net "M_BMC_DDR4_DQ<2>")
	)
	(arc
		(start 73.879456 -51.410616)
		(mid 73.854162 -51.471682)
		(end 73.793096 -51.496976)
		(width 0.08382)
		(layer "In9.Cu")
		(net "M_BMC_DDR4_DQ<2>")
	)
	(arc
		(start 71.346314 -51.167284)
		(mid 71.32102 -51.106218)
		(end 71.259954 -51.080924)
		(width 0.08382)
		(layer "In9.Cu")
		(net "M_BMC_DDR4_DQ<2>")
	)
	(segment
		(start 62.494922 -50.571146)
		(end 62.890146 -50.96637)
		(width 0.11684)
		(layer "F.Cu")
		(net "M_BMC_DDR4_DQ<1>")
	)
	(segment
		(start 77.85227 -49.907444)
		(end 77.583538 -49.907444)
		(width 0.11684)
		(layer "F.Cu")
		(net "M_BMC_DDR4_DQ<1>")
	)
	(segment
		(start 77.17917 -50.075084)
		(end 76.115418 -51.138836)
		(width 0.11684)
		(layer "F.Cu")
		(net "M_BMC_DDR4_DQ<1>")
	)
	(via
		(at 62.890146 -50.96637)
		(size 0.4572)
		(drill 0.254)
		(layers "F.Cu" "B.Cu")
		(net "M_BMC_DDR4_DQ<1>")
	)
	(via
		(at 76.115418 -51.138836)
		(size 0.4572)
		(drill 0.254)
		(layers "F.Cu" "B.Cu")
		(net "M_BMC_DDR4_DQ<1>")
	)
	(arc
		(start 77.583538 -49.907444)
		(mid 77.364694 -49.951068)
		(end 77.17917 -50.075084)
		(width 0.11684)
		(layer "F.Cu")
		(net "M_BMC_DDR4_DQ<1>")
	)
	(segment
		(start 62.42431 -53.441346)
		(end 62.726824 -53.74386)
		(width 0.08382)
		(layer "In9.Cu")
		(net "M_BMC_DDR4_DQ<1>")
	)
	(segment
		(start 72.421496 -53.880766)
		(end 75.19543 -53.880766)
		(width 0.08382)
		(layer "In9.Cu")
		(net "M_BMC_DDR4_DQ<1>")
	)
	(segment
		(start 75.458828 -53.617368)
		(end 75.458828 -52.989734)
		(width 0.08382)
		(layer "In9.Cu")
		(net "M_BMC_DDR4_DQ<1>")
	)
	(segment
		(start 72.283066 -54.65826)
		(end 72.283066 -54.019196)
		(width 0.08382)
		(layer "In9.Cu")
		(net "M_BMC_DDR4_DQ<1>")
	)
	(segment
		(start 69.727826 -54.53507)
		(end 69.727826 -54.906926)
		(width 0.08382)
		(layer "In9.Cu")
		(net "M_BMC_DDR4_DQ<1>")
	)
	(segment
		(start 69.184266 -54.906926)
		(end 69.184266 -54.53507)
		(width 0.08382)
		(layer "In9.Cu")
		(net "M_BMC_DDR4_DQ<1>")
	)
	(segment
		(start 75.545188 -51.741578)
		(end 76.542392 -51.741578)
		(width 0.08382)
		(layer "In9.Cu")
		(net "M_BMC_DDR4_DQ<1>")
	)
	(segment
		(start 69.90334 -55.08244)
		(end 71.858886 -55.08244)
		(width 0.08382)
		(layer "In9.Cu")
		(net "M_BMC_DDR4_DQ<1>")
	)
	(segment
		(start 76.226416 -52.359814)
		(end 75.545188 -52.359814)
		(width 0.08382)
		(layer "In9.Cu")
		(net "M_BMC_DDR4_DQ<1>")
	)
	(segment
		(start 63.482728 -54.54523)
		(end 65.78981 -54.54523)
		(width 0.08382)
		(layer "In9.Cu")
		(net "M_BMC_DDR4_DQ<1>")
	)
	(segment
		(start 66.008504 -55.058564)
		(end 69.051932 -55.058564)
		(width 0.08382)
		(layer "In9.Cu")
		(net "M_BMC_DDR4_DQ<1>")
	)
	(segment
		(start 65.87617 -54.63159)
		(end 65.87617 -54.906926)
		(width 0.08382)
		(layer "In9.Cu")
		(net "M_BMC_DDR4_DQ<1>")
	)
	(segment
		(start 76.628752 -51.655218)
		(end 76.628752 -51.225196)
		(width 0.08382)
		(layer "In9.Cu")
		(net "M_BMC_DDR4_DQ<1>")
	)
	(segment
		(start 75.545188 -52.903374)
		(end 76.226416 -52.903374)
		(width 0.08382)
		(layer "In9.Cu")
		(net "M_BMC_DDR4_DQ<1>")
	)
	(segment
		(start 76.542392 -51.138836)
		(end 76.115418 -51.138836)
		(width 0.08382)
		(layer "In9.Cu")
		(net "M_BMC_DDR4_DQ<1>")
	)
	(segment
		(start 69.270626 -54.44871)
		(end 69.641466 -54.44871)
		(width 0.08382)
		(layer "In9.Cu")
		(net "M_BMC_DDR4_DQ<1>")
	)
	(segment
		(start 62.69736 -51.375818)
		(end 62.108334 -51.375818)
		(width 0.08382)
		(layer "In9.Cu")
		(net "M_BMC_DDR4_DQ<1>")
	)
	(segment
		(start 62.804548 -53.776118)
		(end 62.88659 -53.776118)
		(width 0.08382)
		(layer "In9.Cu")
		(net "M_BMC_DDR4_DQ<1>")
	)
	(segment
		(start 62.890146 -50.96637)
		(end 62.890146 -51.183032)
		(width 0.08382)
		(layer "In9.Cu")
		(net "M_BMC_DDR4_DQ<1>")
	)
	(segment
		(start 63.299594 -54.189122)
		(end 63.299594 -54.362096)
		(width 0.08382)
		(layer "In9.Cu")
		(net "M_BMC_DDR4_DQ<1>")
	)
	(segment
		(start 76.312776 -52.817014)
		(end 76.312776 -52.446174)
		(width 0.08382)
		(layer "In9.Cu")
		(net "M_BMC_DDR4_DQ<1>")
	)
	(segment
		(start 75.458828 -52.273454)
		(end 75.458828 -51.827938)
		(width 0.08382)
		(layer "In9.Cu")
		(net "M_BMC_DDR4_DQ<1>")
	)
	(arc
		(start 76.226416 -52.903374)
		(mid 76.287482 -52.87808)
		(end 76.312776 -52.817014)
		(width 0.08382)
		(layer "In9.Cu")
		(net "M_BMC_DDR4_DQ<1>")
	)
	(arc
		(start 75.458828 -52.989734)
		(mid 75.484122 -52.928668)
		(end 75.545188 -52.903374)
		(width 0.08382)
		(layer "In9.Cu")
		(net "M_BMC_DDR4_DQ<1>")
	)
	(arc
		(start 63.299594 -54.362096)
		(mid 63.353233 -54.491591)
		(end 63.482728 -54.54523)
		(width 0.08382)
		(layer "In9.Cu")
		(net "M_BMC_DDR4_DQ<1>")
	)
	(arc
		(start 65.87617 -54.906926)
		(mid 65.889679 -54.972229)
		(end 65.927986 -55.026814)
		(width 0.08382)
		(layer "In9.Cu")
		(net "M_BMC_DDR4_DQ<1>")
	)
	(arc
		(start 62.726824 -53.74386)
		(mid 62.762484 -53.767687)
		(end 62.804548 -53.776118)
		(width 0.08382)
		(layer "In9.Cu")
		(net "M_BMC_DDR4_DQ<1>")
	)
	(arc
		(start 69.727826 -54.906926)
		(mid 69.779233 -55.031033)
		(end 69.90334 -55.08244)
		(width 0.08382)
		(layer "In9.Cu")
		(net "M_BMC_DDR4_DQ<1>")
	)
	(arc
		(start 62.108334 -51.375818)
		(mid 61.853235 -51.469883)
		(end 61.720222 -51.707034)
		(width 0.08382)
		(layer "In9.Cu")
		(net "M_BMC_DDR4_DQ<1>")
	)
	(arc
		(start 76.312776 -52.446174)
		(mid 76.287482 -52.385108)
		(end 76.226416 -52.359814)
		(width 0.08382)
		(layer "In9.Cu")
		(net "M_BMC_DDR4_DQ<1>")
	)
	(arc
		(start 75.545188 -52.359814)
		(mid 75.484122 -52.33452)
		(end 75.458828 -52.273454)
		(width 0.08382)
		(layer "In9.Cu")
		(net "M_BMC_DDR4_DQ<1>")
	)
	(arc
		(start 61.720222 -51.707034)
		(mid 61.716149 -51.750259)
		(end 61.717682 -51.793648)
		(width 0.08382)
		(layer "In9.Cu")
		(net "M_BMC_DDR4_DQ<1>")
	)
	(arc
		(start 69.641466 -54.44871)
		(mid 69.702532 -54.474004)
		(end 69.727826 -54.53507)
		(width 0.08382)
		(layer "In9.Cu")
		(net "M_BMC_DDR4_DQ<1>")
	)
	(arc
		(start 75.19543 -53.880766)
		(mid 75.381681 -53.803619)
		(end 75.458828 -53.617368)
		(width 0.08382)
		(layer "In9.Cu")
		(net "M_BMC_DDR4_DQ<1>")
	)
	(arc
		(start 61.717682 -51.793648)
		(mid 61.927026 -52.63249)
		(end 62.366398 -53.377084)
		(width 0.08382)
		(layer "In9.Cu")
		(net "M_BMC_DDR4_DQ<1>")
	)
	(arc
		(start 75.458828 -51.827938)
		(mid 75.484122 -51.766872)
		(end 75.545188 -51.741578)
		(width 0.08382)
		(layer "In9.Cu")
		(net "M_BMC_DDR4_DQ<1>")
	)
	(arc
		(start 65.927986 -55.026814)
		(mid 65.965211 -55.050381)
		(end 66.008504 -55.058564)
		(width 0.08382)
		(layer "In9.Cu")
		(net "M_BMC_DDR4_DQ<1>")
	)
	(arc
		(start 69.051932 -55.058564)
		(mid 69.095227 -55.050386)
		(end 69.13245 -55.026814)
		(width 0.08382)
		(layer "In9.Cu")
		(net "M_BMC_DDR4_DQ<1>")
	)
	(arc
		(start 62.890146 -51.183032)
		(mid 62.83368 -51.319352)
		(end 62.69736 -51.375818)
		(width 0.08382)
		(layer "In9.Cu")
		(net "M_BMC_DDR4_DQ<1>")
	)
	(arc
		(start 76.542392 -51.741578)
		(mid 76.603458 -51.716284)
		(end 76.628752 -51.655218)
		(width 0.08382)
		(layer "In9.Cu")
		(net "M_BMC_DDR4_DQ<1>")
	)
	(arc
		(start 69.184266 -54.53507)
		(mid 69.20956 -54.474004)
		(end 69.270626 -54.44871)
		(width 0.08382)
		(layer "In9.Cu")
		(net "M_BMC_DDR4_DQ<1>")
	)
	(arc
		(start 62.88659 -53.776118)
		(mid 63.178628 -53.897084)
		(end 63.299594 -54.189122)
		(width 0.08382)
		(layer "In9.Cu")
		(net "M_BMC_DDR4_DQ<1>")
	)
	(arc
		(start 71.858886 -55.08244)
		(mid 72.158827 -54.958201)
		(end 72.283066 -54.65826)
		(width 0.08382)
		(layer "In9.Cu")
		(net "M_BMC_DDR4_DQ<1>")
	)
	(arc
		(start 72.283066 -54.019196)
		(mid 72.323611 -53.921311)
		(end 72.421496 -53.880766)
		(width 0.08382)
		(layer "In9.Cu")
		(net "M_BMC_DDR4_DQ<1>")
	)
	(arc
		(start 69.13245 -55.026814)
		(mid 69.17076 -54.97223)
		(end 69.184266 -54.906926)
		(width 0.08382)
		(layer "In9.Cu")
		(net "M_BMC_DDR4_DQ<1>")
	)
	(arc
		(start 62.366398 -53.377084)
		(mid 62.394486 -53.409997)
		(end 62.42431 -53.441346)
		(width 0.08382)
		(layer "In9.Cu")
		(net "M_BMC_DDR4_DQ<1>")
	)
	(arc
		(start 76.628752 -51.225196)
		(mid 76.603458 -51.16413)
		(end 76.542392 -51.138836)
		(width 0.08382)
		(layer "In9.Cu")
		(net "M_BMC_DDR4_DQ<1>")
	)
	(arc
		(start 65.78981 -54.54523)
		(mid 65.850876 -54.570524)
		(end 65.87617 -54.63159)
		(width 0.08382)
		(layer "In9.Cu")
		(net "M_BMC_DDR4_DQ<1>")
	)
	(segment
		(start 63.295022 -52.171346)
		(end 63.690246 -52.56657)
		(width 0.11684)
		(layer "F.Cu")
		(net "M_BMC_DDR4_DQ<15>")
	)
	(segment
		(start 77.85227 -51.50739)
		(end 77.470508 -51.925728)
		(width 0.11684)
		(layer "F.Cu")
		(net "M_BMC_DDR4_DQ<15>")
	)
	(via
		(at 63.690246 -52.56657)
		(size 0.4572)
		(drill 0.254)
		(layers "F.Cu" "B.Cu")
		(net "M_BMC_DDR4_DQ<15>")
	)
	(via
		(at 77.470508 -51.925728)
		(size 0.4572)
		(drill 0.254)
		(layers "F.Cu" "B.Cu")
		(net "M_BMC_DDR4_DQ<15>")
	)
	(segment
		(start 77.384148 -51.248564)
		(end 77.146404 -51.248564)
		(width 0.08382)
		(layer "In2.Cu")
		(net "M_BMC_DDR4_DQ<15>")
	)
	(segment
		(start 67.405758 -50.523394)
		(end 67.004438 -50.523394)
		(width 0.08382)
		(layer "In2.Cu")
		(net "M_BMC_DDR4_DQ<15>")
	)
	(segment
		(start 75.913234 -50.802032)
		(end 75.142344 -50.802032)
		(width 0.08382)
		(layer "In2.Cu")
		(net "M_BMC_DDR4_DQ<15>")
	)
	(segment
		(start 64.082168 -51.456336)
		(end 64.082168 -51.871372)
		(width 0.08382)
		(layer "In2.Cu")
		(net "M_BMC_DDR4_DQ<15>")
	)
	(segment
		(start 69.881242 -51.443636)
		(end 69.881242 -50.622454)
		(width 0.08382)
		(layer "In2.Cu")
		(net "M_BMC_DDR4_DQ<15>")
	)
	(segment
		(start 69.205602 -51.353212)
		(end 68.764658 -51.353212)
		(width 0.08382)
		(layer "In2.Cu")
		(net "M_BMC_DDR4_DQ<15>")
	)
	(segment
		(start 75.003406 -50.94097)
		(end 75.003406 -51.34229)
		(width 0.08382)
		(layer "In2.Cu")
		(net "M_BMC_DDR4_DQ<15>")
	)
	(segment
		(start 77.470508 -51.925728)
		(end 77.470508 -51.334924)
		(width 0.08382)
		(layer "In2.Cu")
		(net "M_BMC_DDR4_DQ<15>")
	)
	(segment
		(start 72.287638 -52.125626)
		(end 72.287638 -51.89601)
		(width 0.08382)
		(layer "In2.Cu")
		(net "M_BMC_DDR4_DQ<15>")
	)
	(segment
		(start 76.007214 -50.58918)
		(end 76.007214 -50.708052)
		(width 0.08382)
		(layer "In2.Cu")
		(net "M_BMC_DDR4_DQ<15>")
	)
	(segment
		(start 66.816478 -51.362356)
		(end 66.415158 -51.362356)
		(width 0.08382)
		(layer "In2.Cu")
		(net "M_BMC_DDR4_DQ<15>")
	)
	(segment
		(start 67.499738 -51.268376)
		(end 67.499738 -50.617374)
		(width 0.08382)
		(layer "In2.Cu")
		(net "M_BMC_DDR4_DQ<15>")
	)
	(segment
		(start 68.089018 -50.635916)
		(end 68.089018 -51.268376)
		(width 0.08382)
		(layer "In2.Cu")
		(net "M_BMC_DDR4_DQ<15>")
	)
	(segment
		(start 76.510896 -51.951636)
		(end 76.510896 -50.58918)
		(width 0.08382)
		(layer "In2.Cu")
		(net "M_BMC_DDR4_DQ<15>")
	)
	(segment
		(start 63.690246 -52.341526)
		(end 63.690246 -52.56657)
		(width 0.08382)
		(layer "In2.Cu")
		(net "M_BMC_DDR4_DQ<15>")
	)
	(segment
		(start 77.052424 -51.342544)
		(end 77.052424 -51.951636)
		(width 0.08382)
		(layer "In2.Cu")
		(net "M_BMC_DDR4_DQ<15>")
	)
	(segment
		(start 67.995038 -51.362356)
		(end 67.593718 -51.362356)
		(width 0.08382)
		(layer "In2.Cu")
		(net "M_BMC_DDR4_DQ<15>")
	)
	(segment
		(start 74.216768 -51.965098)
		(end 73.926954 -52.254912)
		(width 0.08382)
		(layer "In2.Cu")
		(net "M_BMC_DDR4_DQ<15>")
	)
	(segment
		(start 69.291962 -50.622454)
		(end 69.291962 -51.266852)
		(width 0.08382)
		(layer "In2.Cu")
		(net "M_BMC_DDR4_DQ<15>")
	)
	(segment
		(start 75.777852 -51.925728)
		(end 74.311764 -51.925728)
		(width 0.08382)
		(layer "In2.Cu")
		(net "M_BMC_DDR4_DQ<15>")
	)
	(segment
		(start 65.637918 -51.362356)
		(end 64.176148 -51.362356)
		(width 0.08382)
		(layer "In2.Cu")
		(net "M_BMC_DDR4_DQ<15>")
	)
	(segment
		(start 76.958444 -52.045616)
		(end 76.604876 -52.045616)
		(width 0.08382)
		(layer "In2.Cu")
		(net "M_BMC_DDR4_DQ<15>")
	)
	(segment
		(start 75.921616 -51.53025)
		(end 75.921616 -51.781964)
		(width 0.08382)
		(layer "In2.Cu")
		(net "M_BMC_DDR4_DQ<15>")
	)
	(segment
		(start 71.92391 -51.529996)
		(end 69.967602 -51.529996)
		(width 0.08382)
		(layer "In2.Cu")
		(net "M_BMC_DDR4_DQ<15>")
	)
	(segment
		(start 75.097386 -51.43627)
		(end 75.827636 -51.43627)
		(width 0.08382)
		(layer "In2.Cu")
		(net "M_BMC_DDR4_DQ<15>")
	)
	(segment
		(start 65.731898 -50.627534)
		(end 65.731898 -51.268376)
		(width 0.08382)
		(layer "In2.Cu")
		(net "M_BMC_DDR4_DQ<15>")
	)
	(segment
		(start 66.910458 -50.617374)
		(end 66.910458 -51.268376)
		(width 0.08382)
		(layer "In2.Cu")
		(net "M_BMC_DDR4_DQ<15>")
	)
	(segment
		(start 68.678298 -51.266852)
		(end 68.678298 -50.632614)
		(width 0.08382)
		(layer "In2.Cu")
		(net "M_BMC_DDR4_DQ<15>")
	)
	(segment
		(start 64.054482 -51.938174)
		(end 63.717932 -52.274724)
		(width 0.08382)
		(layer "In2.Cu")
		(net "M_BMC_DDR4_DQ<15>")
	)
	(segment
		(start 76.416916 -50.4952)
		(end 76.101194 -50.4952)
		(width 0.08382)
		(layer "In2.Cu")
		(net "M_BMC_DDR4_DQ<15>")
	)
	(segment
		(start 72.19315 -51.667918)
		(end 72.148192 -51.62296)
		(width 0.08382)
		(layer "In2.Cu")
		(net "M_BMC_DDR4_DQ<15>")
	)
	(segment
		(start 66.227198 -50.533554)
		(end 65.825878 -50.533554)
		(width 0.08382)
		(layer "In2.Cu")
		(net "M_BMC_DDR4_DQ<15>")
	)
	(segment
		(start 69.787262 -50.528474)
		(end 69.385942 -50.528474)
		(width 0.08382)
		(layer "In2.Cu")
		(net "M_BMC_DDR4_DQ<15>")
	)
	(segment
		(start 68.584318 -50.538634)
		(end 68.1863 -50.538634)
		(width 0.08382)
		(layer "In2.Cu")
		(net "M_BMC_DDR4_DQ<15>")
	)
	(segment
		(start 73.860152 -52.282598)
		(end 72.44461 -52.282598)
		(width 0.08382)
		(layer "In2.Cu")
		(net "M_BMC_DDR4_DQ<15>")
	)
	(segment
		(start 66.321178 -51.268376)
		(end 66.321178 -50.627534)
		(width 0.08382)
		(layer "In2.Cu")
		(net "M_BMC_DDR4_DQ<15>")
	)
	(arc
		(start 74.311764 -51.925728)
		(mid 74.260344 -51.935956)
		(end 74.216768 -51.965098)
		(width 0.08382)
		(layer "In2.Cu")
		(net "M_BMC_DDR4_DQ<15>")
	)
	(arc
		(start 69.385942 -50.528474)
		(mid 69.319488 -50.556)
		(end 69.291962 -50.622454)
		(width 0.08382)
		(layer "In2.Cu")
		(net "M_BMC_DDR4_DQ<15>")
	)
	(arc
		(start 76.101194 -50.4952)
		(mid 76.03474 -50.522726)
		(end 76.007214 -50.58918)
		(width 0.08382)
		(layer "In2.Cu")
		(net "M_BMC_DDR4_DQ<15>")
	)
	(arc
		(start 76.604876 -52.045616)
		(mid 76.538422 -52.01809)
		(end 76.510896 -51.951636)
		(width 0.08382)
		(layer "In2.Cu")
		(net "M_BMC_DDR4_DQ<15>")
	)
	(arc
		(start 66.415158 -51.362356)
		(mid 66.348704 -51.33483)
		(end 66.321178 -51.268376)
		(width 0.08382)
		(layer "In2.Cu")
		(net "M_BMC_DDR4_DQ<15>")
	)
	(arc
		(start 76.510896 -50.58918)
		(mid 76.48337 -50.522726)
		(end 76.416916 -50.4952)
		(width 0.08382)
		(layer "In2.Cu")
		(net "M_BMC_DDR4_DQ<15>")
	)
	(arc
		(start 76.007214 -50.708052)
		(mid 75.979688 -50.774506)
		(end 75.913234 -50.802032)
		(width 0.08382)
		(layer "In2.Cu")
		(net "M_BMC_DDR4_DQ<15>")
	)
	(arc
		(start 64.082168 -51.871372)
		(mid 64.074976 -51.907531)
		(end 64.054482 -51.938174)
		(width 0.08382)
		(layer "In2.Cu")
		(net "M_BMC_DDR4_DQ<15>")
	)
	(arc
		(start 77.146404 -51.248564)
		(mid 77.07995 -51.27609)
		(end 77.052424 -51.342544)
		(width 0.08382)
		(layer "In2.Cu")
		(net "M_BMC_DDR4_DQ<15>")
	)
	(arc
		(start 64.176148 -51.362356)
		(mid 64.109694 -51.389882)
		(end 64.082168 -51.456336)
		(width 0.08382)
		(layer "In2.Cu")
		(net "M_BMC_DDR4_DQ<15>")
	)
	(arc
		(start 68.678298 -50.632614)
		(mid 68.650772 -50.56616)
		(end 68.584318 -50.538634)
		(width 0.08382)
		(layer "In2.Cu")
		(net "M_BMC_DDR4_DQ<15>")
	)
	(arc
		(start 68.764658 -51.353212)
		(mid 68.703592 -51.327918)
		(end 68.678298 -51.266852)
		(width 0.08382)
		(layer "In2.Cu")
		(net "M_BMC_DDR4_DQ<15>")
	)
	(arc
		(start 66.321178 -50.627534)
		(mid 66.293652 -50.56108)
		(end 66.227198 -50.533554)
		(width 0.08382)
		(layer "In2.Cu")
		(net "M_BMC_DDR4_DQ<15>")
	)
	(arc
		(start 72.44461 -52.282598)
		(mid 72.333614 -52.236622)
		(end 72.287638 -52.125626)
		(width 0.08382)
		(layer "In2.Cu")
		(net "M_BMC_DDR4_DQ<15>")
	)
	(arc
		(start 68.089018 -51.268376)
		(mid 68.061492 -51.33483)
		(end 67.995038 -51.362356)
		(width 0.08382)
		(layer "In2.Cu")
		(net "M_BMC_DDR4_DQ<15>")
	)
	(arc
		(start 68.1863 -50.538634)
		(mid 68.117511 -50.567127)
		(end 68.089018 -50.635916)
		(width 0.08382)
		(layer "In2.Cu")
		(net "M_BMC_DDR4_DQ<15>")
	)
	(arc
		(start 69.881242 -50.622454)
		(mid 69.853716 -50.556)
		(end 69.787262 -50.528474)
		(width 0.08382)
		(layer "In2.Cu")
		(net "M_BMC_DDR4_DQ<15>")
	)
	(arc
		(start 67.499738 -50.617374)
		(mid 67.472212 -50.55092)
		(end 67.405758 -50.523394)
		(width 0.08382)
		(layer "In2.Cu")
		(net "M_BMC_DDR4_DQ<15>")
	)
	(arc
		(start 72.148192 -51.62296)
		(mid 72.045305 -51.55415)
		(end 71.92391 -51.529996)
		(width 0.08382)
		(layer "In2.Cu")
		(net "M_BMC_DDR4_DQ<15>")
	)
	(arc
		(start 67.593718 -51.362356)
		(mid 67.527264 -51.33483)
		(end 67.499738 -51.268376)
		(width 0.08382)
		(layer "In2.Cu")
		(net "M_BMC_DDR4_DQ<15>")
	)
	(arc
		(start 75.003406 -51.34229)
		(mid 75.030932 -51.408744)
		(end 75.097386 -51.43627)
		(width 0.08382)
		(layer "In2.Cu")
		(net "M_BMC_DDR4_DQ<15>")
	)
	(arc
		(start 75.142344 -50.802032)
		(mid 75.0441 -50.842726)
		(end 75.003406 -50.94097)
		(width 0.08382)
		(layer "In2.Cu")
		(net "M_BMC_DDR4_DQ<15>")
	)
	(arc
		(start 67.004438 -50.523394)
		(mid 66.937984 -50.55092)
		(end 66.910458 -50.617374)
		(width 0.08382)
		(layer "In2.Cu")
		(net "M_BMC_DDR4_DQ<15>")
	)
	(arc
		(start 77.470508 -51.334924)
		(mid 77.445214 -51.273858)
		(end 77.384148 -51.248564)
		(width 0.08382)
		(layer "In2.Cu")
		(net "M_BMC_DDR4_DQ<15>")
	)
	(arc
		(start 63.717932 -52.274724)
		(mid 63.697453 -52.305373)
		(end 63.690246 -52.341526)
		(width 0.08382)
		(layer "In2.Cu")
		(net "M_BMC_DDR4_DQ<15>")
	)
	(arc
		(start 66.910458 -51.268376)
		(mid 66.882932 -51.33483)
		(end 66.816478 -51.362356)
		(width 0.08382)
		(layer "In2.Cu")
		(net "M_BMC_DDR4_DQ<15>")
	)
	(arc
		(start 75.827636 -51.43627)
		(mid 75.89409 -51.463796)
		(end 75.921616 -51.53025)
		(width 0.08382)
		(layer "In2.Cu")
		(net "M_BMC_DDR4_DQ<15>")
	)
	(arc
		(start 75.921616 -51.781964)
		(mid 75.879508 -51.88362)
		(end 75.777852 -51.925728)
		(width 0.08382)
		(layer "In2.Cu")
		(net "M_BMC_DDR4_DQ<15>")
	)
	(arc
		(start 72.287638 -51.89601)
		(mid 72.263083 -51.772564)
		(end 72.19315 -51.667918)
		(width 0.08382)
		(layer "In2.Cu")
		(net "M_BMC_DDR4_DQ<15>")
	)
	(arc
		(start 69.967602 -51.529996)
		(mid 69.906536 -51.504702)
		(end 69.881242 -51.443636)
		(width 0.08382)
		(layer "In2.Cu")
		(net "M_BMC_DDR4_DQ<15>")
	)
	(arc
		(start 69.291962 -51.266852)
		(mid 69.266668 -51.327918)
		(end 69.205602 -51.353212)
		(width 0.08382)
		(layer "In2.Cu")
		(net "M_BMC_DDR4_DQ<15>")
	)
	(arc
		(start 65.825878 -50.533554)
		(mid 65.759424 -50.56108)
		(end 65.731898 -50.627534)
		(width 0.08382)
		(layer "In2.Cu")
		(net "M_BMC_DDR4_DQ<15>")
	)
	(arc
		(start 65.731898 -51.268376)
		(mid 65.704372 -51.33483)
		(end 65.637918 -51.362356)
		(width 0.08382)
		(layer "In2.Cu")
		(net "M_BMC_DDR4_DQ<15>")
	)
	(arc
		(start 77.052424 -51.951636)
		(mid 77.024898 -52.01809)
		(end 76.958444 -52.045616)
		(width 0.08382)
		(layer "In2.Cu")
		(net "M_BMC_DDR4_DQ<15>")
	)
	(arc
		(start 73.926954 -52.254912)
		(mid 73.896305 -52.275391)
		(end 73.860152 -52.282598)
		(width 0.08382)
		(layer "In2.Cu")
		(net "M_BMC_DDR4_DQ<15>")
	)
	(segment
		(start 62.494922 -52.971192)
		(end 62.890146 -53.366416)
		(width 0.11684)
		(layer "F.Cu")
		(net "M_BMC_DDR4_DQ<14>")
	)
	(segment
		(start 74.652378 -51.50739)
		(end 74.270616 -51.125628)
		(width 0.11684)
		(layer "F.Cu")
		(net "M_BMC_DDR4_DQ<14>")
	)
	(via
		(at 74.270616 -51.125628)
		(size 0.4572)
		(drill 0.254)
		(layers "F.Cu" "B.Cu")
		(net "M_BMC_DDR4_DQ<14>")
	)
	(via
		(at 62.890146 -53.366416)
		(size 0.4572)
		(drill 0.254)
		(layers "F.Cu" "B.Cu")
		(net "M_BMC_DDR4_DQ<14>")
	)
	(segment
		(start 74.270616 -50.760884)
		(end 74.270616 -51.125628)
		(width 0.08382)
		(layer "In2.Cu")
		(net "M_BMC_DDR4_DQ<14>")
	)
	(segment
		(start 60.070238 -50.79873)
		(end 60.070238 -49.507648)
		(width 0.08382)
		(layer "In2.Cu")
		(net "M_BMC_DDR4_DQ<14>")
	)
	(segment
		(start 60.088272 -52.890928)
		(end 60.088272 -51.771042)
		(width 0.08382)
		(layer "In2.Cu")
		(net "M_BMC_DDR4_DQ<14>")
	)
	(segment
		(start 60.825888 -49.805082)
		(end 60.589414 -49.805082)
		(width 0.08382)
		(layer "In2.Cu")
		(net "M_BMC_DDR4_DQ<14>")
	)
	(segment
		(start 63.561976 -49.050194)
		(end 65.56375 -49.050194)
		(width 0.08382)
		(layer "In2.Cu")
		(net "M_BMC_DDR4_DQ<14>")
	)
	(segment
		(start 72.81418 -49.885346)
		(end 73.603104 -49.885346)
		(width 0.08382)
		(layer "In2.Cu")
		(net "M_BMC_DDR4_DQ<14>")
	)
	(segment
		(start 60.912248 -51.598322)
		(end 60.912248 -49.891442)
		(width 0.08382)
		(layer "In2.Cu")
		(net "M_BMC_DDR4_DQ<14>")
	)
	(segment
		(start 73.84161 -50.023522)
		(end 73.852278 -50.042318)
		(width 0.08382)
		(layer "In2.Cu")
		(net "M_BMC_DDR4_DQ<14>")
	)
	(segment
		(start 63.31458 -49.240186)
		(end 63.463932 -49.090834)
		(width 0.08382)
		(layer "In2.Cu")
		(net "M_BMC_DDR4_DQ<14>")
	)
	(segment
		(start 71.817484 -49.594516)
		(end 72.24776 -49.772824)
		(width 0.08382)
		(layer "In2.Cu")
		(net "M_BMC_DDR4_DQ<14>")
	)
	(segment
		(start 60.201048 -49.376838)
		(end 62.984888 -49.376838)
		(width 0.08382)
		(layer "In2.Cu")
		(net "M_BMC_DDR4_DQ<14>")
	)
	(segment
		(start 73.962768 -50.674524)
		(end 74.184256 -50.674524)
		(width 0.08382)
		(layer "In2.Cu")
		(net "M_BMC_DDR4_DQ<14>")
	)
	(segment
		(start 60.174632 -51.684682)
		(end 60.825888 -51.684682)
		(width 0.08382)
		(layer "In2.Cu")
		(net "M_BMC_DDR4_DQ<14>")
	)
	(segment
		(start 62.890146 -53.366416)
		(end 62.40272 -53.366416)
		(width 0.08382)
		(layer "In2.Cu")
		(net "M_BMC_DDR4_DQ<14>")
	)
	(segment
		(start 66.425572 -49.469802)
		(end 71.190612 -49.469802)
		(width 0.08382)
		(layer "In2.Cu")
		(net "M_BMC_DDR4_DQ<14>")
	)
	(segment
		(start 60.790836 -52.977288)
		(end 60.174632 -52.977288)
		(width 0.08382)
		(layer "In2.Cu")
		(net "M_BMC_DDR4_DQ<14>")
	)
	(segment
		(start 60.915804 -53.675534)
		(end 60.915804 -53.102256)
		(width 0.08382)
		(layer "In2.Cu")
		(net "M_BMC_DDR4_DQ<14>")
	)
	(segment
		(start 60.503054 -49.891442)
		(end 60.503054 -50.79873)
		(width 0.08382)
		(layer "In2.Cu")
		(net "M_BMC_DDR4_DQ<14>")
	)
	(segment
		(start 65.997074 -49.229772)
		(end 66.104008 -49.336706)
		(width 0.08382)
		(layer "In2.Cu")
		(net "M_BMC_DDR4_DQ<14>")
	)
	(segment
		(start 60.416694 -50.88509)
		(end 60.156598 -50.88509)
		(width 0.08382)
		(layer "In2.Cu")
		(net "M_BMC_DDR4_DQ<14>")
	)
	(segment
		(start 62.23 -53.761894)
		(end 61.002164 -53.761894)
		(width 0.08382)
		(layer "In2.Cu")
		(net "M_BMC_DDR4_DQ<14>")
	)
	(segment
		(start 62.31636 -53.452776)
		(end 62.31636 -53.675534)
		(width 0.08382)
		(layer "In2.Cu")
		(net "M_BMC_DDR4_DQ<14>")
	)
	(segment
		(start 73.876408 -50.13325)
		(end 73.876408 -50.588164)
		(width 0.08382)
		(layer "In2.Cu")
		(net "M_BMC_DDR4_DQ<14>")
	)
	(arc
		(start 71.190612 -49.469802)
		(mid 71.510187 -49.501293)
		(end 71.817484 -49.594516)
		(width 0.08382)
		(layer "In2.Cu")
		(net "M_BMC_DDR4_DQ<14>")
	)
	(arc
		(start 60.503054 -50.79873)
		(mid 60.47776 -50.859796)
		(end 60.416694 -50.88509)
		(width 0.08382)
		(layer "In2.Cu")
		(net "M_BMC_DDR4_DQ<14>")
	)
	(arc
		(start 62.40272 -53.366416)
		(mid 62.341654 -53.39171)
		(end 62.31636 -53.452776)
		(width 0.08382)
		(layer "In2.Cu")
		(net "M_BMC_DDR4_DQ<14>")
	)
	(arc
		(start 61.002164 -53.761894)
		(mid 60.941098 -53.7366)
		(end 60.915804 -53.675534)
		(width 0.08382)
		(layer "In2.Cu")
		(net "M_BMC_DDR4_DQ<14>")
	)
	(arc
		(start 60.915804 -53.102256)
		(mid 60.879202 -53.01389)
		(end 60.790836 -52.977288)
		(width 0.08382)
		(layer "In2.Cu")
		(net "M_BMC_DDR4_DQ<14>")
	)
	(arc
		(start 62.31636 -53.675534)
		(mid 62.291066 -53.7366)
		(end 62.23 -53.761894)
		(width 0.08382)
		(layer "In2.Cu")
		(net "M_BMC_DDR4_DQ<14>")
	)
	(arc
		(start 60.589414 -49.805082)
		(mid 60.528348 -49.830376)
		(end 60.503054 -49.891442)
		(width 0.08382)
		(layer "In2.Cu")
		(net "M_BMC_DDR4_DQ<14>")
	)
	(arc
		(start 60.088272 -51.771042)
		(mid 60.113566 -51.709976)
		(end 60.174632 -51.684682)
		(width 0.08382)
		(layer "In2.Cu")
		(net "M_BMC_DDR4_DQ<14>")
	)
	(arc
		(start 73.876408 -50.588164)
		(mid 73.901702 -50.64923)
		(end 73.962768 -50.674524)
		(width 0.08382)
		(layer "In2.Cu")
		(net "M_BMC_DDR4_DQ<14>")
	)
	(arc
		(start 72.24776 -49.772824)
		(mid 72.525427 -49.857)
		(end 72.81418 -49.885346)
		(width 0.08382)
		(layer "In2.Cu")
		(net "M_BMC_DDR4_DQ<14>")
	)
	(arc
		(start 65.56375 -49.050194)
		(mid 65.798283 -49.096863)
		(end 65.997074 -49.229772)
		(width 0.08382)
		(layer "In2.Cu")
		(net "M_BMC_DDR4_DQ<14>")
	)
	(arc
		(start 60.912248 -49.891442)
		(mid 60.886954 -49.830376)
		(end 60.825888 -49.805082)
		(width 0.08382)
		(layer "In2.Cu")
		(net "M_BMC_DDR4_DQ<14>")
	)
	(arc
		(start 66.104008 -49.336706)
		(mid 66.251557 -49.435232)
		(end 66.425572 -49.469802)
		(width 0.08382)
		(layer "In2.Cu")
		(net "M_BMC_DDR4_DQ<14>")
	)
	(arc
		(start 73.603104 -49.885346)
		(mid 73.740911 -49.922393)
		(end 73.84161 -50.023522)
		(width 0.08382)
		(layer "In2.Cu")
		(net "M_BMC_DDR4_DQ<14>")
	)
	(arc
		(start 74.184256 -50.674524)
		(mid 74.245322 -50.699818)
		(end 74.270616 -50.760884)
		(width 0.08382)
		(layer "In2.Cu")
		(net "M_BMC_DDR4_DQ<14>")
	)
	(arc
		(start 73.852278 -50.042318)
		(mid 73.870323 -50.086202)
		(end 73.876408 -50.13325)
		(width 0.08382)
		(layer "In2.Cu")
		(net "M_BMC_DDR4_DQ<14>")
	)
	(arc
		(start 60.825888 -51.684682)
		(mid 60.886954 -51.659388)
		(end 60.912248 -51.598322)
		(width 0.08382)
		(layer "In2.Cu")
		(net "M_BMC_DDR4_DQ<14>")
	)
	(arc
		(start 63.463932 -49.090834)
		(mid 63.508915 -49.060777)
		(end 63.561976 -49.050194)
		(width 0.08382)
		(layer "In2.Cu")
		(net "M_BMC_DDR4_DQ<14>")
	)
	(arc
		(start 60.156598 -50.88509)
		(mid 60.095532 -50.859796)
		(end 60.070238 -50.79873)
		(width 0.08382)
		(layer "In2.Cu")
		(net "M_BMC_DDR4_DQ<14>")
	)
	(arc
		(start 62.984888 -49.376838)
		(mid 63.163336 -49.341325)
		(end 63.31458 -49.240186)
		(width 0.08382)
		(layer "In2.Cu")
		(net "M_BMC_DDR4_DQ<14>")
	)
	(arc
		(start 60.070238 -49.507648)
		(mid 60.108551 -49.415151)
		(end 60.201048 -49.376838)
		(width 0.08382)
		(layer "In2.Cu")
		(net "M_BMC_DDR4_DQ<14>")
	)
	(arc
		(start 60.174632 -52.977288)
		(mid 60.113566 -52.951994)
		(end 60.088272 -52.890928)
		(width 0.08382)
		(layer "In2.Cu")
		(net "M_BMC_DDR4_DQ<14>")
	)
	(segment
		(start 62.494922 -52.171346)
		(end 62.890146 -52.56657)
		(width 0.11684)
		(layer "F.Cu")
		(net "M_BMC_DDR4_DQ<13>")
	)
	(segment
		(start 78.65237 -52.30749)
		(end 78.270608 -51.925728)
		(width 0.11684)
		(layer "F.Cu")
		(net "M_BMC_DDR4_DQ<13>")
	)
	(via
		(at 78.270608 -51.925728)
		(size 0.4572)
		(drill 0.254)
		(layers "F.Cu" "B.Cu")
		(net "M_BMC_DDR4_DQ<13>")
	)
	(via
		(at 62.890146 -52.56657)
		(size 0.4572)
		(drill 0.254)
		(layers "F.Cu" "B.Cu")
		(net "M_BMC_DDR4_DQ<13>")
	)
	(segment
		(start 77.106018 -50.863246)
		(end 77.476858 -50.863246)
		(width 0.08382)
		(layer "In2.Cu")
		(net "M_BMC_DDR4_DQ<13>")
	)
	(segment
		(start 78.06436 -51.47691)
		(end 78.184248 -51.47691)
		(width 0.08382)
		(layer "In2.Cu")
		(net "M_BMC_DDR4_DQ<13>")
	)
	(segment
		(start 78.270608 -51.56327)
		(end 78.270608 -51.925728)
		(width 0.08382)
		(layer "In2.Cu")
		(net "M_BMC_DDR4_DQ<13>")
	)
	(segment
		(start 77.563218 -50.776886)
		(end 77.563218 -49.985168)
		(width 0.08382)
		(layer "In2.Cu")
		(net "M_BMC_DDR4_DQ<13>")
	)
	(segment
		(start 78.558136 -50.93335)
		(end 78.06436 -50.93335)
		(width 0.08382)
		(layer "In2.Cu")
		(net "M_BMC_DDR4_DQ<13>")
	)
	(segment
		(start 63.634366 -50.559462)
		(end 65.278508 -50.559462)
		(width 0.08382)
		(layer "In2.Cu")
		(net "M_BMC_DDR4_DQ<13>")
	)
	(segment
		(start 77.649578 -49.898808)
		(end 80.22717 -49.898808)
		(width 0.08382)
		(layer "In2.Cu")
		(net "M_BMC_DDR4_DQ<13>")
	)
	(segment
		(start 78.644496 -50.790348)
		(end 78.644496 -50.84699)
		(width 0.08382)
		(layer "In2.Cu")
		(net "M_BMC_DDR4_DQ<13>")
	)
	(segment
		(start 72.247252 -51.21021)
		(end 72.508872 -51.47183)
		(width 0.08382)
		(layer "In2.Cu")
		(net "M_BMC_DDR4_DQ<13>")
	)
	(segment
		(start 74.809858 -50.474372)
		(end 75.431904 -50.474372)
		(width 0.08382)
		(layer "In2.Cu")
		(net "M_BMC_DDR4_DQ<13>")
	)
	(segment
		(start 63.28918 -51.675538)
		(end 63.28918 -50.904648)
		(width 0.08382)
		(layer "In2.Cu")
		(net "M_BMC_DDR4_DQ<13>")
	)
	(segment
		(start 80.3402 -50.011838)
		(end 80.3402 -50.564288)
		(width 0.08382)
		(layer "In2.Cu")
		(net "M_BMC_DDR4_DQ<13>")
	)
	(segment
		(start 75.738228 -50.347372)
		(end 75.895454 -50.190146)
		(width 0.08382)
		(layer "In2.Cu")
		(net "M_BMC_DDR4_DQ<13>")
	)
	(segment
		(start 62.890146 -52.56657)
		(end 62.9412 -52.515516)
		(width 0.08382)
		(layer "In2.Cu")
		(net "M_BMC_DDR4_DQ<13>")
	)
	(segment
		(start 72.59828 -51.508914)
		(end 74.584052 -51.508914)
		(width 0.08382)
		(layer "In2.Cu")
		(net "M_BMC_DDR4_DQ<13>")
	)
	(segment
		(start 70.34403 -50.262282)
		(end 70.34403 -51.091592)
		(width 0.08382)
		(layer "In2.Cu")
		(net "M_BMC_DDR4_DQ<13>")
	)
	(segment
		(start 70.43039 -51.177952)
		(end 72.169528 -51.177952)
		(width 0.08382)
		(layer "In2.Cu")
		(net "M_BMC_DDR4_DQ<13>")
	)
	(segment
		(start 80.2005 -50.703988)
		(end 78.730856 -50.703988)
		(width 0.08382)
		(layer "In2.Cu")
		(net "M_BMC_DDR4_DQ<13>")
	)
	(segment
		(start 77.019658 -50.140616)
		(end 77.019658 -50.776886)
		(width 0.08382)
		(layer "In2.Cu")
		(net "M_BMC_DDR4_DQ<13>")
	)
	(segment
		(start 74.678032 -51.414934)
		(end 74.678032 -50.606198)
		(width 0.08382)
		(layer "In2.Cu")
		(net "M_BMC_DDR4_DQ<13>")
	)
	(segment
		(start 65.982088 -50.175922)
		(end 70.25767 -50.175922)
		(width 0.08382)
		(layer "In2.Cu")
		(net "M_BMC_DDR4_DQ<13>")
	)
	(segment
		(start 77.978 -51.01971)
		(end 77.978 -51.39055)
		(width 0.08382)
		(layer "In2.Cu")
		(net "M_BMC_DDR4_DQ<13>")
	)
	(segment
		(start 76.223368 -50.054256)
		(end 76.933298 -50.054256)
		(width 0.08382)
		(layer "In2.Cu")
		(net "M_BMC_DDR4_DQ<13>")
	)
	(arc
		(start 65.278508 -50.559462)
		(mid 65.325645 -50.556448)
		(end 65.37198 -50.54727)
		(width 0.08382)
		(layer "In2.Cu")
		(net "M_BMC_DDR4_DQ<13>")
	)
	(arc
		(start 76.933298 -50.054256)
		(mid 76.994364 -50.07955)
		(end 77.019658 -50.140616)
		(width 0.08382)
		(layer "In2.Cu")
		(net "M_BMC_DDR4_DQ<13>")
	)
	(arc
		(start 70.25767 -50.175922)
		(mid 70.318736 -50.201216)
		(end 70.34403 -50.262282)
		(width 0.08382)
		(layer "In2.Cu")
		(net "M_BMC_DDR4_DQ<13>")
	)
	(arc
		(start 65.625472 -50.365914)
		(mid 65.780062 -50.22641)
		(end 65.982088 -50.175922)
		(width 0.08382)
		(layer "In2.Cu")
		(net "M_BMC_DDR4_DQ<13>")
	)
	(arc
		(start 77.019658 -50.776886)
		(mid 77.044952 -50.837952)
		(end 77.106018 -50.863246)
		(width 0.08382)
		(layer "In2.Cu")
		(net "M_BMC_DDR4_DQ<13>")
	)
	(arc
		(start 78.06436 -50.93335)
		(mid 78.003294 -50.958644)
		(end 77.978 -51.01971)
		(width 0.08382)
		(layer "In2.Cu")
		(net "M_BMC_DDR4_DQ<13>")
	)
	(arc
		(start 62.9412 -52.515516)
		(mid 63.19876 -52.130145)
		(end 63.28918 -51.675538)
		(width 0.08382)
		(layer "In2.Cu")
		(net "M_BMC_DDR4_DQ<13>")
	)
	(arc
		(start 75.895454 -50.190146)
		(mid 76.045888 -50.089566)
		(end 76.223368 -50.054256)
		(width 0.08382)
		(layer "In2.Cu")
		(net "M_BMC_DDR4_DQ<13>")
	)
	(arc
		(start 78.730856 -50.703988)
		(mid 78.66979 -50.729282)
		(end 78.644496 -50.790348)
		(width 0.08382)
		(layer "In2.Cu")
		(net "M_BMC_DDR4_DQ<13>")
	)
	(arc
		(start 63.28918 -50.904648)
		(mid 63.390283 -50.660565)
		(end 63.634366 -50.559462)
		(width 0.08382)
		(layer "In2.Cu")
		(net "M_BMC_DDR4_DQ<13>")
	)
	(arc
		(start 78.644496 -50.84699)
		(mid 78.619202 -50.908056)
		(end 78.558136 -50.93335)
		(width 0.08382)
		(layer "In2.Cu")
		(net "M_BMC_DDR4_DQ<13>")
	)
	(arc
		(start 65.37198 -50.54727)
		(mid 65.515099 -50.479472)
		(end 65.625472 -50.365914)
		(width 0.08382)
		(layer "In2.Cu")
		(net "M_BMC_DDR4_DQ<13>")
	)
	(arc
		(start 72.508872 -51.47183)
		(mid 72.549878 -51.499293)
		(end 72.59828 -51.508914)
		(width 0.08382)
		(layer "In2.Cu")
		(net "M_BMC_DDR4_DQ<13>")
	)
	(arc
		(start 75.431904 -50.474372)
		(mid 75.597676 -50.441304)
		(end 75.738228 -50.347372)
		(width 0.08382)
		(layer "In2.Cu")
		(net "M_BMC_DDR4_DQ<13>")
	)
	(arc
		(start 74.584052 -51.508914)
		(mid 74.650506 -51.481388)
		(end 74.678032 -51.414934)
		(width 0.08382)
		(layer "In2.Cu")
		(net "M_BMC_DDR4_DQ<13>")
	)
	(arc
		(start 77.978 -51.39055)
		(mid 78.003294 -51.451616)
		(end 78.06436 -51.47691)
		(width 0.08382)
		(layer "In2.Cu")
		(net "M_BMC_DDR4_DQ<13>")
	)
	(arc
		(start 78.184248 -51.47691)
		(mid 78.245314 -51.502204)
		(end 78.270608 -51.56327)
		(width 0.08382)
		(layer "In2.Cu")
		(net "M_BMC_DDR4_DQ<13>")
	)
	(arc
		(start 77.476858 -50.863246)
		(mid 77.537924 -50.837952)
		(end 77.563218 -50.776886)
		(width 0.08382)
		(layer "In2.Cu")
		(net "M_BMC_DDR4_DQ<13>")
	)
	(arc
		(start 74.678032 -50.606198)
		(mid 74.716643 -50.512983)
		(end 74.809858 -50.474372)
		(width 0.08382)
		(layer "In2.Cu")
		(net "M_BMC_DDR4_DQ<13>")
	)
	(arc
		(start 72.169528 -51.177952)
		(mid 72.211616 -51.186324)
		(end 72.247252 -51.21021)
		(width 0.08382)
		(layer "In2.Cu")
		(net "M_BMC_DDR4_DQ<13>")
	)
	(arc
		(start 80.22717 -49.898808)
		(mid 80.307094 -49.931914)
		(end 80.3402 -50.011838)
		(width 0.08382)
		(layer "In2.Cu")
		(net "M_BMC_DDR4_DQ<13>")
	)
	(arc
		(start 80.3402 -50.564288)
		(mid 80.299283 -50.663071)
		(end 80.2005 -50.703988)
		(width 0.08382)
		(layer "In2.Cu")
		(net "M_BMC_DDR4_DQ<13>")
	)
	(arc
		(start 70.34403 -51.091592)
		(mid 70.369324 -51.152658)
		(end 70.43039 -51.177952)
		(width 0.08382)
		(layer "In2.Cu")
		(net "M_BMC_DDR4_DQ<13>")
	)
	(arc
		(start 77.563218 -49.985168)
		(mid 77.588512 -49.924102)
		(end 77.649578 -49.898808)
		(width 0.08382)
		(layer "In2.Cu")
		(net "M_BMC_DDR4_DQ<13>")
	)
	(segment
		(start 74.270616 -53.489098)
		(end 74.23404 -53.452522)
		(width 0.11684)
		(layer "F.Cu")
		(net "M_BMC_DDR4_DQ<12>")
	)
	(segment
		(start 62.494922 -53.771292)
		(end 62.890146 -54.166516)
		(width 0.11684)
		(layer "F.Cu")
		(net "M_BMC_DDR4_DQ<12>")
	)
	(segment
		(start 74.23404 -53.452522)
		(end 74.23404 -52.689252)
		(width 0.11684)
		(layer "F.Cu")
		(net "M_BMC_DDR4_DQ<12>")
	)
	(segment
		(start 74.23404 -52.689252)
		(end 73.852278 -52.30749)
		(width 0.11684)
		(layer "F.Cu")
		(net "M_BMC_DDR4_DQ<12>")
	)
	(via
		(at 74.270616 -53.489098)
		(size 0.4572)
		(drill 0.254)
		(layers "F.Cu" "B.Cu")
		(net "M_BMC_DDR4_DQ<12>")
	)
	(via
		(at 62.890146 -54.166516)
		(size 0.4572)
		(drill 0.254)
		(layers "F.Cu" "B.Cu")
		(net "M_BMC_DDR4_DQ<12>")
	)
	(segment
		(start 66.411094 -55.51043)
		(end 66.411094 -55.075582)
		(width 0.08382)
		(layer "In2.Cu")
		(net "M_BMC_DDR4_DQ<12>")
	)
	(segment
		(start 74.23404 -53.452522)
		(end 74.23404 -53.191664)
		(width 0.08382)
		(layer "In2.Cu")
		(net "M_BMC_DDR4_DQ<12>")
	)
	(segment
		(start 63.681102 -53.78831)
		(end 62.708282 -53.78831)
		(width 0.08382)
		(layer "In2.Cu")
		(net "M_BMC_DDR4_DQ<12>")
	)
	(segment
		(start 71.409814 -52.699412)
		(end 71.409814 -52.310792)
		(width 0.08382)
		(layer "In2.Cu")
		(net "M_BMC_DDR4_DQ<12>")
	)
	(segment
		(start 62.931548 -55.378858)
		(end 65.585848 -55.378858)
		(width 0.08382)
		(layer "In2.Cu")
		(net "M_BMC_DDR4_DQ<12>")
	)
	(segment
		(start 65.969642 -54.902862)
		(end 65.969642 -54.648354)
		(width 0.08382)
		(layer "In2.Cu")
		(net "M_BMC_DDR4_DQ<12>")
	)
	(segment
		(start 66.344546 -52.093876)
		(end 65.869312 -52.164234)
		(width 0.08382)
		(layer "In2.Cu")
		(net "M_BMC_DDR4_DQ<12>")
	)
	(segment
		(start 69.525642 -52.2224)
		(end 69.44868 -52.145184)
		(width 0.08382)
		(layer "In2.Cu")
		(net "M_BMC_DDR4_DQ<12>")
	)
	(segment
		(start 62.890146 -54.475634)
		(end 62.890146 -54.166516)
		(width 0.08382)
		(layer "In2.Cu")
		(net "M_BMC_DDR4_DQ<12>")
	)
	(segment
		(start 64.774064 -52.914042)
		(end 64.054228 -53.633878)
		(width 0.08382)
		(layer "In2.Cu")
		(net "M_BMC_DDR4_DQ<12>")
	)
	(segment
		(start 69.309742 -52.087526)
		(end 66.430398 -52.087526)
		(width 0.08382)
		(layer "In2.Cu")
		(net "M_BMC_DDR4_DQ<12>")
	)
	(segment
		(start 65.883282 -54.561994)
		(end 62.976506 -54.561994)
		(width 0.08382)
		(layer "In2.Cu")
		(net "M_BMC_DDR4_DQ<12>")
	)
	(segment
		(start 70.296024 -52.757832)
		(end 70.296024 -52.33416)
		(width 0.08382)
		(layer "In2.Cu")
		(net "M_BMC_DDR4_DQ<12>")
	)
	(segment
		(start 62.534292 -55.160672)
		(end 62.625986 -55.252366)
		(width 0.08382)
		(layer "In2.Cu")
		(net "M_BMC_DDR4_DQ<12>")
	)
	(segment
		(start 70.209664 -52.2478)
		(end 69.586856 -52.2478)
		(width 0.08382)
		(layer "In2.Cu")
		(net "M_BMC_DDR4_DQ<12>")
	)
	(segment
		(start 70.852538 -52.310792)
		(end 70.852538 -52.757832)
		(width 0.08382)
		(layer "In2.Cu")
		(net "M_BMC_DDR4_DQ<12>")
	)
	(segment
		(start 74.270616 -53.489098)
		(end 74.23404 -53.452522)
		(width 0.08382)
		(layer "In2.Cu")
		(net "M_BMC_DDR4_DQ<12>")
	)
	(segment
		(start 71.323454 -52.224432)
		(end 70.938898 -52.224432)
		(width 0.08382)
		(layer "In2.Cu")
		(net "M_BMC_DDR4_DQ<12>")
	)
	(segment
		(start 64.900556 -52.470558)
		(end 64.900556 -52.60848)
		(width 0.08382)
		(layer "In2.Cu")
		(net "M_BMC_DDR4_DQ<12>")
	)
	(segment
		(start 65.783206 -52.170584)
		(end 65.20053 -52.170584)
		(width 0.08382)
		(layer "In2.Cu")
		(net "M_BMC_DDR4_DQ<12>")
	)
	(segment
		(start 65.672208 -55.465218)
		(end 65.672208 -55.51043)
		(width 0.08382)
		(layer "In2.Cu")
		(net "M_BMC_DDR4_DQ<12>")
	)
	(segment
		(start 70.766178 -52.844192)
		(end 70.382384 -52.844192)
		(width 0.08382)
		(layer "In2.Cu")
		(net "M_BMC_DDR4_DQ<12>")
	)
	(segment
		(start 62.483492 -54.0131)
		(end 62.483492 -55.038244)
		(width 0.08382)
		(layer "In2.Cu")
		(net "M_BMC_DDR4_DQ<12>")
	)
	(segment
		(start 65.758568 -55.59679)
		(end 66.324734 -55.59679)
		(width 0.08382)
		(layer "In2.Cu")
		(net "M_BMC_DDR4_DQ<12>")
	)
	(segment
		(start 66.324734 -54.989222)
		(end 66.056002 -54.989222)
		(width 0.08382)
		(layer "In2.Cu")
		(net "M_BMC_DDR4_DQ<12>")
	)
	(segment
		(start 74.14768 -53.105304)
		(end 71.815706 -53.105304)
		(width 0.08382)
		(layer "In2.Cu")
		(net "M_BMC_DDR4_DQ<12>")
	)
	(arc
		(start 64.054228 -53.633878)
		(mid 63.883022 -53.748211)
		(end 63.681102 -53.78831)
		(width 0.08382)
		(layer "In2.Cu")
		(net "M_BMC_DDR4_DQ<12>")
	)
	(arc
		(start 71.409814 -52.310792)
		(mid 71.38452 -52.249726)
		(end 71.323454 -52.224432)
		(width 0.08382)
		(layer "In2.Cu")
		(net "M_BMC_DDR4_DQ<12>")
	)
	(arc
		(start 66.056002 -54.989222)
		(mid 65.994936 -54.963928)
		(end 65.969642 -54.902862)
		(width 0.08382)
		(layer "In2.Cu")
		(net "M_BMC_DDR4_DQ<12>")
	)
	(arc
		(start 69.586856 -52.2478)
		(mid 69.553725 -52.241192)
		(end 69.525642 -52.2224)
		(width 0.08382)
		(layer "In2.Cu")
		(net "M_BMC_DDR4_DQ<12>")
	)
	(arc
		(start 62.625986 -55.252366)
		(mid 62.766193 -55.345986)
		(end 62.931548 -55.378858)
		(width 0.08382)
		(layer "In2.Cu")
		(net "M_BMC_DDR4_DQ<12>")
	)
	(arc
		(start 70.296024 -52.33416)
		(mid 70.27073 -52.273094)
		(end 70.209664 -52.2478)
		(width 0.08382)
		(layer "In2.Cu")
		(net "M_BMC_DDR4_DQ<12>")
	)
	(arc
		(start 66.430398 -52.087526)
		(mid 66.387355 -52.089124)
		(end 66.344546 -52.093876)
		(width 0.08382)
		(layer "In2.Cu")
		(net "M_BMC_DDR4_DQ<12>")
	)
	(arc
		(start 66.324734 -55.59679)
		(mid 66.3858 -55.571496)
		(end 66.411094 -55.51043)
		(width 0.08382)
		(layer "In2.Cu")
		(net "M_BMC_DDR4_DQ<12>")
	)
	(arc
		(start 65.672208 -55.51043)
		(mid 65.697502 -55.571496)
		(end 65.758568 -55.59679)
		(width 0.08382)
		(layer "In2.Cu")
		(net "M_BMC_DDR4_DQ<12>")
	)
	(arc
		(start 66.411094 -55.075582)
		(mid 66.3858 -55.014516)
		(end 66.324734 -54.989222)
		(width 0.08382)
		(layer "In2.Cu")
		(net "M_BMC_DDR4_DQ<12>")
	)
	(arc
		(start 65.585848 -55.378858)
		(mid 65.646914 -55.404152)
		(end 65.672208 -55.465218)
		(width 0.08382)
		(layer "In2.Cu")
		(net "M_BMC_DDR4_DQ<12>")
	)
	(arc
		(start 70.938898 -52.224432)
		(mid 70.877832 -52.249726)
		(end 70.852538 -52.310792)
		(width 0.08382)
		(layer "In2.Cu")
		(net "M_BMC_DDR4_DQ<12>")
	)
	(arc
		(start 62.483492 -55.038244)
		(mid 62.496693 -55.104521)
		(end 62.534292 -55.160672)
		(width 0.08382)
		(layer "In2.Cu")
		(net "M_BMC_DDR4_DQ<12>")
	)
	(arc
		(start 64.900556 -52.60848)
		(mid 64.867683 -52.773834)
		(end 64.774064 -52.914042)
		(width 0.08382)
		(layer "In2.Cu")
		(net "M_BMC_DDR4_DQ<12>")
	)
	(arc
		(start 65.20053 -52.170584)
		(mid 64.988416 -52.258444)
		(end 64.900556 -52.470558)
		(width 0.08382)
		(layer "In2.Cu")
		(net "M_BMC_DDR4_DQ<12>")
	)
	(arc
		(start 65.969642 -54.648354)
		(mid 65.944348 -54.587288)
		(end 65.883282 -54.561994)
		(width 0.08382)
		(layer "In2.Cu")
		(net "M_BMC_DDR4_DQ<12>")
	)
	(arc
		(start 62.976506 -54.561994)
		(mid 62.91544 -54.5367)
		(end 62.890146 -54.475634)
		(width 0.08382)
		(layer "In2.Cu")
		(net "M_BMC_DDR4_DQ<12>")
	)
	(arc
		(start 65.869312 -52.164234)
		(mid 65.826376 -52.16899)
		(end 65.783206 -52.170584)
		(width 0.08382)
		(layer "In2.Cu")
		(net "M_BMC_DDR4_DQ<12>")
	)
	(arc
		(start 71.815706 -53.105304)
		(mid 71.528697 -52.986421)
		(end 71.409814 -52.699412)
		(width 0.08382)
		(layer "In2.Cu")
		(net "M_BMC_DDR4_DQ<12>")
	)
	(arc
		(start 69.44868 -52.145184)
		(mid 69.384963 -52.102483)
		(end 69.309742 -52.087526)
		(width 0.08382)
		(layer "In2.Cu")
		(net "M_BMC_DDR4_DQ<12>")
	)
	(arc
		(start 74.23404 -53.191664)
		(mid 74.208746 -53.130598)
		(end 74.14768 -53.105304)
		(width 0.08382)
		(layer "In2.Cu")
		(net "M_BMC_DDR4_DQ<12>")
	)
	(arc
		(start 70.852538 -52.757832)
		(mid 70.827244 -52.818898)
		(end 70.766178 -52.844192)
		(width 0.08382)
		(layer "In2.Cu")
		(net "M_BMC_DDR4_DQ<12>")
	)
	(arc
		(start 70.382384 -52.844192)
		(mid 70.321318 -52.818898)
		(end 70.296024 -52.757832)
		(width 0.08382)
		(layer "In2.Cu")
		(net "M_BMC_DDR4_DQ<12>")
	)
	(arc
		(start 62.708282 -53.78831)
		(mid 62.549331 -53.854149)
		(end 62.483492 -54.0131)
		(width 0.08382)
		(layer "In2.Cu")
		(net "M_BMC_DDR4_DQ<12>")
	)
	(segment
		(start 63.295022 -53.771292)
		(end 63.690246 -54.166516)
		(width 0.11684)
		(layer "F.Cu")
		(net "M_BMC_DDR4_DQ<11>")
	)
	(segment
		(start 77.35443 -52.316888)
		(end 77.842872 -52.316888)
		(width 0.11684)
		(layer "F.Cu")
		(net "M_BMC_DDR4_DQ<11>")
	)
	(segment
		(start 77.842872 -52.316888)
		(end 77.85227 -52.30749)
		(width 0.11684)
		(layer "F.Cu")
		(net "M_BMC_DDR4_DQ<11>")
	)
	(segment
		(start 78.234032 -52.689252)
		(end 76.775564 -52.689252)
		(width 0.11684)
		(layer "F.Cu")
		(net "M_BMC_DDR4_DQ<11>")
	)
	(segment
		(start 76.760832 -51.769264)
		(end 76.78547 -51.765454)
		(width 0.11684)
		(layer "F.Cu")
		(net "M_BMC_DDR4_DQ<11>")
	)
	(segment
		(start 76.448412 -52.295044)
		(end 76.448412 -52.037488)
		(width 0.11684)
		(layer "F.Cu")
		(net "M_BMC_DDR4_DQ<11>")
	)
	(segment
		(start 77.068172 -52.008278)
		(end 77.068172 -52.03063)
		(width 0.11684)
		(layer "F.Cu")
		(net "M_BMC_DDR4_DQ<11>")
	)
	(via
		(at 63.690246 -54.166516)
		(size 0.4572)
		(drill 0.254)
		(layers "F.Cu" "B.Cu")
		(net "M_BMC_DDR4_DQ<11>")
	)
	(via
		(at 78.234032 -52.689252)
		(size 0.4572)
		(drill 0.254)
		(layers "F.Cu" "B.Cu")
		(net "M_BMC_DDR4_DQ<11>")
	)
	(arc
		(start 76.665836 -52.65674)
		(mid 76.544573 -52.545354)
		(end 76.465938 -52.400708)
		(width 0.11684)
		(layer "F.Cu")
		(net "M_BMC_DDR4_DQ<11>")
	)
	(arc
		(start 77.068172 -52.03063)
		(mid 77.152015 -52.233045)
		(end 77.35443 -52.316888)
		(width 0.11684)
		(layer "F.Cu")
		(net "M_BMC_DDR4_DQ<11>")
	)
	(arc
		(start 76.448412 -52.037488)
		(mid 76.543006 -51.83164)
		(end 76.760832 -51.769264)
		(width 0.11684)
		(layer "F.Cu")
		(net "M_BMC_DDR4_DQ<11>")
	)
	(arc
		(start 76.78547 -51.765454)
		(mid 76.9826 -51.821934)
		(end 77.068172 -52.008278)
		(width 0.11684)
		(layer "F.Cu")
		(net "M_BMC_DDR4_DQ<11>")
	)
	(arc
		(start 76.775564 -52.689252)
		(mid 76.718336 -52.680983)
		(end 76.665836 -52.65674)
		(width 0.11684)
		(layer "F.Cu")
		(net "M_BMC_DDR4_DQ<11>")
	)
	(arc
		(start 76.465938 -52.400708)
		(mid 76.452766 -52.348609)
		(end 76.448412 -52.295044)
		(width 0.11684)
		(layer "F.Cu")
		(net "M_BMC_DDR4_DQ<11>")
	)
	(segment
		(start 74.88809 -52.665884)
		(end 74.841608 -52.665884)
		(width 0.08382)
		(layer "In2.Cu")
		(net "M_BMC_DDR4_DQ<11>")
	)
	(segment
		(start 69.403468 -52.888388)
		(end 69.403468 -52.795932)
		(width 0.08382)
		(layer "In2.Cu")
		(net "M_BMC_DDR4_DQ<11>")
	)
	(segment
		(start 74.62647 -52.881022)
		(end 74.6506 -52.905152)
		(width 0.08382)
		(layer "In2.Cu")
		(net "M_BMC_DDR4_DQ<11>")
	)
	(segment
		(start 69.134736 -52.5272)
		(end 69.10578 -52.5272)
		(width 0.08382)
		(layer "In2.Cu")
		(net "M_BMC_DDR4_DQ<11>")
	)
	(segment
		(start 70.416166 -53.397912)
		(end 70.123558 -53.105304)
		(width 0.08382)
		(layer "In2.Cu")
		(net "M_BMC_DDR4_DQ<11>")
	)
	(segment
		(start 76.613004 -53.012594)
		(end 76.55941 -53.012594)
		(width 0.08382)
		(layer "In2.Cu")
		(net "M_BMC_DDR4_DQ<11>")
	)
	(segment
		(start 75.10145 -52.897786)
		(end 75.10145 -52.879244)
		(width 0.08382)
		(layer "In2.Cu")
		(net "M_BMC_DDR4_DQ<11>")
	)
	(segment
		(start 71.603616 -54.03342)
		(end 71.603616 -53.506878)
		(width 0.08382)
		(layer "In2.Cu")
		(net "M_BMC_DDR4_DQ<11>")
	)
	(segment
		(start 68.826888 -52.806092)
		(end 68.826888 -52.909978)
		(width 0.08382)
		(layer "In2.Cu")
		(net "M_BMC_DDR4_DQ<11>")
	)
	(segment
		(start 72.295258 -53.993542)
		(end 72.28205 -54.00675)
		(width 0.08382)
		(layer "In2.Cu")
		(net "M_BMC_DDR4_DQ<11>")
	)
	(segment
		(start 74.545444 -53.872892)
		(end 72.586596 -53.872892)
		(width 0.08382)
		(layer "In2.Cu")
		(net "M_BMC_DDR4_DQ<11>")
	)
	(segment
		(start 70.200266 -53.746908)
		(end 70.416166 -53.531008)
		(width 0.08382)
		(layer "In2.Cu")
		(net "M_BMC_DDR4_DQ<11>")
	)
	(segment
		(start 78.234032 -52.689252)
		(end 78.79969 -52.689252)
		(width 0.08382)
		(layer "In2.Cu")
		(net "M_BMC_DDR4_DQ<11>")
	)
	(segment
		(start 76.336906 -52.79009)
		(end 76.336906 -52.771548)
		(width 0.08382)
		(layer "In2.Cu")
		(net "M_BMC_DDR4_DQ<11>")
	)
	(segment
		(start 63.906654 -54.166516)
		(end 63.690246 -54.166516)
		(width 0.08382)
		(layer "In2.Cu")
		(net "M_BMC_DDR4_DQ<11>")
	)
	(segment
		(start 70.907656 -54.1274)
		(end 70.66026 -54.1274)
		(width 0.08382)
		(layer "In2.Cu")
		(net "M_BMC_DDR4_DQ<11>")
	)
	(segment
		(start 77.115162 -52.519834)
		(end 77.086968 -52.519834)
		(width 0.08382)
		(layer "In2.Cu")
		(net "M_BMC_DDR4_DQ<11>")
	)
	(segment
		(start 64.758824 -53.363876)
		(end 63.991236 -54.131464)
		(width 0.08382)
		(layer "In2.Cu")
		(net "M_BMC_DDR4_DQ<11>")
	)
	(segment
		(start 69.641466 -53.321204)
		(end 69.541136 -53.220874)
		(width 0.08382)
		(layer "In2.Cu")
		(net "M_BMC_DDR4_DQ<11>")
	)
	(segment
		(start 77.361542 -52.820316)
		(end 77.361542 -52.766214)
		(width 0.08382)
		(layer "In2.Cu")
		(net "M_BMC_DDR4_DQ<11>")
	)
	(segment
		(start 78.996794 -52.886356)
		(end 78.996794 -52.905152)
		(width 0.08382)
		(layer "In2.Cu")
		(net "M_BMC_DDR4_DQ<11>")
	)
	(segment
		(start 69.990462 -53.105304)
		(end 69.774562 -53.321204)
		(width 0.08382)
		(layer "In2.Cu")
		(net "M_BMC_DDR4_DQ<11>")
	)
	(segment
		(start 78.79969 -53.102256)
		(end 77.643482 -53.102256)
		(width 0.08382)
		(layer "In2.Cu")
		(net "M_BMC_DDR4_DQ<11>")
	)
	(segment
		(start 71.486522 -53.389784)
		(end 71.095616 -53.389784)
		(width 0.08382)
		(layer "In2.Cu")
		(net "M_BMC_DDR4_DQ<11>")
	)
	(segment
		(start 76.114402 -52.549044)
		(end 75.88631 -52.549044)
		(width 0.08382)
		(layer "In2.Cu")
		(net "M_BMC_DDR4_DQ<11>")
	)
	(segment
		(start 71.001636 -53.483764)
		(end 71.001636 -54.03342)
		(width 0.08382)
		(layer "In2.Cu")
		(net "M_BMC_DDR4_DQ<11>")
	)
	(segment
		(start 76.849986 -52.756816)
		(end 76.849986 -52.775612)
		(width 0.08382)
		(layer "In2.Cu")
		(net "M_BMC_DDR4_DQ<11>")
	)
	(segment
		(start 71.990712 -54.1274)
		(end 71.697596 -54.1274)
		(width 0.08382)
		(layer "In2.Cu")
		(net "M_BMC_DDR4_DQ<11>")
	)
	(segment
		(start 74.6506 -53.767736)
		(end 74.545444 -53.872892)
		(width 0.08382)
		(layer "In2.Cu")
		(net "M_BMC_DDR4_DQ<11>")
	)
	(segment
		(start 75.61453 -52.820824)
		(end 75.61453 -52.864004)
		(width 0.08382)
		(layer "In2.Cu")
		(net "M_BMC_DDR4_DQ<11>")
	)
	(segment
		(start 74.6506 -52.905152)
		(end 74.6506 -53.767736)
		(width 0.08382)
		(layer "In2.Cu")
		(net "M_BMC_DDR4_DQ<11>")
	)
	(segment
		(start 70.297294 -53.977032)
		(end 70.200266 -53.880004)
		(width 0.08382)
		(layer "In2.Cu")
		(net "M_BMC_DDR4_DQ<11>")
	)
	(segment
		(start 75.367388 -53.111146)
		(end 75.31481 -53.111146)
		(width 0.08382)
		(layer "In2.Cu")
		(net "M_BMC_DDR4_DQ<11>")
	)
	(segment
		(start 68.511166 -53.2257)
		(end 65.092326 -53.2257)
		(width 0.08382)
		(layer "In2.Cu")
		(net "M_BMC_DDR4_DQ<11>")
	)
	(arc
		(start 77.361542 -52.766214)
		(mid 77.289379 -52.591997)
		(end 77.115162 -52.519834)
		(width 0.08382)
		(layer "In2.Cu")
		(net "M_BMC_DDR4_DQ<11>")
	)
	(arc
		(start 75.61453 -52.864004)
		(mid 75.542144 -53.03876)
		(end 75.367388 -53.111146)
		(width 0.08382)
		(layer "In2.Cu")
		(net "M_BMC_DDR4_DQ<11>")
	)
	(arc
		(start 75.88631 -52.549044)
		(mid 75.694133 -52.628647)
		(end 75.61453 -52.820824)
		(width 0.08382)
		(layer "In2.Cu")
		(net "M_BMC_DDR4_DQ<11>")
	)
	(arc
		(start 70.123558 -53.105304)
		(mid 70.05701 -53.077664)
		(end 69.990462 -53.105304)
		(width 0.08382)
		(layer "In2.Cu")
		(net "M_BMC_DDR4_DQ<11>")
	)
	(arc
		(start 78.996794 -52.905152)
		(mid 78.939064 -53.044526)
		(end 78.79969 -53.102256)
		(width 0.08382)
		(layer "In2.Cu")
		(net "M_BMC_DDR4_DQ<11>")
	)
	(arc
		(start 77.643482 -53.102256)
		(mid 77.44412 -53.019678)
		(end 77.361542 -52.820316)
		(width 0.08382)
		(layer "In2.Cu")
		(net "M_BMC_DDR4_DQ<11>")
	)
	(arc
		(start 70.200266 -53.880004)
		(mid 70.172701 -53.813456)
		(end 70.200266 -53.746908)
		(width 0.08382)
		(layer "In2.Cu")
		(net "M_BMC_DDR4_DQ<11>")
	)
	(arc
		(start 75.31481 -53.111146)
		(mid 75.163942 -53.048654)
		(end 75.10145 -52.897786)
		(width 0.08382)
		(layer "In2.Cu")
		(net "M_BMC_DDR4_DQ<11>")
	)
	(arc
		(start 69.774562 -53.321204)
		(mid 69.708014 -53.348769)
		(end 69.641466 -53.321204)
		(width 0.08382)
		(layer "In2.Cu")
		(net "M_BMC_DDR4_DQ<11>")
	)
	(arc
		(start 69.541136 -53.220874)
		(mid 69.439262 -53.068314)
		(end 69.403468 -52.888388)
		(width 0.08382)
		(layer "In2.Cu")
		(net "M_BMC_DDR4_DQ<11>")
	)
	(arc
		(start 72.28205 -54.00675)
		(mid 72.148383 -54.096063)
		(end 71.990712 -54.1274)
		(width 0.08382)
		(layer "In2.Cu")
		(net "M_BMC_DDR4_DQ<11>")
	)
	(arc
		(start 70.416166 -53.531008)
		(mid 70.443806 -53.46446)
		(end 70.416166 -53.397912)
		(width 0.08382)
		(layer "In2.Cu")
		(net "M_BMC_DDR4_DQ<11>")
	)
	(arc
		(start 76.336906 -52.771548)
		(mid 76.271736 -52.614214)
		(end 76.114402 -52.549044)
		(width 0.08382)
		(layer "In2.Cu")
		(net "M_BMC_DDR4_DQ<11>")
	)
	(arc
		(start 78.79969 -52.689252)
		(mid 78.939064 -52.746982)
		(end 78.996794 -52.886356)
		(width 0.08382)
		(layer "In2.Cu")
		(net "M_BMC_DDR4_DQ<11>")
	)
	(arc
		(start 76.55941 -53.012594)
		(mid 76.402076 -52.947424)
		(end 76.336906 -52.79009)
		(width 0.08382)
		(layer "In2.Cu")
		(net "M_BMC_DDR4_DQ<11>")
	)
	(arc
		(start 71.603616 -53.506878)
		(mid 71.56932 -53.42408)
		(end 71.486522 -53.389784)
		(width 0.08382)
		(layer "In2.Cu")
		(net "M_BMC_DDR4_DQ<11>")
	)
	(arc
		(start 65.092326 -53.2257)
		(mid 64.911823 -53.261604)
		(end 64.758824 -53.363876)
		(width 0.08382)
		(layer "In2.Cu")
		(net "M_BMC_DDR4_DQ<11>")
	)
	(arc
		(start 76.849986 -52.775612)
		(mid 76.780576 -52.943184)
		(end 76.613004 -53.012594)
		(width 0.08382)
		(layer "In2.Cu")
		(net "M_BMC_DDR4_DQ<11>")
	)
	(arc
		(start 69.10578 -52.5272)
		(mid 68.908574 -52.608886)
		(end 68.826888 -52.806092)
		(width 0.08382)
		(layer "In2.Cu")
		(net "M_BMC_DDR4_DQ<11>")
	)
	(arc
		(start 63.991236 -54.131464)
		(mid 63.952429 -54.157394)
		(end 63.906654 -54.166516)
		(width 0.08382)
		(layer "In2.Cu")
		(net "M_BMC_DDR4_DQ<11>")
	)
	(arc
		(start 71.697596 -54.1274)
		(mid 71.631142 -54.099874)
		(end 71.603616 -54.03342)
		(width 0.08382)
		(layer "In2.Cu")
		(net "M_BMC_DDR4_DQ<11>")
	)
	(arc
		(start 70.66026 -54.1274)
		(mid 70.463816 -54.088325)
		(end 70.297294 -53.977032)
		(width 0.08382)
		(layer "In2.Cu")
		(net "M_BMC_DDR4_DQ<11>")
	)
	(arc
		(start 71.095616 -53.389784)
		(mid 71.029162 -53.41731)
		(end 71.001636 -53.483764)
		(width 0.08382)
		(layer "In2.Cu")
		(net "M_BMC_DDR4_DQ<11>")
	)
	(arc
		(start 74.841608 -52.665884)
		(mid 74.689482 -52.728896)
		(end 74.62647 -52.881022)
		(width 0.08382)
		(layer "In2.Cu")
		(net "M_BMC_DDR4_DQ<11>")
	)
	(arc
		(start 72.586596 -53.872892)
		(mid 72.428935 -53.904253)
		(end 72.295258 -53.993542)
		(width 0.08382)
		(layer "In2.Cu")
		(net "M_BMC_DDR4_DQ<11>")
	)
	(arc
		(start 71.001636 -54.03342)
		(mid 70.97411 -54.099874)
		(end 70.907656 -54.1274)
		(width 0.08382)
		(layer "In2.Cu")
		(net "M_BMC_DDR4_DQ<11>")
	)
	(arc
		(start 69.403468 -52.795932)
		(mid 69.324758 -52.60591)
		(end 69.134736 -52.5272)
		(width 0.08382)
		(layer "In2.Cu")
		(net "M_BMC_DDR4_DQ<11>")
	)
	(arc
		(start 75.10145 -52.879244)
		(mid 75.038958 -52.728376)
		(end 74.88809 -52.665884)
		(width 0.08382)
		(layer "In2.Cu")
		(net "M_BMC_DDR4_DQ<11>")
	)
	(arc
		(start 68.826888 -52.909978)
		(mid 68.734415 -53.133227)
		(end 68.511166 -53.2257)
		(width 0.08382)
		(layer "In2.Cu")
		(net "M_BMC_DDR4_DQ<11>")
	)
	(arc
		(start 77.086968 -52.519834)
		(mid 76.919396 -52.589244)
		(end 76.849986 -52.756816)
		(width 0.08382)
		(layer "In2.Cu")
		(net "M_BMC_DDR4_DQ<11>")
	)
	(segment
		(start 75.5523 -53.460142)
		(end 75.873356 -53.460142)
		(width 0.11684)
		(layer "F.Cu")
		(net "M_BMC_DDR4_DQ<10>")
	)
	(segment
		(start 74.652378 -52.30749)
		(end 74.868278 -52.30749)
		(width 0.11684)
		(layer "F.Cu")
		(net "M_BMC_DDR4_DQ<10>")
	)
	(segment
		(start 75.873356 -54.977792)
		(end 75.873356 -54.260496)
		(width 0.11684)
		(layer "F.Cu")
		(net "M_BMC_DDR4_DQ<10>")
	)
	(segment
		(start 75.355196 -52.917852)
		(end 75.912472 -52.917852)
		(width 0.11684)
		(layer "F.Cu")
		(net "M_BMC_DDR4_DQ<10>")
	)
	(segment
		(start 76.483972 -53.489352)
		(end 76.483972 -54.977792)
		(width 0.11684)
		(layer "F.Cu")
		(net "M_BMC_DDR4_DQ<10>")
	)
	(segment
		(start 76.190094 -55.27167)
		(end 76.167234 -55.27167)
		(width 0.11684)
		(layer "F.Cu")
		(net "M_BMC_DDR4_DQ<10>")
	)
	(segment
		(start 75.667108 -54.054248)
		(end 75.644248 -54.054248)
		(width 0.11684)
		(layer "F.Cu")
		(net "M_BMC_DDR4_DQ<10>")
	)
	(segment
		(start 64.894968 -53.771292)
		(end 65.290192 -54.166516)
		(width 0.11684)
		(layer "F.Cu")
		(net "M_BMC_DDR4_DQ<10>")
	)
	(segment
		(start 75.873356 -53.460142)
		(end 75.873356 -53.461158)
		(width 0.11684)
		(layer "F.Cu")
		(net "M_BMC_DDR4_DQ<10>")
	)
	(segment
		(start 75.061318 -52.50053)
		(end 75.061318 -52.623974)
		(width 0.11684)
		(layer "F.Cu")
		(net "M_BMC_DDR4_DQ<10>")
	)
	(segment
		(start 75.438 -53.848)
		(end 75.438 -53.574442)
		(width 0.11684)
		(layer "F.Cu")
		(net "M_BMC_DDR4_DQ<10>")
	)
	(via
		(at 75.873356 -53.461158)
		(size 0.4572)
		(drill 0.254)
		(layers "F.Cu" "B.Cu")
		(net "M_BMC_DDR4_DQ<10>")
	)
	(via
		(at 65.290192 -54.166516)
		(size 0.4572)
		(drill 0.254)
		(layers "F.Cu" "B.Cu")
		(net "M_BMC_DDR4_DQ<10>")
	)
	(arc
		(start 75.438 -53.574442)
		(mid 75.471478 -53.49362)
		(end 75.5523 -53.460142)
		(width 0.11684)
		(layer "F.Cu")
		(net "M_BMC_DDR4_DQ<10>")
	)
	(arc
		(start 75.061318 -52.623974)
		(mid 75.147393 -52.831777)
		(end 75.355196 -52.917852)
		(width 0.11684)
		(layer "F.Cu")
		(net "M_BMC_DDR4_DQ<10>")
	)
	(arc
		(start 76.167234 -55.27167)
		(mid 75.959431 -55.185595)
		(end 75.873356 -54.977792)
		(width 0.11684)
		(layer "F.Cu")
		(net "M_BMC_DDR4_DQ<10>")
	)
	(arc
		(start 75.873356 -54.260496)
		(mid 75.812947 -54.114657)
		(end 75.667108 -54.054248)
		(width 0.11684)
		(layer "F.Cu")
		(net "M_BMC_DDR4_DQ<10>")
	)
	(arc
		(start 75.912472 -52.917852)
		(mid 76.316584 -53.08524)
		(end 76.483972 -53.489352)
		(width 0.11684)
		(layer "F.Cu")
		(net "M_BMC_DDR4_DQ<10>")
	)
	(arc
		(start 74.868278 -52.30749)
		(mid 75.004778 -52.36403)
		(end 75.061318 -52.50053)
		(width 0.11684)
		(layer "F.Cu")
		(net "M_BMC_DDR4_DQ<10>")
	)
	(arc
		(start 76.483972 -54.977792)
		(mid 76.397897 -55.185595)
		(end 76.190094 -55.27167)
		(width 0.11684)
		(layer "F.Cu")
		(net "M_BMC_DDR4_DQ<10>")
	)
	(arc
		(start 75.644248 -54.054248)
		(mid 75.498409 -53.993839)
		(end 75.438 -53.848)
		(width 0.11684)
		(layer "F.Cu")
		(net "M_BMC_DDR4_DQ<10>")
	)
	(segment
		(start 74.13117 -54.944772)
		(end 73.707752 -54.944772)
		(width 0.08382)
		(layer "In2.Cu")
		(net "M_BMC_DDR4_DQ<10>")
	)
	(segment
		(start 74.82332 -53.909976)
		(end 74.811128 -53.922168)
		(width 0.08382)
		(layer "In2.Cu")
		(net "M_BMC_DDR4_DQ<10>")
	)
	(segment
		(start 68.554854 -53.924962)
		(end 66.275204 -53.924962)
		(width 0.08382)
		(layer "In2.Cu")
		(net "M_BMC_DDR4_DQ<10>")
	)
	(segment
		(start 69.107558 -54.665118)
		(end 69.29628 -54.476396)
		(width 0.08382)
		(layer "In2.Cu")
		(net "M_BMC_DDR4_DQ<10>")
	)
	(segment
		(start 76.733146 -53.793136)
		(end 76.09586 -53.793136)
		(width 0.08382)
		(layer "In2.Cu")
		(net "M_BMC_DDR4_DQ<10>")
	)
	(segment
		(start 76.005182 -54.15915)
		(end 76.703682 -54.15915)
		(width 0.08382)
		(layer "In2.Cu")
		(net "M_BMC_DDR4_DQ<10>")
	)
	(segment
		(start 73.535032 -55.198264)
		(end 70.319392 -55.198264)
		(width 0.08382)
		(layer "In2.Cu")
		(net "M_BMC_DDR4_DQ<10>")
	)
	(segment
		(start 76.703682 -54.557676)
		(end 75.682856 -54.557676)
		(width 0.08382)
		(layer "In2.Cu")
		(net "M_BMC_DDR4_DQ<10>")
	)
	(segment
		(start 66.123058 -53.964078)
		(end 65.910968 -54.166516)
		(width 0.08382)
		(layer "In2.Cu")
		(net "M_BMC_DDR4_DQ<10>")
	)
	(segment
		(start 75.44054 -53.88356)
		(end 74.887328 -53.88356)
		(width 0.08382)
		(layer "In2.Cu")
		(net "M_BMC_DDR4_DQ<10>")
	)
	(segment
		(start 69.511672 -55.069232)
		(end 69.389752 -55.069232)
		(width 0.08382)
		(layer "In2.Cu")
		(net "M_BMC_DDR4_DQ<10>")
	)
	(segment
		(start 75.873356 -53.457348)
		(end 76.865988 -53.457348)
		(width 0.08382)
		(layer "In2.Cu")
		(net "M_BMC_DDR4_DQ<10>")
	)
	(segment
		(start 76.954888 -53.57114)
		(end 76.954888 -53.571394)
		(width 0.08382)
		(layer "In2.Cu")
		(net "M_BMC_DDR4_DQ<10>")
	)
	(segment
		(start 74.698352 -55.215282)
		(end 74.30389 -55.215282)
		(width 0.08382)
		(layer "In2.Cu")
		(net "M_BMC_DDR4_DQ<10>")
	)
	(segment
		(start 69.107558 -54.787038)
		(end 69.107558 -54.665118)
		(width 0.08382)
		(layer "In2.Cu")
		(net "M_BMC_DDR4_DQ<10>")
	)
	(segment
		(start 74.784712 -53.986176)
		(end 74.784712 -55.128922)
		(width 0.08382)
		(layer "In2.Cu")
		(net "M_BMC_DDR4_DQ<10>")
	)
	(segment
		(start 65.910968 -54.166516)
		(end 65.290192 -54.166516)
		(width 0.08382)
		(layer "In2.Cu")
		(net "M_BMC_DDR4_DQ<10>")
	)
	(segment
		(start 75.87615 -54.012846)
		(end 75.87615 -54.030118)
		(width 0.08382)
		(layer "In2.Cu")
		(net "M_BMC_DDR4_DQ<10>")
	)
	(segment
		(start 69.29628 -54.476396)
		(end 69.29628 -54.354476)
		(width 0.08382)
		(layer "In2.Cu")
		(net "M_BMC_DDR4_DQ<10>")
	)
	(segment
		(start 75.873356 -53.461158)
		(end 75.873356 -53.457348)
		(width 0.08382)
		(layer "In2.Cu")
		(net "M_BMC_DDR4_DQ<10>")
	)
	(segment
		(start 73.621392 -55.031132)
		(end 73.621392 -55.111904)
		(width 0.08382)
		(layer "In2.Cu")
		(net "M_BMC_DDR4_DQ<10>")
	)
	(segment
		(start 69.700394 -54.88051)
		(end 69.511672 -55.069232)
		(width 0.08382)
		(layer "In2.Cu")
		(net "M_BMC_DDR4_DQ<10>")
	)
	(segment
		(start 69.389752 -55.069232)
		(end 69.107558 -54.787038)
		(width 0.08382)
		(layer "In2.Cu")
		(net "M_BMC_DDR4_DQ<10>")
	)
	(segment
		(start 76.894436 -54.349904)
		(end 76.894436 -54.366922)
		(width 0.08382)
		(layer "In2.Cu")
		(net "M_BMC_DDR4_DQ<10>")
	)
	(segment
		(start 75.534012 -54.321456)
		(end 75.534012 -53.972968)
		(width 0.08382)
		(layer "In2.Cu")
		(net "M_BMC_DDR4_DQ<10>")
	)
	(segment
		(start 69.29628 -54.354476)
		(end 69.087492 -54.145688)
		(width 0.08382)
		(layer "In2.Cu")
		(net "M_BMC_DDR4_DQ<10>")
	)
	(segment
		(start 69.822314 -54.88051)
		(end 69.700394 -54.88051)
		(width 0.08382)
		(layer "In2.Cu")
		(net "M_BMC_DDR4_DQ<10>")
	)
	(segment
		(start 70.013322 -55.071518)
		(end 69.822314 -54.88051)
		(width 0.08382)
		(layer "In2.Cu")
		(net "M_BMC_DDR4_DQ<10>")
	)
	(segment
		(start 74.21753 -55.128922)
		(end 74.21753 -55.031132)
		(width 0.08382)
		(layer "In2.Cu")
		(net "M_BMC_DDR4_DQ<10>")
	)
	(arc
		(start 74.784712 -55.128922)
		(mid 74.759418 -55.189988)
		(end 74.698352 -55.215282)
		(width 0.08382)
		(layer "In2.Cu")
		(net "M_BMC_DDR4_DQ<10>")
	)
	(arc
		(start 75.508612 -53.911754)
		(mid 75.47738 -53.890886)
		(end 75.44054 -53.88356)
		(width 0.08382)
		(layer "In2.Cu")
		(net "M_BMC_DDR4_DQ<10>")
	)
	(arc
		(start 76.951078 -53.52796)
		(mid 76.95398 -53.549462)
		(end 76.954888 -53.57114)
		(width 0.08382)
		(layer "In2.Cu")
		(net "M_BMC_DDR4_DQ<10>")
	)
	(arc
		(start 69.087492 -54.145688)
		(mid 68.84313 -53.982347)
		(end 68.554854 -53.924962)
		(width 0.08382)
		(layer "In2.Cu")
		(net "M_BMC_DDR4_DQ<10>")
	)
	(arc
		(start 70.319392 -55.198264)
		(mid 70.15376 -55.165318)
		(end 70.013322 -55.071518)
		(width 0.08382)
		(layer "In2.Cu")
		(net "M_BMC_DDR4_DQ<10>")
	)
	(arc
		(start 66.275204 -53.924962)
		(mid 66.196657 -53.934897)
		(end 66.123058 -53.964078)
		(width 0.08382)
		(layer "In2.Cu")
		(net "M_BMC_DDR4_DQ<10>")
	)
	(arc
		(start 74.30389 -55.215282)
		(mid 74.242824 -55.189988)
		(end 74.21753 -55.128922)
		(width 0.08382)
		(layer "In2.Cu")
		(net "M_BMC_DDR4_DQ<10>")
	)
	(arc
		(start 74.887328 -53.88356)
		(mid 74.85271 -53.890428)
		(end 74.82332 -53.909976)
		(width 0.08382)
		(layer "In2.Cu")
		(net "M_BMC_DDR4_DQ<10>")
	)
	(arc
		(start 73.621392 -55.111904)
		(mid 73.596098 -55.17297)
		(end 73.535032 -55.198264)
		(width 0.08382)
		(layer "In2.Cu")
		(net "M_BMC_DDR4_DQ<10>")
	)
	(arc
		(start 74.21753 -55.031132)
		(mid 74.192236 -54.970066)
		(end 74.13117 -54.944772)
		(width 0.08382)
		(layer "In2.Cu")
		(net "M_BMC_DDR4_DQ<10>")
	)
	(arc
		(start 74.811128 -53.922168)
		(mid 74.791559 -53.951549)
		(end 74.784712 -53.986176)
		(width 0.08382)
		(layer "In2.Cu")
		(net "M_BMC_DDR4_DQ<10>")
	)
	(arc
		(start 76.954888 -53.571394)
		(mid 76.889941 -53.728189)
		(end 76.733146 -53.793136)
		(width 0.08382)
		(layer "In2.Cu")
		(net "M_BMC_DDR4_DQ<10>")
	)
	(arc
		(start 76.09586 -53.793136)
		(mid 75.940502 -53.857488)
		(end 75.87615 -54.012846)
		(width 0.08382)
		(layer "In2.Cu")
		(net "M_BMC_DDR4_DQ<10>")
	)
	(arc
		(start 73.707752 -54.944772)
		(mid 73.646686 -54.970066)
		(end 73.621392 -55.031132)
		(width 0.08382)
		(layer "In2.Cu")
		(net "M_BMC_DDR4_DQ<10>")
	)
	(arc
		(start 75.87615 -54.030118)
		(mid 75.913943 -54.121357)
		(end 76.005182 -54.15915)
		(width 0.08382)
		(layer "In2.Cu")
		(net "M_BMC_DDR4_DQ<10>")
	)
	(arc
		(start 75.534012 -53.972968)
		(mid 75.527404 -53.939837)
		(end 75.508612 -53.911754)
		(width 0.08382)
		(layer "In2.Cu")
		(net "M_BMC_DDR4_DQ<10>")
	)
	(arc
		(start 76.703682 -54.15915)
		(mid 76.838565 -54.215021)
		(end 76.894436 -54.349904)
		(width 0.08382)
		(layer "In2.Cu")
		(net "M_BMC_DDR4_DQ<10>")
	)
	(arc
		(start 75.621388 -54.532276)
		(mid 75.556705 -54.435565)
		(end 75.534012 -54.321456)
		(width 0.08382)
		(layer "In2.Cu")
		(net "M_BMC_DDR4_DQ<10>")
	)
	(arc
		(start 76.894436 -54.366922)
		(mid 76.838565 -54.501805)
		(end 76.703682 -54.557676)
		(width 0.08382)
		(layer "In2.Cu")
		(net "M_BMC_DDR4_DQ<10>")
	)
	(arc
		(start 75.682856 -54.557676)
		(mid 75.649599 -54.551079)
		(end 75.621388 -54.532276)
		(width 0.08382)
		(layer "In2.Cu")
		(net "M_BMC_DDR4_DQ<10>")
	)
	(arc
		(start 76.865988 -53.457348)
		(mid 76.921357 -53.477222)
		(end 76.951078 -53.52796)
		(width 0.08382)
		(layer "In2.Cu")
		(net "M_BMC_DDR4_DQ<10>")
	)
	(segment
		(start 73.852278 -49.107344)
		(end 73.470516 -49.489106)
		(width 0.11684)
		(layer "F.Cu")
		(net "M_BMC_DDR4_DQ<0>")
	)
	(segment
		(start 63.295022 -51.371246)
		(end 63.690246 -51.76647)
		(width 0.11684)
		(layer "F.Cu")
		(net "M_BMC_DDR4_DQ<0>")
	)
	(via
		(at 63.690246 -51.76647)
		(size 0.4572)
		(drill 0.254)
		(layers "F.Cu" "B.Cu")
		(net "M_BMC_DDR4_DQ<0>")
	)
	(via
		(at 73.470516 -49.489106)
		(size 0.4572)
		(drill 0.254)
		(layers "F.Cu" "B.Cu")
		(net "M_BMC_DDR4_DQ<0>")
	)
	(segment
		(start 64.554862 -53.595778)
		(end 64.19342 -53.595778)
		(width 0.08382)
		(layer "In9.Cu")
		(net "M_BMC_DDR4_DQ<0>")
	)
	(segment
		(start 63.304166 -51.422554)
		(end 63.304166 -51.913282)
		(width 0.08382)
		(layer "In9.Cu")
		(net "M_BMC_DDR4_DQ<0>")
	)
	(segment
		(start 71.799196 -51.334162)
		(end 72.155812 -51.334162)
		(width 0.08382)
		(layer "In9.Cu")
		(net "M_BMC_DDR4_DQ<0>")
	)
	(segment
		(start 65.188592 -51.674268)
		(end 68.939156 -51.674268)
		(width 0.08382)
		(layer "In9.Cu")
		(net "M_BMC_DDR4_DQ<0>")
	)
	(segment
		(start 69.213476 -51.592988)
		(end 69.3293 -51.51755)
		(width 0.08382)
		(layer "In9.Cu")
		(net "M_BMC_DDR4_DQ<0>")
	)
	(segment
		(start 73.470516 -49.183798)
		(end 73.470516 -49.489106)
		(width 0.08382)
		(layer "In9.Cu")
		(net "M_BMC_DDR4_DQ<0>")
	)
	(segment
		(start 63.497968 -52.187856)
		(end 64.0207 -52.187856)
		(width 0.08382)
		(layer "In9.Cu")
		(net "M_BMC_DDR4_DQ<0>")
	)
	(segment
		(start 63.689738 -51.76647)
		(end 63.689738 -51.41849)
		(width 0.08382)
		(layer "In9.Cu")
		(net "M_BMC_DDR4_DQ<0>")
	)
	(segment
		(start 70.539356 -50.732944)
		(end 71.609712 -50.732944)
		(width 0.08382)
		(layer "In9.Cu")
		(net "M_BMC_DDR4_DQ<0>")
	)
	(segment
		(start 64.641222 -52.964842)
		(end 64.641222 -53.509418)
		(width 0.08382)
		(layer "In9.Cu")
		(net "M_BMC_DDR4_DQ<0>")
	)
	(segment
		(start 64.948054 -52.878482)
		(end 64.727582 -52.878482)
		(width 0.08382)
		(layer "In9.Cu")
		(net "M_BMC_DDR4_DQ<0>")
	)
	(segment
		(start 62.419484 -52.974494)
		(end 63.189612 -52.974494)
		(width 0.08382)
		(layer "In9.Cu")
		(net "M_BMC_DDR4_DQ<0>")
	)
	(segment
		(start 72.258936 -51.231038)
		(end 72.258936 -50.798984)
		(width 0.08382)
		(layer "In9.Cu")
		(net "M_BMC_DDR4_DQ<0>")
	)
	(segment
		(start 64.663574 -51.441096)
		(end 64.663574 -52.184808)
		(width 0.08382)
		(layer "In9.Cu")
		(net "M_BMC_DDR4_DQ<0>")
	)
	(segment
		(start 73.063862 -50.626264)
		(end 73.063862 -49.183798)
		(width 0.08382)
		(layer "In9.Cu")
		(net "M_BMC_DDR4_DQ<0>")
	)
	(segment
		(start 63.40094 -53.78958)
		(end 64.941704 -53.78958)
		(width 0.08382)
		(layer "In9.Cu")
		(net "M_BMC_DDR4_DQ<0>")
	)
	(segment
		(start 72.345296 -50.712624)
		(end 72.977502 -50.712624)
		(width 0.08382)
		(layer "In9.Cu")
		(net "M_BMC_DDR4_DQ<0>")
	)
	(segment
		(start 62.256416 -52.241704)
		(end 62.256416 -52.811426)
		(width 0.08382)
		(layer "In9.Cu")
		(net "M_BMC_DDR4_DQ<0>")
	)
	(segment
		(start 69.465698 -51.470052)
		(end 70.366636 -51.470052)
		(width 0.08382)
		(layer "In9.Cu")
		(net "M_BMC_DDR4_DQ<0>")
	)
	(segment
		(start 63.690246 -51.76647)
		(end 63.689738 -51.76647)
		(width 0.08382)
		(layer "In9.Cu")
		(net "M_BMC_DDR4_DQ<0>")
	)
	(segment
		(start 64.20104 -51.354736)
		(end 64.577214 -51.354736)
		(width 0.08382)
		(layer "In9.Cu")
		(net "M_BMC_DDR4_DQ<0>")
	)
	(segment
		(start 69.333872 -51.514756)
		(end 69.365876 -51.496468)
		(width 0.08382)
		(layer "In9.Cu")
		(net "M_BMC_DDR4_DQ<0>")
	)
	(segment
		(start 64.10706 -53.509418)
		(end 64.10706 -53.042058)
		(width 0.08382)
		(layer "In9.Cu")
		(net "M_BMC_DDR4_DQ<0>")
	)
	(segment
		(start 64.006476 -52.941474)
		(end 63.5508 -52.941474)
		(width 0.08382)
		(layer "In9.Cu")
		(net "M_BMC_DDR4_DQ<0>")
	)
	(segment
		(start 65.102232 -52.184808)
		(end 65.102232 -51.760628)
		(width 0.08382)
		(layer "In9.Cu")
		(net "M_BMC_DDR4_DQ<0>")
	)
	(segment
		(start 71.696072 -50.819304)
		(end 71.696072 -51.231038)
		(width 0.08382)
		(layer "In9.Cu")
		(net "M_BMC_DDR4_DQ<0>")
	)
	(segment
		(start 70.452996 -51.383692)
		(end 70.452996 -50.819304)
		(width 0.08382)
		(layer "In9.Cu")
		(net "M_BMC_DDR4_DQ<0>")
	)
	(segment
		(start 63.603378 -51.33213)
		(end 63.39459 -51.33213)
		(width 0.08382)
		(layer "In9.Cu")
		(net "M_BMC_DDR4_DQ<0>")
	)
	(segment
		(start 65.034414 -53.69687)
		(end 65.034414 -52.964842)
		(width 0.08382)
		(layer "In9.Cu")
		(net "M_BMC_DDR4_DQ<0>")
	)
	(segment
		(start 63.304166 -53.089048)
		(end 63.304166 -53.692806)
		(width 0.08382)
		(layer "In9.Cu")
		(net "M_BMC_DDR4_DQ<0>")
	)
	(segment
		(start 73.150222 -49.097438)
		(end 73.384156 -49.097438)
		(width 0.08382)
		(layer "In9.Cu")
		(net "M_BMC_DDR4_DQ<0>")
	)
	(segment
		(start 63.31458 -52.663598)
		(end 63.31458 -52.371244)
		(width 0.08382)
		(layer "In9.Cu")
		(net "M_BMC_DDR4_DQ<0>")
	)
	(segment
		(start 64.749934 -52.271168)
		(end 65.015872 -52.271168)
		(width 0.08382)
		(layer "In9.Cu")
		(net "M_BMC_DDR4_DQ<0>")
	)
	(segment
		(start 64.10706 -52.101496)
		(end 64.10706 -51.448716)
		(width 0.08382)
		(layer "In9.Cu")
		(net "M_BMC_DDR4_DQ<0>")
	)
	(segment
		(start 63.062104 -52.155344)
		(end 62.342776 -52.155344)
		(width 0.08382)
		(layer "In9.Cu")
		(net "M_BMC_DDR4_DQ<0>")
	)
	(arc
		(start 69.365876 -51.496468)
		(mid 69.414071 -51.476779)
		(end 69.465698 -51.470052)
		(width 0.08382)
		(layer "In9.Cu")
		(net "M_BMC_DDR4_DQ<0>")
	)
	(arc
		(start 63.5508 -52.941474)
		(mid 63.507568 -52.936187)
		(end 63.46698 -52.920392)
		(width 0.08382)
		(layer "In9.Cu")
		(net "M_BMC_DDR4_DQ<0>")
	)
	(arc
		(start 64.941704 -53.78958)
		(mid 65.00726 -53.762426)
		(end 65.034414 -53.69687)
		(width 0.08382)
		(layer "In9.Cu")
		(net "M_BMC_DDR4_DQ<0>")
	)
	(arc
		(start 63.39459 -51.33213)
		(mid 63.330651 -51.358615)
		(end 63.304166 -51.422554)
		(width 0.08382)
		(layer "In9.Cu")
		(net "M_BMC_DDR4_DQ<0>")
	)
	(arc
		(start 70.366636 -51.470052)
		(mid 70.427702 -51.444758)
		(end 70.452996 -51.383692)
		(width 0.08382)
		(layer "In9.Cu")
		(net "M_BMC_DDR4_DQ<0>")
	)
	(arc
		(start 63.304166 -51.913282)
		(mid 63.233268 -52.084446)
		(end 63.062104 -52.155344)
		(width 0.08382)
		(layer "In9.Cu")
		(net "M_BMC_DDR4_DQ<0>")
	)
	(arc
		(start 63.189612 -52.974494)
		(mid 63.270614 -53.008046)
		(end 63.304166 -53.089048)
		(width 0.08382)
		(layer "In9.Cu")
		(net "M_BMC_DDR4_DQ<0>")
	)
	(arc
		(start 64.19342 -53.595778)
		(mid 64.132354 -53.570484)
		(end 64.10706 -53.509418)
		(width 0.08382)
		(layer "In9.Cu")
		(net "M_BMC_DDR4_DQ<0>")
	)
	(arc
		(start 65.102232 -51.760628)
		(mid 65.127526 -51.699562)
		(end 65.188592 -51.674268)
		(width 0.08382)
		(layer "In9.Cu")
		(net "M_BMC_DDR4_DQ<0>")
	)
	(arc
		(start 68.939156 -51.674268)
		(mid 69.082226 -51.653564)
		(end 69.213476 -51.592988)
		(width 0.08382)
		(layer "In9.Cu")
		(net "M_BMC_DDR4_DQ<0>")
	)
	(arc
		(start 62.342776 -52.155344)
		(mid 62.28171 -52.180638)
		(end 62.256416 -52.241704)
		(width 0.08382)
		(layer "In9.Cu")
		(net "M_BMC_DDR4_DQ<0>")
	)
	(arc
		(start 73.384156 -49.097438)
		(mid 73.445222 -49.122732)
		(end 73.470516 -49.183798)
		(width 0.08382)
		(layer "In9.Cu")
		(net "M_BMC_DDR4_DQ<0>")
	)
	(arc
		(start 64.727582 -52.878482)
		(mid 64.666516 -52.903776)
		(end 64.641222 -52.964842)
		(width 0.08382)
		(layer "In9.Cu")
		(net "M_BMC_DDR4_DQ<0>")
	)
	(arc
		(start 64.10706 -51.448716)
		(mid 64.134586 -51.382262)
		(end 64.20104 -51.354736)
		(width 0.08382)
		(layer "In9.Cu")
		(net "M_BMC_DDR4_DQ<0>")
	)
	(arc
		(start 65.015872 -52.271168)
		(mid 65.076938 -52.245874)
		(end 65.102232 -52.184808)
		(width 0.08382)
		(layer "In9.Cu")
		(net "M_BMC_DDR4_DQ<0>")
	)
	(arc
		(start 64.663574 -52.184808)
		(mid 64.688868 -52.245874)
		(end 64.749934 -52.271168)
		(width 0.08382)
		(layer "In9.Cu")
		(net "M_BMC_DDR4_DQ<0>")
	)
	(arc
		(start 72.155812 -51.334162)
		(mid 72.228732 -51.303958)
		(end 72.258936 -51.231038)
		(width 0.08382)
		(layer "In9.Cu")
		(net "M_BMC_DDR4_DQ<0>")
	)
	(arc
		(start 70.452996 -50.819304)
		(mid 70.47829 -50.758238)
		(end 70.539356 -50.732944)
		(width 0.08382)
		(layer "In9.Cu")
		(net "M_BMC_DDR4_DQ<0>")
	)
	(arc
		(start 63.689738 -51.41849)
		(mid 63.664444 -51.357424)
		(end 63.603378 -51.33213)
		(width 0.08382)
		(layer "In9.Cu")
		(net "M_BMC_DDR4_DQ<0>")
	)
	(arc
		(start 71.696072 -51.231038)
		(mid 71.726276 -51.303958)
		(end 71.799196 -51.334162)
		(width 0.08382)
		(layer "In9.Cu")
		(net "M_BMC_DDR4_DQ<0>")
	)
	(arc
		(start 64.641222 -53.509418)
		(mid 64.615928 -53.570484)
		(end 64.554862 -53.595778)
		(width 0.08382)
		(layer "In9.Cu")
		(net "M_BMC_DDR4_DQ<0>")
	)
	(arc
		(start 72.977502 -50.712624)
		(mid 73.038568 -50.68733)
		(end 73.063862 -50.626264)
		(width 0.08382)
		(layer "In9.Cu")
		(net "M_BMC_DDR4_DQ<0>")
	)
	(arc
		(start 64.0207 -52.187856)
		(mid 64.081766 -52.162562)
		(end 64.10706 -52.101496)
		(width 0.08382)
		(layer "In9.Cu")
		(net "M_BMC_DDR4_DQ<0>")
	)
	(arc
		(start 63.31458 -52.371244)
		(mid 63.368293 -52.241569)
		(end 63.497968 -52.187856)
		(width 0.08382)
		(layer "In9.Cu")
		(net "M_BMC_DDR4_DQ<0>")
	)
	(arc
		(start 69.3293 -51.51755)
		(mid 69.331566 -51.51612)
		(end 69.333872 -51.514756)
		(width 0.08382)
		(layer "In9.Cu")
		(net "M_BMC_DDR4_DQ<0>")
	)
	(arc
		(start 73.063862 -49.183798)
		(mid 73.089156 -49.122732)
		(end 73.150222 -49.097438)
		(width 0.08382)
		(layer "In9.Cu")
		(net "M_BMC_DDR4_DQ<0>")
	)
	(arc
		(start 71.609712 -50.732944)
		(mid 71.670778 -50.758238)
		(end 71.696072 -50.819304)
		(width 0.08382)
		(layer "In9.Cu")
		(net "M_BMC_DDR4_DQ<0>")
	)
	(arc
		(start 62.256416 -52.811426)
		(mid 62.304178 -52.926732)
		(end 62.419484 -52.974494)
		(width 0.08382)
		(layer "In9.Cu")
		(net "M_BMC_DDR4_DQ<0>")
	)
	(arc
		(start 64.577214 -51.354736)
		(mid 64.63828 -51.38003)
		(end 64.663574 -51.441096)
		(width 0.08382)
		(layer "In9.Cu")
		(net "M_BMC_DDR4_DQ<0>")
	)
	(arc
		(start 64.10706 -53.042058)
		(mid 64.0776 -52.970934)
		(end 64.006476 -52.941474)
		(width 0.08382)
		(layer "In9.Cu")
		(net "M_BMC_DDR4_DQ<0>")
	)
	(arc
		(start 63.304166 -53.692806)
		(mid 63.33251 -53.761236)
		(end 63.40094 -53.78958)
		(width 0.08382)
		(layer "In9.Cu")
		(net "M_BMC_DDR4_DQ<0>")
	)
	(arc
		(start 63.46698 -52.920392)
		(mid 63.355481 -52.812942)
		(end 63.31458 -52.663598)
		(width 0.08382)
		(layer "In9.Cu")
		(net "M_BMC_DDR4_DQ<0>")
	)
	(arc
		(start 65.034414 -52.964842)
		(mid 65.00912 -52.903776)
		(end 64.948054 -52.878482)
		(width 0.08382)
		(layer "In9.Cu")
		(net "M_BMC_DDR4_DQ<0>")
	)
	(arc
		(start 72.258936 -50.798984)
		(mid 72.28423 -50.737918)
		(end 72.345296 -50.712624)
		(width 0.08382)
		(layer "In9.Cu")
		(net "M_BMC_DDR4_DQ<0>")
	)
	(segment
		(start 79.452216 -45.107352)
		(end 79.99222 -45.107352)
		(width 0.11684)
		(layer "F.Cu")
		(net "M_BMC_DDR4_BG1")
	)
	(via
		(at 79.99222 -45.107352)
		(size 0.4572)
		(drill 0.254)
		(layers "F.Cu" "B.Cu")
		(net "M_BMC_DDR4_BG1")
	)
	(segment
		(start 83.507326 -46.586394)
		(end 83.03768 -46.116748)
		(width 0.11684)
		(layer "B.Cu")
		(net "M_BMC_DDR4_BG1")
	)
	(segment
		(start 81.78419 -45.603414)
		(end 81.335118 -45.603414)
		(width 0.11684)
		(layer "B.Cu")
		(net "M_BMC_DDR4_BG1")
	)
	(segment
		(start 80.785716 -45.054012)
		(end 80.729836 -45.054012)
		(width 0.11684)
		(layer "B.Cu")
		(net "M_BMC_DDR4_BG1")
	)
	(segment
		(start 82.297524 -46.116748)
		(end 81.78419 -45.603414)
		(width 0.11684)
		(layer "B.Cu")
		(net "M_BMC_DDR4_BG1")
	)
	(segment
		(start 81.335118 -45.603414)
		(end 80.785716 -45.054012)
		(width 0.11684)
		(layer "B.Cu")
		(net "M_BMC_DDR4_BG1")
	)
	(segment
		(start 83.03768 -46.116748)
		(end 82.297524 -46.116748)
		(width 0.11684)
		(layer "B.Cu")
		(net "M_BMC_DDR4_BG1")
	)
	(segment
		(start 80.729836 -45.054012)
		(end 80.387952 -45.054012)
		(width 0.11684)
		(layer "B.Cu")
		(net "M_BMC_DDR4_BG1")
	)
	(segment
		(start 80.334612 -45.107352)
		(end 79.99222 -45.107352)
		(width 0.11684)
		(layer "B.Cu")
		(net "M_BMC_DDR4_BG1")
	)
	(segment
		(start 83.56727 -46.586394)
		(end 83.507326 -46.586394)
		(width 0.11684)
		(layer "B.Cu")
		(net "M_BMC_DDR4_BG1")
	)
	(segment
		(start 80.387952 -45.054012)
		(end 80.334612 -45.107352)
		(width 0.11684)
		(layer "B.Cu")
		(net "M_BMC_DDR4_BG1")
	)
	(segment
		(start 79.452216 -43.507406)
		(end 79.99222 -43.507406)
		(width 0.11684)
		(layer "F.Cu")
		(net "M_BMC_DDR4_ALERT_N")
	)
	(segment
		(start 62.494922 -48.9712)
		(end 62.890146 -48.575976)
		(width 0.11684)
		(layer "F.Cu")
		(net "M_BMC_DDR4_ALERT_N")
	)
	(via
		(at 62.890146 -48.575976)
		(size 0.4572)
		(drill 0.254)
		(layers "F.Cu" "B.Cu")
		(net "M_BMC_DDR4_ALERT_N")
	)
	(via
		(at 79.99222 -43.507406)
		(size 0.4572)
		(drill 0.254)
		(layers "F.Cu" "B.Cu")
		(net "M_BMC_DDR4_ALERT_N")
	)
	(segment
		(start 82.285586 -43.538394)
		(end 82.76717 -43.538394)
		(width 0.11684)
		(layer "B.Cu")
		(net "M_BMC_DDR4_ALERT_N")
	)
	(segment
		(start 82.254598 -43.507406)
		(end 82.285586 -43.538394)
		(width 0.11684)
		(layer "B.Cu")
		(net "M_BMC_DDR4_ALERT_N")
	)
	(segment
		(start 79.99222 -43.507406)
		(end 82.254598 -43.507406)
		(width 0.11684)
		(layer "B.Cu")
		(net "M_BMC_DDR4_ALERT_N")
	)
	(segment
		(start 73.147428 -45.912532)
		(end 73.510394 -45.912532)
		(width 0.08382)
		(layer "In9.Cu")
		(net "M_BMC_DDR4_ALERT_N")
	)
	(segment
		(start 70.875144 -46.153832)
		(end 71.737474 -45.480224)
		(width 0.08382)
		(layer "In9.Cu")
		(net "M_BMC_DDR4_ALERT_N")
	)
	(segment
		(start 80.6577 -43.507406)
		(end 79.99222 -43.507406)
		(width 0.08382)
		(layer "In9.Cu")
		(net "M_BMC_DDR4_ALERT_N")
	)
	(segment
		(start 73.649586 -45.97019)
		(end 73.962768 -46.283372)
		(width 0.08382)
		(layer "In9.Cu")
		(net "M_BMC_DDR4_ALERT_N")
	)
	(segment
		(start 63.649098 -48.17745)
		(end 63.80861 -48.17745)
		(width 0.08382)
		(layer "In9.Cu")
		(net "M_BMC_DDR4_ALERT_N")
	)
	(segment
		(start 63.1444 -48.575976)
		(end 63.467742 -48.252634)
		(width 0.08382)
		(layer "In9.Cu")
		(net "M_BMC_DDR4_ALERT_N")
	)
	(segment
		(start 80.224376 -47.234602)
		(end 80.224376 -46.863762)
		(width 0.08382)
		(layer "In9.Cu")
		(net "M_BMC_DDR4_ALERT_N")
	)
	(segment
		(start 67.694556 -47.66564)
		(end 67.822826 -47.53737)
		(width 0.08382)
		(layer "In9.Cu")
		(net "M_BMC_DDR4_ALERT_N")
	)
	(segment
		(start 73.053448 -45.538898)
		(end 73.053448 -45.818552)
		(width 0.08382)
		(layer "In9.Cu")
		(net "M_BMC_DDR4_ALERT_N")
	)
	(segment
		(start 64.204342 -47.563786)
		(end 66.543682 -47.563786)
		(width 0.08382)
		(layer "In9.Cu")
		(net "M_BMC_DDR4_ALERT_N")
	)
	(segment
		(start 79.506826 -47.865284)
		(end 80.696308 -47.865284)
		(width 0.08382)
		(layer "In9.Cu")
		(net "M_BMC_DDR4_ALERT_N")
	)
	(segment
		(start 64.099186 -47.886874)
		(end 64.099186 -47.668942)
		(width 0.08382)
		(layer "In9.Cu")
		(net "M_BMC_DDR4_ALERT_N")
	)
	(segment
		(start 80.310736 -46.777402)
		(end 80.684878 -46.777402)
		(width 0.08382)
		(layer "In9.Cu")
		(net "M_BMC_DDR4_ALERT_N")
	)
	(segment
		(start 80.73644 -47.320962)
		(end 80.310736 -47.320962)
		(width 0.08382)
		(layer "In9.Cu")
		(net "M_BMC_DDR4_ALERT_N")
	)
	(segment
		(start 69.008244 -46.613064)
		(end 69.686424 -46.613064)
		(width 0.08382)
		(layer "In9.Cu")
		(net "M_BMC_DDR4_ALERT_N")
	)
	(segment
		(start 71.817484 -45.452538)
		(end 72.967088 -45.452538)
		(width 0.08382)
		(layer "In9.Cu")
		(net "M_BMC_DDR4_ALERT_N")
	)
	(segment
		(start 66.716402 -48.214788)
		(end 67.088512 -48.214788)
		(width 0.08382)
		(layer "In9.Cu")
		(net "M_BMC_DDR4_ALERT_N")
	)
	(segment
		(start 77.902562 -46.433232)
		(end 77.902562 -46.618906)
		(width 0.08382)
		(layer "In9.Cu")
		(net "M_BMC_DDR4_ALERT_N")
	)
	(segment
		(start 74.052176 -46.320456)
		(end 77.789786 -46.320456)
		(width 0.08382)
		(layer "In9.Cu")
		(net "M_BMC_DDR4_ALERT_N")
	)
	(segment
		(start 77.988922 -46.705266)
		(end 79.295244 -46.705266)
		(width 0.08382)
		(layer "In9.Cu")
		(net "M_BMC_DDR4_ALERT_N")
	)
	(segment
		(start 67.611498 -47.850552)
		(end 67.637152 -47.786036)
		(width 0.08382)
		(layer "In9.Cu")
		(net "M_BMC_DDR4_ALERT_N")
	)
	(segment
		(start 79.412846 -46.822868)
		(end 79.412846 -47.771304)
		(width 0.08382)
		(layer "In9.Cu")
		(net "M_BMC_DDR4_ALERT_N")
	)
	(segment
		(start 70.196456 -46.181518)
		(end 70.79488 -46.181518)
		(width 0.08382)
		(layer "In9.Cu")
		(net "M_BMC_DDR4_ALERT_N")
	)
	(segment
		(start 67.467988 -48.057562)
		(end 67.564 -47.96155)
		(width 0.08382)
		(layer "In9.Cu")
		(net "M_BMC_DDR4_ALERT_N")
	)
	(segment
		(start 66.630042 -47.650146)
		(end 66.630042 -48.128428)
		(width 0.08382)
		(layer "In9.Cu")
		(net "M_BMC_DDR4_ALERT_N")
	)
	(segment
		(start 68.089018 -47.387002)
		(end 68.76034 -46.71568)
		(width 0.08382)
		(layer "In9.Cu")
		(net "M_BMC_DDR4_ALERT_N")
	)
	(segment
		(start 69.753226 -46.585378)
		(end 70.1294 -46.209204)
		(width 0.08382)
		(layer "In9.Cu")
		(net "M_BMC_DDR4_ALERT_N")
	)
	(segment
		(start 62.890146 -48.575976)
		(end 63.1444 -48.575976)
		(width 0.08382)
		(layer "In9.Cu")
		(net "M_BMC_DDR4_ALERT_N")
	)
	(segment
		(start 80.8228 -47.738792)
		(end 80.8228 -47.407322)
		(width 0.08382)
		(layer "In9.Cu")
		(net "M_BMC_DDR4_ALERT_N")
	)
	(segment
		(start 80.771238 -46.691042)
		(end 80.771238 -43.620944)
		(width 0.08382)
		(layer "In9.Cu")
		(net "M_BMC_DDR4_ALERT_N")
	)
	(arc
		(start 80.224376 -46.863762)
		(mid 80.24967 -46.802696)
		(end 80.310736 -46.777402)
		(width 0.08382)
		(layer "In9.Cu")
		(net "M_BMC_DDR4_ALERT_N")
	)
	(arc
		(start 79.295244 -46.705266)
		(mid 79.378401 -46.739711)
		(end 79.412846 -46.822868)
		(width 0.08382)
		(layer "In9.Cu")
		(net "M_BMC_DDR4_ALERT_N")
	)
	(arc
		(start 73.053448 -45.818552)
		(mid 73.080974 -45.885006)
		(end 73.147428 -45.912532)
		(width 0.08382)
		(layer "In9.Cu")
		(net "M_BMC_DDR4_ALERT_N")
	)
	(arc
		(start 67.901312 -47.4853)
		(mid 67.956065 -47.462606)
		(end 68.010786 -47.439834)
		(width 0.08382)
		(layer "In9.Cu")
		(net "M_BMC_DDR4_ALERT_N")
	)
	(arc
		(start 72.967088 -45.452538)
		(mid 73.028154 -45.477832)
		(end 73.053448 -45.538898)
		(width 0.08382)
		(layer "In9.Cu")
		(net "M_BMC_DDR4_ALERT_N")
	)
	(arc
		(start 71.737474 -45.480224)
		(mid 71.775161 -45.459674)
		(end 71.817484 -45.452538)
		(width 0.08382)
		(layer "In9.Cu")
		(net "M_BMC_DDR4_ALERT_N")
	)
	(arc
		(start 80.684878 -46.777402)
		(mid 80.745944 -46.752108)
		(end 80.771238 -46.691042)
		(width 0.08382)
		(layer "In9.Cu")
		(net "M_BMC_DDR4_ALERT_N")
	)
	(arc
		(start 66.630042 -48.128428)
		(mid 66.655336 -48.189494)
		(end 66.716402 -48.214788)
		(width 0.08382)
		(layer "In9.Cu")
		(net "M_BMC_DDR4_ALERT_N")
	)
	(arc
		(start 67.088512 -48.214788)
		(mid 67.293885 -48.173919)
		(end 67.467988 -48.057562)
		(width 0.08382)
		(layer "In9.Cu")
		(net "M_BMC_DDR4_ALERT_N")
	)
	(arc
		(start 80.8228 -47.407322)
		(mid 80.797506 -47.346256)
		(end 80.73644 -47.320962)
		(width 0.08382)
		(layer "In9.Cu")
		(net "M_BMC_DDR4_ALERT_N")
	)
	(arc
		(start 80.771238 -43.620944)
		(mid 80.737983 -43.540661)
		(end 80.6577 -43.507406)
		(width 0.08382)
		(layer "In9.Cu")
		(net "M_BMC_DDR4_ALERT_N")
	)
	(arc
		(start 63.80861 -48.17745)
		(mid 64.014078 -48.092342)
		(end 64.099186 -47.886874)
		(width 0.08382)
		(layer "In9.Cu")
		(net "M_BMC_DDR4_ALERT_N")
	)
	(arc
		(start 70.79488 -46.181518)
		(mid 70.837327 -46.174396)
		(end 70.875144 -46.153832)
		(width 0.08382)
		(layer "In9.Cu")
		(net "M_BMC_DDR4_ALERT_N")
	)
	(arc
		(start 80.696308 -47.865284)
		(mid 80.785751 -47.828235)
		(end 80.8228 -47.738792)
		(width 0.08382)
		(layer "In9.Cu")
		(net "M_BMC_DDR4_ALERT_N")
	)
	(arc
		(start 77.902562 -46.618906)
		(mid 77.927856 -46.679972)
		(end 77.988922 -46.705266)
		(width 0.08382)
		(layer "In9.Cu")
		(net "M_BMC_DDR4_ALERT_N")
	)
	(arc
		(start 67.564 -47.96155)
		(mid 67.58835 -47.906308)
		(end 67.611498 -47.850552)
		(width 0.08382)
		(layer "In9.Cu")
		(net "M_BMC_DDR4_ALERT_N")
	)
	(arc
		(start 66.543682 -47.563786)
		(mid 66.604748 -47.58908)
		(end 66.630042 -47.650146)
		(width 0.08382)
		(layer "In9.Cu")
		(net "M_BMC_DDR4_ALERT_N")
	)
	(arc
		(start 68.76034 -46.71568)
		(mid 68.874094 -46.639735)
		(end 69.008244 -46.613064)
		(width 0.08382)
		(layer "In9.Cu")
		(net "M_BMC_DDR4_ALERT_N")
	)
	(arc
		(start 69.686424 -46.613064)
		(mid 69.722583 -46.605872)
		(end 69.753226 -46.585378)
		(width 0.08382)
		(layer "In9.Cu")
		(net "M_BMC_DDR4_ALERT_N")
	)
	(arc
		(start 73.510394 -45.912532)
		(mid 73.585725 -45.927516)
		(end 73.649586 -45.97019)
		(width 0.08382)
		(layer "In9.Cu")
		(net "M_BMC_DDR4_ALERT_N")
	)
	(arc
		(start 67.637152 -47.786036)
		(mid 67.640197 -47.776774)
		(end 67.642232 -47.76724)
		(width 0.08382)
		(layer "In9.Cu")
		(net "M_BMC_DDR4_ALERT_N")
	)
	(arc
		(start 68.010786 -47.439834)
		(mid 68.052478 -47.417234)
		(end 68.089018 -47.387002)
		(width 0.08382)
		(layer "In9.Cu")
		(net "M_BMC_DDR4_ALERT_N")
	)
	(arc
		(start 64.099186 -47.668942)
		(mid 64.129985 -47.594585)
		(end 64.204342 -47.563786)
		(width 0.08382)
		(layer "In9.Cu")
		(net "M_BMC_DDR4_ALERT_N")
	)
	(arc
		(start 63.467742 -48.252634)
		(mid 63.550935 -48.196983)
		(end 63.649098 -48.17745)
		(width 0.08382)
		(layer "In9.Cu")
		(net "M_BMC_DDR4_ALERT_N")
	)
	(arc
		(start 77.789786 -46.320456)
		(mid 77.869531 -46.353487)
		(end 77.902562 -46.433232)
		(width 0.08382)
		(layer "In9.Cu")
		(net "M_BMC_DDR4_ALERT_N")
	)
	(arc
		(start 73.962768 -46.283372)
		(mid 74.003774 -46.310835)
		(end 74.052176 -46.320456)
		(width 0.08382)
		(layer "In9.Cu")
		(net "M_BMC_DDR4_ALERT_N")
	)
	(arc
		(start 70.1294 -46.209204)
		(mid 70.16018 -46.188701)
		(end 70.196456 -46.181518)
		(width 0.08382)
		(layer "In9.Cu")
		(net "M_BMC_DDR4_ALERT_N")
	)
	(arc
		(start 80.310736 -47.320962)
		(mid 80.24967 -47.295668)
		(end 80.224376 -47.234602)
		(width 0.08382)
		(layer "In9.Cu")
		(net "M_BMC_DDR4_ALERT_N")
	)
	(arc
		(start 67.642232 -47.76724)
		(mid 67.660385 -47.712312)
		(end 67.694556 -47.66564)
		(width 0.08382)
		(layer "In9.Cu")
		(net "M_BMC_DDR4_ALERT_N")
	)
	(arc
		(start 79.412846 -47.771304)
		(mid 79.440372 -47.837758)
		(end 79.506826 -47.865284)
		(width 0.08382)
		(layer "In9.Cu")
		(net "M_BMC_DDR4_ALERT_N")
	)
	(arc
		(start 67.822826 -47.53737)
		(mid 67.859488 -47.507442)
		(end 67.901312 -47.4853)
		(width 0.08382)
		(layer "In9.Cu")
		(net "M_BMC_DDR4_ALERT_N")
	)
	(via
		(at 51.830224 -32.74949)
		(size 0.7112)
		(drill 0.3556)
		(layers "F.Cu" "B.Cu")
		(net "JTAG_MB_TRST_N")
	)
	(segment
		(start 51.3334 -33.246314)
		(end 51.3334 -34.06775)
		(width 0.11684)
		(layer "B.Cu")
		(net "JTAG_MB_TRST_N")
	)
	(segment
		(start 51.830224 -32.74949)
		(end 51.3334 -33.246314)
		(width 0.11684)
		(layer "B.Cu")
		(net "JTAG_MB_TRST_N")
	)
	(segment
		(start 51.308 -32.227266)
		(end 51.830224 -32.74949)
		(width 0.11684)
		(layer "B.Cu")
		(net "JTAG_MB_TRST_N")
	)
	(segment
		(start 51.816 -31.26105)
		(end 51.441096 -31.26105)
		(width 0.11684)
		(layer "B.Cu")
		(net "JTAG_MB_TRST_N")
	)
	(segment
		(start 51.308 -31.394146)
		(end 51.308 -32.227266)
		(width 0.11684)
		(layer "B.Cu")
		(net "JTAG_MB_TRST_N")
	)
	(segment
		(start 51.3334 -34.06775)
		(end 51.5366 -34.27095)
		(width 0.11684)
		(layer "B.Cu")
		(net "JTAG_MB_TRST_N")
	)
	(segment
		(start 51.441096 -31.26105)
		(end 51.308 -31.394146)
		(width 0.11684)
		(layer "B.Cu")
		(net "JTAG_MB_TRST_N")
	)
	(via
		(at 38.46068 -109.95152)
		(size 0.7112)
		(drill 0.3556)
		(layers "F.Cu" "B.Cu")
		(net "JTAG_MB_TMS")
	)
	(via
		(at 52.221892 -35.68192)
		(size 0.508)
		(drill 0.254)
		(layers "F.Cu" "B.Cu")
		(net "JTAG_MB_TMS")
	)
	(via
		(at 37.60724 -107.569)
		(size 0.508)
		(drill 0.254)
		(layers "F.Cu" "B.Cu")
		(net "JTAG_MB_TMS")
	)
	(segment
		(start 39.656512 -116.161058)
		(end 37.5412 -114.045746)
		(width 0.11684)
		(layer "B.Cu")
		(net "JTAG_MB_TMS")
	)
	(segment
		(start 37.5412 -112.6363)
		(end 38.46068 -111.71682)
		(width 0.11684)
		(layer "B.Cu")
		(net "JTAG_MB_TMS")
	)
	(segment
		(start 52.221892 -35.687)
		(end 52.214272 -35.69462)
		(width 0.11684)
		(layer "B.Cu")
		(net "JTAG_MB_TMS")
	)
	(segment
		(start 39.654988 -118.460012)
		(end 39.656512 -118.458488)
		(width 0.11684)
		(layer "B.Cu")
		(net "JTAG_MB_TMS")
	)
	(segment
		(start 37.60724 -107.569)
		(end 37.60724 -106.919014)
		(width 0.11684)
		(layer "B.Cu")
		(net "JTAG_MB_TMS")
	)
	(segment
		(start 38.1254 -109.61624)
		(end 38.1254 -106.78795)
		(width 0.11684)
		(layer "B.Cu")
		(net "JTAG_MB_TMS")
	)
	(segment
		(start 52.214272 -36.26358)
		(end 52.555648 -36.604956)
		(width 0.11684)
		(layer "B.Cu")
		(net "JTAG_MB_TMS")
	)
	(segment
		(start 38.1254 -106.78795)
		(end 38.1 -106.76255)
		(width 0.11684)
		(layer "B.Cu")
		(net "JTAG_MB_TMS")
	)
	(segment
		(start 39.656512 -118.458488)
		(end 39.656512 -116.161058)
		(width 0.11684)
		(layer "B.Cu")
		(net "JTAG_MB_TMS")
	)
	(segment
		(start 38.46068 -109.95152)
		(end 38.1254 -109.61624)
		(width 0.11684)
		(layer "B.Cu")
		(net "JTAG_MB_TMS")
	)
	(segment
		(start 38.46068 -111.71682)
		(end 38.46068 -109.95152)
		(width 0.11684)
		(layer "B.Cu")
		(net "JTAG_MB_TMS")
	)
	(segment
		(start 37.5412 -114.045746)
		(end 37.5412 -112.6363)
		(width 0.11684)
		(layer "B.Cu")
		(net "JTAG_MB_TMS")
	)
	(segment
		(start 52.214272 -35.69462)
		(end 52.214272 -36.26358)
		(width 0.11684)
		(layer "B.Cu")
		(net "JTAG_MB_TMS")
	)
	(segment
		(start 37.60724 -106.919014)
		(end 37.763704 -106.76255)
		(width 0.11684)
		(layer "B.Cu")
		(net "JTAG_MB_TMS")
	)
	(segment
		(start 52.221892 -35.68192)
		(end 52.221892 -35.687)
		(width 0.11684)
		(layer "B.Cu")
		(net "JTAG_MB_TMS")
	)
	(segment
		(start 37.763704 -106.76255)
		(end 38.1 -106.76255)
		(width 0.11684)
		(layer "B.Cu")
		(net "JTAG_MB_TMS")
	)
	(segment
		(start 13.5128 -17.5514)
		(end 13.0556 -17.5514)
		(width 0.10668)
		(layer "In4.Cu")
		(net "JTAG_MB_TMS")
	)
	(segment
		(start 19.23288 -112.381538)
		(end 19.747738 -111.86668)
		(width 0.10668)
		(layer "In4.Cu")
		(net "JTAG_MB_TMS")
	)
	(segment
		(start 12.606528 -29.32684)
		(end 7.468362 -29.32684)
		(width 0.10668)
		(layer "In4.Cu")
		(net "JTAG_MB_TMS")
	)
	(segment
		(start 49.94148 -30.918658)
		(end 49.94148 -29.023818)
		(width 0.10668)
		(layer "In4.Cu")
		(net "JTAG_MB_TMS")
	)
	(segment
		(start 32.9946 -25.91816)
		(end 31.07182 -23.99538)
		(width 0.10668)
		(layer "In4.Cu")
		(net "JTAG_MB_TMS")
	)
	(segment
		(start 26.035 -20.955)
		(end 24.65705 -19.57705)
		(width 0.10668)
		(layer "In4.Cu")
		(net "JTAG_MB_TMS")
	)
	(segment
		(start 4.627626 -106.185208)
		(end 6.134354 -106.185208)
		(width 0.10668)
		(layer "In4.Cu")
		(net "JTAG_MB_TMS")
	)
	(segment
		(start 5.189474 -28.77058)
		(end 2.663952 -31.296102)
		(width 0.10668)
		(layer "In4.Cu")
		(net "JTAG_MB_TMS")
	)
	(segment
		(start 48.001682 -27.08402)
		(end 43.466766 -27.08402)
		(width 0.10668)
		(layer "In4.Cu")
		(net "JTAG_MB_TMS")
	)
	(segment
		(start 31.07182 -23.99538)
		(end 29.539184 -23.99538)
		(width 0.10668)
		(layer "In4.Cu")
		(net "JTAG_MB_TMS")
	)
	(segment
		(start 19.747738 -111.86668)
		(end 20.924774 -111.86668)
		(width 0.10668)
		(layer "In4.Cu")
		(net "JTAG_MB_TMS")
	)
	(segment
		(start 43.466766 -27.08402)
		(end 42.300906 -25.91816)
		(width 0.10668)
		(layer "In4.Cu")
		(net "JTAG_MB_TMS")
	)
	(segment
		(start 51.97094 -32.33674)
		(end 51.359562 -32.33674)
		(width 0.10668)
		(layer "In4.Cu")
		(net "JTAG_MB_TMS")
	)
	(segment
		(start 22.225254 -18.415)
		(end 19.3802 -18.415)
		(width 0.10668)
		(layer "In4.Cu")
		(net "JTAG_MB_TMS")
	)
	(segment
		(start 17.38884 -112.381538)
		(end 19.23288 -112.381538)
		(width 0.10668)
		(layer "In4.Cu")
		(net "JTAG_MB_TMS")
	)
	(segment
		(start 14.4399 -27.493468)
		(end 12.606528 -29.32684)
		(width 0.10668)
		(layer "In4.Cu")
		(net "JTAG_MB_TMS")
	)
	(segment
		(start 24.65705 -19.57705)
		(end 23.387304 -19.57705)
		(width 0.10668)
		(layer "In4.Cu")
		(net "JTAG_MB_TMS")
	)
	(segment
		(start 26.035 -21.209)
		(end 26.035 -20.955)
		(width 0.10668)
		(layer "In4.Cu")
		(net "JTAG_MB_TMS")
	)
	(segment
		(start 38.07714 -108.0389)
		(end 37.60724 -107.569)
		(width 0.10668)
		(layer "In4.Cu")
		(net "JTAG_MB_TMS")
	)
	(segment
		(start 2.765552 -88.61044)
		(end 2.765552 -104.323134)
		(width 0.10668)
		(layer "In4.Cu")
		(net "JTAG_MB_TMS")
	)
	(segment
		(start 18.74774 -16.2306)
		(end 14.8336 -16.2306)
		(width 0.10668)
		(layer "In4.Cu")
		(net "JTAG_MB_TMS")
	)
	(segment
		(start 42.300906 -25.91816)
		(end 32.9946 -25.91816)
		(width 0.10668)
		(layer "In4.Cu")
		(net "JTAG_MB_TMS")
	)
	(segment
		(start 6.053836 -85.190076)
		(end 6.9088 -85.190076)
		(width 0.10668)
		(layer "In4.Cu")
		(net "JTAG_MB_TMS")
	)
	(segment
		(start 5.4356 -84.57184)
		(end 6.053836 -85.190076)
		(width 0.10668)
		(layer "In4.Cu")
		(net "JTAG_MB_TMS")
	)
	(segment
		(start 29.539184 -23.99538)
		(end 27.387804 -21.844)
		(width 0.10668)
		(layer "In4.Cu")
		(net "JTAG_MB_TMS")
	)
	(segment
		(start 2.663952 -77.84592)
		(end 5.4356 -80.617568)
		(width 0.10668)
		(layer "In4.Cu")
		(net "JTAG_MB_TMS")
	)
	(segment
		(start 7.0358 -86.614254)
		(end 6.451854 -87.1982)
		(width 0.10668)
		(layer "In4.Cu")
		(net "JTAG_MB_TMS")
	)
	(segment
		(start 6.451854 -87.1982)
		(end 4.177792 -87.1982)
		(width 0.10668)
		(layer "In4.Cu")
		(net "JTAG_MB_TMS")
	)
	(segment
		(start 22.3266 -110.464854)
		(end 25.095454 -110.464854)
		(width 0.10668)
		(layer "In4.Cu")
		(net "JTAG_MB_TMS")
	)
	(segment
		(start 6.86562 -108.78058)
		(end 6.86562 -109.972348)
		(width 0.10668)
		(layer "In4.Cu")
		(net "JTAG_MB_TMS")
	)
	(segment
		(start 23.387304 -19.57705)
		(end 22.225254 -18.415)
		(width 0.10668)
		(layer "In4.Cu")
		(net "JTAG_MB_TMS")
	)
	(segment
		(start 6.86562 -109.972348)
		(end 8.765032 -111.87176)
		(width 0.10668)
		(layer "In4.Cu")
		(net "JTAG_MB_TMS")
	)
	(segment
		(start 2.663952 -31.296102)
		(end 2.663952 -77.84592)
		(width 0.10668)
		(layer "In4.Cu")
		(net "JTAG_MB_TMS")
	)
	(segment
		(start 7.272782 -108.373418)
		(end 6.86562 -108.78058)
		(width 0.10668)
		(layer "In4.Cu")
		(net "JTAG_MB_TMS")
	)
	(segment
		(start 2.765552 -104.323134)
		(end 4.627626 -106.185208)
		(width 0.10668)
		(layer "In4.Cu")
		(net "JTAG_MB_TMS")
	)
	(segment
		(start 49.94148 -29.023818)
		(end 48.001682 -27.08402)
		(width 0.10668)
		(layer "In4.Cu")
		(net "JTAG_MB_TMS")
	)
	(segment
		(start 52.221892 -34.900108)
		(end 52.32146 -34.80054)
		(width 0.10668)
		(layer "In4.Cu")
		(net "JTAG_MB_TMS")
	)
	(segment
		(start 16.879062 -111.87176)
		(end 17.38884 -112.381538)
		(width 0.10668)
		(layer "In4.Cu")
		(net "JTAG_MB_TMS")
	)
	(segment
		(start 27.387804 -21.844)
		(end 26.67 -21.844)
		(width 0.10668)
		(layer "In4.Cu")
		(net "JTAG_MB_TMS")
	)
	(segment
		(start 52.32146 -32.68726)
		(end 51.97094 -32.33674)
		(width 0.10668)
		(layer "In4.Cu")
		(net "JTAG_MB_TMS")
	)
	(segment
		(start 51.359562 -32.33674)
		(end 49.94148 -30.918658)
		(width 0.10668)
		(layer "In4.Cu")
		(net "JTAG_MB_TMS")
	)
	(segment
		(start 26.79192 -112.16132)
		(end 36.190174 -112.16132)
		(width 0.10668)
		(layer "In4.Cu")
		(net "JTAG_MB_TMS")
	)
	(segment
		(start 38.07714 -110.274354)
		(end 38.07714 -108.0389)
		(width 0.10668)
		(layer "In4.Cu")
		(net "JTAG_MB_TMS")
	)
	(segment
		(start 20.924774 -111.86668)
		(end 22.3266 -110.464854)
		(width 0.10668)
		(layer "In4.Cu")
		(net "JTAG_MB_TMS")
	)
	(segment
		(start 6.9088 -85.190076)
		(end 7.0358 -85.317076)
		(width 0.10668)
		(layer "In4.Cu")
		(net "JTAG_MB_TMS")
	)
	(segment
		(start 12.7762 -17.8308)
		(end 12.7762 -21.083016)
		(width 0.10668)
		(layer "In4.Cu")
		(net "JTAG_MB_TMS")
	)
	(segment
		(start 52.32146 -34.80054)
		(end 52.32146 -32.68726)
		(width 0.10668)
		(layer "In4.Cu")
		(net "JTAG_MB_TMS")
	)
	(segment
		(start 19.3802 -18.415)
		(end 18.87474 -17.90954)
		(width 0.10668)
		(layer "In4.Cu")
		(net "JTAG_MB_TMS")
	)
	(segment
		(start 7.272782 -107.323636)
		(end 7.272782 -108.373418)
		(width 0.10668)
		(layer "In4.Cu")
		(net "JTAG_MB_TMS")
	)
	(segment
		(start 14.8336 -16.2306)
		(end 13.5128 -17.5514)
		(width 0.10668)
		(layer "In4.Cu")
		(net "JTAG_MB_TMS")
	)
	(segment
		(start 13.0556 -17.5514)
		(end 12.7762 -17.8308)
		(width 0.10668)
		(layer "In4.Cu")
		(net "JTAG_MB_TMS")
	)
	(segment
		(start 25.095454 -110.464854)
		(end 26.79192 -112.16132)
		(width 0.10668)
		(layer "In4.Cu")
		(net "JTAG_MB_TMS")
	)
	(segment
		(start 18.87474 -16.3576)
		(end 18.74774 -16.2306)
		(width 0.10668)
		(layer "In4.Cu")
		(net "JTAG_MB_TMS")
	)
	(segment
		(start 6.134354 -106.185208)
		(end 7.272782 -107.323636)
		(width 0.10668)
		(layer "In4.Cu")
		(net "JTAG_MB_TMS")
	)
	(segment
		(start 26.67 -21.844)
		(end 26.035 -21.209)
		(width 0.10668)
		(layer "In4.Cu")
		(net "JTAG_MB_TMS")
	)
	(segment
		(start 52.221892 -35.68192)
		(end 52.221892 -34.900108)
		(width 0.10668)
		(layer "In4.Cu")
		(net "JTAG_MB_TMS")
	)
	(segment
		(start 7.468362 -29.32684)
		(end 6.912102 -28.77058)
		(width 0.10668)
		(layer "In4.Cu")
		(net "JTAG_MB_TMS")
	)
	(segment
		(start 18.87474 -17.90954)
		(end 18.87474 -16.3576)
		(width 0.10668)
		(layer "In4.Cu")
		(net "JTAG_MB_TMS")
	)
	(segment
		(start 5.4356 -80.617568)
		(end 5.4356 -84.57184)
		(width 0.10668)
		(layer "In4.Cu")
		(net "JTAG_MB_TMS")
	)
	(segment
		(start 12.7762 -21.083016)
		(end 14.4399 -22.746716)
		(width 0.10668)
		(layer "In4.Cu")
		(net "JTAG_MB_TMS")
	)
	(segment
		(start 7.0358 -85.317076)
		(end 7.0358 -86.614254)
		(width 0.10668)
		(layer "In4.Cu")
		(net "JTAG_MB_TMS")
	)
	(segment
		(start 8.765032 -111.87176)
		(end 16.879062 -111.87176)
		(width 0.10668)
		(layer "In4.Cu")
		(net "JTAG_MB_TMS")
	)
	(segment
		(start 6.912102 -28.77058)
		(end 5.189474 -28.77058)
		(width 0.10668)
		(layer "In4.Cu")
		(net "JTAG_MB_TMS")
	)
	(segment
		(start 14.4399 -22.746716)
		(end 14.4399 -27.493468)
		(width 0.10668)
		(layer "In4.Cu")
		(net "JTAG_MB_TMS")
	)
	(segment
		(start 4.177792 -87.1982)
		(end 2.765552 -88.61044)
		(width 0.10668)
		(layer "In4.Cu")
		(net "JTAG_MB_TMS")
	)
	(segment
		(start 36.190174 -112.16132)
		(end 38.07714 -110.274354)
		(width 0.10668)
		(layer "In4.Cu")
		(net "JTAG_MB_TMS")
	)
	(via
		(at 46.255432 -32.789876)
		(size 0.508)
		(drill 0.254)
		(layers "F.Cu" "B.Cu")
		(net "JTAG_MB_TCK")
	)
	(via
		(at 38.882066 -104.648)
		(size 0.508)
		(drill 0.254)
		(layers "F.Cu" "B.Cu")
		(net "JTAG_MB_TCK")
	)
	(via
		(at 17.53362 -107.353862)
		(size 0.508)
		(drill 0.254)
		(layers "F.Cu" "B.Cu")
		(net "JTAG_MB_TCK")
	)
	(segment
		(start 46.271688 -32.77362)
		(end 46.255432 -32.789876)
		(width 0.11684)
		(layer "B.Cu")
		(net "JTAG_MB_TCK")
	)
	(segment
		(start 40.706548 -115.219734)
		(end 40.254936 -116.064284)
		(width 0.11684)
		(layer "B.Cu")
		(net "JTAG_MB_TCK")
	)
	(segment
		(start 40.82415 -106.77525)
		(end 40.0304 -106.77525)
		(width 0.11684)
		(layer "B.Cu")
		(net "JTAG_MB_TCK")
	)
	(segment
		(start 40.0304 -107.340146)
		(end 40.9702 -108.279946)
		(width 0.11684)
		(layer "B.Cu")
		(net "JTAG_MB_TCK")
	)
	(segment
		(start 41.4528 -111.3028)
		(end 41.4528 -112.950752)
		(width 0.11684)
		(layer "B.Cu")
		(net "JTAG_MB_TCK")
	)
	(segment
		(start 39.76624 -104.4702)
		(end 41.4528 -104.4702)
		(width 0.11684)
		(layer "B.Cu")
		(net "JTAG_MB_TCK")
	)
	(segment
		(start 40.254936 -116.064284)
		(end 40.254936 -118.25986)
		(width 0.11684)
		(layer "B.Cu")
		(net "JTAG_MB_TCK")
	)
	(segment
		(start 41.9862 -105.6132)
		(end 40.82415 -106.77525)
		(width 0.11684)
		(layer "B.Cu")
		(net "JTAG_MB_TCK")
	)
	(segment
		(start 41.273476 -113.85042)
		(end 40.706548 -115.219734)
		(width 0.11684)
		(layer "B.Cu")
		(net "JTAG_MB_TCK")
	)
	(segment
		(start 41.4528 -112.950752)
		(end 41.273476 -113.85042)
		(width 0.11684)
		(layer "B.Cu")
		(net "JTAG_MB_TCK")
	)
	(segment
		(start 46.95698 -32.89046)
		(end 46.84014 -32.77362)
		(width 0.11684)
		(layer "B.Cu")
		(net "JTAG_MB_TCK")
	)
	(segment
		(start 46.470316 -34.237676)
		(end 46.828456 -34.237676)
		(width 0.11684)
		(layer "B.Cu")
		(net "JTAG_MB_TCK")
	)
	(segment
		(start 46.828456 -34.237676)
		(end 46.95698 -34.109152)
		(width 0.11684)
		(layer "B.Cu")
		(net "JTAG_MB_TCK")
	)
	(segment
		(start 41.9862 -105.0036)
		(end 41.9862 -105.6132)
		(width 0.11684)
		(layer "B.Cu")
		(net "JTAG_MB_TCK")
	)
	(segment
		(start 38.882066 -104.648)
		(end 39.58844 -104.648)
		(width 0.11684)
		(layer "B.Cu")
		(net "JTAG_MB_TCK")
	)
	(segment
		(start 40.0304 -106.77525)
		(end 40.0304 -107.340146)
		(width 0.11684)
		(layer "B.Cu")
		(net "JTAG_MB_TCK")
	)
	(segment
		(start 46.84014 -32.77362)
		(end 46.271688 -32.77362)
		(width 0.11684)
		(layer "B.Cu")
		(net "JTAG_MB_TCK")
	)
	(segment
		(start 40.9702 -108.279946)
		(end 40.9702 -110.8202)
		(width 0.11684)
		(layer "B.Cu")
		(net "JTAG_MB_TCK")
	)
	(segment
		(start 46.95698 -34.109152)
		(end 46.95698 -32.89046)
		(width 0.11684)
		(layer "B.Cu")
		(net "JTAG_MB_TCK")
	)
	(segment
		(start 39.58844 -104.648)
		(end 39.76624 -104.4702)
		(width 0.11684)
		(layer "B.Cu")
		(net "JTAG_MB_TCK")
	)
	(segment
		(start 40.9702 -110.8202)
		(end 41.4528 -111.3028)
		(width 0.11684)
		(layer "B.Cu")
		(net "JTAG_MB_TCK")
	)
	(segment
		(start 41.4528 -104.4702)
		(end 41.9862 -105.0036)
		(width 0.11684)
		(layer "B.Cu")
		(net "JTAG_MB_TCK")
	)
	(segment
		(start 38.341808 -105.905046)
		(end 34.882328 -105.905046)
		(width 0.08382)
		(layer "In2.Cu")
		(net "JTAG_MB_TCK")
	)
	(segment
		(start 24.79294 -107.701842)
		(end 24.287988 -107.19689)
		(width 0.08382)
		(layer "In2.Cu")
		(net "JTAG_MB_TCK")
	)
	(segment
		(start 38.882066 -104.648)
		(end 38.66769 -104.862376)
		(width 0.08382)
		(layer "In2.Cu")
		(net "JTAG_MB_TCK")
	)
	(segment
		(start 30.15107 -106.673142)
		(end 30.15107 -107.889802)
		(width 0.08382)
		(layer "In2.Cu")
		(net "JTAG_MB_TCK")
	)
	(segment
		(start 34.882328 -105.905046)
		(end 34.298128 -105.320846)
		(width 0.08382)
		(layer "In2.Cu")
		(net "JTAG_MB_TCK")
	)
	(segment
		(start 24.79294 -108.32338)
		(end 24.79294 -107.701842)
		(width 0.08382)
		(layer "In2.Cu")
		(net "JTAG_MB_TCK")
	)
	(segment
		(start 25.90292 -109.43336)
		(end 24.79294 -108.32338)
		(width 0.08382)
		(layer "In2.Cu")
		(net "JTAG_MB_TCK")
	)
	(segment
		(start 30.15107 -107.889802)
		(end 28.607512 -109.43336)
		(width 0.08382)
		(layer "In2.Cu")
		(net "JTAG_MB_TCK")
	)
	(segment
		(start 30.675072 -106.14914)
		(end 30.15107 -106.673142)
		(width 0.08382)
		(layer "In2.Cu")
		(net "JTAG_MB_TCK")
	)
	(segment
		(start 33.926272 -105.320846)
		(end 33.097978 -106.14914)
		(width 0.08382)
		(layer "In2.Cu")
		(net "JTAG_MB_TCK")
	)
	(segment
		(start 34.298128 -105.320846)
		(end 33.926272 -105.320846)
		(width 0.08382)
		(layer "In2.Cu")
		(net "JTAG_MB_TCK")
	)
	(segment
		(start 38.66769 -105.579164)
		(end 38.341808 -105.905046)
		(width 0.08382)
		(layer "In2.Cu")
		(net "JTAG_MB_TCK")
	)
	(segment
		(start 17.690592 -107.19689)
		(end 17.53362 -107.353862)
		(width 0.08382)
		(layer "In2.Cu")
		(net "JTAG_MB_TCK")
	)
	(segment
		(start 33.097978 -106.14914)
		(end 30.675072 -106.14914)
		(width 0.08382)
		(layer "In2.Cu")
		(net "JTAG_MB_TCK")
	)
	(segment
		(start 24.287988 -107.19689)
		(end 17.690592 -107.19689)
		(width 0.08382)
		(layer "In2.Cu")
		(net "JTAG_MB_TCK")
	)
	(segment
		(start 38.66769 -104.862376)
		(end 38.66769 -105.579164)
		(width 0.08382)
		(layer "In2.Cu")
		(net "JTAG_MB_TCK")
	)
	(segment
		(start 28.607512 -109.43336)
		(end 25.90292 -109.43336)
		(width 0.08382)
		(layer "In2.Cu")
		(net "JTAG_MB_TCK")
	)
	(segment
		(start 17.4498 -46.177962)
		(end 16.126714 -47.501048)
		(width 0.10668)
		(layer "In4.Cu")
		(net "JTAG_MB_TCK")
	)
	(segment
		(start 14.751558 -80.290416)
		(end 14.8844 -80.423258)
		(width 0.10668)
		(layer "In4.Cu")
		(net "JTAG_MB_TCK")
	)
	(segment
		(start 8.3566 -91.059)
		(end 8.3566 -91.908376)
		(width 0.10668)
		(layer "In4.Cu")
		(net "JTAG_MB_TCK")
	)
	(segment
		(start 16.656304 -48.711358)
		(end 16.656304 -48.94199)
		(width 0.10668)
		(layer "In4.Cu")
		(net "JTAG_MB_TCK")
	)
	(segment
		(start 8.559038 -101.330252)
		(end 8.559038 -101.777292)
		(width 0.10668)
		(layer "In4.Cu")
		(net "JTAG_MB_TCK")
	)
	(segment
		(start 12.83208 -105.181654)
		(end 13.126466 -105.47604)
		(width 0.10668)
		(layer "In4.Cu")
		(net "JTAG_MB_TCK")
	)
	(segment
		(start 16.3576 -71.043546)
		(end 16.027146 -71.374)
		(width 0.10668)
		(layer "In4.Cu")
		(net "JTAG_MB_TCK")
	)
	(segment
		(start 12.83208 -104.34066)
		(end 12.83208 -105.181654)
		(width 0.10668)
		(layer "In4.Cu")
		(net "JTAG_MB_TCK")
	)
	(segment
		(start 46.255432 -32.485584)
		(end 44.031408 -30.26156)
		(width 0.10668)
		(layer "In4.Cu")
		(net "JTAG_MB_TCK")
	)
	(segment
		(start 16.3576 -67.7164)
		(end 16.3576 -71.043546)
		(width 0.10668)
		(layer "In4.Cu")
		(net "JTAG_MB_TCK")
	)
	(segment
		(start 28.69438 -33.61182)
		(end 28.69438 -35.229292)
		(width 0.10668)
		(layer "In4.Cu")
		(net "JTAG_MB_TCK")
	)
	(segment
		(start 16.76146 -59.040776)
		(end 16.76146 -62.96406)
		(width 0.10668)
		(layer "In4.Cu")
		(net "JTAG_MB_TCK")
	)
	(segment
		(start 30.353 -31.9532)
		(end 28.69438 -33.61182)
		(width 0.10668)
		(layer "In4.Cu")
		(net "JTAG_MB_TCK")
	)
	(segment
		(start 17.4498 -45.11548)
		(end 17.4498 -46.177962)
		(width 0.10668)
		(layer "In4.Cu")
		(net "JTAG_MB_TCK")
	)
	(segment
		(start 15.304262 -105.92308)
		(end 15.76832 -105.92308)
		(width 0.10668)
		(layer "In4.Cu")
		(net "JTAG_MB_TCK")
	)
	(segment
		(start 10.822686 -104.04094)
		(end 12.53236 -104.04094)
		(width 0.10668)
		(layer "In4.Cu")
		(net "JTAG_MB_TCK")
	)
	(segment
		(start 23.89759 -37.747702)
		(end 23.89759 -40.039544)
		(width 0.10668)
		(layer "In4.Cu")
		(net "JTAG_MB_TCK")
	)
	(segment
		(start 15.76832 -105.92308)
		(end 17.199102 -107.353862)
		(width 0.10668)
		(layer "In4.Cu")
		(net "JTAG_MB_TCK")
	)
	(segment
		(start 35.190176 -29.757624)
		(end 32.9946 -31.9532)
		(width 0.10668)
		(layer "In4.Cu")
		(net "JTAG_MB_TCK")
	)
	(segment
		(start 16.126714 -47.501048)
		(end 16.126714 -48.181768)
		(width 0.10668)
		(layer "In4.Cu")
		(net "JTAG_MB_TCK")
	)
	(segment
		(start 36.831524 -29.757624)
		(end 35.190176 -29.757624)
		(width 0.10668)
		(layer "In4.Cu")
		(net "JTAG_MB_TCK")
	)
	(segment
		(start 17.47266 -51.522884)
		(end 16.322802 -52.672742)
		(width 0.10668)
		(layer "In4.Cu")
		(net "JTAG_MB_TCK")
	)
	(segment
		(start 27.550872 -36.3728)
		(end 25.272492 -36.3728)
		(width 0.10668)
		(layer "In4.Cu")
		(net "JTAG_MB_TCK")
	)
	(segment
		(start 14.15796 -77.903324)
		(end 14.751558 -78.496922)
		(width 0.10668)
		(layer "In4.Cu")
		(net "JTAG_MB_TCK")
	)
	(segment
		(start 14.751558 -78.496922)
		(end 14.751558 -80.290416)
		(width 0.10668)
		(layer "In4.Cu")
		(net "JTAG_MB_TCK")
	)
	(segment
		(start 17.254474 -49.908968)
		(end 17.47266 -50.127154)
		(width 0.10668)
		(layer "In4.Cu")
		(net "JTAG_MB_TCK")
	)
	(segment
		(start 11.8618 -91.5924)
		(end 11.55446 -91.89974)
		(width 0.10668)
		(layer "In4.Cu")
		(net "JTAG_MB_TCK")
	)
	(segment
		(start 44.031408 -30.26156)
		(end 37.33546 -30.26156)
		(width 0.10668)
		(layer "In4.Cu")
		(net "JTAG_MB_TCK")
	)
	(segment
		(start 14.8844 -80.423258)
		(end 14.8844 -82.964782)
		(width 0.10668)
		(layer "In4.Cu")
		(net "JTAG_MB_TCK")
	)
	(segment
		(start 11.8618 -85.987382)
		(end 11.8618 -91.5924)
		(width 0.10668)
		(layer "In4.Cu")
		(net "JTAG_MB_TCK")
	)
	(segment
		(start 17.47266 -50.127154)
		(end 17.47266 -51.522884)
		(width 0.10668)
		(layer "In4.Cu")
		(net "JTAG_MB_TCK")
	)
	(segment
		(start 12.53236 -104.04094)
		(end 12.83208 -104.34066)
		(width 0.10668)
		(layer "In4.Cu")
		(net "JTAG_MB_TCK")
	)
	(segment
		(start 14.857222 -105.47604)
		(end 15.304262 -105.92308)
		(width 0.10668)
		(layer "In4.Cu")
		(net "JTAG_MB_TCK")
	)
	(segment
		(start 11.55446 -91.89974)
		(end 11.05154 -91.89974)
		(width 0.10668)
		(layer "In4.Cu")
		(net "JTAG_MB_TCK")
	)
	(segment
		(start 46.255432 -32.789876)
		(end 46.255432 -32.485584)
		(width 0.10668)
		(layer "In4.Cu")
		(net "JTAG_MB_TCK")
	)
	(segment
		(start 7.47522 -92.789756)
		(end 7.47522 -100.246434)
		(width 0.10668)
		(layer "In4.Cu")
		(net "JTAG_MB_TCK")
	)
	(segment
		(start 19.413474 -44.52366)
		(end 18.04162 -44.52366)
		(width 0.10668)
		(layer "In4.Cu")
		(net "JTAG_MB_TCK")
	)
	(segment
		(start 8.3566 -91.908376)
		(end 7.47522 -92.789756)
		(width 0.10668)
		(layer "In4.Cu")
		(net "JTAG_MB_TCK")
	)
	(segment
		(start 16.322802 -58.602118)
		(end 16.76146 -59.040776)
		(width 0.10668)
		(layer "In4.Cu")
		(net "JTAG_MB_TCK")
	)
	(segment
		(start 16.322802 -52.672742)
		(end 16.322802 -58.602118)
		(width 0.10668)
		(layer "In4.Cu")
		(net "JTAG_MB_TCK")
	)
	(segment
		(start 17.71396 -66.61785)
		(end 17.45615 -66.61785)
		(width 0.10668)
		(layer "In4.Cu")
		(net "JTAG_MB_TCK")
	)
	(segment
		(start 16.027146 -71.374)
		(end 16.027146 -73.335134)
		(width 0.10668)
		(layer "In4.Cu")
		(net "JTAG_MB_TCK")
	)
	(segment
		(start 17.199102 -107.353862)
		(end 17.53362 -107.353862)
		(width 0.10668)
		(layer "In4.Cu")
		(net "JTAG_MB_TCK")
	)
	(segment
		(start 8.559038 -101.777292)
		(end 10.822686 -104.04094)
		(width 0.10668)
		(layer "In4.Cu")
		(net "JTAG_MB_TCK")
	)
	(segment
		(start 13.126466 -105.47604)
		(end 14.857222 -105.47604)
		(width 0.10668)
		(layer "In4.Cu")
		(net "JTAG_MB_TCK")
	)
	(segment
		(start 17.9832 -64.1858)
		(end 17.9832 -66.34861)
		(width 0.10668)
		(layer "In4.Cu")
		(net "JTAG_MB_TCK")
	)
	(segment
		(start 17.45615 -66.61785)
		(end 16.3576 -67.7164)
		(width 0.10668)
		(layer "In4.Cu")
		(net "JTAG_MB_TCK")
	)
	(segment
		(start 32.9946 -31.9532)
		(end 30.353 -31.9532)
		(width 0.10668)
		(layer "In4.Cu")
		(net "JTAG_MB_TCK")
	)
	(segment
		(start 16.126714 -48.181768)
		(end 16.656304 -48.711358)
		(width 0.10668)
		(layer "In4.Cu")
		(net "JTAG_MB_TCK")
	)
	(segment
		(start 17.254474 -49.54016)
		(end 17.254474 -49.908968)
		(width 0.10668)
		(layer "In4.Cu")
		(net "JTAG_MB_TCK")
	)
	(segment
		(start 17.9832 -66.34861)
		(end 17.71396 -66.61785)
		(width 0.10668)
		(layer "In4.Cu")
		(net "JTAG_MB_TCK")
	)
	(segment
		(start 23.89759 -40.039544)
		(end 19.413474 -44.52366)
		(width 0.10668)
		(layer "In4.Cu")
		(net "JTAG_MB_TCK")
	)
	(segment
		(start 25.272492 -36.3728)
		(end 23.89759 -37.747702)
		(width 0.10668)
		(layer "In4.Cu")
		(net "JTAG_MB_TCK")
	)
	(segment
		(start 16.656304 -48.94199)
		(end 17.254474 -49.54016)
		(width 0.10668)
		(layer "In4.Cu")
		(net "JTAG_MB_TCK")
	)
	(segment
		(start 9.9568 -90.805)
		(end 8.6106 -90.805)
		(width 0.10668)
		(layer "In4.Cu")
		(net "JTAG_MB_TCK")
	)
	(segment
		(start 16.027146 -73.335134)
		(end 14.15796 -75.20432)
		(width 0.10668)
		(layer "In4.Cu")
		(net "JTAG_MB_TCK")
	)
	(segment
		(start 7.47522 -100.246434)
		(end 8.559038 -101.330252)
		(width 0.10668)
		(layer "In4.Cu")
		(net "JTAG_MB_TCK")
	)
	(segment
		(start 14.8844 -82.964782)
		(end 11.8618 -85.987382)
		(width 0.10668)
		(layer "In4.Cu")
		(net "JTAG_MB_TCK")
	)
	(segment
		(start 18.04162 -44.52366)
		(end 17.4498 -45.11548)
		(width 0.10668)
		(layer "In4.Cu")
		(net "JTAG_MB_TCK")
	)
	(segment
		(start 28.69438 -35.229292)
		(end 27.550872 -36.3728)
		(width 0.10668)
		(layer "In4.Cu")
		(net "JTAG_MB_TCK")
	)
	(segment
		(start 8.6106 -90.805)
		(end 8.3566 -91.059)
		(width 0.10668)
		(layer "In4.Cu")
		(net "JTAG_MB_TCK")
	)
	(segment
		(start 16.76146 -62.96406)
		(end 17.9832 -64.1858)
		(width 0.10668)
		(layer "In4.Cu")
		(net "JTAG_MB_TCK")
	)
	(segment
		(start 37.33546 -30.26156)
		(end 36.831524 -29.757624)
		(width 0.10668)
		(layer "In4.Cu")
		(net "JTAG_MB_TCK")
	)
	(segment
		(start 14.15796 -75.20432)
		(end 14.15796 -77.903324)
		(width 0.10668)
		(layer "In4.Cu")
		(net "JTAG_MB_TCK")
	)
	(segment
		(start 11.05154 -91.89974)
		(end 9.9568 -90.805)
		(width 0.10668)
		(layer "In4.Cu")
		(net "JTAG_MB_TCK")
	)
	(segment
		(start 60.094876 -56.971184)
		(end 59.699652 -56.57596)
		(width 0.11684)
		(layer "F.Cu")
		(net "ESPI_LPC_D3_IO3")
	)
	(via
		(at 59.699652 -56.57596)
		(size 0.4572)
		(drill 0.254)
		(layers "F.Cu" "B.Cu")
		(net "ESPI_LPC_D3_IO3")
	)
	(via
		(at 62.9158 -58.2676)
		(size 0.6604)
		(drill 0.3302)
		(layers "F.Cu" "B.Cu")
		(net "ESPI_LPC_D3_IO3")
	)
	(segment
		(start 64.5414 -60.5536)
		(end 64.901572 -60.193428)
		(width 0.11684)
		(layer "B.Cu")
		(net "ESPI_LPC_D3_IO3")
	)
	(segment
		(start 64.0842 -58.801)
		(end 63.8556 -58.5724)
		(width 0.11684)
		(layer "B.Cu")
		(net "ESPI_LPC_D3_IO3")
	)
	(segment
		(start 62.9158 -58.2676)
		(end 62.616334 -58.567066)
		(width 0.11684)
		(layer "B.Cu")
		(net "ESPI_LPC_D3_IO3")
	)
	(segment
		(start 64.901572 -60.193428)
		(end 64.901572 -59.583828)
		(width 0.11684)
		(layer "B.Cu")
		(net "ESPI_LPC_D3_IO3")
	)
	(segment
		(start 61.027056 -58.567066)
		(end 60.890912 -58.430922)
		(width 0.11684)
		(layer "B.Cu")
		(net "ESPI_LPC_D3_IO3")
	)
	(segment
		(start 63.61811 -60.9854)
		(end 64.04991 -60.5536)
		(width 0.11684)
		(layer "B.Cu")
		(net "ESPI_LPC_D3_IO3")
	)
	(segment
		(start 64.677544 -59.3598)
		(end 64.2874 -59.3598)
		(width 0.11684)
		(layer "B.Cu")
		(net "ESPI_LPC_D3_IO3")
	)
	(segment
		(start 60.890912 -57.14238)
		(end 60.724288 -56.975756)
		(width 0.11684)
		(layer "B.Cu")
		(net "ESPI_LPC_D3_IO3")
	)
	(segment
		(start 63.2206 -58.5724)
		(end 62.9158 -58.2676)
		(width 0.11684)
		(layer "B.Cu")
		(net "ESPI_LPC_D3_IO3")
	)
	(segment
		(start 63.61811 -61.614812)
		(end 63.61811 -60.9854)
		(width 0.11684)
		(layer "B.Cu")
		(net "ESPI_LPC_D3_IO3")
	)
	(segment
		(start 64.0842 -59.1566)
		(end 64.0842 -58.801)
		(width 0.11684)
		(layer "B.Cu")
		(net "ESPI_LPC_D3_IO3")
	)
	(segment
		(start 60.890912 -58.430922)
		(end 60.890912 -57.14238)
		(width 0.11684)
		(layer "B.Cu")
		(net "ESPI_LPC_D3_IO3")
	)
	(segment
		(start 62.616334 -58.567066)
		(end 61.027056 -58.567066)
		(width 0.11684)
		(layer "B.Cu")
		(net "ESPI_LPC_D3_IO3")
	)
	(segment
		(start 64.901572 -59.583828)
		(end 64.677544 -59.3598)
		(width 0.11684)
		(layer "B.Cu")
		(net "ESPI_LPC_D3_IO3")
	)
	(segment
		(start 60.332112 -56.975756)
		(end 60.096908 -56.740552)
		(width 0.11684)
		(layer "B.Cu")
		(net "ESPI_LPC_D3_IO3")
	)
	(segment
		(start 64.04991 -60.5536)
		(end 64.5414 -60.5536)
		(width 0.11684)
		(layer "B.Cu")
		(net "ESPI_LPC_D3_IO3")
	)
	(segment
		(start 63.8556 -58.5724)
		(end 63.2206 -58.5724)
		(width 0.11684)
		(layer "B.Cu")
		(net "ESPI_LPC_D3_IO3")
	)
	(segment
		(start 64.2874 -59.3598)
		(end 64.0842 -59.1566)
		(width 0.11684)
		(layer "B.Cu")
		(net "ESPI_LPC_D3_IO3")
	)
	(segment
		(start 60.724288 -56.975756)
		(end 60.332112 -56.975756)
		(width 0.11684)
		(layer "B.Cu")
		(net "ESPI_LPC_D3_IO3")
	)
	(segment
		(start 60.096908 -56.740552)
		(end 59.699652 -56.57596)
		(width 0.11684)
		(layer "B.Cu")
		(net "ESPI_LPC_D3_IO3")
	)
	(segment
		(start 59.29503 -56.971184)
		(end 58.899806 -56.57596)
		(width 0.11684)
		(layer "F.Cu")
		(net "ESPI_LPC_D2_IO2")
	)
	(via
		(at 60.54979 -59.046364)
		(size 0.6604)
		(drill 0.3302)
		(layers "F.Cu" "B.Cu")
		(net "ESPI_LPC_D2_IO2")
	)
	(via
		(at 58.899806 -56.57596)
		(size 0.4572)
		(drill 0.254)
		(layers "F.Cu" "B.Cu")
		(net "ESPI_LPC_D2_IO2")
	)
	(segment
		(start 60.54979 -58.034428)
		(end 60.54979 -59.046364)
		(width 0.11684)
		(layer "B.Cu")
		(net "ESPI_LPC_D2_IO2")
	)
	(segment
		(start 60.556902 -60.826396)
		(end 60.21451 -59.997594)
		(width 0.11684)
		(layer "B.Cu")
		(net "ESPI_LPC_D2_IO2")
	)
	(segment
		(start 60.21451 -59.381644)
		(end 60.54979 -59.046364)
		(width 0.11684)
		(layer "B.Cu")
		(net "ESPI_LPC_D2_IO2")
	)
	(segment
		(start 59.882532 -56.984646)
		(end 60.109354 -57.211468)
		(width 0.11684)
		(layer "B.Cu")
		(net "ESPI_LPC_D2_IO2")
	)
	(segment
		(start 60.109354 -57.593992)
		(end 60.54979 -58.034428)
		(width 0.11684)
		(layer "B.Cu")
		(net "ESPI_LPC_D2_IO2")
	)
	(segment
		(start 59.31281 -56.747156)
		(end 59.5503 -56.984646)
		(width 0.11684)
		(layer "B.Cu")
		(net "ESPI_LPC_D2_IO2")
	)
	(segment
		(start 58.899806 -56.57596)
		(end 59.31281 -56.747156)
		(width 0.11684)
		(layer "B.Cu")
		(net "ESPI_LPC_D2_IO2")
	)
	(segment
		(start 60.109354 -57.211468)
		(end 60.109354 -57.593992)
		(width 0.11684)
		(layer "B.Cu")
		(net "ESPI_LPC_D2_IO2")
	)
	(segment
		(start 60.21451 -59.997594)
		(end 60.21451 -59.381644)
		(width 0.11684)
		(layer "B.Cu")
		(net "ESPI_LPC_D2_IO2")
	)
	(segment
		(start 60.556902 -61.458856)
		(end 60.556902 -60.826396)
		(width 0.11684)
		(layer "B.Cu")
		(net "ESPI_LPC_D2_IO2")
	)
	(segment
		(start 59.5503 -56.984646)
		(end 59.882532 -56.984646)
		(width 0.11684)
		(layer "B.Cu")
		(net "ESPI_LPC_D2_IO2")
	)
	(segment
		(start 59.29503 -56.171338)
		(end 58.899806 -55.776114)
		(width 0.11684)
		(layer "F.Cu")
		(net "ESPI_LPC_D1_IO1")
	)
	(via
		(at 58.899806 -55.776114)
		(size 0.4572)
		(drill 0.254)
		(layers "F.Cu" "B.Cu")
		(net "ESPI_LPC_D1_IO1")
	)
	(via
		(at 67.0814 -59.817)
		(size 0.6604)
		(drill 0.3302)
		(layers "F.Cu" "B.Cu")
		(net "ESPI_LPC_D1_IO1")
	)
	(segment
		(start 59.29884 -56.175148)
		(end 58.899806 -55.776114)
		(width 0.11684)
		(layer "B.Cu")
		(net "ESPI_LPC_D1_IO1")
	)
	(segment
		(start 64.0842 -56.3372)
		(end 63.922148 -56.175148)
		(width 0.11684)
		(layer "B.Cu")
		(net "ESPI_LPC_D1_IO1")
	)
	(segment
		(start 67.0814 -59.2836)
		(end 65.7352 -57.9374)
		(width 0.11684)
		(layer "B.Cu")
		(net "ESPI_LPC_D1_IO1")
	)
	(segment
		(start 65.151 -57.9374)
		(end 64.0842 -56.8706)
		(width 0.11684)
		(layer "B.Cu")
		(net "ESPI_LPC_D1_IO1")
	)
	(segment
		(start 67.0814 -59.817)
		(end 67.0814 -61.04255)
		(width 0.11684)
		(layer "B.Cu")
		(net "ESPI_LPC_D1_IO1")
	)
	(segment
		(start 65.7352 -57.9374)
		(end 65.151 -57.9374)
		(width 0.11684)
		(layer "B.Cu")
		(net "ESPI_LPC_D1_IO1")
	)
	(segment
		(start 67.0814 -61.04255)
		(end 66.4972 -61.62675)
		(width 0.11684)
		(layer "B.Cu")
		(net "ESPI_LPC_D1_IO1")
	)
	(segment
		(start 67.0814 -59.817)
		(end 67.0814 -59.2836)
		(width 0.11684)
		(layer "B.Cu")
		(net "ESPI_LPC_D1_IO1")
	)
	(segment
		(start 64.0842 -56.8706)
		(end 64.0842 -56.3372)
		(width 0.11684)
		(layer "B.Cu")
		(net "ESPI_LPC_D1_IO1")
	)
	(segment
		(start 63.922148 -56.175148)
		(end 59.29884 -56.175148)
		(width 0.11684)
		(layer "B.Cu")
		(net "ESPI_LPC_D1_IO1")
	)
	(segment
		(start 60.4901 -56.566562)
		(end 60.094876 -56.171338)
		(width 0.11684)
		(layer "F.Cu")
		(net "ESPI_LPC_D0_IO0")
	)
	(via
		(at 65.786 -60.3504)
		(size 0.6604)
		(drill 0.3302)
		(layers "F.Cu" "B.Cu")
		(net "ESPI_LPC_D0_IO0")
	)
	(via
		(at 60.4901 -56.566562)
		(size 0.4572)
		(drill 0.254)
		(layers "F.Cu" "B.Cu")
		(net "ESPI_LPC_D0_IO0")
	)
	(segment
		(start 60.736734 -56.566562)
		(end 60.4901 -56.566562)
		(width 0.11684)
		(layer "B.Cu")
		(net "ESPI_LPC_D0_IO0")
	)
	(segment
		(start 61.702188 -57.555892)
		(end 61.702188 -57.127394)
		(width 0.11684)
		(layer "B.Cu")
		(net "ESPI_LPC_D0_IO0")
	)
	(segment
		(start 65.9638 -60.019946)
		(end 65.9638 -58.851546)
		(width 0.11684)
		(layer "B.Cu")
		(net "ESPI_LPC_D0_IO0")
	)
	(segment
		(start 61.905896 -57.7596)
		(end 61.702188 -57.555892)
		(width 0.11684)
		(layer "B.Cu")
		(net "ESPI_LPC_D0_IO0")
	)
	(segment
		(start 65.786 -60.833)
		(end 64.981328 -61.637672)
		(width 0.11684)
		(layer "B.Cu")
		(net "ESPI_LPC_D0_IO0")
	)
	(segment
		(start 64.900048 -57.995566)
		(end 64.664082 -57.7596)
		(width 0.11684)
		(layer "B.Cu")
		(net "ESPI_LPC_D0_IO0")
	)
	(segment
		(start 65.786 -60.3504)
		(end 65.786 -60.833)
		(width 0.11684)
		(layer "B.Cu")
		(net "ESPI_LPC_D0_IO0")
	)
	(segment
		(start 61.066172 -56.896)
		(end 60.736734 -56.566562)
		(width 0.11684)
		(layer "B.Cu")
		(net "ESPI_LPC_D0_IO0")
	)
	(segment
		(start 65.786 -60.3504)
		(end 65.786 -60.197746)
		(width 0.11684)
		(layer "B.Cu")
		(net "ESPI_LPC_D0_IO0")
	)
	(segment
		(start 61.702188 -57.127394)
		(end 61.470794 -56.896)
		(width 0.11684)
		(layer "B.Cu")
		(net "ESPI_LPC_D0_IO0")
	)
	(segment
		(start 65.786 -60.197746)
		(end 65.9638 -60.019946)
		(width 0.11684)
		(layer "B.Cu")
		(net "ESPI_LPC_D0_IO0")
	)
	(segment
		(start 65.9638 -58.851546)
		(end 65.532254 -58.42)
		(width 0.11684)
		(layer "B.Cu")
		(net "ESPI_LPC_D0_IO0")
	)
	(segment
		(start 61.470794 -56.896)
		(end 61.066172 -56.896)
		(width 0.11684)
		(layer "B.Cu")
		(net "ESPI_LPC_D0_IO0")
	)
	(segment
		(start 64.981328 -61.637672)
		(end 64.634364 -61.637672)
		(width 0.11684)
		(layer "B.Cu")
		(net "ESPI_LPC_D0_IO0")
	)
	(segment
		(start 65.532254 -58.42)
		(end 65.2526 -58.42)
		(width 0.11684)
		(layer "B.Cu")
		(net "ESPI_LPC_D0_IO0")
	)
	(segment
		(start 64.664082 -57.7596)
		(end 61.905896 -57.7596)
		(width 0.11684)
		(layer "B.Cu")
		(net "ESPI_LPC_D0_IO0")
	)
	(segment
		(start 65.2526 -58.42)
		(end 64.900048 -58.067448)
		(width 0.11684)
		(layer "B.Cu")
		(net "ESPI_LPC_D0_IO0")
	)
	(segment
		(start 64.900048 -58.067448)
		(end 64.900048 -57.995566)
		(width 0.11684)
		(layer "B.Cu")
		(net "ESPI_LPC_D0_IO0")
	)
	(segment
		(start 52.094892 -41.771316)
		(end 51.699668 -41.376092)
		(width 0.11684)
		(layer "F.Cu")
		(net "JTAG_1_BMC_TRST_R")
	)
	(via
		(at 51.699668 -41.376092)
		(size 0.4572)
		(drill 0.254)
		(layers "F.Cu" "B.Cu")
		(net "JTAG_1_BMC_TRST_R")
	)
	(via
		(at 51.370738 -36.9316)
		(size 0.6604)
		(drill 0.3302)
		(layers "F.Cu" "B.Cu")
		(net "JTAG_1_BMC_TRST_R")
	)
	(segment
		(start 51.5366 -35.07105)
		(end 51.370738 -35.236912)
		(width 0.11684)
		(layer "B.Cu")
		(net "JTAG_1_BMC_TRST_R")
	)
	(segment
		(start 51.370738 -35.236912)
		(end 51.370738 -36.9316)
		(width 0.11684)
		(layer "B.Cu")
		(net "JTAG_1_BMC_TRST_R")
	)
	(segment
		(start 52.10556 -40.344598)
		(end 52.10556 -40.9702)
		(width 0.11684)
		(layer "B.Cu")
		(net "JTAG_1_BMC_TRST_R")
	)
	(segment
		(start 52.10556 -40.9702)
		(end 51.699668 -41.376092)
		(width 0.11684)
		(layer "B.Cu")
		(net "JTAG_1_BMC_TRST_R")
	)
	(segment
		(start 51.8414 -40.080438)
		(end 52.10556 -40.344598)
		(width 0.11684)
		(layer "B.Cu")
		(net "JTAG_1_BMC_TRST_R")
	)
	(segment
		(start 51.8414 -39.014654)
		(end 51.8414 -40.080438)
		(width 0.11684)
		(layer "B.Cu")
		(net "JTAG_1_BMC_TRST_R")
	)
	(segment
		(start 51.80076 -38.974014)
		(end 51.8414 -39.014654)
		(width 0.11684)
		(layer "B.Cu")
		(net "JTAG_1_BMC_TRST_R")
	)
	(segment
		(start 51.80076 -37.361114)
		(end 51.80076 -38.974014)
		(width 0.11684)
		(layer "B.Cu")
		(net "JTAG_1_BMC_TRST_R")
	)
	(segment
		(start 51.370738 -36.9316)
		(end 51.80076 -37.361114)
		(width 0.11684)
		(layer "B.Cu")
		(net "JTAG_1_BMC_TRST_R")
	)
	(segment
		(start 52.894992 -41.771316)
		(end 52.499768 -41.376092)
		(width 0.11684)
		(layer "F.Cu")
		(net "JTAG_1_BMC_TMS_R")
	)
	(via
		(at 52.499768 -41.376092)
		(size 0.4572)
		(drill 0.254)
		(layers "F.Cu" "B.Cu")
		(net "JTAG_1_BMC_TMS_R")
	)
	(segment
		(start 52.89296 -40.9829)
		(end 52.499768 -41.376092)
		(width 0.11684)
		(layer "B.Cu")
		(net "JTAG_1_BMC_TMS_R")
	)
	(segment
		(start 52.2732 -37.687504)
		(end 52.2732 -39.269924)
		(width 0.11684)
		(layer "B.Cu")
		(net "JTAG_1_BMC_TMS_R")
	)
	(segment
		(start 52.328318 -40.17264)
		(end 52.66944 -40.17264)
		(width 0.11684)
		(layer "B.Cu")
		(net "JTAG_1_BMC_TMS_R")
	)
	(segment
		(start 52.091844 -39.936166)
		(end 52.328318 -40.17264)
		(width 0.11684)
		(layer "B.Cu")
		(net "JTAG_1_BMC_TMS_R")
	)
	(segment
		(start 52.091844 -39.708074)
		(end 52.091844 -39.936166)
		(width 0.11684)
		(layer "B.Cu")
		(net "JTAG_1_BMC_TMS_R")
	)
	(segment
		(start 52.2732 -39.269924)
		(end 52.091844 -39.708074)
		(width 0.11684)
		(layer "B.Cu")
		(net "JTAG_1_BMC_TMS_R")
	)
	(segment
		(start 52.89296 -40.39616)
		(end 52.89296 -40.9829)
		(width 0.11684)
		(layer "B.Cu")
		(net "JTAG_1_BMC_TMS_R")
	)
	(segment
		(start 52.555648 -37.405056)
		(end 52.2732 -37.687504)
		(width 0.11684)
		(layer "B.Cu")
		(net "JTAG_1_BMC_TMS_R")
	)
	(segment
		(start 52.66944 -40.17264)
		(end 52.89296 -40.39616)
		(width 0.11684)
		(layer "B.Cu")
		(net "JTAG_1_BMC_TMS_R")
	)
	(segment
		(start 53.71846 -36.4998)
		(end 53.71846 -36.857686)
		(width 0.11684)
		(layer "F.Cu")
		(net "JTAG_1_BMC_TDI_R")
	)
	(segment
		(start 53.1622 -36.3728)
		(end 53.1622 -35.208718)
		(width 0.11684)
		(layer "F.Cu")
		(net "JTAG_1_BMC_TDI_R")
	)
	(segment
		(start 53.2892 -36.4998)
		(end 53.1622 -36.3728)
		(width 0.11684)
		(layer "F.Cu")
		(net "JTAG_1_BMC_TDI_R")
	)
	(segment
		(start 53.71846 -36.857686)
		(end 52.894992 -37.681154)
		(width 0.11684)
		(layer "F.Cu")
		(net "JTAG_1_BMC_TDI_R")
	)
	(segment
		(start 53.71846 -36.4998)
		(end 53.2892 -36.4998)
		(width 0.11684)
		(layer "F.Cu")
		(net "JTAG_1_BMC_TDI_R")
	)
	(segment
		(start 53.1622 -35.208718)
		(end 52.991258 -35.037776)
		(width 0.11684)
		(layer "F.Cu")
		(net "JTAG_1_BMC_TDI_R")
	)
	(segment
		(start 52.894992 -37.681154)
		(end 52.894992 -39.37127)
		(width 0.11684)
		(layer "F.Cu")
		(net "JTAG_1_BMC_TDI_R")
	)
	(via
		(at 53.71846 -36.4998)
		(size 0.508)
		(drill 0.254)
		(layers "F.Cu" "B.Cu")
		(net "JTAG_1_BMC_TDI_R")
	)
	(segment
		(start 52.094892 -42.571162)
		(end 51.699668 -42.175938)
		(width 0.11684)
		(layer "F.Cu")
		(net "JTAG_1_BMC_TCK_R")
	)
	(via
		(at 51.699668 -42.175938)
		(size 0.4572)
		(drill 0.254)
		(layers "F.Cu" "B.Cu")
		(net "JTAG_1_BMC_TCK_R")
	)
	(via
		(at 47.541688 -36.492688)
		(size 0.6604)
		(drill 0.3302)
		(layers "F.Cu" "B.Cu")
		(net "JTAG_1_BMC_TCK_R")
	)
	(segment
		(start 50.501042 -41.1988)
		(end 50.501042 -42.456608)
		(width 0.11684)
		(layer "B.Cu")
		(net "JTAG_1_BMC_TCK_R")
	)
	(segment
		(start 47.541688 -36.492688)
		(end 47.768764 -36.492688)
		(width 0.11684)
		(layer "B.Cu")
		(net "JTAG_1_BMC_TCK_R")
	)
	(segment
		(start 50.266854 -40.964612)
		(end 50.501042 -41.1988)
		(width 0.11684)
		(layer "B.Cu")
		(net "JTAG_1_BMC_TCK_R")
	)
	(segment
		(start 47.768764 -36.492688)
		(end 48.640238 -37.364162)
		(width 0.11684)
		(layer "B.Cu")
		(net "JTAG_1_BMC_TCK_R")
	)
	(segment
		(start 49.492662 -38.84422)
		(end 49.492662 -40.150796)
		(width 0.11684)
		(layer "B.Cu")
		(net "JTAG_1_BMC_TCK_R")
	)
	(segment
		(start 49.492662 -40.150796)
		(end 49.711102 -40.369236)
		(width 0.11684)
		(layer "B.Cu")
		(net "JTAG_1_BMC_TCK_R")
	)
	(segment
		(start 49.711102 -40.369236)
		(end 49.711102 -40.737028)
		(width 0.11684)
		(layer "B.Cu")
		(net "JTAG_1_BMC_TCK_R")
	)
	(segment
		(start 46.27118 -35.236912)
		(end 46.27118 -35.879786)
		(width 0.11684)
		(layer "B.Cu")
		(net "JTAG_1_BMC_TCK_R")
	)
	(segment
		(start 49.938686 -40.964612)
		(end 50.266854 -40.964612)
		(width 0.11684)
		(layer "B.Cu")
		(net "JTAG_1_BMC_TCK_R")
	)
	(segment
		(start 46.27118 -35.879786)
		(end 46.884082 -36.492688)
		(width 0.11684)
		(layer "B.Cu")
		(net "JTAG_1_BMC_TCK_R")
	)
	(segment
		(start 48.640238 -37.364162)
		(end 48.640238 -37.991796)
		(width 0.11684)
		(layer "B.Cu")
		(net "JTAG_1_BMC_TCK_R")
	)
	(segment
		(start 50.630836 -42.586402)
		(end 51.289204 -42.586402)
		(width 0.11684)
		(layer "B.Cu")
		(net "JTAG_1_BMC_TCK_R")
	)
	(segment
		(start 51.289204 -42.586402)
		(end 51.699668 -42.175938)
		(width 0.11684)
		(layer "B.Cu")
		(net "JTAG_1_BMC_TCK_R")
	)
	(segment
		(start 46.884082 -36.492688)
		(end 47.541688 -36.492688)
		(width 0.11684)
		(layer "B.Cu")
		(net "JTAG_1_BMC_TCK_R")
	)
	(segment
		(start 49.711102 -40.737028)
		(end 49.938686 -40.964612)
		(width 0.11684)
		(layer "B.Cu")
		(net "JTAG_1_BMC_TCK_R")
	)
	(segment
		(start 50.501042 -42.456608)
		(end 50.630836 -42.586402)
		(width 0.11684)
		(layer "B.Cu")
		(net "JTAG_1_BMC_TCK_R")
	)
	(segment
		(start 46.470316 -35.037776)
		(end 46.27118 -35.236912)
		(width 0.11684)
		(layer "B.Cu")
		(net "JTAG_1_BMC_TCK_R")
	)
	(segment
		(start 48.640238 -37.991796)
		(end 49.492662 -38.84422)
		(width 0.11684)
		(layer "B.Cu")
		(net "JTAG_1_BMC_TCK_R")
	)
	(segment
		(start 73.2028 -88.4682)
		(end 73.2028 -90.3732)
		(width 0.11684)
		(layer "F.Cu")
		(net "IRQ_TPM_SPI_N")
	)
	(segment
		(start 71.4502 -86.7156)
		(end 73.2028 -88.4682)
		(width 0.11684)
		(layer "F.Cu")
		(net "IRQ_TPM_SPI_N")
	)
	(segment
		(start 73.2028 -90.3732)
		(end 72.25665 -91.31935)
		(width 0.11684)
		(layer "F.Cu")
		(net "IRQ_TPM_SPI_N")
	)
	(segment
		(start 53.695092 -59.37123)
		(end 53.275484 -59.790838)
		(width 0.11684)
		(layer "F.Cu")
		(net "IRQ_TPM_SPI_N")
	)
	(segment
		(start 72.842628 -94.644718)
		(end 73.238868 -94.644718)
		(width 0.11684)
		(layer "F.Cu")
		(net "IRQ_TPM_SPI_N")
	)
	(segment
		(start 72.25665 -91.31935)
		(end 72.25665 -94.470982)
		(width 0.11684)
		(layer "F.Cu")
		(net "IRQ_TPM_SPI_N")
	)
	(segment
		(start 72.25665 -94.470982)
		(end 72.279764 -94.494096)
		(width 0.11684)
		(layer "F.Cu")
		(net "IRQ_TPM_SPI_N")
	)
	(segment
		(start 73.238868 -94.644718)
		(end 73.25995 -94.6658)
		(width 0.11684)
		(layer "F.Cu")
		(net "IRQ_TPM_SPI_N")
	)
	(segment
		(start 72.279764 -94.494096)
		(end 72.692006 -94.494096)
		(width 0.11684)
		(layer "F.Cu")
		(net "IRQ_TPM_SPI_N")
	)
	(segment
		(start 71.4502 -78.4352)
		(end 71.4502 -86.7156)
		(width 0.11684)
		(layer "F.Cu")
		(net "IRQ_TPM_SPI_N")
	)
	(segment
		(start 72.692006 -94.494096)
		(end 72.842628 -94.644718)
		(width 0.11684)
		(layer "F.Cu")
		(net "IRQ_TPM_SPI_N")
	)
	(via
		(at 42.771568 -75.817222)
		(size 0.508)
		(drill 0.254)
		(layers "F.Cu" "B.Cu")
		(net "IRQ_TPM_SPI_N")
	)
	(via
		(at 73.2028 -88.4682)
		(size 0.762)
		(drill 0.381)
		(layers "F.Cu" "B.Cu")
		(net "IRQ_TPM_SPI_N")
	)
	(via
		(at 71.4502 -78.4352)
		(size 0.508)
		(drill 0.254)
		(layers "F.Cu" "B.Cu")
		(net "IRQ_TPM_SPI_N")
	)
	(via
		(at 53.275484 -59.790838)
		(size 0.4572)
		(drill 0.254)
		(layers "F.Cu" "B.Cu")
		(net "IRQ_TPM_SPI_N")
	)
	(segment
		(start 47.71517 -76.89977)
		(end 47.9552 -77.1398)
		(width 0.08382)
		(layer "In2.Cu")
		(net "IRQ_TPM_SPI_N")
	)
	(segment
		(start 71.0946 -78.7908)
		(end 71.4502 -78.4352)
		(width 0.08382)
		(layer "In2.Cu")
		(net "IRQ_TPM_SPI_N")
	)
	(segment
		(start 44.443904 -75.817222)
		(end 45.329856 -76.703174)
		(width 0.08382)
		(layer "In2.Cu")
		(net "IRQ_TPM_SPI_N")
	)
	(segment
		(start 54.01945 -77.095096)
		(end 54.01945 -76.963524)
		(width 0.08382)
		(layer "In2.Cu")
		(net "IRQ_TPM_SPI_N")
	)
	(segment
		(start 54.6354 -76.7588)
		(end 57.785 -79.9084)
		(width 0.08382)
		(layer "In2.Cu")
		(net "IRQ_TPM_SPI_N")
	)
	(segment
		(start 54.224174 -76.7588)
		(end 54.6354 -76.7588)
		(width 0.08382)
		(layer "In2.Cu")
		(net "IRQ_TPM_SPI_N")
	)
	(segment
		(start 54.01945 -76.963524)
		(end 54.224174 -76.7588)
		(width 0.08382)
		(layer "In2.Cu")
		(net "IRQ_TPM_SPI_N")
	)
	(segment
		(start 59.884818 -79.9084)
		(end 60.143898 -79.64932)
		(width 0.08382)
		(layer "In2.Cu")
		(net "IRQ_TPM_SPI_N")
	)
	(segment
		(start 60.143898 -79.64932)
		(end 61.72708 -79.64932)
		(width 0.08382)
		(layer "In2.Cu")
		(net "IRQ_TPM_SPI_N")
	)
	(segment
		(start 53.229256 -77.88529)
		(end 54.01945 -77.095096)
		(width 0.08382)
		(layer "In2.Cu")
		(net "IRQ_TPM_SPI_N")
	)
	(segment
		(start 61.72708 -79.64932)
		(end 62.4586 -78.9178)
		(width 0.08382)
		(layer "In2.Cu")
		(net "IRQ_TPM_SPI_N")
	)
	(segment
		(start 57.785 -79.9084)
		(end 59.884818 -79.9084)
		(width 0.08382)
		(layer "In2.Cu")
		(net "IRQ_TPM_SPI_N")
	)
	(segment
		(start 45.80509 -76.89977)
		(end 47.71517 -76.89977)
		(width 0.08382)
		(layer "In2.Cu")
		(net "IRQ_TPM_SPI_N")
	)
	(segment
		(start 65.59677 -78.3336)
		(end 66.8274 -78.3336)
		(width 0.08382)
		(layer "In2.Cu")
		(net "IRQ_TPM_SPI_N")
	)
	(segment
		(start 65.01257 -78.9178)
		(end 65.59677 -78.3336)
		(width 0.08382)
		(layer "In2.Cu")
		(net "IRQ_TPM_SPI_N")
	)
	(segment
		(start 62.4586 -78.9178)
		(end 65.01257 -78.9178)
		(width 0.08382)
		(layer "In2.Cu")
		(net "IRQ_TPM_SPI_N")
	)
	(segment
		(start 47.9552 -77.1398)
		(end 50.632868 -77.1398)
		(width 0.08382)
		(layer "In2.Cu")
		(net "IRQ_TPM_SPI_N")
	)
	(segment
		(start 67.2846 -78.7908)
		(end 71.0946 -78.7908)
		(width 0.08382)
		(layer "In2.Cu")
		(net "IRQ_TPM_SPI_N")
	)
	(segment
		(start 66.8274 -78.3336)
		(end 67.2846 -78.7908)
		(width 0.08382)
		(layer "In2.Cu")
		(net "IRQ_TPM_SPI_N")
	)
	(segment
		(start 50.632868 -77.1398)
		(end 51.378358 -77.88529)
		(width 0.08382)
		(layer "In2.Cu")
		(net "IRQ_TPM_SPI_N")
	)
	(segment
		(start 45.512736 -76.778866)
		(end 45.80509 -76.89977)
		(width 0.08382)
		(layer "In2.Cu")
		(net "IRQ_TPM_SPI_N")
	)
	(segment
		(start 45.329856 -76.703174)
		(end 45.512736 -76.778866)
		(width 0.08382)
		(layer "In2.Cu")
		(net "IRQ_TPM_SPI_N")
	)
	(segment
		(start 42.771568 -75.817222)
		(end 44.443904 -75.817222)
		(width 0.08382)
		(layer "In2.Cu")
		(net "IRQ_TPM_SPI_N")
	)
	(segment
		(start 51.378358 -77.88529)
		(end 53.229256 -77.88529)
		(width 0.08382)
		(layer "In2.Cu")
		(net "IRQ_TPM_SPI_N")
	)
	(segment
		(start 46.1518 -71.12)
		(end 46.1518 -70.0024)
		(width 0.08382)
		(layer "In9.Cu")
		(net "IRQ_TPM_SPI_N")
	)
	(segment
		(start 42.771568 -75.368658)
		(end 44.958 -73.182226)
		(width 0.08382)
		(layer "In9.Cu")
		(net "IRQ_TPM_SPI_N")
	)
	(segment
		(start 44.958 -72.3138)
		(end 46.1518 -71.12)
		(width 0.08382)
		(layer "In9.Cu")
		(net "IRQ_TPM_SPI_N")
	)
	(segment
		(start 47.0916 -64.977518)
		(end 47.0916 -64.24422)
		(width 0.08382)
		(layer "In9.Cu")
		(net "IRQ_TPM_SPI_N")
	)
	(segment
		(start 51.779678 -61.286644)
		(end 53.275484 -59.790838)
		(width 0.08382)
		(layer "In9.Cu")
		(net "IRQ_TPM_SPI_N")
	)
	(segment
		(start 45.81398 -68.326)
		(end 46.34738 -67.7926)
		(width 0.08382)
		(layer "In9.Cu")
		(net "IRQ_TPM_SPI_N")
	)
	(segment
		(start 47.538132 -67.346068)
		(end 47.538132 -65.521332)
		(width 0.08382)
		(layer "In9.Cu")
		(net "IRQ_TPM_SPI_N")
	)
	(segment
		(start 44.958 -73.182226)
		(end 44.958 -72.3138)
		(width 0.08382)
		(layer "In9.Cu")
		(net "IRQ_TPM_SPI_N")
	)
	(segment
		(start 42.771568 -75.817222)
		(end 42.771568 -75.368658)
		(width 0.08382)
		(layer "In9.Cu")
		(net "IRQ_TPM_SPI_N")
	)
	(segment
		(start 46.1518 -70.0024)
		(end 45.81398 -69.66458)
		(width 0.08382)
		(layer "In9.Cu")
		(net "IRQ_TPM_SPI_N")
	)
	(segment
		(start 47.538132 -65.521332)
		(end 47.160434 -65.143634)
		(width 0.08382)
		(layer "In9.Cu")
		(net "IRQ_TPM_SPI_N")
	)
	(segment
		(start 47.0916 -67.7926)
		(end 47.538132 -67.346068)
		(width 0.08382)
		(layer "In9.Cu")
		(net "IRQ_TPM_SPI_N")
	)
	(segment
		(start 48.825912 -62.509908)
		(end 51.779678 -61.286644)
		(width 0.08382)
		(layer "In9.Cu")
		(net "IRQ_TPM_SPI_N")
	)
	(segment
		(start 46.34738 -67.7926)
		(end 47.0916 -67.7926)
		(width 0.08382)
		(layer "In9.Cu")
		(net "IRQ_TPM_SPI_N")
	)
	(segment
		(start 47.160434 -65.143634)
		(end 47.0916 -64.977518)
		(width 0.08382)
		(layer "In9.Cu")
		(net "IRQ_TPM_SPI_N")
	)
	(segment
		(start 45.81398 -69.66458)
		(end 45.81398 -68.326)
		(width 0.08382)
		(layer "In9.Cu")
		(net "IRQ_TPM_SPI_N")
	)
	(segment
		(start 47.0916 -64.24422)
		(end 48.825912 -62.509908)
		(width 0.08382)
		(layer "In9.Cu")
		(net "IRQ_TPM_SPI_N")
	)
	(segment
		(start 40.607996 -48.6918)
		(end 40.35425 -48.6918)
		(width 0.11684)
		(layer "F.Cu")
		(net "H_CPU1_PROCHOT_LVC1_N")
	)
	(segment
		(start 46.09973 -49.376076)
		(end 46.494954 -49.7713)
		(width 0.11684)
		(layer "F.Cu")
		(net "H_CPU1_PROCHOT_LVC1_N")
	)
	(segment
		(start 41.759378 -48.8696)
		(end 40.785796 -48.8696)
		(width 0.11684)
		(layer "F.Cu")
		(net "H_CPU1_PROCHOT_LVC1_N")
	)
	(segment
		(start 43.575986 -49.51222)
		(end 43.71213 -49.376076)
		(width 0.11684)
		(layer "F.Cu")
		(net "H_CPU1_PROCHOT_LVC1_N")
	)
	(segment
		(start 43.190414 -49.51222)
		(end 43.575986 -49.51222)
		(width 0.11684)
		(layer "F.Cu")
		(net "H_CPU1_PROCHOT_LVC1_N")
	)
	(segment
		(start 43.71213 -49.376076)
		(end 46.09973 -49.376076)
		(width 0.11684)
		(layer "F.Cu")
		(net "H_CPU1_PROCHOT_LVC1_N")
	)
	(segment
		(start 41.91 -48.718978)
		(end 42.397172 -48.718978)
		(width 0.11684)
		(layer "F.Cu")
		(net "H_CPU1_PROCHOT_LVC1_N")
	)
	(segment
		(start 41.91 -48.718978)
		(end 41.759378 -48.8696)
		(width 0.11684)
		(layer "F.Cu")
		(net "H_CPU1_PROCHOT_LVC1_N")
	)
	(segment
		(start 42.397172 -48.718978)
		(end 43.190414 -49.51222)
		(width 0.11684)
		(layer "F.Cu")
		(net "H_CPU1_PROCHOT_LVC1_N")
	)
	(segment
		(start 40.785796 -48.8696)
		(end 40.607996 -48.6918)
		(width 0.11684)
		(layer "F.Cu")
		(net "H_CPU1_PROCHOT_LVC1_N")
	)
	(via
		(at 41.91 -48.718978)
		(size 0.762)
		(drill 0.381)
		(layers "F.Cu" "B.Cu")
		(net "H_CPU1_PROCHOT_LVC1_N")
	)
	(via
		(at 57.710324 -101.6254)
		(size 0.508)
		(drill 0.254)
		(layers "F.Cu" "B.Cu")
		(net "IRQ_SMI_ACTIVE_GF_N")
	)
	(via
		(at 56.896 -114.0714)
		(size 0.508)
		(drill 0.254)
		(layers "F.Cu" "B.Cu")
		(net "IRQ_SMI_ACTIVE_GF_N")
	)
	(via
		(at 20.06854 -113.2205)
		(size 0.508)
		(drill 0.254)
		(layers "F.Cu" "B.Cu")
		(net "IRQ_SMI_ACTIVE_GF_N")
	)
	(via
		(at 58.55589 -62.119256)
		(size 0.508)
		(drill 0.254)
		(layers "F.Cu" "B.Cu")
		(net "IRQ_SMI_ACTIVE_GF_N")
	)
	(segment
		(start 20.06854 -113.743486)
		(end 21.7424 -115.417346)
		(width 0.11684)
		(layer "B.Cu")
		(net "IRQ_SMI_ACTIVE_GF_N")
	)
	(segment
		(start 22.479 -117.0686)
		(end 22.746462 -117.336062)
		(width 0.11684)
		(layer "B.Cu")
		(net "IRQ_SMI_ACTIVE_GF_N")
	)
	(segment
		(start 22.475444 -117.061742)
		(end 22.479 -117.065298)
		(width 0.11684)
		(layer "B.Cu")
		(net "IRQ_SMI_ACTIVE_GF_N")
	)
	(segment
		(start 22.746462 -117.336062)
		(end 22.744938 -117.337586)
		(width 0.11684)
		(layer "B.Cu")
		(net "IRQ_SMI_ACTIVE_GF_N")
	)
	(segment
		(start 58.55589 -61.46546)
		(end 58.55589 -62.119256)
		(width 0.11684)
		(layer "B.Cu")
		(net "IRQ_SMI_ACTIVE_GF_N")
	)
	(segment
		(start 20.06854 -113.2205)
		(end 20.06854 -113.743486)
		(width 0.11684)
		(layer "B.Cu")
		(net "IRQ_SMI_ACTIVE_GF_N")
	)
	(segment
		(start 21.7424 -115.468146)
		(end 22.475444 -116.20119)
		(width 0.11684)
		(layer "B.Cu")
		(net "IRQ_SMI_ACTIVE_GF_N")
	)
	(segment
		(start 22.744938 -117.337586)
		(end 22.744938 -118.25986)
		(width 0.11684)
		(layer "B.Cu")
		(net "IRQ_SMI_ACTIVE_GF_N")
	)
	(segment
		(start 22.475444 -116.20119)
		(end 22.475444 -117.061742)
		(width 0.11684)
		(layer "B.Cu")
		(net "IRQ_SMI_ACTIVE_GF_N")
	)
	(segment
		(start 22.479 -117.065298)
		(end 22.479 -117.0686)
		(width 0.11684)
		(layer "B.Cu")
		(net "IRQ_SMI_ACTIVE_GF_N")
	)
	(segment
		(start 21.7424 -115.417346)
		(end 21.7424 -115.468146)
		(width 0.11684)
		(layer "B.Cu")
		(net "IRQ_SMI_ACTIVE_GF_N")
	)
	(segment
		(start 58.55208 -61.46165)
		(end 58.55589 -61.46546)
		(width 0.11684)
		(layer "B.Cu")
		(net "IRQ_SMI_ACTIVE_GF_N")
	)
	(segment
		(start 44.4246 -112.5474)
		(end 41.0464 -115.9256)
		(width 0.08382)
		(layer "In2.Cu")
		(net "IRQ_SMI_ACTIVE_GF_N")
	)
	(segment
		(start 48.274732 -114.28984)
		(end 46.532292 -112.5474)
		(width 0.08382)
		(layer "In2.Cu")
		(net "IRQ_SMI_ACTIVE_GF_N")
	)
	(segment
		(start 46.532292 -112.5474)
		(end 44.4246 -112.5474)
		(width 0.08382)
		(layer "In2.Cu")
		(net "IRQ_SMI_ACTIVE_GF_N")
	)
	(segment
		(start 35.70986 -112.82426)
		(end 30.2006 -112.82426)
		(width 0.08382)
		(layer "In2.Cu")
		(net "IRQ_SMI_ACTIVE_GF_N")
	)
	(segment
		(start 22.05228 -112.68202)
		(end 20.60702 -112.68202)
		(width 0.08382)
		(layer "In2.Cu")
		(net "IRQ_SMI_ACTIVE_GF_N")
	)
	(segment
		(start 41.0464 -115.9256)
		(end 38.8112 -115.9256)
		(width 0.08382)
		(layer "In2.Cu")
		(net "IRQ_SMI_ACTIVE_GF_N")
	)
	(segment
		(start 24.88946 -113.92662)
		(end 23.29688 -113.92662)
		(width 0.08382)
		(layer "In2.Cu")
		(net "IRQ_SMI_ACTIVE_GF_N")
	)
	(segment
		(start 56.896 -114.0714)
		(end 55.9689 -114.9985)
		(width 0.08382)
		(layer "In2.Cu")
		(net "IRQ_SMI_ACTIVE_GF_N")
	)
	(segment
		(start 50.1523 -114.9985)
		(end 49.44364 -114.28984)
		(width 0.08382)
		(layer "In2.Cu")
		(net "IRQ_SMI_ACTIVE_GF_N")
	)
	(segment
		(start 28.48864 -114.53622)
		(end 25.49906 -114.53622)
		(width 0.08382)
		(layer "In2.Cu")
		(net "IRQ_SMI_ACTIVE_GF_N")
	)
	(segment
		(start 49.44364 -114.28984)
		(end 48.274732 -114.28984)
		(width 0.08382)
		(layer "In2.Cu")
		(net "IRQ_SMI_ACTIVE_GF_N")
	)
	(segment
		(start 38.8112 -115.9256)
		(end 35.70986 -112.82426)
		(width 0.08382)
		(layer "In2.Cu")
		(net "IRQ_SMI_ACTIVE_GF_N")
	)
	(segment
		(start 30.2006 -112.82426)
		(end 28.48864 -114.53622)
		(width 0.08382)
		(layer "In2.Cu")
		(net "IRQ_SMI_ACTIVE_GF_N")
	)
	(segment
		(start 23.29688 -113.92662)
		(end 22.05228 -112.68202)
		(width 0.08382)
		(layer "In2.Cu")
		(net "IRQ_SMI_ACTIVE_GF_N")
	)
	(segment
		(start 55.9689 -114.9985)
		(end 50.1523 -114.9985)
		(width 0.08382)
		(layer "In2.Cu")
		(net "IRQ_SMI_ACTIVE_GF_N")
	)
	(segment
		(start 25.49906 -114.53622)
		(end 24.88946 -113.92662)
		(width 0.08382)
		(layer "In2.Cu")
		(net "IRQ_SMI_ACTIVE_GF_N")
	)
	(segment
		(start 20.60702 -112.68202)
		(end 20.06854 -113.2205)
		(width 0.08382)
		(layer "In2.Cu")
		(net "IRQ_SMI_ACTIVE_GF_N")
	)
	(segment
		(start 57.13222 -103.32212)
		(end 57.710324 -102.744016)
		(width 0.10668)
		(layer "In4.Cu")
		(net "IRQ_SMI_ACTIVE_GF_N")
	)
	(segment
		(start 59.703462 -85.98408)
		(end 58.433462 -85.98408)
		(width 0.10668)
		(layer "In4.Cu")
		(net "IRQ_SMI_ACTIVE_GF_N")
	)
	(segment
		(start 60.13196 -93.198188)
		(end 60.41136 -92.52331)
		(width 0.10668)
		(layer "In4.Cu")
		(net "IRQ_SMI_ACTIVE_GF_N")
	)
	(segment
		(start 57.710324 -102.744016)
		(end 57.710324 -101.6254)
		(width 0.10668)
		(layer "In4.Cu")
		(net "IRQ_SMI_ACTIVE_GF_N")
	)
	(segment
		(start 57.08904 -84.404708)
		(end 56.57596 -83.891628)
		(width 0.10668)
		(layer "In4.Cu")
		(net "IRQ_SMI_ACTIVE_GF_N")
	)
	(segment
		(start 58.433462 -85.98408)
		(end 57.09412 -84.644738)
		(width 0.10668)
		(layer "In4.Cu")
		(net "IRQ_SMI_ACTIVE_GF_N")
	)
	(segment
		(start 55.90794 -108.60786)
		(end 56.2356 -108.2802)
		(width 0.10668)
		(layer "In4.Cu")
		(net "IRQ_SMI_ACTIVE_GF_N")
	)
	(segment
		(start 56.2356 -105.37444)
		(end 57.13222 -104.47782)
		(width 0.10668)
		(layer "In4.Cu")
		(net "IRQ_SMI_ACTIVE_GF_N")
	)
	(segment
		(start 58.81116 -79.36484)
		(end 58.81116 -73.90384)
		(width 0.10668)
		(layer "In4.Cu")
		(net "IRQ_SMI_ACTIVE_GF_N")
	)
	(segment
		(start 56.2356 -108.2802)
		(end 56.2356 -105.37444)
		(width 0.10668)
		(layer "In4.Cu")
		(net "IRQ_SMI_ACTIVE_GF_N")
	)
	(segment
		(start 56.57596 -83.891628)
		(end 56.57596 -81.60004)
		(width 0.10668)
		(layer "In4.Cu")
		(net "IRQ_SMI_ACTIVE_GF_N")
	)
	(segment
		(start 56.896 -114.0714)
		(end 56.55056 -114.0714)
		(width 0.10668)
		(layer "In4.Cu")
		(net "IRQ_SMI_ACTIVE_GF_N")
	)
	(segment
		(start 57.09412 -84.602574)
		(end 57.08904 -84.597494)
		(width 0.10668)
		(layer "In4.Cu")
		(net "IRQ_SMI_ACTIVE_GF_N")
	)
	(segment
		(start 59.653932 -64.428878)
		(end 58.55589 -63.330836)
		(width 0.10668)
		(layer "In4.Cu")
		(net "IRQ_SMI_ACTIVE_GF_N")
	)
	(segment
		(start 57.13222 -104.47782)
		(end 57.13222 -103.32212)
		(width 0.10668)
		(layer "In4.Cu")
		(net "IRQ_SMI_ACTIVE_GF_N")
	)
	(segment
		(start 59.653932 -73.061068)
		(end 59.653932 -64.428878)
		(width 0.10668)
		(layer "In4.Cu")
		(net "IRQ_SMI_ACTIVE_GF_N")
	)
	(segment
		(start 58.43016 -97.0661)
		(end 58.85688 -96.63938)
		(width 0.10668)
		(layer "In4.Cu")
		(net "IRQ_SMI_ACTIVE_GF_N")
	)
	(segment
		(start 57.710324 -101.024436)
		(end 58.43016 -100.3046)
		(width 0.10668)
		(layer "In4.Cu")
		(net "IRQ_SMI_ACTIVE_GF_N")
	)
	(segment
		(start 58.55589 -63.330836)
		(end 58.55589 -62.119256)
		(width 0.10668)
		(layer "In4.Cu")
		(net "IRQ_SMI_ACTIVE_GF_N")
	)
	(segment
		(start 55.90794 -113.42878)
		(end 55.90794 -108.60786)
		(width 0.10668)
		(layer "In4.Cu")
		(net "IRQ_SMI_ACTIVE_GF_N")
	)
	(segment
		(start 57.710324 -101.6254)
		(end 57.710324 -101.024436)
		(width 0.10668)
		(layer "In4.Cu")
		(net "IRQ_SMI_ACTIVE_GF_N")
	)
	(segment
		(start 57.08904 -84.597494)
		(end 57.08904 -84.404708)
		(width 0.10668)
		(layer "In4.Cu")
		(net "IRQ_SMI_ACTIVE_GF_N")
	)
	(segment
		(start 58.85688 -96.63938)
		(end 59.387486 -96.63938)
		(width 0.10668)
		(layer "In4.Cu")
		(net "IRQ_SMI_ACTIVE_GF_N")
	)
	(segment
		(start 58.81116 -73.90384)
		(end 59.653932 -73.061068)
		(width 0.10668)
		(layer "In4.Cu")
		(net "IRQ_SMI_ACTIVE_GF_N")
	)
	(segment
		(start 60.13196 -95.894906)
		(end 60.13196 -93.198188)
		(width 0.10668)
		(layer "In4.Cu")
		(net "IRQ_SMI_ACTIVE_GF_N")
	)
	(segment
		(start 58.43016 -100.3046)
		(end 58.43016 -97.0661)
		(width 0.10668)
		(layer "In4.Cu")
		(net "IRQ_SMI_ACTIVE_GF_N")
	)
	(segment
		(start 60.41136 -92.52331)
		(end 60.41136 -86.691978)
		(width 0.10668)
		(layer "In4.Cu")
		(net "IRQ_SMI_ACTIVE_GF_N")
	)
	(segment
		(start 56.57596 -81.60004)
		(end 58.81116 -79.36484)
		(width 0.10668)
		(layer "In4.Cu")
		(net "IRQ_SMI_ACTIVE_GF_N")
	)
	(segment
		(start 57.09412 -84.644738)
		(end 57.09412 -84.602574)
		(width 0.10668)
		(layer "In4.Cu")
		(net "IRQ_SMI_ACTIVE_GF_N")
	)
	(segment
		(start 59.387486 -96.63938)
		(end 60.13196 -95.894906)
		(width 0.10668)
		(layer "In4.Cu")
		(net "IRQ_SMI_ACTIVE_GF_N")
	)
	(segment
		(start 56.55056 -114.0714)
		(end 55.90794 -113.42878)
		(width 0.10668)
		(layer "In4.Cu")
		(net "IRQ_SMI_ACTIVE_GF_N")
	)
	(segment
		(start 60.41136 -86.691978)
		(end 59.703462 -85.98408)
		(width 0.10668)
		(layer "In4.Cu")
		(net "IRQ_SMI_ACTIVE_GF_N")
	)
	(segment
		(start 58.49493 -56.971184)
		(end 58.099706 -57.366408)
		(width 0.11684)
		(layer "F.Cu")
		(net "IRQ_SMI_ACTIVE_BMC_N")
	)
	(via
		(at 58.099706 -57.366408)
		(size 0.4572)
		(drill 0.254)
		(layers "F.Cu" "B.Cu")
		(net "IRQ_SMI_ACTIVE_BMC_N")
	)
	(segment
		(start 58.55208 -60.66155)
		(end 58.55208 -59.315604)
		(width 0.11684)
		(layer "B.Cu")
		(net "IRQ_SMI_ACTIVE_BMC_N")
	)
	(segment
		(start 58.50128 -59.192922)
		(end 58.50128 -57.767982)
		(width 0.11684)
		(layer "B.Cu")
		(net "IRQ_SMI_ACTIVE_BMC_N")
	)
	(segment
		(start 58.50128 -57.767982)
		(end 58.099706 -57.366408)
		(width 0.11684)
		(layer "B.Cu")
		(net "IRQ_SMI_ACTIVE_BMC_N")
	)
	(segment
		(start 58.55208 -59.315604)
		(end 58.50128 -59.192922)
		(width 0.11684)
		(layer "B.Cu")
		(net "IRQ_SMI_ACTIVE_BMC_N")
	)
	(segment
		(start 60.094876 -57.771284)
		(end 59.699652 -57.37606)
		(width 0.11684)
		(layer "F.Cu")
		(net "IRQ_ESPI_LPC_SERIRQ_ALERT0_N")
	)
	(segment
		(start 63.62827 -63.519812)
		(end 63.202312 -63.093854)
		(width 0.11684)
		(layer "F.Cu")
		(net "IRQ_ESPI_LPC_SERIRQ_ALERT0_N")
	)
	(segment
		(start 63.202312 -63.093854)
		(end 62.913006 -62.973966)
		(width 0.11684)
		(layer "F.Cu")
		(net "IRQ_ESPI_LPC_SERIRQ_ALERT0_N")
	)
	(via
		(at 62.913006 -62.973966)
		(size 0.508)
		(drill 0.254)
		(layers "F.Cu" "B.Cu")
		(net "IRQ_ESPI_LPC_SERIRQ_ALERT0_N")
	)
	(via
		(at 59.699652 -57.37606)
		(size 0.4572)
		(drill 0.254)
		(layers "F.Cu" "B.Cu")
		(net "IRQ_ESPI_LPC_SERIRQ_ALERT0_N")
	)
	(segment
		(start 62.913006 -62.973966)
		(end 61.568584 -62.973966)
		(width 0.10668)
		(layer "In4.Cu")
		(net "IRQ_ESPI_LPC_SERIRQ_ALERT0_N")
	)
	(segment
		(start 61.568584 -62.973966)
		(end 60.794138 -62.19952)
		(width 0.10668)
		(layer "In4.Cu")
		(net "IRQ_ESPI_LPC_SERIRQ_ALERT0_N")
	)
	(segment
		(start 60.083192 -58.357262)
		(end 60.083192 -58.016902)
		(width 0.10668)
		(layer "In4.Cu")
		(net "IRQ_ESPI_LPC_SERIRQ_ALERT0_N")
	)
	(segment
		(start 59.1058 -59.334654)
		(end 60.083192 -58.357262)
		(width 0.10668)
		(layer "In4.Cu")
		(net "IRQ_ESPI_LPC_SERIRQ_ALERT0_N")
	)
	(segment
		(start 60.083192 -58.016902)
		(end 59.699652 -57.633362)
		(width 0.10668)
		(layer "In4.Cu")
		(net "IRQ_ESPI_LPC_SERIRQ_ALERT0_N")
	)
	(segment
		(start 60.353702 -62.19952)
		(end 59.1058 -60.951618)
		(width 0.10668)
		(layer "In4.Cu")
		(net "IRQ_ESPI_LPC_SERIRQ_ALERT0_N")
	)
	(segment
		(start 59.1058 -60.951618)
		(end 59.1058 -59.334654)
		(width 0.10668)
		(layer "In4.Cu")
		(net "IRQ_ESPI_LPC_SERIRQ_ALERT0_N")
	)
	(segment
		(start 60.794138 -62.19952)
		(end 60.353702 -62.19952)
		(width 0.10668)
		(layer "In4.Cu")
		(net "IRQ_ESPI_LPC_SERIRQ_ALERT0_N")
	)
	(segment
		(start 59.699652 -57.633362)
		(end 59.699652 -57.37606)
		(width 0.10668)
		(layer "In4.Cu")
		(net "IRQ_ESPI_LPC_SERIRQ_ALERT0_N")
	)
	(segment
		(start 25.859486 -88.387174)
		(end 26.25471 -87.99195)
		(width 0.11684)
		(layer "F.Cu")
		(net "IRQ_BMC_CPU_NMI_R")
	)
	(via
		(at 28.702 -40.8178)
		(size 0.508)
		(drill 0.254)
		(layers "F.Cu" "B.Cu")
		(net "IRQ_BMC_CPU_NMI_R")
	)
	(via
		(at 33.891982 -47.3456)
		(size 0.6604)
		(drill 0.3302)
		(layers "F.Cu" "B.Cu")
		(net "IRQ_BMC_CPU_NMI_R")
	)
	(via
		(at 26.25471 -87.99195)
		(size 0.4572)
		(drill 0.254)
		(layers "F.Cu" "B.Cu")
		(net "IRQ_BMC_CPU_NMI_R")
	)
	(segment
		(start 35.88766 -45.92574)
		(end 35.88766 -45.212254)
		(width 0.11684)
		(layer "B.Cu")
		(net "IRQ_BMC_CPU_NMI_R")
	)
	(segment
		(start 28.1178 -41.402)
		(end 28.1178 -42.44594)
		(width 0.11684)
		(layer "B.Cu")
		(net "IRQ_BMC_CPU_NMI_R")
	)
	(segment
		(start 31.46298 -45.79112)
		(end 31.46298 -46.852586)
		(width 0.11684)
		(layer "B.Cu")
		(net "IRQ_BMC_CPU_NMI_R")
	)
	(segment
		(start 28.1178 -42.44594)
		(end 31.46298 -45.79112)
		(width 0.11684)
		(layer "B.Cu")
		(net "IRQ_BMC_CPU_NMI_R")
	)
	(segment
		(start 38.1508 -43.5102)
		(end 38.5572 -43.9166)
		(width 0.11684)
		(layer "B.Cu")
		(net "IRQ_BMC_CPU_NMI_R")
	)
	(segment
		(start 35.88766 -45.212254)
		(end 37.589714 -43.5102)
		(width 0.11684)
		(layer "B.Cu")
		(net "IRQ_BMC_CPU_NMI_R")
	)
	(segment
		(start 40.553894 -43.9166)
		(end 41.566084 -44.92879)
		(width 0.11684)
		(layer "B.Cu")
		(net "IRQ_BMC_CPU_NMI_R")
	)
	(segment
		(start 38.5572 -43.9166)
		(end 40.553894 -43.9166)
		(width 0.11684)
		(layer "B.Cu")
		(net "IRQ_BMC_CPU_NMI_R")
	)
	(segment
		(start 33.891982 -47.3456)
		(end 34.4678 -47.3456)
		(width 0.11684)
		(layer "B.Cu")
		(net "IRQ_BMC_CPU_NMI_R")
	)
	(segment
		(start 34.4678 -47.3456)
		(end 35.88766 -45.92574)
		(width 0.11684)
		(layer "B.Cu")
		(net "IRQ_BMC_CPU_NMI_R")
	)
	(segment
		(start 28.702 -40.8178)
		(end 28.1178 -41.402)
		(width 0.11684)
		(layer "B.Cu")
		(net "IRQ_BMC_CPU_NMI_R")
	)
	(segment
		(start 31.955994 -47.3456)
		(end 33.891982 -47.3456)
		(width 0.11684)
		(layer "B.Cu")
		(net "IRQ_BMC_CPU_NMI_R")
	)
	(segment
		(start 31.46298 -46.852586)
		(end 31.955994 -47.3456)
		(width 0.11684)
		(layer "B.Cu")
		(net "IRQ_BMC_CPU_NMI_R")
	)
	(segment
		(start 37.589714 -43.5102)
		(end 38.1508 -43.5102)
		(width 0.11684)
		(layer "B.Cu")
		(net "IRQ_BMC_CPU_NMI_R")
	)
	(segment
		(start 23.9522 -86.6648)
		(end 24.765 -87.4776)
		(width 0.10668)
		(layer "In4.Cu")
		(net "IRQ_BMC_CPU_NMI_R")
	)
	(segment
		(start 24.467058 -84.245958)
		(end 23.9522 -84.760816)
		(width 0.10668)
		(layer "In4.Cu")
		(net "IRQ_BMC_CPU_NMI_R")
	)
	(segment
		(start 22.62886 -51.289966)
		(end 22.62886 -56.794654)
		(width 0.10668)
		(layer "In4.Cu")
		(net "IRQ_BMC_CPU_NMI_R")
	)
	(segment
		(start 25.93086 -65.775078)
		(end 25.477978 -66.22796)
		(width 0.10668)
		(layer "In4.Cu")
		(net "IRQ_BMC_CPU_NMI_R")
	)
	(segment
		(start 25.90546 -71.447406)
		(end 25.90546 -73.303384)
		(width 0.10668)
		(layer "In4.Cu")
		(net "IRQ_BMC_CPU_NMI_R")
	)
	(segment
		(start 25.90546 -73.303384)
		(end 26.7081 -74.106024)
		(width 0.10668)
		(layer "In4.Cu")
		(net "IRQ_BMC_CPU_NMI_R")
	)
	(segment
		(start 27.357324 -40.8178)
		(end 23.594314 -44.58081)
		(width 0.10668)
		(layer "In4.Cu")
		(net "IRQ_BMC_CPU_NMI_R")
	)
	(segment
		(start 25.12568 -67.565016)
		(end 25.12568 -70.667626)
		(width 0.10668)
		(layer "In4.Cu")
		(net "IRQ_BMC_CPU_NMI_R")
	)
	(segment
		(start 25.12568 -70.667626)
		(end 25.90546 -71.447406)
		(width 0.10668)
		(layer "In4.Cu")
		(net "IRQ_BMC_CPU_NMI_R")
	)
	(segment
		(start 22.87778 -50.68824)
		(end 22.62886 -51.289966)
		(width 0.10668)
		(layer "In4.Cu")
		(net "IRQ_BMC_CPU_NMI_R")
	)
	(segment
		(start 28.702 -40.8178)
		(end 27.357324 -40.8178)
		(width 0.10668)
		(layer "In4.Cu")
		(net "IRQ_BMC_CPU_NMI_R")
	)
	(segment
		(start 26.7081 -74.106024)
		(end 26.7081 -76.314046)
		(width 0.10668)
		(layer "In4.Cu")
		(net "IRQ_BMC_CPU_NMI_R")
	)
	(segment
		(start 27.15514 -76.761086)
		(end 27.15514 -80.40116)
		(width 0.10668)
		(layer "In4.Cu")
		(net "IRQ_BMC_CPU_NMI_R")
	)
	(segment
		(start 25.8191 -61.847984)
		(end 25.93086 -61.959744)
		(width 0.10668)
		(layer "In4.Cu")
		(net "IRQ_BMC_CPU_NMI_R")
	)
	(segment
		(start 25.8191 -59.984894)
		(end 25.8191 -61.847984)
		(width 0.10668)
		(layer "In4.Cu")
		(net "IRQ_BMC_CPU_NMI_R")
	)
	(segment
		(start 26.19502 -84.245958)
		(end 24.467058 -84.245958)
		(width 0.10668)
		(layer "In4.Cu")
		(net "IRQ_BMC_CPU_NMI_R")
	)
	(segment
		(start 24.765 -87.4776)
		(end 25.74036 -87.4776)
		(width 0.10668)
		(layer "In4.Cu")
		(net "IRQ_BMC_CPU_NMI_R")
	)
	(segment
		(start 26.7081 -76.314046)
		(end 27.15514 -76.761086)
		(width 0.10668)
		(layer "In4.Cu")
		(net "IRQ_BMC_CPU_NMI_R")
	)
	(segment
		(start 23.9522 -84.760816)
		(end 23.9522 -86.6648)
		(width 0.10668)
		(layer "In4.Cu")
		(net "IRQ_BMC_CPU_NMI_R")
	)
	(segment
		(start 25.74036 -87.4776)
		(end 26.25471 -87.99195)
		(width 0.10668)
		(layer "In4.Cu")
		(net "IRQ_BMC_CPU_NMI_R")
	)
	(segment
		(start 26.63698 -80.91932)
		(end 26.63698 -82.70494)
		(width 0.10668)
		(layer "In4.Cu")
		(net "IRQ_BMC_CPU_NMI_R")
	)
	(segment
		(start 25.93086 -61.959744)
		(end 25.93086 -65.775078)
		(width 0.10668)
		(layer "In4.Cu")
		(net "IRQ_BMC_CPU_NMI_R")
	)
	(segment
		(start 26.32202 -84.118958)
		(end 26.19502 -84.245958)
		(width 0.10668)
		(layer "In4.Cu")
		(net "IRQ_BMC_CPU_NMI_R")
	)
	(segment
		(start 23.594314 -44.58081)
		(end 22.87778 -46.311312)
		(width 0.10668)
		(layer "In4.Cu")
		(net "IRQ_BMC_CPU_NMI_R")
	)
	(segment
		(start 26.32202 -83.0199)
		(end 26.32202 -84.118958)
		(width 0.10668)
		(layer "In4.Cu")
		(net "IRQ_BMC_CPU_NMI_R")
	)
	(segment
		(start 22.87778 -46.311312)
		(end 22.87778 -50.68824)
		(width 0.10668)
		(layer "In4.Cu")
		(net "IRQ_BMC_CPU_NMI_R")
	)
	(segment
		(start 25.477978 -67.212718)
		(end 25.12568 -67.565016)
		(width 0.10668)
		(layer "In4.Cu")
		(net "IRQ_BMC_CPU_NMI_R")
	)
	(segment
		(start 26.63698 -82.70494)
		(end 26.32202 -83.0199)
		(width 0.10668)
		(layer "In4.Cu")
		(net "IRQ_BMC_CPU_NMI_R")
	)
	(segment
		(start 25.477978 -66.22796)
		(end 25.477978 -67.212718)
		(width 0.10668)
		(layer "In4.Cu")
		(net "IRQ_BMC_CPU_NMI_R")
	)
	(segment
		(start 27.15514 -80.40116)
		(end 26.63698 -80.91932)
		(width 0.10668)
		(layer "In4.Cu")
		(net "IRQ_BMC_CPU_NMI_R")
	)
	(segment
		(start 22.62886 -56.794654)
		(end 25.8191 -59.984894)
		(width 0.10668)
		(layer "In4.Cu")
		(net "IRQ_BMC_CPU_NMI_R")
	)
	(segment
		(start 46.494954 -45.771308)
		(end 46.09973 -45.376084)
		(width 0.11684)
		(layer "F.Cu")
		(net "IRQ_BMC_CPU_NMI")
	)
	(via
		(at 46.09973 -45.376084)
		(size 0.4572)
		(drill 0.254)
		(layers "F.Cu" "B.Cu")
		(net "IRQ_BMC_CPU_NMI")
	)
	(via
		(at 43.5864 -45.212)
		(size 0.6604)
		(drill 0.3302)
		(layers "F.Cu" "B.Cu")
		(net "IRQ_BMC_CPU_NMI")
	)
	(segment
		(start 42.512742 -45.075348)
		(end 42.366184 -44.92879)
		(width 0.11684)
		(layer "B.Cu")
		(net "IRQ_BMC_CPU_NMI")
	)
	(segment
		(start 44.100496 -45.3644)
		(end 44.516802 -45.3644)
		(width 0.11684)
		(layer "B.Cu")
		(net "IRQ_BMC_CPU_NMI")
	)
	(segment
		(start 44.528486 -45.376084)
		(end 46.09973 -45.376084)
		(width 0.11684)
		(layer "B.Cu")
		(net "IRQ_BMC_CPU_NMI")
	)
	(segment
		(start 43.5864 -45.212)
		(end 42.898822 -45.075348)
		(width 0.11684)
		(layer "B.Cu")
		(net "IRQ_BMC_CPU_NMI")
	)
	(segment
		(start 43.625008 -45.269658)
		(end 44.100496 -45.3644)
		(width 0.11684)
		(layer "B.Cu")
		(net "IRQ_BMC_CPU_NMI")
	)
	(segment
		(start 43.5864 -45.212)
		(end 43.625008 -45.269658)
		(width 0.11684)
		(layer "B.Cu")
		(net "IRQ_BMC_CPU_NMI")
	)
	(segment
		(start 44.516802 -45.3644)
		(end 44.528486 -45.376084)
		(width 0.11684)
		(layer "B.Cu")
		(net "IRQ_BMC_CPU_NMI")
	)
	(segment
		(start 42.898822 -45.075348)
		(end 42.512742 -45.075348)
		(width 0.11684)
		(layer "B.Cu")
		(net "IRQ_BMC_CPU_NMI")
	)
	(segment
		(start 29.729938 -6.290056)
		(end 30.607 -7.167118)
		(width 0.11684)
		(layer "F.Cu")
		(net "ID_LED_P3V3_AUX")
	)
	(segment
		(start 30.607 -7.167118)
		(end 30.607 -9.88695)
		(width 0.11684)
		(layer "F.Cu")
		(net "ID_LED_P3V3_AUX")
	)
	(segment
		(start 61.695076 -49.7713)
		(end 62.0903 -50.166524)
		(width 0.11684)
		(layer "F.Cu")
		(net "IBMC_MIOZ")
	)
	(via
		(at 62.0903 -50.166524)
		(size 0.4572)
		(drill 0.254)
		(layers "F.Cu" "B.Cu")
		(net "IBMC_MIOZ")
	)
	(segment
		(start 63.405004 -51.374802)
		(end 63.290704 -51.260502)
		(width 0.11684)
		(layer "B.Cu")
		(net "IBMC_MIOZ")
	)
	(segment
		(start 63.290704 -51.260502)
		(end 63.290704 -50.747168)
		(width 0.11684)
		(layer "B.Cu")
		(net "IBMC_MIOZ")
	)
	(segment
		(start 64.050418 -51.374802)
		(end 63.405004 -51.374802)
		(width 0.11684)
		(layer "B.Cu")
		(net "IBMC_MIOZ")
	)
	(segment
		(start 64.262254 -51.586638)
		(end 64.050418 -51.374802)
		(width 0.11684)
		(layer "B.Cu")
		(net "IBMC_MIOZ")
	)
	(segment
		(start 63.11392 -50.570384)
		(end 62.49416 -50.570384)
		(width 0.11684)
		(layer "B.Cu")
		(net "IBMC_MIOZ")
	)
	(segment
		(start 62.49416 -50.570384)
		(end 62.0903 -50.166524)
		(width 0.11684)
		(layer "B.Cu")
		(net "IBMC_MIOZ")
	)
	(segment
		(start 63.290704 -50.747168)
		(end 63.11392 -50.570384)
		(width 0.11684)
		(layer "B.Cu")
		(net "IBMC_MIOZ")
	)
	(segment
		(start 41.913302 -64.156844)
		(end 41.913302 -64.766444)
		(width 0.11684)
		(layer "F.Cu")
		(net "I3C4_SPD_SDA")
	)
	(via
		(at 67.748658 -112.56899)
		(size 0.508)
		(drill 0.254)
		(layers "F.Cu" "B.Cu")
		(net "I3C4_SPD_SDA")
	)
	(via
		(at 41.913302 -64.766444)
		(size 0.508)
		(drill 0.254)
		(layers "F.Cu" "B.Cu")
		(net "I3C4_SPD_SDA")
	)
	(via
		(at 67.0052 -109.2962)
		(size 0.508)
		(drill 0.254)
		(layers "F.Cu" "B.Cu")
		(net "I3C4_SPD_SDA")
	)
	(segment
		(start 41.913302 -64.156844)
		(end 41.913302 -64.766444)
		(width 0.11684)
		(layer "B.Cu")
		(net "I3C4_SPD_SDA")
	)
	(segment
		(start 69.06006 -115.542314)
		(end 69.06006 -118.25986)
		(width 0.11684)
		(layer "B.Cu")
		(net "I3C4_SPD_SDA")
	)
	(segment
		(start 67.748658 -112.56899)
		(end 68.4022 -113.222532)
		(width 0.11684)
		(layer "B.Cu")
		(net "I3C4_SPD_SDA")
	)
	(segment
		(start 68.4022 -113.222532)
		(end 68.4022 -114.884454)
		(width 0.11684)
		(layer "B.Cu")
		(net "I3C4_SPD_SDA")
	)
	(segment
		(start 68.4022 -114.884454)
		(end 69.06006 -115.542314)
		(width 0.11684)
		(layer "B.Cu")
		(net "I3C4_SPD_SDA")
	)
	(segment
		(start 60.30468 -96.247204)
		(end 60.30468 -95.424752)
		(width 0.10668)
		(layer "In7.Cu")
		(net "I3C4_SPD_SDA")
	)
	(segment
		(start 67.748658 -112.56899)
		(end 68.09232 -112.225328)
		(width 0.10668)
		(layer "In7.Cu")
		(net "I3C4_SPD_SDA")
	)
	(segment
		(start 68.09232 -111.83112)
		(end 67.0052 -110.744)
		(width 0.10668)
		(layer "In7.Cu")
		(net "I3C4_SPD_SDA")
	)
	(segment
		(start 46.822106 -73.756774)
		(end 46.555152 -73.48982)
		(width 0.10668)
		(layer "In7.Cu")
		(net "I3C4_SPD_SDA")
	)
	(segment
		(start 65.54724 -103.988616)
		(end 62.738 -101.179376)
		(width 0.10668)
		(layer "In7.Cu")
		(net "I3C4_SPD_SDA")
	)
	(segment
		(start 62.738 -98.680524)
		(end 60.30468 -96.247204)
		(width 0.10668)
		(layer "In7.Cu")
		(net "I3C4_SPD_SDA")
	)
	(segment
		(start 56.69534 -90.164158)
		(end 56.69534 -89.304114)
		(width 0.10668)
		(layer "In7.Cu")
		(net "I3C4_SPD_SDA")
	)
	(segment
		(start 48.05172 -74.784966)
		(end 48.05172 -74.62012)
		(width 0.10668)
		(layer "In7.Cu")
		(net "I3C4_SPD_SDA")
	)
	(segment
		(start 44.018708 -72.476106)
		(end 43.218608 -72.476106)
		(width 0.10668)
		(layer "In7.Cu")
		(net "I3C4_SPD_SDA")
	)
	(segment
		(start 49.499266 -75.48626)
		(end 48.753014 -75.48626)
		(width 0.10668)
		(layer "In7.Cu")
		(net "I3C4_SPD_SDA")
	)
	(segment
		(start 39.6113 -68.034154)
		(end 39.00932 -67.432174)
		(width 0.10668)
		(layer "In7.Cu")
		(net "I3C4_SPD_SDA")
	)
	(segment
		(start 62.738 -101.179376)
		(end 62.738 -98.680524)
		(width 0.10668)
		(layer "In7.Cu")
		(net "I3C4_SPD_SDA")
	)
	(segment
		(start 41.312846 -64.165988)
		(end 41.913302 -64.766444)
		(width 0.10668)
		(layer "In7.Cu")
		(net "I3C4_SPD_SDA")
	)
	(segment
		(start 39.6113 -68.371466)
		(end 39.6113 -68.034154)
		(width 0.10668)
		(layer "In7.Cu")
		(net "I3C4_SPD_SDA")
	)
	(segment
		(start 51.1302 -79.2607)
		(end 51.1302 -78.253844)
		(width 0.10668)
		(layer "In7.Cu")
		(net "I3C4_SPD_SDA")
	)
	(segment
		(start 39.6494 -68.409566)
		(end 39.6113 -68.371466)
		(width 0.10668)
		(layer "In7.Cu")
		(net "I3C4_SPD_SDA")
	)
	(segment
		(start 67.0052 -110.744)
		(end 67.0052 -109.2962)
		(width 0.10668)
		(layer "In7.Cu")
		(net "I3C4_SPD_SDA")
	)
	(segment
		(start 48.753014 -75.48626)
		(end 48.05172 -74.784966)
		(width 0.10668)
		(layer "In7.Cu")
		(net "I3C4_SPD_SDA")
	)
	(segment
		(start 51.1302 -78.253844)
		(end 50.2158 -77.339444)
		(width 0.10668)
		(layer "In7.Cu")
		(net "I3C4_SPD_SDA")
	)
	(segment
		(start 58.79592 -92.264738)
		(end 56.69534 -90.164158)
		(width 0.10668)
		(layer "In7.Cu")
		(net "I3C4_SPD_SDA")
	)
	(segment
		(start 50.2158 -77.339444)
		(end 50.2158 -77.236066)
		(width 0.10668)
		(layer "In7.Cu")
		(net "I3C4_SPD_SDA")
	)
	(segment
		(start 58.79592 -93.17228)
		(end 58.79592 -92.264738)
		(width 0.10668)
		(layer "In7.Cu")
		(net "I3C4_SPD_SDA")
	)
	(segment
		(start 39.12616 -64.75984)
		(end 39.720012 -64.165988)
		(width 0.10668)
		(layer "In7.Cu")
		(net "I3C4_SPD_SDA")
	)
	(segment
		(start 56.69534 -89.304114)
		(end 55.94858 -88.557354)
		(width 0.10668)
		(layer "In7.Cu")
		(net "I3C4_SPD_SDA")
	)
	(segment
		(start 65.54724 -107.83824)
		(end 65.54724 -103.988616)
		(width 0.10668)
		(layer "In7.Cu")
		(net "I3C4_SPD_SDA")
	)
	(segment
		(start 39.6494 -68.906898)
		(end 39.6494 -68.409566)
		(width 0.10668)
		(layer "In7.Cu")
		(net "I3C4_SPD_SDA")
	)
	(segment
		(start 39.12616 -66.449194)
		(end 39.12616 -64.75984)
		(width 0.10668)
		(layer "In7.Cu")
		(net "I3C4_SPD_SDA")
	)
	(segment
		(start 43.218608 -72.476106)
		(end 39.6494 -68.906898)
		(width 0.10668)
		(layer "In7.Cu")
		(net "I3C4_SPD_SDA")
	)
	(segment
		(start 67.0052 -109.2962)
		(end 65.54724 -107.83824)
		(width 0.10668)
		(layer "In7.Cu")
		(net "I3C4_SPD_SDA")
	)
	(segment
		(start 55.535322 -84.152486)
		(end 53.89626 -82.513424)
		(width 0.10668)
		(layer "In7.Cu")
		(net "I3C4_SPD_SDA")
	)
	(segment
		(start 50.2158 -77.236066)
		(end 50.10404 -77.124306)
		(width 0.10668)
		(layer "In7.Cu")
		(net "I3C4_SPD_SDA")
	)
	(segment
		(start 47.34179 -73.91019)
		(end 47.1932 -73.91019)
		(width 0.10668)
		(layer "In7.Cu")
		(net "I3C4_SPD_SDA")
	)
	(segment
		(start 55.94858 -88.557354)
		(end 55.535322 -87.559642)
		(width 0.10668)
		(layer "In7.Cu")
		(net "I3C4_SPD_SDA")
	)
	(segment
		(start 39.00932 -66.566034)
		(end 39.12616 -66.449194)
		(width 0.10668)
		(layer "In7.Cu")
		(net "I3C4_SPD_SDA")
	)
	(segment
		(start 45.032422 -73.48982)
		(end 44.018708 -72.476106)
		(width 0.10668)
		(layer "In7.Cu")
		(net "I3C4_SPD_SDA")
	)
	(segment
		(start 59.79414 -94.1705)
		(end 58.79592 -93.17228)
		(width 0.10668)
		(layer "In7.Cu")
		(net "I3C4_SPD_SDA")
	)
	(segment
		(start 50.10404 -76.091034)
		(end 49.499266 -75.48626)
		(width 0.10668)
		(layer "In7.Cu")
		(net "I3C4_SPD_SDA")
	)
	(segment
		(start 39.720012 -64.165988)
		(end 41.312846 -64.165988)
		(width 0.10668)
		(layer "In7.Cu")
		(net "I3C4_SPD_SDA")
	)
	(segment
		(start 60.30468 -95.424752)
		(end 59.79414 -94.914212)
		(width 0.10668)
		(layer "In7.Cu")
		(net "I3C4_SPD_SDA")
	)
	(segment
		(start 53.89626 -82.513424)
		(end 53.89626 -82.02676)
		(width 0.10668)
		(layer "In7.Cu")
		(net "I3C4_SPD_SDA")
	)
	(segment
		(start 48.05172 -74.62012)
		(end 47.34179 -73.91019)
		(width 0.10668)
		(layer "In7.Cu")
		(net "I3C4_SPD_SDA")
	)
	(segment
		(start 39.00932 -67.432174)
		(end 39.00932 -66.566034)
		(width 0.10668)
		(layer "In7.Cu")
		(net "I3C4_SPD_SDA")
	)
	(segment
		(start 53.89626 -82.02676)
		(end 51.1302 -79.2607)
		(width 0.10668)
		(layer "In7.Cu")
		(net "I3C4_SPD_SDA")
	)
	(segment
		(start 47.1932 -73.91019)
		(end 46.822106 -73.756774)
		(width 0.10668)
		(layer "In7.Cu")
		(net "I3C4_SPD_SDA")
	)
	(segment
		(start 50.10404 -77.124306)
		(end 50.10404 -76.091034)
		(width 0.10668)
		(layer "In7.Cu")
		(net "I3C4_SPD_SDA")
	)
	(segment
		(start 68.09232 -112.225328)
		(end 68.09232 -111.83112)
		(width 0.10668)
		(layer "In7.Cu")
		(net "I3C4_SPD_SDA")
	)
	(segment
		(start 55.535322 -87.559642)
		(end 55.535322 -84.152486)
		(width 0.10668)
		(layer "In7.Cu")
		(net "I3C4_SPD_SDA")
	)
	(segment
		(start 59.79414 -94.914212)
		(end 59.79414 -94.1705)
		(width 0.10668)
		(layer "In7.Cu")
		(net "I3C4_SPD_SDA")
	)
	(segment
		(start 46.555152 -73.48982)
		(end 45.032422 -73.48982)
		(width 0.10668)
		(layer "In7.Cu")
		(net "I3C4_SPD_SDA")
	)
	(segment
		(start 39.871142 -64.769238)
		(end 39.87038 -64.77)
		(width 0.11684)
		(layer "F.Cu")
		(net "I3C4_SPD_SCL")
	)
	(segment
		(start 39.871142 -64.156844)
		(end 39.871142 -64.769238)
		(width 0.11684)
		(layer "F.Cu")
		(net "I3C4_SPD_SCL")
	)
	(via
		(at 67.8434 -109.9566)
		(size 0.508)
		(drill 0.254)
		(layers "F.Cu" "B.Cu")
		(net "I3C4_SPD_SCL")
	)
	(via
		(at 39.87038 -64.77)
		(size 0.508)
		(drill 0.254)
		(layers "F.Cu" "B.Cu")
		(net "I3C4_SPD_SCL")
	)
	(via
		(at 69.01434 -114.25936)
		(size 0.508)
		(drill 0.254)
		(layers "F.Cu" "B.Cu")
		(net "I3C4_SPD_SCL")
	)
	(segment
		(start 69.478398 -115.096798)
		(end 69.478398 -117.1702)
		(width 0.11684)
		(layer "B.Cu")
		(net "I3C4_SPD_SCL")
	)
	(segment
		(start 69.01434 -114.25936)
		(end 69.01434 -114.63274)
		(width 0.11684)
		(layer "B.Cu")
		(net "I3C4_SPD_SCL")
	)
	(segment
		(start 69.01434 -114.63274)
		(end 69.478398 -115.096798)
		(width 0.11684)
		(layer "B.Cu")
		(net "I3C4_SPD_SCL")
	)
	(segment
		(start 69.478398 -117.1702)
		(end 69.660008 -117.35181)
		(width 0.11684)
		(layer "B.Cu")
		(net "I3C4_SPD_SCL")
	)
	(segment
		(start 39.87038 -64.77)
		(end 39.87038 -64.158622)
		(width 0.11684)
		(layer "B.Cu")
		(net "I3C4_SPD_SCL")
	)
	(segment
		(start 69.660008 -117.35181)
		(end 69.660008 -118.25986)
		(width 0.11684)
		(layer "B.Cu")
		(net "I3C4_SPD_SCL")
	)
	(segment
		(start 39.87038 -64.158622)
		(end 39.868602 -64.156844)
		(width 0.11684)
		(layer "B.Cu")
		(net "I3C4_SPD_SCL")
	)
	(segment
		(start 39.37 -66.71564)
		(end 39.37 -67.0814)
		(width 0.10668)
		(layer "In7.Cu")
		(net "I3C4_SPD_SCL")
	)
	(segment
		(start 49.64049 -75.12558)
		(end 49.655222 -75.131676)
		(width 0.10668)
		(layer "In7.Cu")
		(net "I3C4_SPD_SCL")
	)
	(segment
		(start 67.843146 -109.9566)
		(end 67.8434 -109.9566)
		(width 0.10668)
		(layer "In7.Cu")
		(net "I3C4_SPD_SCL")
	)
	(segment
		(start 68.453 -111.246158)
		(end 68.453 -113.69802)
		(width 0.10668)
		(layer "In7.Cu")
		(net "I3C4_SPD_SCL")
	)
	(segment
		(start 60.23102 -93.989398)
		(end 60.23102 -94.610682)
		(width 0.10668)
		(layer "In7.Cu")
		(net "I3C4_SPD_SCL")
	)
	(segment
		(start 47.265082 -73.54951)
		(end 47.554388 -73.54951)
		(width 0.10668)
		(layer "In7.Cu")
		(net "I3C4_SPD_SCL")
	)
	(segment
		(start 67.8434 -109.9566)
		(end 68.453 -111.246158)
		(width 0.10668)
		(layer "In7.Cu")
		(net "I3C4_SPD_SCL")
	)
	(segment
		(start 39.90721 -67.61861)
		(end 40.018716 -67.61861)
		(width 0.10668)
		(layer "In7.Cu")
		(net "I3C4_SPD_SCL")
	)
	(segment
		(start 48.4124 -74.407522)
		(end 48.4124 -74.63536)
		(width 0.10668)
		(layer "In7.Cu")
		(net "I3C4_SPD_SCL")
	)
	(segment
		(start 46.694852 -73.11898)
		(end 47.026576 -73.450704)
		(width 0.10668)
		(layer "In7.Cu")
		(net "I3C4_SPD_SCL")
	)
	(segment
		(start 58.49112 -90.342466)
		(end 58.49112 -91.341956)
		(width 0.10668)
		(layer "In7.Cu")
		(net "I3C4_SPD_SCL")
	)
	(segment
		(start 59.2328 -92.991178)
		(end 60.23102 -93.989398)
		(width 0.10668)
		(layer "In7.Cu")
		(net "I3C4_SPD_SCL")
	)
	(segment
		(start 39.87038 -66.21526)
		(end 39.37 -66.71564)
		(width 0.10668)
		(layer "In7.Cu")
		(net "I3C4_SPD_SCL")
	)
	(segment
		(start 60.23102 -94.610682)
		(end 62.699138 -97.0788)
		(width 0.10668)
		(layer "In7.Cu")
		(net "I3C4_SPD_SCL")
	)
	(segment
		(start 51.6636 -77.929486)
		(end 51.6636 -79.03972)
		(width 0.10668)
		(layer "In7.Cu")
		(net "I3C4_SPD_SCL")
	)
	(segment
		(start 56.068722 -83.931506)
		(end 56.068722 -86.465918)
		(width 0.10668)
		(layer "In7.Cu")
		(net "I3C4_SPD_SCL")
	)
	(segment
		(start 39.87038 -64.77)
		(end 39.87038 -66.21526)
		(width 0.10668)
		(layer "In7.Cu")
		(net "I3C4_SPD_SCL")
	)
	(segment
		(start 49.655222 -75.131676)
		(end 50.63744 -76.113894)
		(width 0.10668)
		(layer "In7.Cu")
		(net "I3C4_SPD_SCL")
	)
	(segment
		(start 44.171108 -72.115426)
		(end 45.174662 -73.11898)
		(width 0.10668)
		(layer "In7.Cu")
		(net "I3C4_SPD_SCL")
	)
	(segment
		(start 65.90792 -106.651552)
		(end 67.183762 -108.561632)
		(width 0.10668)
		(layer "In7.Cu")
		(net "I3C4_SPD_SCL")
	)
	(segment
		(start 59.2328 -92.083636)
		(end 59.2328 -92.991178)
		(width 0.10668)
		(layer "In7.Cu")
		(net "I3C4_SPD_SCL")
	)
	(segment
		(start 47.554388 -73.54951)
		(end 48.4124 -74.407522)
		(width 0.10668)
		(layer "In7.Cu")
		(net "I3C4_SPD_SCL")
	)
	(segment
		(start 62.699138 -97.0788)
		(end 62.956694 -97.0788)
		(width 0.10668)
		(layer "In7.Cu")
		(net "I3C4_SPD_SCL")
	)
	(segment
		(start 62.956694 -97.0788)
		(end 63.65494 -97.777046)
		(width 0.10668)
		(layer "In7.Cu")
		(net "I3C4_SPD_SCL")
	)
	(segment
		(start 56.69534 -87.092536)
		(end 56.69534 -88.546686)
		(width 0.10668)
		(layer "In7.Cu")
		(net "I3C4_SPD_SCL")
	)
	(segment
		(start 56.068722 -86.465918)
		(end 56.69534 -87.092536)
		(width 0.10668)
		(layer "In7.Cu")
		(net "I3C4_SPD_SCL")
	)
	(segment
		(start 67.183762 -108.561632)
		(end 67.843146 -109.9566)
		(width 0.10668)
		(layer "In7.Cu")
		(net "I3C4_SPD_SCL")
	)
	(segment
		(start 40.2844 -67.884294)
		(end 40.2844 -69.031612)
		(width 0.10668)
		(layer "In7.Cu")
		(net "I3C4_SPD_SCL")
	)
	(segment
		(start 56.69534 -88.546686)
		(end 58.49112 -90.342466)
		(width 0.10668)
		(layer "In7.Cu")
		(net "I3C4_SPD_SCL")
	)
	(segment
		(start 50.63744 -76.903326)
		(end 51.6636 -77.929486)
		(width 0.10668)
		(layer "In7.Cu")
		(net "I3C4_SPD_SCL")
	)
	(segment
		(start 47.026576 -73.450704)
		(end 47.265082 -73.54951)
		(width 0.10668)
		(layer "In7.Cu")
		(net "I3C4_SPD_SCL")
	)
	(segment
		(start 63.65494 -97.777046)
		(end 63.65494 -101.58603)
		(width 0.10668)
		(layer "In7.Cu")
		(net "I3C4_SPD_SCL")
	)
	(segment
		(start 48.4124 -74.63536)
		(end 48.90262 -75.12558)
		(width 0.10668)
		(layer "In7.Cu")
		(net "I3C4_SPD_SCL")
	)
	(segment
		(start 54.42966 -81.80578)
		(end 54.42966 -82.292444)
		(width 0.10668)
		(layer "In7.Cu")
		(net "I3C4_SPD_SCL")
	)
	(segment
		(start 48.90262 -75.12558)
		(end 49.64049 -75.12558)
		(width 0.10668)
		(layer "In7.Cu")
		(net "I3C4_SPD_SCL")
	)
	(segment
		(start 51.6636 -79.03972)
		(end 54.42966 -81.80578)
		(width 0.10668)
		(layer "In7.Cu")
		(net "I3C4_SPD_SCL")
	)
	(segment
		(start 39.37 -67.0814)
		(end 39.90721 -67.61861)
		(width 0.10668)
		(layer "In7.Cu")
		(net "I3C4_SPD_SCL")
	)
	(segment
		(start 58.49112 -91.341956)
		(end 59.2328 -92.083636)
		(width 0.10668)
		(layer "In7.Cu")
		(net "I3C4_SPD_SCL")
	)
	(segment
		(start 54.42966 -82.292444)
		(end 56.068722 -83.931506)
		(width 0.10668)
		(layer "In7.Cu")
		(net "I3C4_SPD_SCL")
	)
	(segment
		(start 40.2844 -69.031612)
		(end 43.368214 -72.115426)
		(width 0.10668)
		(layer "In7.Cu")
		(net "I3C4_SPD_SCL")
	)
	(segment
		(start 43.368214 -72.115426)
		(end 44.171108 -72.115426)
		(width 0.10668)
		(layer "In7.Cu")
		(net "I3C4_SPD_SCL")
	)
	(segment
		(start 45.174662 -73.11898)
		(end 46.694852 -73.11898)
		(width 0.10668)
		(layer "In7.Cu")
		(net "I3C4_SPD_SCL")
	)
	(segment
		(start 50.63744 -76.113894)
		(end 50.63744 -76.903326)
		(width 0.10668)
		(layer "In7.Cu")
		(net "I3C4_SPD_SCL")
	)
	(segment
		(start 65.90792 -103.83901)
		(end 65.90792 -106.651552)
		(width 0.10668)
		(layer "In7.Cu")
		(net "I3C4_SPD_SCL")
	)
	(segment
		(start 68.453 -113.69802)
		(end 69.01434 -114.25936)
		(width 0.10668)
		(layer "In7.Cu")
		(net "I3C4_SPD_SCL")
	)
	(segment
		(start 63.65494 -101.58603)
		(end 65.90792 -103.83901)
		(width 0.10668)
		(layer "In7.Cu")
		(net "I3C4_SPD_SCL")
	)
	(segment
		(start 40.018716 -67.61861)
		(end 40.2844 -67.884294)
		(width 0.10668)
		(layer "In7.Cu")
		(net "I3C4_SPD_SCL")
	)
	(segment
		(start 43.828208 -61.441838)
		(end 44.679362 -61.441838)
		(width 0.11684)
		(layer "F.Cu")
		(net "I3C4_SDA_R")
	)
	(segment
		(start 45.965618 -60.155582)
		(end 45.965618 -59.900566)
		(width 0.11684)
		(layer "F.Cu")
		(net "I3C4_SDA_R")
	)
	(segment
		(start 44.679362 -61.441838)
		(end 45.965618 -60.155582)
		(width 0.11684)
		(layer "F.Cu")
		(net "I3C4_SDA_R")
	)
	(segment
		(start 45.965618 -59.900566)
		(end 46.494954 -59.37123)
		(width 0.11684)
		(layer "F.Cu")
		(net "I3C4_SDA_R")
	)
	(segment
		(start 41.913302 -63.356744)
		(end 43.828208 -61.441838)
		(width 0.11684)
		(layer "F.Cu")
		(net "I3C4_SDA_R")
	)
	(segment
		(start 43.18 -60.172346)
		(end 43.18 -59.8678)
		(width 0.11684)
		(layer "F.Cu")
		(net "I3C4_SCL_R")
	)
	(segment
		(start 44.45 -59.16168)
		(end 44.631356 -58.980324)
		(width 0.11684)
		(layer "F.Cu")
		(net "I3C4_SCL_R")
	)
	(segment
		(start 40.494966 -62.85738)
		(end 43.18 -60.172346)
		(width 0.11684)
		(layer "F.Cu")
		(net "I3C4_SCL_R")
	)
	(segment
		(start 45.057822 -58.980324)
		(end 45.467016 -58.57113)
		(width 0.11684)
		(layer "F.Cu")
		(net "I3C4_SCL_R")
	)
	(segment
		(start 39.871142 -63.356744)
		(end 40.370506 -62.85738)
		(width 0.11684)
		(layer "F.Cu")
		(net "I3C4_SCL_R")
	)
	(segment
		(start 43.18 -59.8678)
		(end 43.88612 -59.16168)
		(width 0.11684)
		(layer "F.Cu")
		(net "I3C4_SCL_R")
	)
	(segment
		(start 40.370506 -62.85738)
		(end 40.494966 -62.85738)
		(width 0.11684)
		(layer "F.Cu")
		(net "I3C4_SCL_R")
	)
	(segment
		(start 44.631356 -58.980324)
		(end 45.057822 -58.980324)
		(width 0.11684)
		(layer "F.Cu")
		(net "I3C4_SCL_R")
	)
	(segment
		(start 45.467016 -58.57113)
		(end 45.695108 -58.57113)
		(width 0.11684)
		(layer "F.Cu")
		(net "I3C4_SCL_R")
	)
	(segment
		(start 43.88612 -59.16168)
		(end 44.45 -59.16168)
		(width 0.11684)
		(layer "F.Cu")
		(net "I3C4_SCL_R")
	)
	(segment
		(start 39.805102 -66.193416)
		(end 39.878 -66.266314)
		(width 0.11684)
		(layer "F.Cu")
		(net "I3C3_SPD_SDA")
	)
	(segment
		(start 39.878 -66.266314)
		(end 39.878 -66.85788)
		(width 0.11684)
		(layer "F.Cu")
		(net "I3C3_SPD_SDA")
	)
	(segment
		(start 39.878 -66.85788)
		(end 39.87038 -66.8655)
		(width 0.11684)
		(layer "F.Cu")
		(net "I3C3_SPD_SDA")
	)
	(via
		(at 39.87038 -66.8655)
		(size 0.508)
		(drill 0.254)
		(layers "F.Cu" "B.Cu")
		(net "I3C3_SPD_SDA")
	)
	(via
		(at 69.885052 -114.60861)
		(size 0.508)
		(drill 0.254)
		(layers "F.Cu" "B.Cu")
		(net "I3C3_SPD_SDA")
	)
	(segment
		(start 70.26148 -117.32006)
		(end 70.26148 -118.458488)
		(width 0.11684)
		(layer "B.Cu")
		(net "I3C3_SPD_SDA")
	)
	(segment
		(start 69.885052 -114.60861)
		(end 69.885052 -116.943632)
		(width 0.11684)
		(layer "B.Cu")
		(net "I3C3_SPD_SDA")
	)
	(segment
		(start 70.26148 -118.458488)
		(end 70.259956 -118.460012)
		(width 0.11684)
		(layer "B.Cu")
		(net "I3C3_SPD_SDA")
	)
	(segment
		(start 69.885052 -116.943632)
		(end 70.26148 -117.32006)
		(width 0.11684)
		(layer "B.Cu")
		(net "I3C3_SPD_SDA")
	)
	(segment
		(start 39.87038 -66.24955)
		(end 39.80053 -66.1797)
		(width 0.11684)
		(layer "B.Cu")
		(net "I3C3_SPD_SDA")
	)
	(segment
		(start 39.87038 -66.8655)
		(end 39.87038 -66.24955)
		(width 0.11684)
		(layer "B.Cu")
		(net "I3C3_SPD_SDA")
	)
	(segment
		(start 52.197 -79.062834)
		(end 54.617366 -81.4832)
		(width 0.10668)
		(layer "In7.Cu")
		(net "I3C3_SPD_SDA")
	)
	(segment
		(start 59.45886 -89.53246)
		(end 59.5757 -89.53246)
		(width 0.10668)
		(layer "In7.Cu")
		(net "I3C3_SPD_SDA")
	)
	(segment
		(start 55.76316 -83.115658)
		(end 56.429402 -83.7819)
		(width 0.10668)
		(layer "In7.Cu")
		(net "I3C3_SPD_SDA")
	)
	(segment
		(start 56.429402 -86.047326)
		(end 57.829958 -87.447882)
		(width 0.10668)
		(layer "In7.Cu")
		(net "I3C3_SPD_SDA")
	)
	(segment
		(start 39.87038 -66.8655)
		(end 39.8907 -66.8655)
		(width 0.10668)
		(layer "In7.Cu")
		(net "I3C3_SPD_SDA")
	)
	(segment
		(start 59.84494 -89.8017)
		(end 59.84494 -91.193366)
		(width 0.10668)
		(layer "In7.Cu")
		(net "I3C3_SPD_SDA")
	)
	(segment
		(start 40.64508 -68.882006)
		(end 43.51782 -71.754746)
		(width 0.10668)
		(layer "In7.Cu")
		(net "I3C3_SPD_SDA")
	)
	(segment
		(start 66.2686 -103.689404)
		(end 66.2686 -105.978706)
		(width 0.10668)
		(layer "In7.Cu")
		(net "I3C3_SPD_SDA")
	)
	(segment
		(start 50.99812 -76.75372)
		(end 52.197 -77.9526)
		(width 0.10668)
		(layer "In7.Cu")
		(net "I3C3_SPD_SDA")
	)
	(segment
		(start 59.84494 -91.193366)
		(end 64.01562 -95.364046)
		(width 0.10668)
		(layer "In7.Cu")
		(net "I3C3_SPD_SDA")
	)
	(segment
		(start 46.844458 -72.7583)
		(end 47.198026 -73.111868)
		(width 0.10668)
		(layer "In7.Cu")
		(net "I3C3_SPD_SDA")
	)
	(segment
		(start 47.763684 -73.18883)
		(end 49.94783 -74.093324)
		(width 0.10668)
		(layer "In7.Cu")
		(net "I3C3_SPD_SDA")
	)
	(segment
		(start 49.94783 -74.093324)
		(end 50.99812 -75.143614)
		(width 0.10668)
		(layer "In7.Cu")
		(net "I3C3_SPD_SDA")
	)
	(segment
		(start 44.320714 -71.754746)
		(end 45.324268 -72.7583)
		(width 0.10668)
		(layer "In7.Cu")
		(net "I3C3_SPD_SDA")
	)
	(segment
		(start 39.8907 -66.8655)
		(end 40.64508 -67.61988)
		(width 0.10668)
		(layer "In7.Cu")
		(net "I3C3_SPD_SDA")
	)
	(segment
		(start 57.829958 -87.903558)
		(end 59.45886 -89.53246)
		(width 0.10668)
		(layer "In7.Cu")
		(net "I3C3_SPD_SDA")
	)
	(segment
		(start 55.499 -81.4832)
		(end 55.76316 -81.74736)
		(width 0.10668)
		(layer "In7.Cu")
		(net "I3C3_SPD_SDA")
	)
	(segment
		(start 47.198026 -73.111868)
		(end 47.3837 -73.18883)
		(width 0.10668)
		(layer "In7.Cu")
		(net "I3C3_SPD_SDA")
	)
	(segment
		(start 67.9196 -108.567474)
		(end 69.518276 -112.427258)
		(width 0.10668)
		(layer "In7.Cu")
		(net "I3C3_SPD_SDA")
	)
	(segment
		(start 69.518276 -112.427258)
		(end 69.518276 -114.241834)
		(width 0.10668)
		(layer "In7.Cu")
		(net "I3C3_SPD_SDA")
	)
	(segment
		(start 40.64508 -67.61988)
		(end 40.64508 -68.882006)
		(width 0.10668)
		(layer "In7.Cu")
		(net "I3C3_SPD_SDA")
	)
	(segment
		(start 55.76316 -81.74736)
		(end 55.76316 -83.115658)
		(width 0.10668)
		(layer "In7.Cu")
		(net "I3C3_SPD_SDA")
	)
	(segment
		(start 47.3837 -73.18883)
		(end 47.763684 -73.18883)
		(width 0.10668)
		(layer "In7.Cu")
		(net "I3C3_SPD_SDA")
	)
	(segment
		(start 45.324268 -72.7583)
		(end 46.844458 -72.7583)
		(width 0.10668)
		(layer "In7.Cu")
		(net "I3C3_SPD_SDA")
	)
	(segment
		(start 64.01562 -95.364046)
		(end 64.01562 -101.436424)
		(width 0.10668)
		(layer "In7.Cu")
		(net "I3C3_SPD_SDA")
	)
	(segment
		(start 69.518276 -114.241834)
		(end 69.885052 -114.60861)
		(width 0.10668)
		(layer "In7.Cu")
		(net "I3C3_SPD_SDA")
	)
	(segment
		(start 56.429402 -83.7819)
		(end 56.429402 -86.047326)
		(width 0.10668)
		(layer "In7.Cu")
		(net "I3C3_SPD_SDA")
	)
	(segment
		(start 66.2686 -105.978706)
		(end 67.9196 -107.629706)
		(width 0.10668)
		(layer "In7.Cu")
		(net "I3C3_SPD_SDA")
	)
	(segment
		(start 59.5757 -89.53246)
		(end 59.84494 -89.8017)
		(width 0.10668)
		(layer "In7.Cu")
		(net "I3C3_SPD_SDA")
	)
	(segment
		(start 57.829958 -87.447882)
		(end 57.829958 -87.903558)
		(width 0.10668)
		(layer "In7.Cu")
		(net "I3C3_SPD_SDA")
	)
	(segment
		(start 54.617366 -81.4832)
		(end 55.499 -81.4832)
		(width 0.10668)
		(layer "In7.Cu")
		(net "I3C3_SPD_SDA")
	)
	(segment
		(start 64.01562 -101.436424)
		(end 66.2686 -103.689404)
		(width 0.10668)
		(layer "In7.Cu")
		(net "I3C3_SPD_SDA")
	)
	(segment
		(start 67.9196 -107.629706)
		(end 67.9196 -108.567474)
		(width 0.10668)
		(layer "In7.Cu")
		(net "I3C3_SPD_SDA")
	)
	(segment
		(start 50.99812 -75.143614)
		(end 50.99812 -76.75372)
		(width 0.10668)
		(layer "In7.Cu")
		(net "I3C3_SPD_SDA")
	)
	(segment
		(start 52.197 -77.9526)
		(end 52.197 -79.062834)
		(width 0.10668)
		(layer "In7.Cu")
		(net "I3C3_SPD_SDA")
	)
	(segment
		(start 43.51782 -71.754746)
		(end 44.320714 -71.754746)
		(width 0.10668)
		(layer "In7.Cu")
		(net "I3C3_SPD_SDA")
	)
	(segment
		(start 40.821102 -66.846958)
		(end 40.78986 -66.8782)
		(width 0.11684)
		(layer "F.Cu")
		(net "I3C3_SPD_SCL")
	)
	(segment
		(start 40.821102 -66.193416)
		(end 40.821102 -66.846958)
		(width 0.11684)
		(layer "F.Cu")
		(net "I3C3_SPD_SCL")
	)
	(via
		(at 72.039988 -113.57737)
		(size 0.508)
		(drill 0.254)
		(layers "F.Cu" "B.Cu")
		(net "I3C3_SPD_SCL")
	)
	(via
		(at 40.78986 -66.8782)
		(size 0.508)
		(drill 0.254)
		(layers "F.Cu" "B.Cu")
		(net "I3C3_SPD_SCL")
	)
	(segment
		(start 71.12 -114.497358)
		(end 71.12 -116.735098)
		(width 0.11684)
		(layer "B.Cu")
		(net "I3C3_SPD_SCL")
	)
	(segment
		(start 70.859904 -117.363494)
		(end 70.859904 -118.460012)
		(width 0.11684)
		(layer "B.Cu")
		(net "I3C3_SPD_SCL")
	)
	(segment
		(start 40.83431 -66.86169)
		(end 40.83431 -66.176652)
		(width 0.11684)
		(layer "B.Cu")
		(net "I3C3_SPD_SCL")
	)
	(segment
		(start 72.039988 -113.57737)
		(end 71.12 -114.497358)
		(width 0.11684)
		(layer "B.Cu")
		(net "I3C3_SPD_SCL")
	)
	(segment
		(start 40.78986 -66.8782)
		(end 40.8178 -66.8782)
		(width 0.11684)
		(layer "B.Cu")
		(net "I3C3_SPD_SCL")
	)
	(segment
		(start 71.12 -116.735098)
		(end 70.859904 -117.363494)
		(width 0.11684)
		(layer "B.Cu")
		(net "I3C3_SPD_SCL")
	)
	(segment
		(start 40.8178 -66.8782)
		(end 40.83431 -66.86169)
		(width 0.11684)
		(layer "B.Cu")
		(net "I3C3_SPD_SCL")
	)
	(segment
		(start 58.190638 -87.753952)
		(end 59.608466 -89.17178)
		(width 0.10668)
		(layer "In7.Cu")
		(net "I3C3_SPD_SCL")
	)
	(segment
		(start 41.00576 -68.7324)
		(end 43.667426 -71.394066)
		(width 0.10668)
		(layer "In7.Cu")
		(net "I3C3_SPD_SCL")
	)
	(segment
		(start 56.12384 -81.523586)
		(end 56.12384 -82.966052)
		(width 0.10668)
		(layer "In7.Cu")
		(net "I3C3_SPD_SCL")
	)
	(segment
		(start 40.78986 -66.8782)
		(end 41.00576 -67.0941)
		(width 0.10668)
		(layer "In7.Cu")
		(net "I3C3_SPD_SCL")
	)
	(segment
		(start 56.790082 -85.89772)
		(end 58.190638 -87.298276)
		(width 0.10668)
		(layer "In7.Cu")
		(net "I3C3_SPD_SCL")
	)
	(segment
		(start 51.3588 -76.604114)
		(end 52.55768 -77.802994)
		(width 0.10668)
		(layer "In7.Cu")
		(net "I3C3_SPD_SCL")
	)
	(segment
		(start 64.3763 -95.214186)
		(end 64.3763 -101.286564)
		(width 0.10668)
		(layer "In7.Cu")
		(net "I3C3_SPD_SCL")
	)
	(segment
		(start 45.473874 -72.39762)
		(end 46.994064 -72.39762)
		(width 0.10668)
		(layer "In7.Cu")
		(net "I3C3_SPD_SCL")
	)
	(segment
		(start 56.12384 -82.966052)
		(end 56.790082 -83.632294)
		(width 0.10668)
		(layer "In7.Cu")
		(net "I3C3_SPD_SCL")
	)
	(segment
		(start 59.725306 -89.17178)
		(end 60.20562 -89.652094)
		(width 0.10668)
		(layer "In7.Cu")
		(net "I3C3_SPD_SCL")
	)
	(segment
		(start 52.55768 -78.912974)
		(end 54.767226 -81.12252)
		(width 0.10668)
		(layer "In7.Cu")
		(net "I3C3_SPD_SCL")
	)
	(segment
		(start 47.336456 -72.740012)
		(end 47.549308 -72.82815)
		(width 0.10668)
		(layer "In7.Cu")
		(net "I3C3_SPD_SCL")
	)
	(segment
		(start 68.3768 -108.645198)
		(end 69.614796 -111.634016)
		(width 0.10668)
		(layer "In7.Cu")
		(net "I3C3_SPD_SCL")
	)
	(segment
		(start 59.608466 -89.17178)
		(end 59.725306 -89.17178)
		(width 0.10668)
		(layer "In7.Cu")
		(net "I3C3_SPD_SCL")
	)
	(segment
		(start 68.3768 -107.576366)
		(end 68.3768 -108.645198)
		(width 0.10668)
		(layer "In7.Cu")
		(net "I3C3_SPD_SCL")
	)
	(segment
		(start 43.667426 -71.394066)
		(end 44.47032 -71.394066)
		(width 0.10668)
		(layer "In7.Cu")
		(net "I3C3_SPD_SCL")
	)
	(segment
		(start 55.722774 -81.12252)
		(end 56.12384 -81.523586)
		(width 0.10668)
		(layer "In7.Cu")
		(net "I3C3_SPD_SCL")
	)
	(segment
		(start 56.790082 -83.632294)
		(end 56.790082 -85.89772)
		(width 0.10668)
		(layer "In7.Cu")
		(net "I3C3_SPD_SCL")
	)
	(segment
		(start 51.3588 -74.994008)
		(end 51.3588 -76.604114)
		(width 0.10668)
		(layer "In7.Cu")
		(net "I3C3_SPD_SCL")
	)
	(segment
		(start 69.614796 -111.634016)
		(end 71.55815 -113.57737)
		(width 0.10668)
		(layer "In7.Cu")
		(net "I3C3_SPD_SCL")
	)
	(segment
		(start 58.190638 -87.298276)
		(end 58.190638 -87.753952)
		(width 0.10668)
		(layer "In7.Cu")
		(net "I3C3_SPD_SCL")
	)
	(segment
		(start 46.994064 -72.39762)
		(end 47.336456 -72.740012)
		(width 0.10668)
		(layer "In7.Cu")
		(net "I3C3_SPD_SCL")
	)
	(segment
		(start 50.152046 -73.787254)
		(end 51.3588 -74.994008)
		(width 0.10668)
		(layer "In7.Cu")
		(net "I3C3_SPD_SCL")
	)
	(segment
		(start 54.767226 -81.12252)
		(end 55.722774 -81.12252)
		(width 0.10668)
		(layer "In7.Cu")
		(net "I3C3_SPD_SCL")
	)
	(segment
		(start 60.20562 -91.043506)
		(end 64.3763 -95.214186)
		(width 0.10668)
		(layer "In7.Cu")
		(net "I3C3_SPD_SCL")
	)
	(segment
		(start 66.62928 -105.828846)
		(end 68.3768 -107.576366)
		(width 0.10668)
		(layer "In7.Cu")
		(net "I3C3_SPD_SCL")
	)
	(segment
		(start 71.55815 -113.57737)
		(end 72.039988 -113.57737)
		(width 0.10668)
		(layer "In7.Cu")
		(net "I3C3_SPD_SCL")
	)
	(segment
		(start 66.62928 -103.539544)
		(end 66.62928 -105.828846)
		(width 0.10668)
		(layer "In7.Cu")
		(net "I3C3_SPD_SCL")
	)
	(segment
		(start 44.47032 -71.394066)
		(end 45.473874 -72.39762)
		(width 0.10668)
		(layer "In7.Cu")
		(net "I3C3_SPD_SCL")
	)
	(segment
		(start 47.836074 -72.82815)
		(end 50.152046 -73.787254)
		(width 0.10668)
		(layer "In7.Cu")
		(net "I3C3_SPD_SCL")
	)
	(segment
		(start 47.549308 -72.82815)
		(end 47.836074 -72.82815)
		(width 0.10668)
		(layer "In7.Cu")
		(net "I3C3_SPD_SCL")
	)
	(segment
		(start 64.3763 -101.286564)
		(end 66.62928 -103.539544)
		(width 0.10668)
		(layer "In7.Cu")
		(net "I3C3_SPD_SCL")
	)
	(segment
		(start 60.20562 -89.652094)
		(end 60.20562 -91.043506)
		(width 0.10668)
		(layer "In7.Cu")
		(net "I3C3_SPD_SCL")
	)
	(segment
		(start 41.00576 -67.0941)
		(end 41.00576 -68.7324)
		(width 0.10668)
		(layer "In7.Cu")
		(net "I3C3_SPD_SCL")
	)
	(segment
		(start 52.55768 -77.802994)
		(end 52.55768 -78.912974)
		(width 0.10668)
		(layer "In7.Cu")
		(net "I3C3_SPD_SCL")
	)
	(segment
		(start 39.2176 -65.201546)
		(end 39.2176 -63.130684)
		(width 0.11684)
		(layer "F.Cu")
		(net "I3C3_SDA_R")
	)
	(segment
		(start 42.8244 -59.918346)
		(end 42.8244 -59.233562)
		(width 0.11684)
		(layer "F.Cu")
		(net "I3C3_SDA_R")
	)
	(segment
		(start 40.122094 -62.25794)
		(end 40.484806 -62.25794)
		(width 0.11684)
		(layer "F.Cu")
		(net "I3C3_SDA_R")
	)
	(segment
		(start 39.40937 -65.393316)
		(end 39.2176 -65.201546)
		(width 0.11684)
		(layer "F.Cu")
		(net "I3C3_SDA_R")
	)
	(segment
		(start 39.2176 -63.130684)
		(end 39.732204 -62.61608)
		(width 0.11684)
		(layer "F.Cu")
		(net "I3C3_SDA_R")
	)
	(segment
		(start 40.484806 -62.25794)
		(end 42.8244 -59.918346)
		(width 0.11684)
		(layer "F.Cu")
		(net "I3C3_SDA_R")
	)
	(segment
		(start 43.495722 -58.56224)
		(end 44.631356 -58.56224)
		(width 0.11684)
		(layer "F.Cu")
		(net "I3C3_SDA_R")
	)
	(segment
		(start 44.640246 -58.57113)
		(end 44.895008 -58.57113)
		(width 0.11684)
		(layer "F.Cu")
		(net "I3C3_SDA_R")
	)
	(segment
		(start 39.763954 -62.61608)
		(end 40.122094 -62.25794)
		(width 0.11684)
		(layer "F.Cu")
		(net "I3C3_SDA_R")
	)
	(segment
		(start 42.8244 -59.233562)
		(end 43.495722 -58.56224)
		(width 0.11684)
		(layer "F.Cu")
		(net "I3C3_SDA_R")
	)
	(segment
		(start 39.805102 -65.393316)
		(end 39.40937 -65.393316)
		(width 0.11684)
		(layer "F.Cu")
		(net "I3C3_SDA_R")
	)
	(segment
		(start 44.631356 -58.56224)
		(end 44.640246 -58.57113)
		(width 0.11684)
		(layer "F.Cu")
		(net "I3C3_SDA_R")
	)
	(segment
		(start 39.732204 -62.61608)
		(end 39.763954 -62.61608)
		(width 0.11684)
		(layer "F.Cu")
		(net "I3C3_SDA_R")
	)
	(segment
		(start 45.695108 -59.689746)
		(end 45.695108 -59.37123)
		(width 0.11684)
		(layer "F.Cu")
		(net "I3C3_SCL_R")
	)
	(segment
		(start 41.171114 -65.393316)
		(end 41.3512 -65.21323)
		(width 0.11684)
		(layer "F.Cu")
		(net "I3C3_SCL_R")
	)
	(segment
		(start 41.477692 -63.051182)
		(end 41.586404 -62.94247)
		(width 0.11684)
		(layer "F.Cu")
		(net "I3C3_SCL_R")
	)
	(segment
		(start 41.3512 -65.21323)
		(end 41.3512 -63.3984)
		(width 0.11684)
		(layer "F.Cu")
		(net "I3C3_SCL_R")
	)
	(segment
		(start 44.90339 -60.481464)
		(end 45.695108 -59.689746)
		(width 0.11684)
		(layer "F.Cu")
		(net "I3C3_SCL_R")
	)
	(segment
		(start 40.821102 -65.393316)
		(end 41.171114 -65.393316)
		(width 0.11684)
		(layer "F.Cu")
		(net "I3C3_SCL_R")
	)
	(segment
		(start 41.477692 -63.271908)
		(end 41.477692 -63.051182)
		(width 0.11684)
		(layer "F.Cu")
		(net "I3C3_SCL_R")
	)
	(segment
		(start 44.268136 -60.481464)
		(end 44.90339 -60.481464)
		(width 0.11684)
		(layer "F.Cu")
		(net "I3C3_SCL_R")
	)
	(segment
		(start 41.80713 -62.94247)
		(end 44.268136 -60.481464)
		(width 0.11684)
		(layer "F.Cu")
		(net "I3C3_SCL_R")
	)
	(segment
		(start 41.3512 -63.3984)
		(end 41.477692 -63.271908)
		(width 0.11684)
		(layer "F.Cu")
		(net "I3C3_SCL_R")
	)
	(segment
		(start 41.586404 -62.94247)
		(end 41.80713 -62.94247)
		(width 0.11684)
		(layer "F.Cu")
		(net "I3C3_SCL_R")
	)
	(segment
		(start 44.155868 -62.2808)
		(end 45.237654 -62.2808)
		(width 0.11684)
		(layer "F.Cu")
		(net "I3C2_SDA_R")
	)
	(segment
		(start 43.171618 -63.76543)
		(end 43.52544 -62.911228)
		(width 0.11684)
		(layer "F.Cu")
		(net "I3C2_SDA_R")
	)
	(segment
		(start 47.690278 -59.828176)
		(end 47.690278 -58.975752)
		(width 0.11684)
		(layer "F.Cu")
		(net "I3C2_SDA_R")
	)
	(segment
		(start 45.237654 -62.2808)
		(end 47.690278 -59.828176)
		(width 0.11684)
		(layer "F.Cu")
		(net "I3C2_SDA_R")
	)
	(segment
		(start 43.171618 -65.376044)
		(end 43.171618 -63.76543)
		(width 0.11684)
		(layer "F.Cu")
		(net "I3C2_SDA_R")
	)
	(segment
		(start 43.52544 -62.911228)
		(end 44.155868 -62.2808)
		(width 0.11684)
		(layer "F.Cu")
		(net "I3C2_SDA_R")
	)
	(segment
		(start 47.690278 -58.975752)
		(end 48.0949 -58.57113)
		(width 0.11684)
		(layer "F.Cu")
		(net "I3C2_SDA_R")
	)
	(segment
		(start 44.246546 -62.6872)
		(end 45.491654 -62.6872)
		(width 0.11684)
		(layer "F.Cu")
		(net "I3C2_SCL_R")
	)
	(segment
		(start 47.9298 -59.53633)
		(end 48.0949 -59.37123)
		(width 0.11684)
		(layer "F.Cu")
		(net "I3C2_SCL_R")
	)
	(segment
		(start 43.955716 -62.97803)
		(end 44.246546 -62.6872)
		(width 0.11684)
		(layer "F.Cu")
		(net "I3C2_SCL_R")
	)
	(segment
		(start 43.6372 -63.747396)
		(end 43.955716 -62.97803)
		(width 0.11684)
		(layer "F.Cu")
		(net "I3C2_SCL_R")
	)
	(segment
		(start 45.491654 -62.6872)
		(end 47.9298 -60.249054)
		(width 0.11684)
		(layer "F.Cu")
		(net "I3C2_SCL_R")
	)
	(segment
		(start 47.9298 -60.249054)
		(end 47.9298 -59.53633)
		(width 0.11684)
		(layer "F.Cu")
		(net "I3C2_SCL_R")
	)
	(segment
		(start 43.6372 -64.819276)
		(end 43.6372 -63.747396)
		(width 0.11684)
		(layer "F.Cu")
		(net "I3C2_SCL_R")
	)
	(segment
		(start 44.193968 -65.376044)
		(end 43.6372 -64.819276)
		(width 0.11684)
		(layer "F.Cu")
		(net "I3C2_SCL_R")
	)
	(segment
		(start 64.520572 -36.512246)
		(end 64.251332 -36.78174)
		(width 0.14224)
		(layer "F.Cu")
		(net "USB_HOST_BMC_A_R_DP")
	)
	(segment
		(start 64.729614 -34.64306)
		(end 64.729614 -35.05454)
		(width 0.14224)
		(layer "F.Cu")
		(net "USB_HOST_BMC_A_R_DP")
	)
	(segment
		(start 64.709294 -33.317434)
		(end 64.925194 -33.533334)
		(width 0.14224)
		(layer "F.Cu")
		(net "USB_HOST_BMC_A_R_DP")
	)
	(segment
		(start 63.982092 -37.338508)
		(end 63.69431 -37.338508)
		(width 0.14224)
		(layer "F.Cu")
		(net "USB_HOST_BMC_A_R_DP")
	)
	(segment
		(start 64.925194 -36.395406)
		(end 64.808354 -36.512246)
		(width 0.14224)
		(layer "F.Cu")
		(net "USB_HOST_BMC_A_R_DP")
	)
	(segment
		(start 64.925194 -32.674814)
		(end 64.709294 -32.890714)
		(width 0.14224)
		(layer "F.Cu")
		(net "USB_HOST_BMC_A_R_DP")
	)
	(segment
		(start 64.808354 -36.512246)
		(end 64.520572 -36.512246)
		(width 0.14224)
		(layer "F.Cu")
		(net "USB_HOST_BMC_A_R_DP")
	)
	(segment
		(start 62.494922 -38.825678)
		(end 62.494922 -39.37127)
		(width 0.13716)
		(layer "F.Cu")
		(net "USB_HOST_BMC_A_R_DP")
	)
	(segment
		(start 64.925194 -31.389574)
		(end 64.709294 -31.605474)
		(width 0.14224)
		(layer "F.Cu")
		(net "USB_HOST_BMC_A_R_DP")
	)
	(segment
		(start 64.925194 -32.248094)
		(end 64.925194 -32.674814)
		(width 0.14224)
		(layer "F.Cu")
		(net "USB_HOST_BMC_A_R_DP")
	)
	(segment
		(start 63.69431 -37.338508)
		(end 63.42507 -37.608002)
		(width 0.14224)
		(layer "F.Cu")
		(net "USB_HOST_BMC_A_R_DP")
	)
	(segment
		(start 64.729614 -35.05454)
		(end 64.925194 -35.25012)
		(width 0.14224)
		(layer "F.Cu")
		(net "USB_HOST_BMC_A_R_DP")
	)
	(segment
		(start 64.709294 -32.890714)
		(end 64.709294 -33.317434)
		(width 0.14224)
		(layer "F.Cu")
		(net "USB_HOST_BMC_A_R_DP")
	)
	(segment
		(start 64.925194 -35.25012)
		(end 64.925194 -36.395406)
		(width 0.14224)
		(layer "F.Cu")
		(net "USB_HOST_BMC_A_R_DP")
	)
	(segment
		(start 63.42507 -37.89553)
		(end 62.79515 -38.52545)
		(width 0.14224)
		(layer "F.Cu")
		(net "USB_HOST_BMC_A_R_DP")
	)
	(segment
		(start 64.709294 -32.032194)
		(end 64.925194 -32.248094)
		(width 0.14224)
		(layer "F.Cu")
		(net "USB_HOST_BMC_A_R_DP")
	)
	(segment
		(start 64.925194 -33.533334)
		(end 64.925194 -34.44748)
		(width 0.14224)
		(layer "F.Cu")
		(net "USB_HOST_BMC_A_R_DP")
	)
	(segment
		(start 63.42507 -37.608002)
		(end 63.42507 -37.89553)
		(width 0.14224)
		(layer "F.Cu")
		(net "USB_HOST_BMC_A_R_DP")
	)
	(segment
		(start 64.600328 -29.777182)
		(end 64.925194 -30.102048)
		(width 0.14224)
		(layer "F.Cu")
		(net "USB_HOST_BMC_A_R_DP")
	)
	(segment
		(start 64.709294 -31.605474)
		(end 64.709294 -32.032194)
		(width 0.14224)
		(layer "F.Cu")
		(net "USB_HOST_BMC_A_R_DP")
	)
	(segment
		(start 62.79515 -38.52545)
		(end 62.494922 -38.825678)
		(width 0.13716)
		(layer "F.Cu")
		(net "USB_HOST_BMC_A_R_DP")
	)
	(segment
		(start 64.925194 -34.44748)
		(end 64.729614 -34.64306)
		(width 0.14224)
		(layer "F.Cu")
		(net "USB_HOST_BMC_A_R_DP")
	)
	(segment
		(start 64.251332 -36.78174)
		(end 64.251332 -37.069268)
		(width 0.14224)
		(layer "F.Cu")
		(net "USB_HOST_BMC_A_R_DP")
	)
	(segment
		(start 64.925194 -30.102048)
		(end 64.925194 -31.389574)
		(width 0.14224)
		(layer "F.Cu")
		(net "USB_HOST_BMC_A_R_DP")
	)
	(segment
		(start 64.251332 -37.069268)
		(end 63.982092 -37.338508)
		(width 0.14224)
		(layer "F.Cu")
		(net "USB_HOST_BMC_A_R_DP")
	)
	(segment
		(start 62.893702 -39.50081)
		(end 62.893702 -38.947852)
		(width 0.13716)
		(layer "F.Cu")
		(net "USB_HOST_BMC_A_R_DN")
	)
	(segment
		(start 62.893702 -38.947852)
		(end 65.293494 -36.54806)
		(width 0.14224)
		(layer "F.Cu")
		(net "USB_HOST_BMC_A_R_DN")
	)
	(segment
		(start 62.701678 -39.964614)
		(end 62.893702 -39.50081)
		(width 0.13716)
		(layer "F.Cu")
		(net "USB_HOST_BMC_A_R_DN")
	)
	(segment
		(start 65.293494 -30.101794)
		(end 65.618106 -29.777182)
		(width 0.14224)
		(layer "F.Cu")
		(net "USB_HOST_BMC_A_R_DN")
	)
	(segment
		(start 65.293494 -36.54806)
		(end 65.293494 -30.101794)
		(width 0.14224)
		(layer "F.Cu")
		(net "USB_HOST_BMC_A_R_DN")
	)
	(segment
		(start 62.494922 -40.17137)
		(end 62.701678 -39.964614)
		(width 0.13716)
		(layer "F.Cu")
		(net "USB_HOST_BMC_A_R_DN")
	)
	(segment
		(start 10.85977 -15.810992)
		(end 10.653014 -16.017748)
		(width 0.381)
		(layer "F.Cu")
		(net "GND")
	)
	(segment
		(start 53.695092 -47.371254)
		(end 53.299868 -46.97603)
		(width 0.3556)
		(layer "F.Cu")
		(net "GND")
	)
	(segment
		(start 48.650652 -64.366394)
		(end 48.35906 -64.657986)
		(width 0.3048)
		(layer "F.Cu")
		(net "GND")
	)
	(segment
		(start 13.335 -17.76095)
		(end 12.540996 -17.76095)
		(width 0.381)
		(layer "F.Cu")
		(net "GND")
	)
	(segment
		(start 58.099706 -54.166516)
		(end 58.49493 -53.771292)
		(width 0.3556)
		(layer "F.Cu")
		(net "GND")
	)
	(segment
		(start 17.22755 -66.7766)
		(end 16.7132 -66.26225)
		(width 0.381)
		(layer "F.Cu")
		(net "GND")
	)
	(segment
		(start 10.653014 -16.017748)
		(end 10.653014 -16.44904)
		(width 0.381)
		(layer "F.Cu")
		(net "GND")
	)
	(segment
		(start 59.08929 -26.38806)
		(end 58.98134 -26.38806)
		(width 0.254)
		(layer "F.Cu")
		(net "GND")
	)
	(segment
		(start 62.687962 -90.65006)
		(end 62.701932 -90.63609)
		(width 0.381)
		(layer "F.Cu")
		(net "GND")
	)
	(segment
		(start 17.500092 -80.910176)
		(end 17.500092 -78.969108)
		(width 0.2794)
		(layer "F.Cu")
		(net "GND")
	)
	(segment
		(start 53.695092 -40.17137)
		(end 53.299868 -39.776146)
		(width 0.3556)
		(layer "F.Cu")
		(net "GND")
	)
	(segment
		(start 31.317946 -34.2646)
		(end 28.702 -34.2646)
		(width 0.381)
		(layer "F.Cu")
		(net "GND")
	)
	(segment
		(start 60.094876 -55.371238)
		(end 60.4901 -55.766462)
		(width 0.3556)
		(layer "F.Cu")
		(net "GND")
	)
	(segment
		(start 61.98108 -59.821572)
		(end 61.985652 -59.817)
		(width 0.3556)
		(layer "F.Cu")
		(net "GND")
	)
	(segment
		(start 16.664178 -98.382328)
		(end 17.059402 -97.987104)
		(width 0.381)
		(layer "F.Cu")
		(net "GND")
	)
	(segment
		(start 10.43305 -89.55405)
		(end 10.43305 -89.408)
		(width 0.381)
		(layer "F.Cu")
		(net "GND")
	)
	(segment
		(start 28.194 -11.06805)
		(end 28.194 -11.3284)
		(width 0.381)
		(layer "F.Cu")
		(net "GND")
	)
	(segment
		(start 54.494938 -45.780706)
		(end 54.099714 -46.17593)
		(width 0.3556)
		(layer "F.Cu")
		(net "GND")
	)
	(segment
		(start 70.8914 -28.9814)
		(end 70.9168 -28.9814)
		(width 0.381)
		(layer "F.Cu")
		(net "GND")
	)
	(segment
		(start 16.664178 -88.791796)
		(end 16.259556 -88.387174)
		(width 0.381)
		(layer "F.Cu")
		(net "GND")
	)
	(segment
		(start 12.012676 -47.63135)
		(end 12.012676 -46.860714)
		(width 0.3556)
		(layer "F.Cu")
		(net "GND")
	)
	(segment
		(start 45.695108 -50.571146)
		(end 45.299884 -50.96637)
		(width 0.3556)
		(layer "F.Cu")
		(net "GND")
	)
	(segment
		(start 32.179514 -28.2702)
		(end 32.15005 -28.299664)
		(width 0.254)
		(layer "F.Cu")
		(net "GND")
	)
	(segment
		(start 70.358 -11.28395)
		(end 70.358 -10.663428)
		(width 0.381)
		(layer "F.Cu")
		(net "GND")
	)
	(segment
		(start 20.0152 -107.6452)
		(end 20.30222 -107.35818)
		(width 0.381)
		(layer "F.Cu")
		(net "GND")
	)
	(segment
		(start 10.287 -59.45505)
		(end 10.287 -60.1726)
		(width 0.381)
		(layer "F.Cu")
		(net "GND")
	)
	(segment
		(start 81.9404 -18.912586)
		(end 81.9404 -19.3294)
		(width 0.3556)
		(layer "F.Cu")
		(net "GND")
	)
	(segment
		(start 14.513814 -52.067206)
		(end 14.513814 -53.172614)
		(width 0.254)
		(layer "F.Cu")
		(net "GND")
	)
	(segment
		(start 46.4185 -108.3945)
		(end 46.0756 -108.7374)
		(width 0.381)
		(layer "F.Cu")
		(net "GND")
	)
	(segment
		(start 48.35906 -64.657986)
		(end 48.35906 -66.08318)
		(width 0.3048)
		(layer "F.Cu")
		(net "GND")
	)
	(segment
		(start 34.26714 -33.274)
		(end 33.4518 -33.274)
		(width 0.381)
		(layer "F.Cu")
		(net "GND")
	)
	(segment
		(start 84.126832 -72.733408)
		(end 84.372196 -72.733408)
		(width 0.254)
		(layer "F.Cu")
		(net "GND")
	)
	(segment
		(start 34.625026 -28.619958)
		(end 35.780726 -28.619958)
		(width 0.381)
		(layer "F.Cu")
		(net "GND")
	)
	(segment
		(start 53.537612 -27.20848)
		(end 53.295296 -26.966164)
		(width 0.381)
		(layer "F.Cu")
		(net "GND")
	)
	(segment
		(start 24.654764 -96.782382)
		(end 24.25954 -96.387158)
		(width 0.381)
		(layer "F.Cu")
		(net "GND")
	)
	(segment
		(start 46.586902 -63.534544)
		(end 46.637702 -63.483744)
		(width 0.381)
		(layer "F.Cu")
		(net "GND")
	)
	(segment
		(start 34.500058 -79.820516)
		(end 34.3662 -79.686658)
		(width 0.254)
		(layer "F.Cu")
		(net "GND")
	)
	(segment
		(start 38.916864 -45.357288)
		(end 38.896036 -45.357288)
		(width 0.381)
		(layer "F.Cu")
		(net "GND")
	)
	(segment
		(start 42.291 -24.4856)
		(end 42.291 -25.0444)
		(width 0.3048)
		(layer "F.Cu")
		(net "GND")
	)
	(segment
		(start 15.864332 -99.182174)
		(end 16.259556 -98.78695)
		(width 0.381)
		(layer "F.Cu")
		(net "GND")
	)
	(segment
		(start 21.336 -66.38925)
		(end 21.844 -66.38925)
		(width 0.381)
		(layer "F.Cu")
		(net "GND")
	)
	(segment
		(start 9.296146 -48.314356)
		(end 9.296146 -48.010064)
		(width 0.1778)
		(layer "F.Cu")
		(net "GND")
	)
	(segment
		(start 60.779152 -53.887116)
		(end 60.894976 -53.771292)
		(width 0.381)
		(layer "F.Cu")
		(net "GND")
	)
	(segment
		(start 59.34583 -26.13152)
		(end 59.08929 -26.38806)
		(width 0.254)
		(layer "F.Cu")
		(net "GND")
	)
	(segment
		(start 42.02176 -25.31364)
		(end 41.116758 -25.31364)
		(width 0.3048)
		(layer "F.Cu")
		(net "GND")
	)
	(segment
		(start 3.984752 -65.802002)
		(end 4.428744 -65.802002)
		(width 0.254)
		(layer "F.Cu")
		(net "GND")
	)
	(segment
		(start 61.695076 -40.17137)
		(end 61.695076 -40.180768)
		(width 0.3556)
		(layer "F.Cu")
		(net "GND")
	)
	(segment
		(start 56.094884 -47.371254)
		(end 56.894984 -47.371254)
		(width 0.3556)
		(layer "F.Cu")
		(net "GND")
	)
	(segment
		(start 53.695092 -50.571146)
		(end 53.299868 -50.96637)
		(width 0.3556)
		(layer "F.Cu")
		(net "GND")
	)
	(segment
		(start 51.295046 -52.971192)
		(end 50.899822 -53.366416)
		(width 0.3556)
		(layer "F.Cu")
		(net "GND")
	)
	(segment
		(start 59.29503 -42.571162)
		(end 59.690254 -42.175938)
		(width 0.3556)
		(layer "F.Cu")
		(net "GND")
	)
	(segment
		(start 52.894992 -50.571146)
		(end 52.895246 -50.571146)
		(width 0.3556)
		(layer "F.Cu")
		(net "GND")
	)
	(segment
		(start 36.880546 -30.149546)
		(end 36.251134 -30.149546)
		(width 0.381)
		(layer "F.Cu")
		(net "GND")
	)
	(segment
		(start 9.4869 -104.54005)
		(end 9.4869 -104.26065)
		(width 0.381)
		(layer "F.Cu")
		(net "GND")
	)
	(segment
		(start 32.15005 -33.274)
		(end 32.15005 -33.432496)
		(width 0.381)
		(layer "F.Cu")
		(net "GND")
	)
	(segment
		(start 58.49493 -52.171346)
		(end 58.619644 -52.29606)
		(width 0.3556)
		(layer "F.Cu")
		(net "GND")
	)
	(segment
		(start 31.115 -14.934946)
		(end 30.958028 -15.091918)
		(width 0.381)
		(layer "F.Cu")
		(net "GND")
	)
	(segment
		(start 60.591954 -96.856042)
		(end 61.82614 -96.856042)
		(width 0.381)
		(layer "F.Cu")
		(net "GND")
	)
	(segment
		(start 56.094884 -52.171346)
		(end 56.490108 -52.56657)
		(width 0.3556)
		(layer "F.Cu")
		(net "GND")
	)
	(segment
		(start 54.599586 -80.304386)
		(end 53.540406 -80.304386)
		(width 0.3048)
		(layer "F.Cu")
		(net "GND")
	)
	(segment
		(start 12.80795 -10.73404)
		(end 12.80795 -9.833864)
		(width 0.381)
		(layer "F.Cu")
		(net "GND")
	)
	(segment
		(start 53.975 -27.076146)
		(end 53.975 -27.189938)
		(width 0.254)
		(layer "F.Cu")
		(net "GND")
	)
	(segment
		(start 60.30722 -27.34564)
		(end 60.26912 -27.30754)
		(width 0.254)
		(layer "F.Cu")
		(net "GND")
	)
	(segment
		(start 51.295046 -49.7713)
		(end 51.304444 -49.7713)
		(width 0.3556)
		(layer "F.Cu")
		(net "GND")
	)
	(segment
		(start 60.094876 -54.96687)
		(end 60.094876 -55.371238)
		(width 0.381)
		(layer "F.Cu")
		(net "GND")
	)
	(segment
		(start 61.836554 -53.124354)
		(end 61.695076 -52.982876)
		(width 0.3556)
		(layer "F.Cu")
		(net "GND")
	)
	(segment
		(start 17.859502 -89.98712)
		(end 17.464278 -89.591896)
		(width 0.381)
		(layer "F.Cu")
		(net "GND")
	)
	(segment
		(start 16.709644 -46.70425)
		(end 17.104868 -47.099474)
		(width 0.381)
		(layer "F.Cu")
		(net "GND")
	)
	(segment
		(start 73.5965 -92.305632)
		(end 73.09866 -92.305632)
		(width 0.381)
		(layer "F.Cu")
		(net "GND")
	)
	(segment
		(start 13.64996 -58.5216)
		(end 14.03096 -58.1406)
		(width 0.381)
		(layer "F.Cu")
		(net "GND")
	)
	(segment
		(start 19.744944 -116.925344)
		(end 19.685 -116.8654)
		(width 0.381)
		(layer "F.Cu")
		(net "GND")
	)
	(segment
		(start 70.4088 -29.44495)
		(end 70.42785 -29.44495)
		(width 0.381)
		(layer "F.Cu")
		(net "GND")
	)
	(segment
		(start 58.98134 -26.38806)
		(end 58.131456 -27.237944)
		(width 0.254)
		(layer "F.Cu")
		(net "GND")
	)
	(segment
		(start 32.3596 -11.292586)
		(end 32.4866 -11.419586)
		(width 0.381)
		(layer "F.Cu")
		(net "GND")
	)
	(segment
		(start 30.0482 -60.325)
		(end 30.117796 -60.394596)
		(width 0.381)
		(layer "F.Cu")
		(net "GND")
	)
	(segment
		(start 50.494946 -51.371246)
		(end 51.295046 -51.371246)
		(width 0.3556)
		(layer "F.Cu")
		(net "GND")
	)
	(segment
		(start 85.6996 -39.347394)
		(end 86.3092 -39.347394)
		(width 0.3556)
		(layer "F.Cu")
		(net "GND")
	)
	(segment
		(start 25.996138 -72.28586)
		(end 26.250138 -72.53986)
		(width 0.254)
		(layer "F.Cu")
		(net "GND")
	)
	(segment
		(start 6.51383 -6.99008)
		(end 6.940042 -6.563868)
		(width 0.381)
		(layer "F.Cu")
		(net "GND")
	)
	(segment
		(start 11.05535 -61.214)
		(end 10.80135 -61.468)
		(width 0.381)
		(layer "F.Cu")
		(net "GND")
	)
	(segment
		(start 32.517842 -65.22085)
		(end 32.7406 -64.998092)
		(width 0.381)
		(layer "F.Cu")
		(net "GND")
	)
	(segment
		(start 67.3354 -107.696)
		(end 67.40525 -107.62615)
		(width 0.381)
		(layer "F.Cu")
		(net "GND")
	)
	(segment
		(start 33.908238 -26.619962)
		(end 33.5534 -26.9748)
		(width 0.254)
		(layer "F.Cu")
		(net "GND")
	)
	(segment
		(start 75.053444 -31.014924)
		(end 74.01052 -32.057848)
		(width 0.381)
		(layer "F.Cu")
		(net "GND")
	)
	(segment
		(start 23.57755 -105.918)
		(end 23.57755 -104.775)
		(width 0.381)
		(layer "F.Cu")
		(net "GND")
	)
	(segment
		(start 33.782 -44.85005)
		(end 32.766 -44.85005)
		(width 0.381)
		(layer "F.Cu")
		(net "GND")
	)
	(segment
		(start 35.941 -36.957)
		(end 36.068 -37.084)
		(width 0.381)
		(layer "F.Cu")
		(net "GND")
	)
	(segment
		(start 34.625026 -26.619962)
		(end 35.780726 -26.619962)
		(width 0.381)
		(layer "F.Cu")
		(net "GND")
	)
	(segment
		(start 5.125466 -83.4644)
		(end 5.07365 -83.4644)
		(width 0.381)
		(layer "F.Cu")
		(net "GND")
	)
	(segment
		(start 77.420724 -69.534024)
		(end 77.324712 -69.534024)
		(width 0.3556)
		(layer "F.Cu")
		(net "GND")
	)
	(segment
		(start 23.181564 -66.543936)
		(end 23.153878 -66.51625)
		(width 0.381)
		(layer "F.Cu")
		(net "GND")
	)
	(segment
		(start 79.070454 -46.32579)
		(end 79.452216 -46.707552)
		(width 0.3556)
		(layer "F.Cu")
		(net "GND")
	)
	(segment
		(start 12.017248 -14.812518)
		(end 11.470894 -14.812518)
		(width 0.381)
		(layer "F.Cu")
		(net "GND")
	)
	(segment
		(start 23.57755 -104.775)
		(end 24.20112 -104.775)
		(width 0.381)
		(layer "F.Cu")
		(net "GND")
	)
	(segment
		(start 75.032108 -11.486896)
		(end 75.032108 -12.204954)
		(width 0.381)
		(layer "F.Cu")
		(net "GND")
	)
	(segment
		(start 58.49493 -48.180752)
		(end 58.890154 -48.575976)
		(width 0.3556)
		(layer "F.Cu")
		(net "GND")
	)
	(segment
		(start 64.094868 -56.971184)
		(end 64.894968 -57.771284)
		(width 0.3556)
		(layer "F.Cu")
		(net "GND")
	)
	(segment
		(start 74.069448 -32.057848)
		(end 74.7268 -32.7152)
		(width 0.381)
		(layer "F.Cu")
		(net "GND")
	)
	(segment
		(start 17.074896 -32.562292)
		(end 17.869916 -32.562292)
		(width 0.254)
		(layer "F.Cu")
		(net "GND")
	)
	(segment
		(start 9.4869 -104.26065)
		(end 9.2964 -104.07015)
		(width 0.381)
		(layer "F.Cu")
		(net "GND")
	)
	(segment
		(start 52.104544 -45.771308)
		(end 52.499768 -45.376084)
		(width 0.3556)
		(layer "F.Cu")
		(net "GND")
	)
	(segment
		(start 29.730954 -67.0941)
		(end 29.1592 -66.522346)
		(width 0.381)
		(layer "F.Cu")
		(net "GND")
	)
	(segment
		(start 8.459724 -48.779938)
		(end 8.830564 -48.779938)
		(width 0.1778)
		(layer "F.Cu")
		(net "GND")
	)
	(segment
		(start 14.344904 -118.460012)
		(end 14.344904 -116.8654)
		(width 0.381)
		(layer "F.Cu")
		(net "GND")
	)
	(segment
		(start 82.61731 -99.076002)
		(end 82.63128 -99.089972)
		(width 0.381)
		(layer "F.Cu")
		(net "GND")
	)
	(segment
		(start 78.907894 -31.014924)
		(end 78.907894 -31.369)
		(width 0.381)
		(layer "F.Cu")
		(net "GND")
	)
	(segment
		(start 24.654764 -90.391742)
		(end 24.25954 -90.786966)
		(width 0.381)
		(layer "F.Cu")
		(net "GND")
	)
	(segment
		(start 13.462 -10.541)
		(end 12.862814 -9.941814)
		(width 0.381)
		(layer "F.Cu")
		(net "GND")
	)
	(segment
		(start 25.06472 -108.84535)
		(end 25.2984 -108.84535)
		(width 0.381)
		(layer "F.Cu")
		(net "GND")
	)
	(segment
		(start 16.145002 -118.460012)
		(end 16.145002 -116.8654)
		(width 0.381)
		(layer "F.Cu")
		(net "GND")
	)
	(segment
		(start 77.281786 -28.488894)
		(end 77.155294 -28.488894)
		(width 0.381)
		(layer "F.Cu")
		(net "GND")
	)
	(segment
		(start 9.56945 -105.5878)
		(end 9.56945 -104.6226)
		(width 0.381)
		(layer "F.Cu")
		(net "GND")
	)
	(segment
		(start 63.295022 -40.971216)
		(end 63.690246 -40.575992)
		(width 0.3556)
		(layer "F.Cu")
		(net "GND")
	)
	(segment
		(start 13.765784 -105.688384)
		(end 14.29385 -106.21645)
		(width 0.381)
		(layer "F.Cu")
		(net "GND")
	)
	(segment
		(start 45.695108 -44.171362)
		(end 45.299884 -43.776138)
		(width 0.3556)
		(layer "F.Cu")
		(net "GND")
	)
	(segment
		(start 52.894992 -48.180752)
		(end 52.499768 -48.575976)
		(width 0.3556)
		(layer "F.Cu")
		(net "GND")
	)
	(segment
		(start 79.202026 -99.076002)
		(end 82.61731 -99.076002)
		(width 0.381)
		(layer "F.Cu")
		(net "GND")
	)
	(segment
		(start 22.8854 -72.136)
		(end 21.764498 -72.136)
		(width 0.254)
		(layer "F.Cu")
		(net "GND")
	)
	(segment
		(start 57.742328 -26.289)
		(end 56.9468 -26.289)
		(width 0.254)
		(layer "F.Cu")
		(net "GND")
	)
	(segment
		(start 34.625026 -26.619962)
		(end 33.908238 -26.619962)
		(width 0.254)
		(layer "F.Cu")
		(net "GND")
	)
	(segment
		(start 48.03775 -79.0194)
		(end 48.03775 -78.92288)
		(width 0.381)
		(layer "F.Cu")
		(net "GND")
	)
	(segment
		(start 52.894992 -52.971192)
		(end 52.904644 -52.971192)
		(width 0.3556)
		(layer "F.Cu")
		(net "GND")
	)
	(segment
		(start 27.616658 -25.184862)
		(end 27.41295 -25.38857)
		(width 0.381)
		(layer "F.Cu")
		(net "GND")
	)
	(segment
		(start 44.895008 -39.37127)
		(end 44.895008 -39.35984)
		(width 0.3556)
		(layer "F.Cu")
		(net "GND")
	)
	(segment
		(start 51.9938 -27.7876)
		(end 51.9938 -28.5242)
		(width 0.254)
		(layer "F.Cu")
		(net "GND")
	)
	(segment
		(start 11.303 -90.297)
		(end 11.049 -90.043)
		(width 0.381)
		(layer "F.Cu")
		(net "GND")
	)
	(segment
		(start 26.945082 -118.460012)
		(end 26.945082 -116.40185)
		(width 0.381)
		(layer "F.Cu")
		(net "GND")
	)
	(segment
		(start 48.0949 -53.771292)
		(end 47.699676 -54.166516)
		(width 0.3556)
		(layer "F.Cu")
		(net "GND")
	)
	(segment
		(start 49.27473 -66.25082)
		(end 49.22139 -66.25082)
		(width 0.3048)
		(layer "F.Cu")
		(net "GND")
	)
	(segment
		(start 49.25187 -67.25666)
		(end 49.25187 -66.31686)
		(width 0.381)
		(layer "F.Cu")
		(net "GND")
	)
	(segment
		(start 77.155294 -28.488894)
		(end 76.492354 -27.825954)
		(width 0.381)
		(layer "F.Cu")
		(net "GND")
	)
	(segment
		(start 32.741108 -64.998092)
		(end 33.12795 -64.61125)
		(width 0.381)
		(layer "F.Cu")
		(net "GND")
	)
	(segment
		(start 72.060054 -118.460012)
		(end 72.060054 -116.688616)
		(width 0.381)
		(layer "F.Cu")
		(net "GND")
	)
	(segment
		(start 56.894984 -53.771292)
		(end 56.885332 -53.771292)
		(width 0.3556)
		(layer "F.Cu")
		(net "GND")
	)
	(segment
		(start 41.8592 -86.6394)
		(end 41.85666 -86.6394)
		(width 0.381)
		(layer "F.Cu")
		(net "GND")
	)
	(segment
		(start 37.15004 -30.41904)
		(end 36.880546 -30.149546)
		(width 0.381)
		(layer "F.Cu")
		(net "GND")
	)
	(segment
		(start 4.428744 -65.802002)
		(end 4.6101 -65.983358)
		(width 0.254)
		(layer "F.Cu")
		(net "GND")
	)
	(segment
		(start 25.4 -24.40305)
		(end 25.4 -25.019)
		(width 0.381)
		(layer "F.Cu")
		(net "GND")
	)
	(segment
		(start 56.094884 -51.371246)
		(end 56.894984 -51.371246)
		(width 0.3556)
		(layer "F.Cu")
		(net "GND")
	)
	(segment
		(start 42.242232 -57.198006)
		(end 42.776394 -57.198006)
		(width 0.381)
		(layer "F.Cu")
		(net "GND")
	)
	(segment
		(start 71.013828 -62.376558)
		(end 69.148198 -62.376558)
		(width 0.381)
		(layer "F.Cu")
		(net "GND")
	)
	(segment
		(start 67.287902 -20.193)
		(end 65.5066 -20.193)
		(width 0.381)
		(layer "F.Cu")
		(net "GND")
	)
	(segment
		(start 36.880546 -25.508712)
		(end 35.9918 -24.619966)
		(width 0.381)
		(layer "F.Cu")
		(net "GND")
	)
	(segment
		(start 58.6994 -31.9024)
		(end 58.6232 -31.541212)
		(width 0.254)
		(layer "F.Cu")
		(net "GND")
	)
	(segment
		(start 49.086008 -66.386202)
		(end 48.662082 -66.386202)
		(width 0.3048)
		(layer "F.Cu")
		(net "GND")
	)
	(segment
		(start 60.894976 -48.9712)
		(end 61.2902 -48.575976)
		(width 0.3556)
		(layer "F.Cu")
		(net "GND")
	)
	(segment
		(start 11.673078 -25.015952)
		(end 11.803126 -25.146)
		(width 0.381)
		(layer "F.Cu")
		(net "GND")
	)
	(segment
		(start 53.09362 -77.37729)
		(end 52.63388 -76.91755)
		(width 0.381)
		(layer "F.Cu")
		(net "GND")
	)
	(segment
		(start 53.695092 -51.361594)
		(end 53.299868 -50.96637)
		(width 0.3556)
		(layer "F.Cu")
		(net "GND")
	)
	(segment
		(start 56.89473 -52.971192)
		(end 56.490108 -52.56657)
		(width 0.3556)
		(layer "F.Cu")
		(net "GND")
	)
	(segment
		(start 32.8422 -108.18495)
		(end 32.8422 -107.7595)
		(width 0.381)
		(layer "F.Cu")
		(net "GND")
	)
	(segment
		(start 86.0552 -41.887394)
		(end 86.3092 -42.141394)
		(width 0.3556)
		(layer "F.Cu")
		(net "GND")
	)
	(segment
		(start 12.012676 -47.63135)
		(end 12.012676 -47.75327)
		(width 0.381)
		(layer "F.Cu")
		(net "GND")
	)
	(segment
		(start 32.627062 -79.386938)
		(end 32.312864 -79.701136)
		(width 0.254)
		(layer "F.Cu")
		(net "GND")
	)
	(segment
		(start 50.494946 -49.7713)
		(end 50.494946 -48.9712)
		(width 0.3556)
		(layer "F.Cu")
		(net "GND")
	)
	(segment
		(start 32.15005 -28.956)
		(end 32.15005 -28.299664)
		(width 0.381)
		(layer "F.Cu")
		(net "GND")
	)
	(segment
		(start 26.250138 -72.53986)
		(end 26.250138 -73.360534)
		(width 0.254)
		(layer "F.Cu")
		(net "GND")
	)
	(segment
		(start 54.852316 -29.147262)
		(end 55.3466 -29.641546)
		(width 0.254)
		(layer "F.Cu")
		(net "GND")
	)
	(segment
		(start 29.974286 -79.0448)
		(end 28.829 -79.0448)
		(width 0.254)
		(layer "F.Cu")
		(net "GND")
	)
	(segment
		(start 77.707744 -35.127438)
		(end 77.580744 -35.127438)
		(width 0.3556)
		(layer "F.Cu")
		(net "GND")
	)
	(segment
		(start 37.15004 -32.919924)
		(end 34.621216 -32.919924)
		(width 0.381)
		(layer "F.Cu")
		(net "GND")
	)
	(segment
		(start 56.21274 -53.653436)
		(end 56.21274 -53.089048)
		(width 0.3556)
		(layer "F.Cu")
		(net "GND")
	)
	(segment
		(start 37.100002 -80.135222)
		(end 38.174422 -80.135222)
		(width 0.381)
		(layer "F.Cu")
		(net "GND")
	)
	(segment
		(start 44.676822 -59.589416)
		(end 44.216066 -59.589416)
		(width 0.3556)
		(layer "F.Cu")
		(net "GND")
	)
	(segment
		(start 66.400172 -3.090164)
		(end 67.823588 -3.090164)
		(width 0.381)
		(layer "F.Cu")
		(net "GND")
	)
	(segment
		(start 73.052432 -50.707544)
		(end 72.67067 -51.089306)
		(width 0.3556)
		(layer "F.Cu")
		(net "GND")
	)
	(segment
		(start 62.0014 -59.817)
		(end 62.44717 -59.37123)
		(width 0.3556)
		(layer "F.Cu")
		(net "GND")
	)
	(segment
		(start 50.504598 -52.971192)
		(end 50.899822 -53.366416)
		(width 0.381)
		(layer "F.Cu")
		(net "GND")
	)
	(segment
		(start 15.3416 -47.45355)
		(end 15.13205 -47.244)
		(width 0.381)
		(layer "F.Cu")
		(net "GND")
	)
	(segment
		(start 50.494946 -52.161694)
		(end 50.099722 -51.76647)
		(width 0.381)
		(layer "F.Cu")
		(net "GND")
	)
	(segment
		(start 59.825382 -43.901614)
		(end 59.29503 -43.371262)
		(width 0.381)
		(layer "F.Cu")
		(net "GND")
	)
	(segment
		(start 16.400018 -80.135222)
		(end 16.400018 -77.89291)
		(width 0.381)
		(layer "F.Cu")
		(net "GND")
	)
	(segment
		(start 46.761146 -74.694796)
		(end 46.023276 -74.694796)
		(width 0.381)
		(layer "F.Cu")
		(net "GND")
	)
	(segment
		(start 61.595 -86.46795)
		(end 62.484 -85.57895)
		(width 0.381)
		(layer "F.Cu")
		(net "GND")
	)
	(segment
		(start 40.41648 -30.23743)
		(end 40.41648 -29.79674)
		(width 0.381)
		(layer "F.Cu")
		(net "GND")
	)
	(segment
		(start 85.6996 -46.717204)
		(end 85.6996 -46.840394)
		(width 0.381)
		(layer "F.Cu")
		(net "GND")
	)
	(segment
		(start 47.295054 -40.17137)
		(end 47.699676 -40.575992)
		(width 0.381)
		(layer "F.Cu")
		(net "GND")
	)
	(segment
		(start 21.844 -66.38925)
		(end 21.971 -66.51625)
		(width 0.381)
		(layer "F.Cu")
		(net "GND")
	)
	(segment
		(start 55.3466 -30.861)
		(end 56.261 -31.7754)
		(width 0.254)
		(layer "F.Cu")
		(net "GND")
	)
	(segment
		(start 52.7685 -91.7194)
		(end 52.7685 -93.091)
		(width 0.381)
		(layer "F.Cu")
		(net "GND")
	)
	(segment
		(start 74.01052 -28.488894)
		(end 74.01052 -28.402534)
		(width 0.381)
		(layer "F.Cu")
		(net "GND")
	)
	(segment
		(start 12.201652 -11.340338)
		(end 12.80795 -10.73404)
		(width 0.381)
		(layer "F.Cu")
		(net "GND")
	)
	(segment
		(start 37.85489 -116.524024)
		(end 37.856414 -116.5225)
		(width 0.381)
		(layer "F.Cu")
		(net "GND")
	)
	(segment
		(start 75.330304 -27.7622)
		(end 75.646534 -27.44597)
		(width 0.381)
		(layer "F.Cu")
		(net "GND")
	)
	(segment
		(start 13.82395 -17.76095)
		(end 13.335 -17.76095)
		(width 0.381)
		(layer "F.Cu")
		(net "GND")
	)
	(segment
		(start 52.72913 -97.56775)
		(end 52.72913 -96.051116)
		(width 0.381)
		(layer "F.Cu")
		(net "GND")
	)
	(segment
		(start 60.894976 -54.571138)
		(end 60.894976 -54.56174)
		(width 0.3556)
		(layer "F.Cu")
		(net "GND")
	)
	(segment
		(start 62.484 -85.57895)
		(end 62.484 -83.947)
		(width 0.381)
		(layer "F.Cu")
		(net "GND")
	)
	(segment
		(start 50.099722 -50.96637)
		(end 50.494946 -50.571146)
		(width 0.3556)
		(layer "F.Cu")
		(net "GND")
	)
	(segment
		(start 25.859486 -97.987104)
		(end 26.259282 -98.3869)
		(width 0.381)
		(layer "F.Cu")
		(net "GND")
	)
	(segment
		(start 26.902664 -27.815286)
		(end 26.902664 -27.927808)
		(width 0.381)
		(layer "F.Cu")
		(net "GND")
	)
	(segment
		(start 6.3754 -80.49895)
		(end 6.38175 -80.4926)
		(width 0.381)
		(layer "F.Cu")
		(net "GND")
	)
	(segment
		(start 10.122662 -50.379884)
		(end 10.517632 -49.984914)
		(width 0.1778)
		(layer "F.Cu")
		(net "GND")
	)
	(segment
		(start 68.18249 -30.854904)
		(end 67.900804 -31.13659)
		(width 0.381)
		(layer "F.Cu")
		(net "GND")
	)
	(segment
		(start 78.26629 -31.75)
		(end 78.105 -31.91129)
		(width 0.381)
		(layer "F.Cu")
		(net "GND")
	)
	(segment
		(start 50.494946 -52.971192)
		(end 50.504598 -52.971192)
		(width 0.381)
		(layer "F.Cu")
		(net "GND")
	)
	(segment
		(start 60.419488 -27.23007)
		(end 60.4774 -27.047444)
		(width 0.254)
		(layer "F.Cu")
		(net "GND")
	)
	(segment
		(start 37.973 -19.142964)
		(end 37.973 -24.416258)
		(width 0.381)
		(layer "F.Cu")
		(net "GND")
	)
	(segment
		(start 10.050018 -62.513464)
		(end 10.050018 -61.755782)
		(width 0.381)
		(layer "F.Cu")
		(net "GND")
	)
	(segment
		(start 48.0949 -54.56174)
		(end 47.699676 -54.166516)
		(width 0.3556)
		(layer "F.Cu")
		(net "GND")
	)
	(segment
		(start 74.650854 -27.7622)
		(end 75.330304 -27.7622)
		(width 0.381)
		(layer "F.Cu")
		(net "GND")
	)
	(segment
		(start 45.695108 -41.771316)
		(end 45.299884 -41.376092)
		(width 0.3556)
		(layer "F.Cu")
		(net "GND")
	)
	(segment
		(start 32.999934 -79.4004)
		(end 32.999934 -80.910176)
		(width 0.254)
		(layer "F.Cu")
		(net "GND")
	)
	(segment
		(start 24.4856 -34.30905)
		(end 24.4856 -34.91865)
		(width 0.381)
		(layer "F.Cu")
		(net "GND")
	)
	(segment
		(start 53.695092 -52.971192)
		(end 53.299868 -53.366416)
		(width 0.3556)
		(layer "F.Cu")
		(net "GND")
	)
	(segment
		(start 50.494946 -40.17137)
		(end 50.099722 -39.776146)
		(width 0.3556)
		(layer "F.Cu")
		(net "GND")
	)
	(segment
		(start 36.251134 -30.149546)
		(end 35.780726 -30.619954)
		(width 0.381)
		(layer "F.Cu")
		(net "GND")
	)
	(segment
		(start 57.695084 -52.171346)
		(end 57.825386 -52.301648)
		(width 0.381)
		(layer "F.Cu")
		(net "GND")
	)
	(segment
		(start 62.44717 -59.37123)
		(end 62.494922 -59.37123)
		(width 0.3556)
		(layer "F.Cu")
		(net "GND")
	)
	(segment
		(start 81.788 -37.925756)
		(end 81.340706 -38.37305)
		(width 0.381)
		(layer "F.Cu")
		(net "GND")
	)
	(segment
		(start 31.500064 -80.910176)
		(end 31.500064 -79.701136)
		(width 0.254)
		(layer "F.Cu")
		(net "GND")
	)
	(segment
		(start 42.346626 -18.598896)
		(end 42.346626 -17.836388)
		(width 0.381)
		(layer "F.Cu")
		(net "GND")
	)
	(segment
		(start 52.094892 -58.57113)
		(end 51.699668 -58.966354)
		(width 0.3556)
		(layer "F.Cu")
		(net "GND")
	)
	(segment
		(start 41.57726 -68.22694)
		(end 41.500298 -68.149978)
		(width 0.381)
		(layer "F.Cu")
		(net "GND")
	)
	(segment
		(start 63.64605 -79.629)
		(end 64.3636 -79.629)
		(width 0.381)
		(layer "F.Cu")
		(net "GND")
	)
	(segment
		(start 49.403 -43.879262)
		(end 50.786792 -43.879262)
		(width 0.3556)
		(layer "F.Cu")
		(net "GND")
	)
	(segment
		(start 11.571986 -53.518054)
		(end 11.857736 -53.803804)
		(width 0.381)
		(layer "F.Cu")
		(net "GND")
	)
	(segment
		(start 51.9938 -28.5242)
		(end 52.616862 -29.147262)
		(width 0.254)
		(layer "F.Cu")
		(net "GND")
	)
	(segment
		(start 36.1442 -70.00875)
		(end 35.8394 -69.70395)
		(width 0.381)
		(layer "F.Cu")
		(net "GND")
	)
	(segment
		(start 28.06192 -79.81188)
		(end 27.27452 -79.81188)
		(width 0.254)
		(layer "F.Cu")
		(net "GND")
	)
	(segment
		(start 16.256 -33.05175)
		(end 15.363444 -33.05175)
		(width 0.3556)
		(layer "F.Cu")
		(net "GND")
	)
	(segment
		(start 9.607042 -50.379884)
		(end 10.122662 -50.379884)
		(width 0.1778)
		(layer "F.Cu")
		(net "GND")
	)
	(segment
		(start 43.18 -56.2102)
		(end 41.889934 -54.920134)
		(width 0.381)
		(layer "F.Cu")
		(net "GND")
	)
	(segment
		(start 22.999954 -81.963768)
		(end 22.820122 -82.1436)
		(width 0.254)
		(layer "F.Cu")
		(net "GND")
	)
	(segment
		(start 56.21274 -53.089048)
		(end 56.094884 -52.971192)
		(width 0.3556)
		(layer "F.Cu")
		(net "GND")
	)
	(segment
		(start 48.03775 -78.92288)
		(end 47.17415 -78.05928)
		(width 0.381)
		(layer "F.Cu")
		(net "GND")
	)
	(segment
		(start 34.621216 -32.919924)
		(end 34.26714 -33.274)
		(width 0.381)
		(layer "F.Cu")
		(net "GND")
	)
	(segment
		(start 53.695092 -55.371238)
		(end 53.70449 -55.371238)
		(width 0.381)
		(layer "F.Cu")
		(net "GND")
	)
	(segment
		(start 29.9466 -79.70774)
		(end 28.77566 -79.70774)
		(width 0.254)
		(layer "F.Cu")
		(net "GND")
	)
	(segment
		(start 55.3466 -29.641546)
		(end 55.3466 -30.861)
		(width 0.254)
		(layer "F.Cu")
		(net "GND")
	)
	(segment
		(start 8.901176 -9.080754)
		(end 9.37895 -9.558528)
		(width 0.381)
		(layer "F.Cu")
		(net "GND")
	)
	(segment
		(start 28.6512 -62.07252)
		(end 28.85186 -62.27318)
		(width 0.254)
		(layer "F.Cu")
		(net "GND")
	)
	(segment
		(start 18.127726 -42.09542)
		(end 17.92732 -42.295826)
		(width 0.381)
		(layer "F.Cu")
		(net "GND")
	)
	(segment
		(start 30.664404 -31.369)
		(end 30.639004 -31.369)
		(width 0.381)
		(layer "F.Cu")
		(net "GND")
	)
	(segment
		(start 32.950912 -31.0134)
		(end 32.849312 -31.115)
		(width 0.381)
		(layer "F.Cu")
		(net "GND")
	)
	(segment
		(start 15.89278 -29.5783)
		(end 15.268448 -28.953968)
		(width 0.381)
		(layer "F.Cu")
		(net "GND")
	)
	(segment
		(start 33.12795 -64.61125)
		(end 33.12795 -64.4398)
		(width 0.381)
		(layer "F.Cu")
		(net "GND")
	)
	(segment
		(start 61.985652 -59.817)
		(end 62.0014 -59.817)
		(width 0.3556)
		(layer "F.Cu")
		(net "GND")
	)
	(segment
		(start 64.894968 -57.771284)
		(end 65.290192 -57.37606)
		(width 0.3556)
		(layer "F.Cu")
		(net "GND")
	)
	(segment
		(start 36.195 -88.170512)
		(end 36.56203 -88.537542)
		(width 0.381)
		(layer "F.Cu")
		(net "GND")
	)
	(segment
		(start 64.094868 -44.171362)
		(end 64.490092 -43.776138)
		(width 0.3556)
		(layer "F.Cu")
		(net "GND")
	)
	(segment
		(start 16.586454 -47.691548)
		(end 16.251428 -47.356522)
		(width 0.381)
		(layer "F.Cu")
		(net "GND")
	)
	(segment
		(start 81.07045 -15.9258)
		(end 81.07045 -15.2908)
		(width 0.3556)
		(layer "F.Cu")
		(net "GND")
	)
	(segment
		(start 12.829032 -14.594586)
		(end 12.23518 -14.594586)
		(width 0.381)
		(layer "F.Cu")
		(net "GND")
	)
	(segment
		(start 17.104868 -47.099474)
		(end 17.104868 -47.31258)
		(width 0.381)
		(layer "F.Cu")
		(net "GND")
	)
	(segment
		(start 22.254718 -94.382336)
		(end 21.859494 -93.987112)
		(width 0.381)
		(layer "F.Cu")
		(net "GND")
	)
	(segment
		(start 11.803126 -25.146)
		(end 14.249908 -25.146)
		(width 0.381)
		(layer "F.Cu")
		(net "GND")
	)
	(segment
		(start 73.72223 -11.322812)
		(end 73.72223 -11.932412)
		(width 0.381)
		(layer "F.Cu")
		(net "GND")
	)
	(segment
		(start 20.155662 -60.98159)
		(end 20.155662 -61.086746)
		(width 0.254)
		(layer "F.Cu")
		(net "GND")
	)
	(segment
		(start 52.094892 -45.771308)
		(end 52.104544 -45.771308)
		(width 0.3556)
		(layer "F.Cu")
		(net "GND")
	)
	(segment
		(start 11.12012 -49.251108)
		(end 11.12012 -49.358296)
		(width 0.381)
		(layer "F.Cu")
		(net "GND")
	)
	(segment
		(start 46.0756 -108.7374)
		(end 46.0756 -109.12475)
		(width 0.381)
		(layer "F.Cu")
		(net "GND")
	)
	(segment
		(start 30.117796 -60.394596)
		(end 31.46806 -60.394596)
		(width 0.381)
		(layer "F.Cu")
		(net "GND")
	)
	(segment
		(start 85.6996 -43.157394)
		(end 86.3092 -43.157394)
		(width 0.3556)
		(layer "F.Cu")
		(net "GND")
	)
	(segment
		(start 32.8422 -28.2702)
		(end 32.179514 -28.2702)
		(width 0.254)
		(layer "F.Cu")
		(net "GND")
	)
	(segment
		(start 33.909 -38.85819)
		(end 33.909 -37.94379)
		(width 0.381)
		(layer "F.Cu")
		(net "GND")
	)
	(segment
		(start 25.500076 -80.910176)
		(end 25.500076 -81.70926)
		(width 0.254)
		(layer "F.Cu")
		(net "GND")
	)
	(segment
		(start 25.45461 -89.591896)
		(end 25.059386 -89.98712)
		(width 0.381)
		(layer "F.Cu")
		(net "GND")
	)
	(segment
		(start 44.895008 -39.35984)
		(end 44.541186 -39.006018)
		(width 0.3556)
		(layer "F.Cu")
		(net "GND")
	)
	(segment
		(start 12.202414 -53.8226)
		(end 12.119356 -53.905658)
		(width 0.254)
		(layer "F.Cu")
		(net "GND")
	)
	(segment
		(start 10.922 -90.043)
		(end 10.43305 -89.55405)
		(width 0.381)
		(layer "F.Cu")
		(net "GND")
	)
	(segment
		(start 60.579 -83.7184)
		(end 60.96 -83.3374)
		(width 0.381)
		(layer "F.Cu")
		(net "GND")
	)
	(segment
		(start 45.062902 -63.356744)
		(end 44.986702 -63.280544)
		(width 0.3556)
		(layer "F.Cu")
		(net "GND")
	)
	(segment
		(start 28.194 -11.566144)
		(end 28.194 -11.3284)
		(width 0.381)
		(layer "F.Cu")
		(net "GND")
	)
	(segment
		(start 23.24989 -72.50049)
		(end 22.8854 -72.136)
		(width 0.254)
		(layer "F.Cu")
		(net "GND")
	)
	(segment
		(start 24.724614 -73.335134)
		(end 24.724614 -72.03186)
		(width 0.254)
		(layer "F.Cu")
		(net "GND")
	)
	(segment
		(start 32.766 -44.85005)
		(end 32.0802 -44.85005)
		(width 0.381)
		(layer "F.Cu")
		(net "GND")
	)
	(segment
		(start 44.541186 -39.006018)
		(end 44.541186 -38.934644)
		(width 0.3556)
		(layer "F.Cu")
		(net "GND")
	)
	(segment
		(start 52.894992 -48.9712)
		(end 52.499768 -48.575976)
		(width 0.3556)
		(layer "F.Cu")
		(net "GND")
	)
	(segment
		(start 53.695092 -45.771308)
		(end 53.695092 -45.780706)
		(width 0.3556)
		(layer "F.Cu")
		(net "GND")
	)
	(segment
		(start 39.37 -74.31405)
		(end 38.91915 -74.31405)
		(width 0.3556)
		(layer "F.Cu")
		(net "GND")
	)
	(segment
		(start 38.20795 -108.55325)
		(end 38.20795 -108.966)
		(width 0.381)
		(layer "F.Cu")
		(net "GND")
	)
	(segment
		(start 73.052432 -49.907444)
		(end 72.67067 -50.289206)
		(width 0.3556)
		(layer "F.Cu")
		(net "GND")
	)
	(segment
		(start 18.6182 -82.1436)
		(end 18.999962 -81.761838)
		(width 0.254)
		(layer "F.Cu")
		(net "GND")
	)
	(segment
		(start 12.862814 -9.941814)
		(end 12.862814 -9.779)
		(width 0.381)
		(layer "F.Cu")
		(net "GND")
	)
	(segment
		(start 32.75838 -105.794302)
		(end 32.9946 -105.558082)
		(width 0.381)
		(layer "F.Cu")
		(net "GND")
	)
	(segment
		(start 20.409916 -61.341)
		(end 20.7264 -61.341)
		(width 0.254)
		(layer "F.Cu")
		(net "GND")
	)
	(segment
		(start 85.69325 -18.796)
		(end 85.69325 -19.4564)
		(width 0.381)
		(layer "F.Cu")
		(net "GND")
	)
	(segment
		(start 26.0604 -106.68)
		(end 26.2636 -106.68)
		(width 0.381)
		(layer "F.Cu")
		(net "GND")
	)
	(segment
		(start 62.494922 -48.171354)
		(end 62.890146 -47.77613)
		(width 0.3556)
		(layer "F.Cu")
		(net "GND")
	)
	(segment
		(start 73.6981 -91.061032)
		(end 73.6981 -92.204032)
		(width 0.381)
		(layer "F.Cu")
		(net "GND")
	)
	(segment
		(start 79.60995 -72.930512)
		(end 79.276956 -73.263506)
		(width 0.254)
		(layer "F.Cu")
		(net "GND")
	)
	(segment
		(start 50.494946 -52.171346)
		(end 50.494946 -52.161694)
		(width 0.381)
		(layer "F.Cu")
		(net "GND")
	)
	(segment
		(start 74.799952 -3.090164)
		(end 73.369424 -3.090164)
		(width 0.381)
		(layer "F.Cu")
		(net "GND")
	)
	(segment
		(start 40.005 -59.232546)
		(end 39.623746 -59.6138)
		(width 0.381)
		(layer "F.Cu")
		(net "GND")
	)
	(segment
		(start 66.78422 -82.04962)
		(end 66.78422 -82.6262)
		(width 0.381)
		(layer "F.Cu")
		(net "GND")
	)
	(segment
		(start 52.094892 -48.171354)
		(end 52.094892 -48.180752)
		(width 0.3556)
		(layer "F.Cu")
		(net "GND")
	)
	(segment
		(start 33.896046 -30.619954)
		(end 33.5026 -31.0134)
		(width 0.381)
		(layer "F.Cu")
		(net "GND")
	)
	(segment
		(start 22.225 -61.306202)
		(end 22.225 -60.2742)
		(width 0.381)
		(layer "F.Cu")
		(net "GND")
	)
	(segment
		(start 64.360552 -68.174362)
		(end 64.360552 -69.50837)
		(width 0.381)
		(layer "F.Cu")
		(net "GND")
	)
	(segment
		(start 78.25105 -79.121)
		(end 78.25105 -79.64805)
		(width 0.381)
		(layer "F.Cu")
		(net "GND")
	)
	(segment
		(start 60.1726 -27.845512)
		(end 60.30722 -27.710892)
		(width 0.254)
		(layer "F.Cu")
		(net "GND")
	)
	(segment
		(start 12.23518 -14.594586)
		(end 12.017248 -14.812518)
		(width 0.381)
		(layer "F.Cu")
		(net "GND")
	)
	(segment
		(start 41.916604 -87.279734)
		(end 41.837356 -87.200486)
		(width 0.381)
		(layer "F.Cu")
		(net "GND")
	)
	(segment
		(start 85.8012 -44.427394)
		(end 86.3092 -44.935394)
		(width 0.3556)
		(layer "F.Cu")
		(net "GND")
	)
	(segment
		(start 76.34605 -77.978)
		(end 76.85405 -77.47)
		(width 0.381)
		(layer "F.Cu")
		(net "GND")
	)
	(segment
		(start 60.885324 -55.371238)
		(end 60.4901 -55.766462)
		(width 0.3556)
		(layer "F.Cu")
		(net "GND")
	)
	(segment
		(start 64.094868 -47.371254)
		(end 64.490092 -46.97603)
		(width 0.3556)
		(layer "F.Cu")
		(net "GND")
	)
	(segment
		(start 60.4774 -26.57348)
		(end 60.03544 -26.13152)
		(width 0.254)
		(layer "F.Cu")
		(net "GND")
	)
	(segment
		(start 12.92225 -53.8226)
		(end 12.202414 -53.8226)
		(width 0.254)
		(layer "F.Cu")
		(net "GND")
	)
	(segment
		(start 52.894992 -51.371246)
		(end 52.094892 -51.371246)
		(width 0.3556)
		(layer "F.Cu")
		(net "GND")
	)
	(segment
		(start 29.06395 -31.369)
		(end 28.448 -31.369)
		(width 0.381)
		(layer "F.Cu")
		(net "GND")
	)
	(segment
		(start 63.295022 -58.57113)
		(end 63.690246 -58.966354)
		(width 0.3556)
		(layer "F.Cu")
		(net "GND")
	)
	(segment
		(start 40.5638 -28.448)
		(end 40.6146 -28.448)
		(width 0.381)
		(layer "F.Cu")
		(net "GND")
	)
	(segment
		(start 58.123328 -27.237944)
		(end 57.139332 -27.237944)
		(width 0.381)
		(layer "F.Cu")
		(net "GND")
	)
	(segment
		(start 84.372196 -72.733408)
		(end 84.792312 -72.733408)
		(width 0.381)
		(layer "F.Cu")
		(net "GND")
	)
	(segment
		(start 55.295038 -46.571154)
		(end 55.295038 -45.771308)
		(width 0.3556)
		(layer "F.Cu")
		(net "GND")
	)
	(segment
		(start 72.028304 -74.69505)
		(end 71.599806 -74.266552)
		(width 0.381)
		(layer "F.Cu")
		(net "GND")
	)
	(segment
		(start 68.35013 -8.79475)
		(end 68.35013 -7.39013)
		(width 0.381)
		(layer "F.Cu")
		(net "GND")
	)
	(segment
		(start 51.295046 -48.180752)
		(end 50.899822 -48.575976)
		(width 0.3556)
		(layer "F.Cu")
		(net "GND")
	)
	(segment
		(start 40.41648 -29.79674)
		(end 40.23868 -29.61894)
		(width 0.381)
		(layer "F.Cu")
		(net "GND")
	)
	(segment
		(start 51.295046 -47.371254)
		(end 51.295046 -48.171354)
		(width 0.3556)
		(layer "F.Cu")
		(net "GND")
	)
	(segment
		(start 58.49493 -44.171362)
		(end 59.29503 -43.371262)
		(width 0.3556)
		(layer "F.Cu")
		(net "GND")
	)
	(segment
		(start 26.289 -61.117226)
		(end 26.127964 -60.95619)
		(width 0.254)
		(layer "F.Cu")
		(net "GND")
	)
	(segment
		(start 26.95448 -30.58668)
		(end 27.7368 -31.369)
		(width 0.254)
		(layer "F.Cu")
		(net "GND")
	)
	(segment
		(start 54.494938 -43.371262)
		(end 54.099714 -42.976038)
		(width 0.3556)
		(layer "F.Cu")
		(net "GND")
	)
	(segment
		(start 19.054572 -96.782382)
		(end 18.659348 -96.387158)
		(width 0.381)
		(layer "F.Cu")
		(net "GND")
	)
	(segment
		(start 49.22139 -66.25082)
		(end 49.086008 -66.386202)
		(width 0.3048)
		(layer "F.Cu")
		(net "GND")
	)
	(segment
		(start 9.48944 -49.332388)
		(end 9.48944 -49.2887)
		(width 0.2032)
		(layer "F.Cu")
		(net "GND")
	)
	(segment
		(start 56.094884 -53.771292)
		(end 56.21274 -53.653436)
		(width 0.3556)
		(layer "F.Cu")
		(net "GND")
	)
	(segment
		(start 60.894976 -56.971184)
		(end 60.499752 -57.366408)
		(width 0.3556)
		(layer "F.Cu")
		(net "GND")
	)
	(segment
		(start 73.052432 -41.90746)
		(end 72.63892 -41.525698)
		(width 0.3556)
		(layer "F.Cu")
		(net "GND")
	)
	(segment
		(start 9.242044 -49.579784)
		(end 9.48944 -49.332388)
		(width 0.2032)
		(layer "F.Cu")
		(net "GND")
	)
	(segment
		(start 78.723744 -35.127438)
		(end 77.707744 -35.127438)
		(width 0.3556)
		(layer "F.Cu")
		(net "GND")
	)
	(segment
		(start 21.760688 -72.13219)
		(end 21.75002 -72.142858)
		(width 0.254)
		(layer "F.Cu")
		(net "GND")
	)
	(segment
		(start 57.42305 -76.3524)
		(end 57.5818 -76.3524)
		(width 0.381)
		(layer "F.Cu")
		(net "GND")
	)
	(segment
		(start 9.56945 -104.6226)
		(end 9.4869 -104.54005)
		(width 0.381)
		(layer "F.Cu")
		(net "GND")
	)
	(segment
		(start 32.8422 -107.7595)
		(end 32.75838 -107.557062)
		(width 0.381)
		(layer "F.Cu")
		(net "GND")
	)
	(segment
		(start 51.295046 -48.171354)
		(end 51.295046 -48.180752)
		(width 0.3556)
		(layer "F.Cu")
		(net "GND")
	)
	(segment
		(start 22.820122 -82.1436)
		(end 21.717 -82.1436)
		(width 0.254)
		(layer "F.Cu")
		(net "GND")
	)
	(segment
		(start 16.251428 -47.356522)
		(end 15.438628 -47.356522)
		(width 0.381)
		(layer "F.Cu")
		(net "GND")
	)
	(segment
		(start 31.81604 -11.292586)
		(end 32.3596 -11.292586)
		(width 0.381)
		(layer "F.Cu")
		(net "GND")
	)
	(segment
		(start 53.695092 -45.780706)
		(end 53.299868 -46.17593)
		(width 0.3556)
		(layer "F.Cu")
		(net "GND")
	)
	(segment
		(start 11.761978 -52.408582)
		(end 12.07516 -52.408582)
		(width 0.3556)
		(layer "F.Cu")
		(net "GND")
	)
	(segment
		(start 37.85489 -118.460012)
		(end 37.85489 -116.524024)
		(width 0.381)
		(layer "F.Cu")
		(net "GND")
	)
	(segment
		(start 59.699652 -55.766462)
		(end 60.094876 -55.371238)
		(width 0.381)
		(layer "F.Cu")
		(net "GND")
	)
	(segment
		(start 82.55508 -18.556986)
		(end 82.296 -18.556986)
		(width 0.3556)
		(layer "F.Cu")
		(net "GND")
	)
	(segment
		(start 85.6996 -41.887394)
		(end 86.0552 -41.887394)
		(width 0.3556)
		(layer "F.Cu")
		(net "GND")
	)
	(segment
		(start 32.100012 -31.115)
		(end 31.337504 -31.115)
		(width 0.381)
		(layer "F.Cu")
		(net "GND")
	)
	(segment
		(start 17.464278 -97.582228)
		(end 17.859502 -97.187004)
		(width 0.381)
		(layer "F.Cu")
		(net "GND")
	)
	(segment
		(start 61.8998 -26.93035)
		(end 61.8998 -26.62301)
		(width 0.381)
		(layer "F.Cu")
		(net "GND")
	)
	(segment
		(start 64.3636 -79.629)
		(end 66.78422 -82.04962)
		(width 0.381)
		(layer "F.Cu")
		(net "GND")
	)
	(segment
		(start 61.695076 -39.37127)
		(end 61.695076 -39.380922)
		(width 0.3556)
		(layer "F.Cu")
		(net "GND")
	)
	(segment
		(start 10.517632 -49.984914)
		(end 10.517632 -49.960784)
		(width 0.1778)
		(layer "F.Cu")
		(net "GND")
	)
	(segment
		(start 57.695084 -53.771292)
		(end 57.704482 -53.771292)
		(width 0.381)
		(layer "F.Cu")
		(net "GND")
	)
	(segment
		(start 16.0782 -61.306202)
		(end 16.0782 -60.3504)
		(width 0.381)
		(layer "F.Cu")
		(net "GND")
	)
	(segment
		(start 56.8198 -26.416)
		(end 54.635146 -26.416)
		(width 0.254)
		(layer "F.Cu")
		(net "GND")
	)
	(segment
		(start 85.6996 -46.840394)
		(end 86.0806 -47.221394)
		(width 0.381)
		(layer "F.Cu")
		(net "GND")
	)
	(segment
		(start 59.690254 -50.96637)
		(end 59.29503 -50.571146)
		(width 0.3556)
		(layer "F.Cu")
		(net "GND")
	)
	(segment
		(start 56.894984 -44.971208)
		(end 56.894984 -44.98086)
		(width 0.3556)
		(layer "F.Cu")
		(net "GND")
	)
	(segment
		(start 6.38175 -80.953356)
		(end 6.555994 -81.1276)
		(width 0.381)
		(layer "F.Cu")
		(net "GND")
	)
	(segment
		(start 49.25695 -67.26174)
		(end 49.25187 -67.25666)
		(width 0.381)
		(layer "F.Cu")
		(net "GND")
	)
	(segment
		(start 62.494922 -44.971208)
		(end 62.890146 -44.575984)
		(width 0.3556)
		(layer "F.Cu")
		(net "GND")
	)
	(segment
		(start 61.695076 -40.17137)
		(end 62.0903 -39.776146)
		(width 0.3556)
		(layer "F.Cu")
		(net "GND")
	)
	(segment
		(start 78.65237 -49.107344)
		(end 79.034132 -49.489106)
		(width 0.3556)
		(layer "F.Cu")
		(net "GND")
	)
	(segment
		(start 53.975 -27.189938)
		(end 53.537612 -27.627326)
		(width 0.254)
		(layer "F.Cu")
		(net "GND")
	)
	(segment
		(start 33.5026 -31.0134)
		(end 32.950912 -31.0134)
		(width 0.381)
		(layer "F.Cu")
		(net "GND")
	)
	(segment
		(start 49.27473 -66.294)
		(end 49.27473 -66.25082)
		(width 0.381)
		(layer "F.Cu")
		(net "GND")
	)
	(segment
		(start 75.646534 -27.201876)
		(end 75.646534 -27.44597)
		(width 0.381)
		(layer "F.Cu")
		(net "GND")
	)
	(segment
		(start 18.415 -66.44005)
		(end 18.07845 -66.7766)
		(width 0.381)
		(layer "F.Cu")
		(net "GND")
	)
	(segment
		(start 77.85227 -41.90746)
		(end 78.234032 -41.525698)
		(width 0.3556)
		(layer "F.Cu")
		(net "GND")
	)
	(segment
		(start 61.5188 -30.46095)
		(end 61.674248 -30.305502)
		(width 0.381)
		(layer "F.Cu")
		(net "GND")
	)
	(segment
		(start 48.464978 -117.222778)
		(end 48.1584 -116.9162)
		(width 0.381)
		(layer "F.Cu")
		(net "GND")
	)
	(segment
		(start 39.532814 -45.384466)
		(end 38.944042 -45.384466)
		(width 0.381)
		(layer "F.Cu")
		(net "GND")
	)
	(segment
		(start 59.29503 -47.371254)
		(end 59.690254 -46.97603)
		(width 0.3556)
		(layer "F.Cu")
		(net "GND")
	)
	(segment
		(start 75.895962 -99.076002)
		(end 75.881992 -99.089972)
		(width 0.381)
		(layer "F.Cu")
		(net "GND")
	)
	(segment
		(start 45.299884 -57.366408)
		(end 45.695108 -56.971184)
		(width 0.3556)
		(layer "F.Cu")
		(net "GND")
	)
	(segment
		(start 59.183778 -53.882544)
		(end 59.29503 -53.771292)
		(width 0.3556)
		(layer "F.Cu")
		(net "GND")
	)
	(segment
		(start 52.63388 -76.91755)
		(end 52.63388 -76.49972)
		(width 0.381)
		(layer "F.Cu")
		(net "GND")
	)
	(segment
		(start 42.675048 -101.873304)
		(end 42.675048 -102.70998)
		(width 0.381)
		(layer "F.Cu")
		(net "GND")
	)
	(segment
		(start 60.894976 -54.571138)
		(end 60.490608 -54.571138)
		(width 0.381)
		(layer "F.Cu")
		(net "GND")
	)
	(segment
		(start 10.59942 -47.453296)
		(end 9.852914 -47.453296)
		(width 0.254)
		(layer "F.Cu")
		(net "GND")
	)
	(segment
		(start 50.099722 -50.166524)
		(end 50.494946 -49.7713)
		(width 0.3556)
		(layer "F.Cu")
		(net "GND")
	)
	(segment
		(start 36.574222 -88.52535)
		(end 36.56203 -88.537542)
		(width 0.381)
		(layer "F.Cu")
		(net "GND")
	)
	(segment
		(start 52.094892 -51.371246)
		(end 52.094892 -51.361594)
		(width 0.3556)
		(layer "F.Cu")
		(net "GND")
	)
	(segment
		(start 56.894984 -44.98086)
		(end 57.290208 -45.376084)
		(width 0.3556)
		(layer "F.Cu")
		(net "GND")
	)
	(segment
		(start 53.695092 -48.171354)
		(end 52.894992 -48.171354)
		(width 0.3556)
		(layer "F.Cu")
		(net "GND")
	)
	(segment
		(start 55.24373 -24.55418)
		(end 54.5846 -23.89505)
		(width 0.381)
		(layer "F.Cu")
		(net "GND")
	)
	(segment
		(start 56.894984 -50.571146)
		(end 57.290208 -50.175922)
		(width 0.3556)
		(layer "F.Cu")
		(net "GND")
	)
	(segment
		(start 50.494946 -47.371254)
		(end 50.494946 -48.171354)
		(width 0.3556)
		(layer "F.Cu")
		(net "GND")
	)
	(segment
		(start 51.304444 -49.7713)
		(end 51.699668 -50.166524)
		(width 0.3556)
		(layer "F.Cu")
		(net "GND")
	)
	(segment
		(start 84.652612 -38.386766)
		(end 84.652612 -37.703506)
		(width 0.381)
		(layer "F.Cu")
		(net "GND")
	)
	(segment
		(start 11.547094 -48.824134)
		(end 11.12012 -49.251108)
		(width 0.381)
		(layer "F.Cu")
		(net "GND")
	)
	(segment
		(start 34.625026 -22.61997)
		(end 35.780726 -22.61997)
		(width 0.381)
		(layer "F.Cu")
		(net "GND")
	)
	(segment
		(start 54.635146 -26.416)
		(end 53.975 -27.076146)
		(width 0.254)
		(layer "F.Cu")
		(net "GND")
	)
	(segment
		(start 39.623746 -59.6138)
		(end 39.5732 -59.6138)
		(width 0.381)
		(layer "F.Cu")
		(net "GND")
	)
	(segment
		(start 70.259956 -117.088158)
		(end 70.501002 -116.847112)
		(width 0.381)
		(layer "F.Cu")
		(net "GND")
	)
	(segment
		(start 30.958028 -15.091918)
		(end 30.958028 -15.503398)
		(width 0.381)
		(layer "F.Cu")
		(net "GND")
	)
	(segment
		(start 16.637 -46.70425)
		(end 16.709644 -46.70425)
		(width 0.381)
		(layer "F.Cu")
		(net "GND")
	)
	(segment
		(start 16.8275 -106.21645)
		(end 17.153128 -106.21645)
		(width 0.381)
		(layer "F.Cu")
		(net "GND")
	)
	(segment
		(start 62.494922 -49.7713)
		(end 62.890146 -50.166524)
		(width 0.3556)
		(layer "F.Cu")
		(net "GND")
	)
	(segment
		(start 40.6146 -28.448)
		(end 40.8178 -28.6512)
		(width 0.381)
		(layer "F.Cu")
		(net "GND")
	)
	(segment
		(start 78.907894 -27.44597)
		(end 78.32471 -27.44597)
		(width 0.381)
		(layer "F.Cu")
		(net "GND")
	)
	(segment
		(start 25.500076 -81.70926)
		(end 25.11806 -82.091276)
		(width 0.254)
		(layer "F.Cu")
		(net "GND")
	)
	(segment
		(start 9.607042 -50.379884)
		(end 8.459724 -50.379884)
		(width 0.2032)
		(layer "F.Cu")
		(net "GND")
	)
	(segment
		(start 55.295038 -44.412408)
		(end 55.295038 -44.971208)
		(width 0.3556)
		(layer "F.Cu")
		(net "GND")
	)
	(segment
		(start 76.691744 -35.102038)
		(end 76.691744 -34.492438)
		(width 0.381)
		(layer "F.Cu")
		(net "GND")
	)
	(segment
		(start 79.202026 -99.076002)
		(end 75.895962 -99.076002)
		(width 0.381)
		(layer "F.Cu")
		(net "GND")
	)
	(segment
		(start 38.944042 -45.384466)
		(end 38.916864 -45.357288)
		(width 0.381)
		(layer "F.Cu")
		(net "GND")
	)
	(segment
		(start 11.049 -90.043)
		(end 10.922 -90.043)
		(width 0.381)
		(layer "F.Cu")
		(net "GND")
	)
	(segment
		(start 78.359 -97.0534)
		(end 78.161642 -96.856042)
		(width 0.3556)
		(layer "F.Cu")
		(net "GND")
	)
	(segment
		(start 17.050004 -32.5374)
		(end 17.074896 -32.562292)
		(width 0.254)
		(layer "F.Cu")
		(net "GND")
	)
	(segment
		(start 58.6232 -30.993588)
		(end 59.027822 -29.9466)
		(width 0.254)
		(layer "F.Cu")
		(net "GND")
	)
	(segment
		(start 17.059402 -89.18702)
		(end 16.664178 -88.791796)
		(width 0.381)
		(layer "F.Cu")
		(net "GND")
	)
	(segment
		(start 78.526894 -31.75)
		(end 78.26629 -31.75)
		(width 0.381)
		(layer "F.Cu")
		(net "GND")
	)
	(segment
		(start 85.6996 -40.617394)
		(end 86.3092 -40.617394)
		(width 0.3556)
		(layer "F.Cu")
		(net "GND")
	)
	(segment
		(start 60.03544 -26.13152)
		(end 59.34583 -26.13152)
		(width 0.254)
		(layer "F.Cu")
		(net "GND")
	)
	(segment
		(start 53.865018 -118.25986)
		(end 53.865018 -117.229382)
		(width 0.254)
		(layer "F.Cu")
		(net "GND")
	)
	(segment
		(start 52.094892 -48.180752)
		(end 51.699668 -48.575976)
		(width 0.3556)
		(layer "F.Cu")
		(net "GND")
	)
	(segment
		(start 53.590952 -77.37729)
		(end 53.09362 -77.37729)
		(width 0.381)
		(layer "F.Cu")
		(net "GND")
	)
	(segment
		(start 29.99994 -80.910176)
		(end 29.99994 -79.76108)
		(width 0.254)
		(layer "F.Cu")
		(net "GND")
	)
	(segment
		(start 36.26612 -67.85229)
		(end 36.26612 -67.77482)
		(width 0.381)
		(layer "F.Cu")
		(net "GND")
	)
	(segment
		(start 11.547094 -48.218852)
		(end 11.547094 -48.64989)
		(width 0.381)
		(layer "F.Cu")
		(net "GND")
	)
	(segment
		(start 10.287 -93.23705)
		(end 10.0838 -93.23705)
		(width 0.381)
		(layer "F.Cu")
		(net "GND")
	)
	(segment
		(start 64.094868 -48.9712)
		(end 64.490092 -48.575976)
		(width 0.3556)
		(layer "F.Cu")
		(net "GND")
	)
	(segment
		(start 51.182016 -43.484038)
		(end 51.295046 -43.371262)
		(width 0.3556)
		(layer "F.Cu")
		(net "GND")
	)
	(segment
		(start 61.51753 -33.73247)
		(end 61.6712 -33.5788)
		(width 0.381)
		(layer "F.Cu")
		(net "GND")
	)
	(segment
		(start 13.163042 -105.688384)
		(end 13.765784 -105.688384)
		(width 0.381)
		(layer "F.Cu")
		(net "GND")
	)
	(segment
		(start 46.637702 -63.483744)
		(end 47.217838 -63.483744)
		(width 0.381)
		(layer "F.Cu")
		(net "GND")
	)
	(segment
		(start 63.64605 -81.788)
		(end 63.64605 -79.629)
		(width 0.381)
		(layer "F.Cu")
		(net "GND")
	)
	(segment
		(start 38.718236 -38.93566)
		(end 38.718236 -39.18331)
		(width 0.381)
		(layer "F.Cu")
		(net "GND")
	)
	(segment
		(start 72.644 -16.65605)
		(end 72.644 -17.26565)
		(width 0.381)
		(layer "F.Cu")
		(net "GND")
	)
	(segment
		(start 30.664404 -26.67)
		(end 31.337504 -26.67)
		(width 0.381)
		(layer "F.Cu")
		(net "GND")
	)
	(segment
		(start 30.91688 -67.39382)
		(end 30.366716 -67.39382)
		(width 0.381)
		(layer "F.Cu")
		(net "GND")
	)
	(segment
		(start 41.837356 -87.200486)
		(end 41.837356 -86.661244)
		(width 0.381)
		(layer "F.Cu")
		(net "GND")
	)
	(segment
		(start 12.017502 -53.803804)
		(end 12.119356 -53.905658)
		(width 0.381)
		(layer "F.Cu")
		(net "GND")
	)
	(segment
		(start 73.852278 -53.107336)
		(end 73.470516 -53.489098)
		(width 0.3556)
		(layer "F.Cu")
		(net "GND")
	)
	(segment
		(start 45.695108 -47.371254)
		(end 45.299884 -46.97603)
		(width 0.3556)
		(layer "F.Cu")
		(net "GND")
	)
	(segment
		(start 42.776394 -57.198006)
		(end 43.18 -56.7944)
		(width 0.381)
		(layer "F.Cu")
		(net "GND")
	)
	(segment
		(start 48.1584 -116.9162)
		(end 48.1584 -116.7892)
		(width 0.381)
		(layer "F.Cu")
		(net "GND")
	)
	(segment
		(start 56.894984 -52.171346)
		(end 56.885332 -52.171346)
		(width 0.3556)
		(layer "F.Cu")
		(net "GND")
	)
	(segment
		(start 61.695076 -53.771292)
		(end 61.836554 -53.629814)
		(width 0.3556)
		(layer "F.Cu")
		(net "GND")
	)
	(segment
		(start 15.24 -19.177)
		(end 15.24 -18.200878)
		(width 0.381)
		(layer "F.Cu")
		(net "GND")
	)
	(segment
		(start 79.452216 -48.307498)
		(end 79.833978 -48.68926)
		(width 0.3556)
		(layer "F.Cu")
		(net "GND")
	)
	(segment
		(start 61.836554 -53.629814)
		(end 61.836554 -53.124354)
		(width 0.3556)
		(layer "F.Cu")
		(net "GND")
	)
	(segment
		(start 48.895 -43.371262)
		(end 49.403 -43.879262)
		(width 0.3556)
		(layer "F.Cu")
		(net "GND")
	)
	(segment
		(start 58.49493 -49.7713)
		(end 57.695084 -49.7713)
		(width 0.3556)
		(layer "F.Cu")
		(net "GND")
	)
	(segment
		(start 58.123328 -26.67)
		(end 57.742328 -26.289)
		(width 0.254)
		(layer "F.Cu")
		(net "GND")
	)
	(segment
		(start 28.152598 -33.715198)
		(end 27.285696 -33.355788)
		(width 0.381)
		(layer "F.Cu")
		(net "GND")
	)
	(segment
		(start 26.659332 -88.387174)
		(end 26.259282 -88.787224)
		(width 0.381)
		(layer "F.Cu")
		(net "GND")
	)
	(segment
		(start 21.764498 -72.136)
		(end 21.760688 -72.13219)
		(width 0.254)
		(layer "F.Cu")
		(net "GND")
	)
	(segment
		(start 47.295054 -58.57113)
		(end 46.89983 -58.966354)
		(width 0.3556)
		(layer "F.Cu")
		(net "GND")
	)
	(segment
		(start 52.904644 -52.971192)
		(end 53.299868 -53.366416)
		(width 0.3556)
		(layer "F.Cu")
		(net "GND")
	)
	(segment
		(start 52.895246 -50.571146)
		(end 53.299868 -50.166524)
		(width 0.3556)
		(layer "F.Cu")
		(net "GND")
	)
	(segment
		(start 6.38175 -80.4926)
		(end 6.38175 -80.953356)
		(width 0.381)
		(layer "F.Cu")
		(net "GND")
	)
	(segment
		(start 22.538436 -66.493136)
		(end 21.994114 -66.493136)
		(width 0.381)
		(layer "F.Cu")
		(net "GND")
	)
	(segment
		(start 86.19998 -2.690114)
		(end 77.8002 -2.690114)
		(width 0.381)
		(layer "F.Cu")
		(net "GND")
	)
	(segment
		(start 32.999934 -79.4004)
		(end 32.986472 -79.386938)
		(width 0.254)
		(layer "F.Cu")
		(net "GND")
	)
	(segment
		(start 5.334 -80.49895)
		(end 6.3754 -80.49895)
		(width 0.381)
		(layer "F.Cu")
		(net "GND")
	)
	(segment
		(start 73.09866 -92.305632)
		(end 73.08215 -92.322142)
		(width 0.381)
		(layer "F.Cu")
		(net "GND")
	)
	(segment
		(start 60.364624 -43.901614)
		(end 59.825382 -43.901614)
		(width 0.381)
		(layer "F.Cu")
		(net "GND")
	)
	(segment
		(start 32.4866 -11.419586)
		(end 32.4866 -11.43)
		(width 0.381)
		(layer "F.Cu")
		(net "GND")
	)
	(segment
		(start 26.95448 -27.979624)
		(end 26.95448 -30.58668)
		(width 0.254)
		(layer "F.Cu")
		(net "GND")
	)
	(segment
		(start 22.254718 -92.791788)
		(end 21.859494 -93.187012)
		(width 0.381)
		(layer "F.Cu")
		(net "GND")
	)
	(segment
		(start 60.30722 -27.710892)
		(end 60.30722 -27.34564)
		(width 0.254)
		(layer "F.Cu")
		(net "GND")
	)
	(segment
		(start 84.792312 -72.733408)
		(end 85.423248 -72.733408)
		(width 0.381)
		(layer "F.Cu")
		(net "GND")
	)
	(segment
		(start 50.494946 -48.180752)
		(end 50.099722 -48.575976)
		(width 0.3556)
		(layer "F.Cu")
		(net "GND")
	)
	(segment
		(start 11.192002 -46.860714)
		(end 10.59942 -47.453296)
		(width 0.254)
		(layer "F.Cu")
		(net "GND")
	)
	(segment
		(start 11.12012 -49.358296)
		(end 10.767568 -49.710848)
		(width 0.381)
		(layer "F.Cu")
		(net "GND")
	)
	(segment
		(start 29.9466 -79.70774)
		(end 29.974286 -79.70774)
		(width 0.254)
		(layer "F.Cu")
		(net "GND")
	)
	(segment
		(start 77.281786 -32.057848)
		(end 77.286358 -32.06242)
		(width 0.381)
		(layer "F.Cu")
		(net "GND")
	)
	(segment
		(start 56.490108 -54.166516)
		(end 56.094884 -53.771292)
		(width 0.3556)
		(layer "F.Cu")
		(net "GND")
	)
	(segment
		(start 40.854884 -116.871496)
		(end 40.856408 -116.869972)
		(width 0.381)
		(layer "F.Cu")
		(net "GND")
	)
	(segment
		(start 74.84999 -35.761168)
		(end 75.48372 -35.127438)
		(width 0.381)
		(layer "F.Cu")
		(net "GND")
	)
	(segment
		(start 21.75002 -72.142858)
		(end 21.75002 -73.360534)
		(width 0.254)
		(layer "F.Cu")
		(net "GND")
	)
	(segment
		(start 12.540996 -17.76095)
		(end 11.952986 -18.34896)
		(width 0.381)
		(layer "F.Cu")
		(net "GND")
	)
	(segment
		(start 52.894992 -43.371262)
		(end 52.499768 -42.976038)
		(width 0.3556)
		(layer "F.Cu")
		(net "GND")
	)
	(segment
		(start 60.1726 -28.48102)
		(end 60.1726 -27.845512)
		(width 0.254)
		(layer "F.Cu")
		(net "GND")
	)
	(segment
		(start 56.9468 -26.289)
		(end 56.8198 -26.416)
		(width 0.254)
		(layer "F.Cu")
		(net "GND")
	)
	(segment
		(start 22.56155 -66.51625)
		(end 22.538436 -66.493136)
		(width 0.381)
		(layer "F.Cu")
		(net "GND")
	)
	(segment
		(start 64.894968 -59.37123)
		(end 65.290192 -59.766454)
		(width 0.3556)
		(layer "F.Cu")
		(net "GND")
	)
	(segment
		(start 83.194144 -72.43064)
		(end 83.824064 -72.43064)
		(width 0.254)
		(layer "F.Cu")
		(net "GND")
	)
	(segment
		(start 23.749 -66.56705)
		(end 23.725886 -66.543936)
		(width 0.381)
		(layer "F.Cu")
		(net "GND")
	)
	(segment
		(start 16.1036 -29.5783)
		(end 15.89278 -29.5783)
		(width 0.381)
		(layer "F.Cu")
		(net "GND")
	)
	(segment
		(start 59.29503 -46.571154)
		(end 59.29503 -46.580806)
		(width 0.3556)
		(layer "F.Cu")
		(net "GND")
	)
	(segment
		(start 32.849312 -31.115)
		(end 32.100012 -31.115)
		(width 0.381)
		(layer "F.Cu")
		(net "GND")
	)
	(segment
		(start 85.6996 -44.427394)
		(end 85.8012 -44.427394)
		(width 0.3556)
		(layer "F.Cu")
		(net "GND")
	)
	(segment
		(start 63.295022 -55.371238)
		(end 63.690246 -55.766462)
		(width 0.3556)
		(layer "F.Cu")
		(net "GND")
	)
	(segment
		(start 37.15004 -18.320004)
		(end 37.973 -19.142964)
		(width 0.381)
		(layer "F.Cu")
		(net "GND")
	)
	(segment
		(start 9.7028 -92.85605)
		(end 9.7028 -92.67317)
		(width 0.381)
		(layer "F.Cu")
		(net "GND")
	)
	(segment
		(start 29.1592 -66.522346)
		(end 29.1592 -66.26225)
		(width 0.381)
		(layer "F.Cu")
		(net "GND")
	)
	(segment
		(start 40.781986 -68.489068)
		(end 40.781986 -69.522594)
		(width 0.381)
		(layer "F.Cu")
		(net "GND")
	)
	(segment
		(start 40.75557 -54.920134)
		(end 40.648128 -55.027576)
		(width 0.381)
		(layer "F.Cu")
		(net "GND")
	)
	(segment
		(start 56.894984 -52.971192)
		(end 56.89473 -52.971192)
		(width 0.3556)
		(layer "F.Cu")
		(net "GND")
	)
	(segment
		(start 57.825386 -52.301648)
		(end 58.364628 -52.301648)
		(width 0.381)
		(layer "F.Cu")
		(net "GND")
	)
	(segment
		(start 53.84165 -23.89505)
		(end 53.7972 -23.8506)
		(width 0.381)
		(layer "F.Cu")
		(net "GND")
	)
	(segment
		(start 78.161642 -96.856042)
		(end 77.092048 -96.856042)
		(width 0.3556)
		(layer "F.Cu")
		(net "GND")
	)
	(segment
		(start 50.494946 -45.771308)
		(end 50.099722 -45.376084)
		(width 0.3556)
		(layer "F.Cu")
		(net "GND")
	)
	(segment
		(start 48.0949 -46.571154)
		(end 47.699676 -46.17593)
		(width 0.3556)
		(layer "F.Cu")
		(net "GND")
	)
	(segment
		(start 36.195 -87.8332)
		(end 36.195 -88.170512)
		(width 0.381)
		(layer "F.Cu")
		(net "GND")
	)
	(segment
		(start 61.674248 -30.305502)
		(end 61.674248 -29.845254)
		(width 0.381)
		(layer "F.Cu")
		(net "GND")
	)
	(segment
		(start 78.907894 -31.369)
		(end 78.526894 -31.75)
		(width 0.381)
		(layer "F.Cu")
		(net "GND")
	)
	(segment
		(start 24.74976 -72.03186)
		(end 25.00376 -72.28586)
		(width 0.254)
		(layer "F.Cu")
		(net "GND")
	)
	(segment
		(start 26.259282 -88.787224)
		(end 25.859486 -89.18702)
		(width 0.381)
		(layer "F.Cu")
		(net "GND")
	)
	(segment
		(start 18.127726 -41.625266)
		(end 18.127726 -42.09542)
		(width 0.381)
		(layer "F.Cu")
		(net "GND")
	)
	(segment
		(start 34.625026 -30.619954)
		(end 35.780726 -30.619954)
		(width 0.381)
		(layer "F.Cu")
		(net "GND")
	)
	(segment
		(start 17.153128 -106.21645)
		(end 17.540478 -106.6038)
		(width 0.381)
		(layer "F.Cu")
		(net "GND")
	)
	(segment
		(start 36.880546 -30.149546)
		(end 36.880546 -25.508712)
		(width 0.381)
		(layer "F.Cu")
		(net "GND")
	)
	(segment
		(start 75.646534 -31.014924)
		(end 75.053444 -31.014924)
		(width 0.381)
		(layer "F.Cu")
		(net "GND")
	)
	(segment
		(start 15.438628 -47.356522)
		(end 15.3416 -47.45355)
		(width 0.381)
		(layer "F.Cu")
		(net "GND")
	)
	(segment
		(start 32.75838 -107.557062)
		(end 32.75838 -105.794302)
		(width 0.381)
		(layer "F.Cu")
		(net "GND")
	)
	(segment
		(start 54.494938 -52.971192)
		(end 54.099714 -53.366416)
		(width 0.3556)
		(layer "F.Cu")
		(net "GND")
	)
	(segment
		(start 80.755744 -37.959538)
		(end 81.169256 -38.37305)
		(width 0.381)
		(layer "F.Cu")
		(net "GND")
	)
	(segment
		(start 60.50661 -42.982896)
		(end 60.894976 -43.371262)
		(width 0.3556)
		(layer "F.Cu")
		(net "GND")
	)
	(segment
		(start 65.913 -25.6794)
		(end 66.18605 -25.6794)
		(width 0.381)
		(layer "F.Cu")
		(net "GND")
	)
	(segment
		(start 67.900804 -31.13659)
		(end 67.900804 -32.39135)
		(width 0.381)
		(layer "F.Cu")
		(net "GND")
	)
	(segment
		(start 72.060054 -116.688616)
		(end 72.061578 -116.687092)
		(width 0.381)
		(layer "F.Cu")
		(net "GND")
	)
	(segment
		(start 50.494946 -50.571146)
		(end 51.295046 -50.571146)
		(width 0.3556)
		(layer "F.Cu")
		(net "GND")
	)
	(segment
		(start 59.027822 -29.9466)
		(end 59.027822 -29.625798)
		(width 0.254)
		(layer "F.Cu")
		(net "GND")
	)
	(segment
		(start 60.26912 -27.30754)
		(end 60.419488 -27.23007)
		(width 0.254)
		(layer "F.Cu")
		(net "GND")
	)
	(segment
		(start 58.495184 -49.7713)
		(end 58.49493 -49.7713)
		(width 0.3556)
		(layer "F.Cu")
		(net "GND")
	)
	(segment
		(start 70.259956 -118.460012)
		(end 70.259956 -117.088158)
		(width 0.381)
		(layer "F.Cu")
		(net "GND")
	)
	(segment
		(start 60.4774 -27.047444)
		(end 60.4774 -26.57348)
		(width 0.254)
		(layer "F.Cu")
		(net "GND")
	)
	(segment
		(start 60.894976 -55.371238)
		(end 60.885324 -55.371238)
		(width 0.3556)
		(layer "F.Cu")
		(net "GND")
	)
	(segment
		(start 54.494938 -45.771308)
		(end 54.494938 -45.780706)
		(width 0.3556)
		(layer "F.Cu")
		(net "GND")
	)
	(segment
		(start 78.65237 -50.707544)
		(end 79.034132 -51.089306)
		(width 0.3556)
		(layer "F.Cu")
		(net "GND")
	)
	(segment
		(start 79.750158 -6.99008)
		(end 79.750158 -8.4836)
		(width 0.381)
		(layer "F.Cu")
		(net "GND")
	)
	(segment
		(start 32.986472 -79.386938)
		(end 32.627062 -79.386938)
		(width 0.254)
		(layer "F.Cu")
		(net "GND")
	)
	(segment
		(start 56.885332 -52.171346)
		(end 56.490108 -52.56657)
		(width 0.3556)
		(layer "F.Cu")
		(net "GND")
	)
	(segment
		(start 57.704482 -53.771292)
		(end 58.099706 -54.166516)
		(width 0.381)
		(layer "F.Cu")
		(net "GND")
	)
	(segment
		(start 59.29503 -52.171346)
		(end 59.690254 -52.56657)
		(width 0.3556)
		(layer "F.Cu")
		(net "GND")
	)
	(segment
		(start 64.094868 -52.171346)
		(end 64.490092 -52.56657)
		(width 0.3556)
		(layer "F.Cu")
		(net "GND")
	)
	(segment
		(start 30.918404 -31.115)
		(end 30.664404 -31.369)
		(width 0.381)
		(layer "F.Cu")
		(net "GND")
	)
	(segment
		(start 59.29503 -46.580806)
		(end 59.690254 -46.97603)
		(width 0.3556)
		(layer "F.Cu")
		(net "GND")
	)
	(segment
		(start 20.66417 -92.791788)
		(end 21.059394 -93.187012)
		(width 0.381)
		(layer "F.Cu")
		(net "GND")
	)
	(segment
		(start 18.999962 -81.761838)
		(end 18.999962 -80.910176)
		(width 0.254)
		(layer "F.Cu")
		(net "GND")
	)
	(segment
		(start 78.994 -82.14995)
		(end 78.994 -81.407)
		(width 0.381)
		(layer "F.Cu")
		(net "GND")
	)
	(segment
		(start 85.56625 -75.1586)
		(end 86.2838 -75.1586)
		(width 0.381)
		(layer "F.Cu")
		(net "GND")
	)
	(segment
		(start 79.202026 -90.63609)
		(end 82.545682 -90.63609)
		(width 0.381)
		(layer "F.Cu")
		(net "GND")
	)
	(segment
		(start 53.7972 -23.8506)
		(end 53.7972 -23.84298)
		(width 0.381)
		(layer "F.Cu")
		(net "GND")
	)
	(segment
		(start 81.788 -37.61105)
		(end 81.788 -37.925756)
		(width 0.381)
		(layer "F.Cu")
		(net "GND")
	)
	(segment
		(start 18.659348 -90.786966)
		(end 18.264124 -90.391742)
		(width 0.381)
		(layer "F.Cu")
		(net "GND")
	)
	(segment
		(start 53.695092 -46.571154)
		(end 53.299868 -46.17593)
		(width 0.3556)
		(layer "F.Cu")
		(net "GND")
	)
	(segment
		(start 35.8394 -68.27901)
		(end 36.26612 -67.85229)
		(width 0.381)
		(layer "F.Cu")
		(net "GND")
	)
	(segment
		(start 58.131456 -27.237944)
		(end 58.123328 -27.237944)
		(width 0.254)
		(layer "F.Cu")
		(net "GND")
	)
	(segment
		(start 77.580744 -35.127438)
		(end 77.326744 -34.873438)
		(width 0.3556)
		(layer "F.Cu")
		(net "GND")
	)
	(segment
		(start 14.03096 -58.1406)
		(end 14.03096 -57.423304)
		(width 0.381)
		(layer "F.Cu")
		(net "GND")
	)
	(segment
		(start 27.285696 -33.355788)
		(end 26.9113 -32.981392)
		(width 0.381)
		(layer "F.Cu")
		(net "GND")
	)
	(segment
		(start 41.837356 -86.661244)
		(end 41.8592 -86.6394)
		(width 0.381)
		(layer "F.Cu")
		(net "GND")
	)
	(segment
		(start 28.77566 -79.70774)
		(end 28.50007 -79.98333)
		(width 0.254)
		(layer "F.Cu")
		(net "GND")
	)
	(segment
		(start 27.27452 -79.81188)
		(end 26.999946 -80.086454)
		(width 0.254)
		(layer "F.Cu")
		(net "GND")
	)
	(segment
		(start 35.999928 -79.967328)
		(end 35.999928 -80.910176)
		(width 0.254)
		(layer "F.Cu")
		(net "GND")
	)
	(segment
		(start 49.25187 -66.31686)
		(end 49.27473 -66.294)
		(width 0.381)
		(layer "F.Cu")
		(net "GND")
	)
	(segment
		(start 56.885332 -53.771292)
		(end 56.490108 -54.166516)
		(width 0.3556)
		(layer "F.Cu")
		(net "GND")
	)
	(segment
		(start 17.9451 -118.460012)
		(end 17.9451 -116.8654)
		(width 0.381)
		(layer "F.Cu")
		(net "GND")
	)
	(segment
		(start 23.854664 -91.191842)
		(end 23.45944 -91.587066)
		(width 0.381)
		(layer "F.Cu")
		(net "GND")
	)
	(segment
		(start 17.104868 -47.31258)
		(end 17.141444 -47.349156)
		(width 0.381)
		(layer "F.Cu")
		(net "GND")
	)
	(segment
		(start 28.829 -79.0448)
		(end 28.06192 -79.81188)
		(width 0.254)
		(layer "F.Cu")
		(net "GND")
	)
	(segment
		(start 57.695084 -55.371238)
		(end 58.090308 -55.766462)
		(width 0.3556)
		(layer "F.Cu")
		(net "GND")
	)
	(segment
		(start 52.094892 -51.361594)
		(end 51.699668 -50.96637)
		(width 0.3556)
		(layer "F.Cu")
		(net "GND")
	)
	(segment
		(start 61.51753 -34.237676)
		(end 61.51753 -33.73247)
		(width 0.381)
		(layer "F.Cu")
		(net "GND")
	)
	(segment
		(start 7.7978 -82.55)
		(end 7.17804 -82.55)
		(width 0.381)
		(layer "F.Cu")
		(net "GND")
	)
	(segment
		(start 74.01052 -32.057848)
		(end 74.069448 -32.057848)
		(width 0.381)
		(layer "F.Cu")
		(net "GND")
	)
	(segment
		(start 61.695076 -40.180768)
		(end 62.0903 -40.575992)
		(width 0.3556)
		(layer "F.Cu")
		(net "GND")
	)
	(segment
		(start 40.8178 -28.6512)
		(end 41.45915 -28.6512)
		(width 0.381)
		(layer "F.Cu")
		(net "GND")
	)
	(segment
		(start 60.894976 -43.371262)
		(end 60.364624 -43.901614)
		(width 0.381)
		(layer "F.Cu")
		(net "GND")
	)
	(segment
		(start 71.599806 -74.266552)
		(end 71.599806 -73.059544)
		(width 0.381)
		(layer "F.Cu")
		(net "GND")
	)
	(segment
		(start 27.41295 -25.38857)
		(end 27.41295 -25.908)
		(width 0.381)
		(layer "F.Cu")
		(net "GND")
	)
	(segment
		(start 41.500298 -68.149978)
		(end 41.121076 -68.149978)
		(width 0.381)
		(layer "F.Cu")
		(net "GND")
	)
	(segment
		(start 55.295038 -45.771308)
		(end 55.690262 -45.376084)
		(width 0.3556)
		(layer "F.Cu")
		(net "GND")
	)
	(segment
		(start 41.889934 -54.920134)
		(end 40.75557 -54.920134)
		(width 0.381)
		(layer "F.Cu")
		(net "GND")
	)
	(segment
		(start 34.3662 -79.686658)
		(end 34.407348 -79.686658)
		(width 0.254)
		(layer "F.Cu")
		(net "GND")
	)
	(segment
		(start 48.464978 -118.25986)
		(end 48.464978 -117.222778)
		(width 0.381)
		(layer "F.Cu")
		(net "GND")
	)
	(segment
		(start 51.295046 -48.9712)
		(end 51.304444 -48.9712)
		(width 0.3556)
		(layer "F.Cu")
		(net "GND")
	)
	(segment
		(start 30.366716 -67.39382)
		(end 30.066996 -67.0941)
		(width 0.381)
		(layer "F.Cu")
		(net "GND")
	)
	(segment
		(start 20.612354 -107.35818)
		(end 21.026374 -106.94416)
		(width 0.381)
		(layer "F.Cu")
		(net "GND")
	)
	(segment
		(start 59.39917 -99.076002)
		(end 59.3852 -99.089972)
		(width 0.381)
		(layer "F.Cu")
		(net "GND")
	)
	(segment
		(start 84.652612 -37.703506)
		(end 83.617308 -37.703506)
		(width 0.381)
		(layer "F.Cu")
		(net "GND")
	)
	(segment
		(start 56.094884 -48.171354)
		(end 55.69966 -48.566578)
		(width 0.3556)
		(layer "F.Cu")
		(net "GND")
	)
	(segment
		(start 75.48372 -35.127438)
		(end 76.691744 -35.127438)
		(width 0.381)
		(layer "F.Cu")
		(net "GND")
	)
	(segment
		(start 52.094892 -48.9712)
		(end 51.699668 -48.575976)
		(width 0.3556)
		(layer "F.Cu")
		(net "GND")
	)
	(segment
		(start 71.013828 -62.376558)
		(end 71.760842 -62.376558)
		(width 0.381)
		(layer "F.Cu")
		(net "GND")
	)
	(segment
		(start 13.822172 -16.78305)
		(end 13.335 -16.78305)
		(width 0.381)
		(layer "F.Cu")
		(net "GND")
	)
	(segment
		(start 46.86935 -74.803)
		(end 46.761146 -74.694796)
		(width 0.381)
		(layer "F.Cu")
		(net "GND")
	)
	(segment
		(start 78.25105 -79.64805)
		(end 78.613 -80.01)
		(width 0.381)
		(layer "F.Cu")
		(net "GND")
	)
	(segment
		(start 29.60624 -21.704554)
		(end 29.60624 -22.517354)
		(width 0.381)
		(layer "F.Cu")
		(net "GND")
	)
	(segment
		(start 53.295296 -26.966164)
		(end 53.295296 -26.954988)
		(width 0.381)
		(layer "F.Cu")
		(net "GND")
	)
	(segment
		(start 31.46806 -60.394596)
		(end 32.099504 -61.02604)
		(width 0.381)
		(layer "F.Cu")
		(net "GND")
	)
	(segment
		(start 58.364628 -52.301648)
		(end 58.49493 -52.171346)
		(width 0.381)
		(layer "F.Cu")
		(net "GND")
	)
	(segment
		(start 58.606182 -53.882544)
		(end 59.183778 -53.882544)
		(width 0.3556)
		(layer "F.Cu")
		(net "GND")
	)
	(segment
		(start 34.625026 -30.619954)
		(end 33.896046 -30.619954)
		(width 0.381)
		(layer "F.Cu")
		(net "GND")
	)
	(segment
		(start 52.094892 -50.571146)
		(end 51.699668 -50.96637)
		(width 0.3556)
		(layer "F.Cu")
		(net "GND")
	)
	(segment
		(start 64.094868 -45.771308)
		(end 64.490092 -45.376084)
		(width 0.3556)
		(layer "F.Cu")
		(net "GND")
	)
	(segment
		(start 42.675302 -102.710234)
		(end 42.675302 -103.060246)
		(width 0.381)
		(layer "F.Cu")
		(net "GND")
	)
	(segment
		(start 70.370446 -33.433766)
		(end 69.723 -33.433766)
		(width 0.381)
		(layer "F.Cu")
		(net "GND")
	)
	(segment
		(start 20.155662 -61.086746)
		(end 20.409916 -61.341)
		(width 0.254)
		(layer "F.Cu")
		(net "GND")
	)
	(segment
		(start 21.994114 -66.493136)
		(end 21.971 -66.51625)
		(width 0.381)
		(layer "F.Cu")
		(net "GND")
	)
	(segment
		(start 15.098014 -46.447964)
		(end 15.098014 -37.741606)
		(width 0.254)
		(layer "F.Cu")
		(net "GND")
	)
	(segment
		(start 77.95387 -32.06242)
		(end 78.105 -31.91129)
		(width 0.381)
		(layer "F.Cu")
		(net "GND")
	)
	(segment
		(start 48.0949 -55.371238)
		(end 48.0949 -54.571138)
		(width 0.3556)
		(layer "F.Cu")
		(net "GND")
	)
	(segment
		(start 58.49493 -48.171354)
		(end 58.49493 -48.180752)
		(width 0.3556)
		(layer "F.Cu")
		(net "GND")
	)
	(segment
		(start 35.8394 -69.70395)
		(end 35.8394 -68.27901)
		(width 0.381)
		(layer "F.Cu")
		(net "GND")
	)
	(segment
		(start 64.01435 -28.0162)
		(end 64.01435 -27.416506)
		(width 0.254)
		(layer "F.Cu")
		(net "GND")
	)
	(segment
		(start 61.695076 -39.380922)
		(end 62.0903 -39.776146)
		(width 0.3556)
		(layer "F.Cu")
		(net "GND")
	)
	(segment
		(start 69.148198 -62.376558)
		(end 69.097398 -62.325758)
		(width 0.381)
		(layer "F.Cu")
		(net "GND")
	)
	(segment
		(start 53.295296 -26.954988)
		(end 52.826412 -26.954988)
		(width 0.254)
		(layer "F.Cu")
		(net "GND")
	)
	(segment
		(start 56.894984 -47.371254)
		(end 57.290208 -46.97603)
		(width 0.3556)
		(layer "F.Cu")
		(net "GND")
	)
	(segment
		(start 17.500092 -78.969108)
		(end 17.653 -78.8162)
		(width 0.2794)
		(layer "F.Cu")
		(net "GND")
	)
	(segment
		(start 34.625026 -24.619966)
		(end 35.9918 -24.619966)
		(width 0.381)
		(layer "F.Cu")
		(net "GND")
	)
	(segment
		(start 77.324712 -69.534024)
		(end 76.882498 -69.976238)
		(width 0.3556)
		(layer "F.Cu")
		(net "GND")
	)
	(segment
		(start 38.6334 -108.1278)
		(end 38.20795 -108.55325)
		(width 0.381)
		(layer "F.Cu")
		(net "GND")
	)
	(segment
		(start 73.852278 -53.907436)
		(end 73.470516 -54.289198)
		(width 0.3556)
		(layer "F.Cu")
		(net "GND")
	)
	(segment
		(start 77.547724 -69.407024)
		(end 77.420724 -69.534024)
		(width 0.3556)
		(layer "F.Cu")
		(net "GND")
	)
	(segment
		(start 58.49493 -58.57113)
		(end 58.890154 -58.966354)
		(width 0.3556)
		(layer "F.Cu")
		(net "GND")
	)
	(segment
		(start 32.91205 -13.7922)
		(end 32.91205 -14.57325)
		(width 0.381)
		(layer "F.Cu")
		(net "GND")
	)
	(segment
		(start 10.80135 -61.468)
		(end 10.3378 -61.468)
		(width 0.381)
		(layer "F.Cu")
		(net "GND")
	)
	(segment
		(start 15.13205 -47.244)
		(end 15.13205 -46.482)
		(width 0.381)
		(layer "F.Cu")
		(net "GND")
	)
	(segment
		(start 58.49493 -46.571154)
		(end 59.29503 -46.571154)
		(width 0.3556)
		(layer "F.Cu")
		(net "GND")
	)
	(segment
		(start 50.786792 -43.879262)
		(end 51.182016 -43.484038)
		(width 0.3556)
		(layer "F.Cu")
		(net "GND")
	)
	(segment
		(start 32.15005 -33.274)
		(end 33.4518 -33.274)
		(width 0.381)
		(layer "F.Cu")
		(net "GND")
	)
	(segment
		(start 37.5666 -88.52535)
		(end 36.574222 -88.52535)
		(width 0.381)
		(layer "F.Cu")
		(net "GND")
	)
	(segment
		(start 52.894992 -47.371254)
		(end 52.904644 -47.371254)
		(width 0.3556)
		(layer "F.Cu")
		(net "GND")
	)
	(segment
		(start 38.337236 -39.56431)
		(end 37.6936 -39.56431)
		(width 0.381)
		(layer "F.Cu")
		(net "GND")
	)
	(segment
		(start 25.6794 -108.46435)
		(end 25.6794 -107.061)
		(width 0.381)
		(layer "F.Cu")
		(net "GND")
	)
	(segment
		(start 54.5846 -23.89505)
		(end 54.483 -23.89505)
		(width 0.381)
		(layer "F.Cu")
		(net "GND")
	)
	(segment
		(start 12.201652 -11.657838)
		(end 12.201652 -11.340338)
		(width 0.381)
		(layer "F.Cu")
		(net "GND")
	)
	(segment
		(start 67.40525 -107.62615)
		(end 68.072 -107.62615)
		(width 0.381)
		(layer "F.Cu")
		(net "GND")
	)
	(segment
		(start 33.5534 -27.559)
		(end 32.8422 -28.2702)
		(width 0.254)
		(layer "F.Cu")
		(net "GND")
	)
	(segment
		(start 26.999946 -80.086454)
		(end 26.999946 -80.910176)
		(width 0.254)
		(layer "F.Cu")
		(net "GND")
	)
	(segment
		(start 60.894976 -53.771292)
		(end 61.2902 -54.166516)
		(width 0.3556)
		(layer "F.Cu")
		(net "GND")
	)
	(segment
		(start 64.894968 -39.37127)
		(end 64.894968 -38.83787)
		(width 0.3556)
		(layer "F.Cu")
		(net "GND")
	)
	(segment
		(start 74.652378 -50.707544)
		(end 74.259694 -50.28438)
		(width 0.3556)
		(layer "F.Cu")
		(net "GND")
	)
	(segment
		(start 10.517632 -49.960784)
		(end 10.767568 -49.710848)
		(width 0.1778)
		(layer "F.Cu")
		(net "GND")
	)
	(segment
		(start 50.494946 -48.171354)
		(end 50.494946 -48.180752)
		(width 0.3556)
		(layer "F.Cu")
		(net "GND")
	)
	(segment
		(start 26.259282 -98.3869)
		(end 26.659332 -98.78695)
		(width 0.381)
		(layer "F.Cu")
		(net "GND")
	)
	(segment
		(start 56.094884 -43.371262)
		(end 56.490108 -42.976038)
		(width 0.3556)
		(layer "F.Cu")
		(net "GND")
	)
	(segment
		(start 23.24989 -73.360534)
		(end 23.24989 -72.50049)
		(width 0.254)
		(layer "F.Cu")
		(net "GND")
	)
	(segment
		(start 72.644 -13.193014)
		(end 71.73976 -13.193014)
		(width 0.381)
		(layer "F.Cu")
		(net "GND")
	)
	(segment
		(start 85.6996 -45.697394)
		(end 86.3092 -45.697394)
		(width 0.3556)
		(layer "F.Cu")
		(net "GND")
	)
	(segment
		(start 34.500058 -80.910176)
		(end 34.500058 -79.820516)
		(width 0.254)
		(layer "F.Cu")
		(net "GND")
	)
	(segment
		(start 53.299868 -50.166524)
		(end 53.695092 -49.7713)
		(width 0.3556)
		(layer "F.Cu")
		(net "GND")
	)
	(segment
		(start 15.13205 -46.482)
		(end 15.098014 -46.447964)
		(width 0.254)
		(layer "F.Cu")
		(net "GND")
	)
	(segment
		(start 28.702 -34.2646)
		(end 28.152598 -33.715198)
		(width 0.381)
		(layer "F.Cu")
		(net "GND")
	)
	(segment
		(start 27.7368 -31.369)
		(end 28.448 -31.369)
		(width 0.381)
		(layer "F.Cu")
		(net "GND")
	)
	(segment
		(start 49.704498 -55.371238)
		(end 50.099722 -55.766462)
		(width 0.3556)
		(layer "F.Cu")
		(net "GND")
	)
	(segment
		(start 57.695084 -44.971208)
		(end 57.695084 -43.371262)
		(width 0.3556)
		(layer "F.Cu")
		(net "GND")
	)
	(segment
		(start 31.115 -14.732)
		(end 31.115 -14.934946)
		(width 0.381)
		(layer "F.Cu")
		(net "GND")
	)
	(segment
		(start 12.07516 -52.408582)
		(end 12.43076 -52.052982)
		(width 0.3556)
		(layer "F.Cu")
		(net "GND")
	)
	(segment
		(start 84.0486 -80.60055)
		(end 84.0486 -79.9338)
		(width 0.381)
		(layer "F.Cu")
		(net "GND")
	)
	(segment
		(start 31.337504 -26.67)
		(end 32.100012 -26.67)
		(width 0.381)
		(layer "F.Cu")
		(net "GND")
	)
	(segment
		(start 52.894992 -48.171354)
		(end 52.894992 -48.180752)
		(width 0.3556)
		(layer "F.Cu")
		(net "GND")
	)
	(segment
		(start 49.6951 -58.57113)
		(end 49.299876 -58.966354)
		(width 0.3556)
		(layer "F.Cu")
		(net "GND")
	)
	(segment
		(start 32.7406 -64.998092)
		(end 32.741108 -64.998092)
		(width 0.381)
		(layer "F.Cu")
		(net "GND")
	)
	(segment
		(start 21.545042 -118.460012)
		(end 21.545042 -116.8654)
		(width 0.381)
		(layer "F.Cu")
		(net "GND")
	)
	(segment
		(start 15.363444 -33.05175)
		(end 15.344394 -33.0708)
		(width 0.3556)
		(layer "F.Cu")
		(net "GND")
	)
	(segment
		(start 20.30222 -107.35818)
		(end 20.612354 -107.35818)
		(width 0.381)
		(layer "F.Cu")
		(net "GND")
	)
	(segment
		(start 43.18 -56.7944)
		(end 43.18 -56.2102)
		(width 0.381)
		(layer "F.Cu")
		(net "GND")
	)
	(segment
		(start 32.15005 -33.432496)
		(end 31.317946 -34.2646)
		(width 0.381)
		(layer "F.Cu")
		(net "GND")
	)
	(segment
		(start 26.9113 -32.981392)
		(end 26.9113 -32.1945)
		(width 0.381)
		(layer "F.Cu")
		(net "GND")
	)
	(segment
		(start 12.80795 -9.833864)
		(end 12.862814 -9.779)
		(width 0.381)
		(layer "F.Cu")
		(net "GND")
	)
	(segment
		(start 44.986702 -63.280544)
		(end 44.2976 -63.280544)
		(width 0.3556)
		(layer "F.Cu")
		(net "GND")
	)
	(segment
		(start 53.865018 -117.229382)
		(end 54.61 -116.4844)
		(width 0.254)
		(layer "F.Cu")
		(net "GND")
	)
	(segment
		(start 23.153878 -66.51625)
		(end 22.56155 -66.51625)
		(width 0.381)
		(layer "F.Cu")
		(net "GND")
	)
	(segment
		(start 78.65237 -53.907436)
		(end 79.034132 -54.289198)
		(width 0.3556)
		(layer "F.Cu")
		(net "GND")
	)
	(segment
		(start 45.695108 -53.771292)
		(end 45.299884 -54.166516)
		(width 0.3556)
		(layer "F.Cu")
		(net "GND")
	)
	(segment
		(start 16.7132 -66.26225)
		(end 16.0782 -66.26225)
		(width 0.381)
		(layer "F.Cu")
		(net "GND")
	)
	(segment
		(start 10.0838 -93.23705)
		(end 9.7028 -92.85605)
		(width 0.381)
		(layer "F.Cu")
		(net "GND")
	)
	(segment
		(start 57.9628 -116.6114)
		(end 58.064908 -116.713508)
		(width 0.3556)
		(layer "F.Cu")
		(net "GND")
	)
	(segment
		(start 25.00376 -72.28586)
		(end 25.996138 -72.28586)
		(width 0.254)
		(layer "F.Cu")
		(net "GND")
	)
	(segment
		(start 37.973 -24.416258)
		(end 36.880546 -25.508712)
		(width 0.381)
		(layer "F.Cu")
		(net "GND")
	)
	(segment
		(start 51.304444 -48.9712)
		(end 51.699668 -48.575976)
		(width 0.3556)
		(layer "F.Cu")
		(net "GND")
	)
	(segment
		(start 62.494922 -57.771284)
		(end 62.099698 -58.166508)
		(width 0.3556)
		(layer "F.Cu")
		(net "GND")
	)
	(segment
		(start 11.547094 -48.64989)
		(end 12.20089 -48.64989)
		(width 0.3556)
		(layer "F.Cu")
		(net "GND")
	)
	(segment
		(start 52.894992 -45.771308)
		(end 52.499768 -45.376084)
		(width 0.3556)
		(layer "F.Cu")
		(net "GND")
	)
	(segment
		(start 54.7624 -80.4672)
		(end 54.599586 -80.304386)
		(width 0.3048)
		(layer "F.Cu")
		(net "GND")
	)
	(segment
		(start 46.89983 -52.56657)
		(end 47.295054 -52.171346)
		(width 0.3556)
		(layer "F.Cu")
		(net "GND")
	)
	(segment
		(start 40.005 -58.94705)
		(end 40.005 -59.232546)
		(width 0.381)
		(layer "F.Cu")
		(net "GND")
	)
	(segment
		(start 48.35906 -66.08318)
		(end 48.662082 -66.386202)
		(width 0.3048)
		(layer "F.Cu")
		(net "GND")
	)
	(segment
		(start 59.170316 -52.29606)
		(end 59.29503 -52.171346)
		(width 0.3556)
		(layer "F.Cu")
		(net "GND")
	)
	(segment
		(start 79.739744 -35.127438)
		(end 78.723744 -35.127438)
		(width 0.3556)
		(layer "F.Cu")
		(net "GND")
	)
	(segment
		(start 82.545682 -90.63609)
		(end 82.559652 -90.65006)
		(width 0.381)
		(layer "F.Cu")
		(net "GND")
	)
	(segment
		(start 51.699668 -50.166524)
		(end 52.094892 -49.7713)
		(width 0.3556)
		(layer "F.Cu")
		(net "GND")
	)
	(segment
		(start 40.622728 -55.002176)
		(end 40.648128 -55.027576)
		(width 0.381)
		(layer "F.Cu")
		(net "GND")
	)
	(segment
		(start 52.094892 -52.971192)
		(end 51.699668 -53.366416)
		(width 0.3556)
		(layer "F.Cu")
		(net "GND")
	)
	(segment
		(start 76.691744 -35.127438)
		(end 76.691744 -35.102038)
		(width 0.381)
		(layer "F.Cu")
		(net "GND")
	)
	(segment
		(start 55.295038 -58.57113)
		(end 55.690262 -58.966354)
		(width 0.3556)
		(layer "F.Cu")
		(net "GND")
	)
	(segment
		(start 59.410854 -53.887116)
		(end 60.779152 -53.887116)
		(width 0.381)
		(layer "F.Cu")
		(net "GND")
	)
	(segment
		(start 54.494938 -52.171346)
		(end 54.099714 -52.56657)
		(width 0.3556)
		(layer "F.Cu")
		(net "GND")
	)
	(segment
		(start 27.629104 -12.13104)
		(end 28.194 -11.566144)
		(width 0.381)
		(layer "F.Cu")
		(net "GND")
	)
	(segment
		(start 8.128 -82.8802)
		(end 7.7978 -82.55)
		(width 0.381)
		(layer "F.Cu")
		(net "GND")
	)
	(segment
		(start 11.857736 -53.803804)
		(end 12.017502 -53.803804)
		(width 0.381)
		(layer "F.Cu")
		(net "GND")
	)
	(segment
		(start 58.619644 -52.29606)
		(end 59.170316 -52.29606)
		(width 0.3556)
		(layer "F.Cu")
		(net "GND")
	)
	(segment
		(start 8.10768 -47.39894)
		(end 8.38327 -47.12335)
		(width 0.381)
		(layer "F.Cu")
		(net "GND")
	)
	(segment
		(start 11.157204 -15.810992)
		(end 10.85977 -15.810992)
		(width 0.381)
		(layer "F.Cu")
		(net "GND")
	)
	(segment
		(start 65.5066 -20.193)
		(end 64.9605 -19.6469)
		(width 0.381)
		(layer "F.Cu")
		(net "GND")
	)
	(segment
		(start 32.131 -65.22085)
		(end 32.517842 -65.22085)
		(width 0.381)
		(layer "F.Cu")
		(net "GND")
	)
	(segment
		(start 54.483 -23.89505)
		(end 53.84165 -23.89505)
		(width 0.381)
		(layer "F.Cu")
		(net "GND")
	)
	(segment
		(start 5.97789 -83.81746)
		(end 5.125466 -83.4644)
		(width 0.381)
		(layer "F.Cu")
		(net "GND")
	)
	(segment
		(start 61.695076 -52.982876)
		(end 61.695076 -52.971192)
		(width 0.3556)
		(layer "F.Cu")
		(net "GND")
	)
	(segment
		(start 67.183 -10.780014)
		(end 66.28638 -10.780014)
		(width 0.381)
		(layer "F.Cu")
		(net "GND")
	)
	(segment
		(start 62.42304 -11.825986)
		(end 63.083186 -11.825986)
		(width 0.381)
		(layer "F.Cu")
		(net "GND")
	)
	(segment
		(start 18.07845 -66.7766)
		(end 17.22755 -66.7766)
		(width 0.381)
		(layer "F.Cu")
		(net "GND")
	)
	(segment
		(start 56.894984 -51.371246)
		(end 56.894984 -50.571146)
		(width 0.3556)
		(layer "F.Cu")
		(net "GND")
	)
	(segment
		(start 54.494938 -55.371238)
		(end 54.099714 -55.766462)
		(width 0.3556)
		(layer "F.Cu")
		(net "GND")
	)
	(segment
		(start 13.208 -58.5216)
		(end 13.64996 -58.5216)
		(width 0.381)
		(layer "F.Cu")
		(net "GND")
	)
	(segment
		(start 37.15004 -32.919924)
		(end 37.15004 -30.41904)
		(width 0.381)
		(layer "F.Cu")
		(net "GND")
	)
	(segment
		(start 59.2582 -90.65006)
		(end 62.687962 -90.65006)
		(width 0.381)
		(layer "F.Cu")
		(net "GND")
	)
	(segment
		(start 77.10805 -14.478)
		(end 77.10805 -13.847064)
		(width 0.381)
		(layer "F.Cu")
		(net "GND")
	)
	(segment
		(start 72.67067 -46.32579)
		(end 73.052432 -46.707552)
		(width 0.3556)
		(layer "F.Cu")
		(net "GND")
	)
	(segment
		(start 52.92344 -97.76206)
		(end 52.72913 -97.56775)
		(width 0.381)
		(layer "F.Cu")
		(net "GND")
	)
	(segment
		(start 51.295046 -45.771308)
		(end 50.494946 -45.771308)
		(width 0.3556)
		(layer "F.Cu")
		(net "GND")
	)
	(segment
		(start 46.46295 -22.352)
		(end 46.46295 -21.4122)
		(width 0.381)
		(layer "F.Cu")
		(net "GND")
	)
	(segment
		(start 58.49493 -48.9712)
		(end 58.890154 -48.575976)
		(width 0.3556)
		(layer "F.Cu")
		(net "GND")
	)
	(segment
		(start 48.0949 -54.571138)
		(end 48.0949 -54.56174)
		(width 0.3556)
		(layer "F.Cu")
		(net "GND")
	)
	(segment
		(start 42.675048 -102.70998)
		(end 42.675302 -102.710234)
		(width 0.381)
		(layer "F.Cu")
		(net "GND")
	)
	(segment
		(start 17.653 -78.8162)
		(end 17.653 -78.4098)
		(width 0.2794)
		(layer "F.Cu")
		(net "GND")
	)
	(segment
		(start 64.01435 -27.416506)
		(end 64.0842 -27.346656)
		(width 0.254)
		(layer "F.Cu")
		(net "GND")
	)
	(segment
		(start 52.094892 -49.7713)
		(end 52.894992 -49.7713)
		(width 0.3556)
		(layer "F.Cu")
		(net "GND")
	)
	(segment
		(start 12.012676 -47.75327)
		(end 11.547094 -48.218852)
		(width 0.381)
		(layer "F.Cu")
		(net "GND")
	)
	(segment
		(start 39.505636 -46.391576)
		(end 39.505636 -45.411644)
		(width 0.381)
		(layer "F.Cu")
		(net "GND")
	)
	(segment
		(start 17.92732 -42.295826)
		(end 17.92732 -42.463466)
		(width 0.381)
		(layer "F.Cu")
		(net "GND")
	)
	(segment
		(start 14.605 -18.542)
		(end 13.82395 -17.76095)
		(width 0.381)
		(layer "F.Cu")
		(net "GND")
	)
	(segment
		(start 66.56705 -26.0604)
		(end 66.56705 -28.0162)
		(width 0.381)
		(layer "F.Cu")
		(net "GND")
	)
	(segment
		(start 58.123328 -27.237944)
		(end 58.123328 -26.67)
		(width 0.254)
		(layer "F.Cu")
		(net "GND")
	)
	(segment
		(start 57.42305 -75.3364)
		(end 57.42305 -76.3524)
		(width 0.381)
		(layer "F.Cu")
		(net "GND")
	)
	(segment
		(start 74.84999 -36.298378)
		(end 74.84999 -35.761168)
		(width 0.381)
		(layer "F.Cu")
		(net "GND")
	)
	(segment
		(start 26.902664 -27.927808)
		(end 26.95448 -27.979624)
		(width 0.254)
		(layer "F.Cu")
		(net "GND")
	)
	(segment
		(start 35.941 -36.46805)
		(end 35.941 -36.957)
		(width 0.381)
		(layer "F.Cu")
		(net "GND")
	)
	(segment
		(start 25.2984 -108.84535)
		(end 25.6794 -108.46435)
		(width 0.381)
		(layer "F.Cu")
		(net "GND")
	)
	(segment
		(start 24.750014 -73.360534)
		(end 24.724614 -73.335134)
		(width 0.254)
		(layer "F.Cu")
		(net "GND")
	)
	(segment
		(start 77.8002 -2.690114)
		(end 76.3524 -2.690114)
		(width 0.381)
		(layer "F.Cu")
		(net "GND")
	)
	(segment
		(start 50.494946 -55.371238)
		(end 50.099722 -55.766462)
		(width 0.3556)
		(layer "F.Cu")
		(net "GND")
	)
	(segment
		(start 58.49493 -44.971208)
		(end 58.49493 -44.171362)
		(width 0.3556)
		(layer "F.Cu")
		(net "GND")
	)
	(segment
		(start 83.824064 -72.43064)
		(end 84.126832 -72.733408)
		(width 0.254)
		(layer "F.Cu")
		(net "GND")
	)
	(segment
		(start 25.45461 -97.582228)
		(end 25.059386 -97.187004)
		(width 0.381)
		(layer "F.Cu")
		(net "GND")
	)
	(segment
		(start 53.695092 -49.7713)
		(end 53.695092 -48.9712)
		(width 0.3556)
		(layer "F.Cu")
		(net "GND")
	)
	(segment
		(start 19.064224 -91.191842)
		(end 19.459448 -91.587066)
		(width 0.381)
		(layer "F.Cu")
		(net "GND")
	)
	(segment
		(start 47.295054 -52.171346)
		(end 48.0949 -52.171346)
		(width 0.3556)
		(layer "F.Cu")
		(net "GND")
	)
	(segment
		(start 60.96 -83.3374)
		(end 61.3156 -83.3374)
		(width 0.381)
		(layer "F.Cu")
		(net "GND")
	)
	(segment
		(start 8.38327 -47.12335)
		(end 8.38327 -46.798738)
		(width 0.381)
		(layer "F.Cu")
		(net "GND")
	)
	(segment
		(start 30.066996 -67.0941)
		(end 29.730954 -67.0941)
		(width 0.381)
		(layer "F.Cu")
		(net "GND")
	)
	(segment
		(start 62.494922 -51.371246)
		(end 62.890146 -51.76647)
		(width 0.3556)
		(layer "F.Cu")
		(net "GND")
	)
	(segment
		(start 42.291 -25.0444)
		(end 42.02176 -25.31364)
		(width 0.3048)
		(layer "F.Cu")
		(net "GND")
	)
	(segment
		(start 33.5534 -26.9748)
		(end 33.5534 -27.559)
		(width 0.254)
		(layer "F.Cu")
		(net "GND")
	)
	(segment
		(start 81.169256 -38.37305)
		(end 81.340706 -38.37305)
		(width 0.381)
		(layer "F.Cu")
		(net "GND")
	)
	(segment
		(start 76.85405 -77.47)
		(end 77.216 -77.47)
		(width 0.381)
		(layer "F.Cu")
		(net "GND")
	)
	(segment
		(start 25.144984 -118.460012)
		(end 25.144984 -116.40185)
		(width 0.381)
		(layer "F.Cu")
		(net "GND")
	)
	(segment
		(start 40.622728 -53.992272)
		(end 40.622728 -55.002176)
		(width 0.381)
		(layer "F.Cu")
		(net "GND")
	)
	(segment
		(start 78.32471 -27.44597)
		(end 77.281786 -28.488894)
		(width 0.381)
		(layer "F.Cu")
		(net "GND")
	)
	(segment
		(start 57.695084 -48.171354)
		(end 57.695084 -48.180752)
		(width 0.3556)
		(layer "F.Cu")
		(net "GND")
	)
	(segment
		(start 73.052432 -48.307498)
		(end 72.512428 -48.307498)
		(width 0.3556)
		(layer "F.Cu")
		(net "GND")
	)
	(segment
		(start 77.286358 -32.06242)
		(end 77.95387 -32.06242)
		(width 0.381)
		(layer "F.Cu")
		(net "GND")
	)
	(segment
		(start 62.484 -83.947)
		(end 61.8744 -83.3374)
		(width 0.381)
		(layer "F.Cu")
		(net "GND")
	)
	(segment
		(start 34.12109 -79.4004)
		(end 32.999934 -79.4004)
		(width 0.254)
		(layer "F.Cu")
		(net "GND")
	)
	(segment
		(start 60.894976 -58.57113)
		(end 61.2902 -58.966354)
		(width 0.3556)
		(layer "F.Cu")
		(net "GND")
	)
	(segment
		(start 23.725886 -66.543936)
		(end 23.181564 -66.543936)
		(width 0.381)
		(layer "F.Cu")
		(net "GND")
	)
	(segment
		(start 56.894984 -45.771308)
		(end 57.290208 -45.376084)
		(width 0.3556)
		(layer "F.Cu")
		(net "GND")
	)
	(segment
		(start 57.695084 -43.371262)
		(end 58.090308 -42.976038)
		(width 0.3556)
		(layer "F.Cu")
		(net "GND")
	)
	(segment
		(start 12.43076 -52.052982)
		(end 12.43076 -52.037234)
		(width 0.3556)
		(layer "F.Cu")
		(net "GND")
	)
	(segment
		(start 28.50007 -79.98333)
		(end 28.50007 -80.910176)
		(width 0.254)
		(layer "F.Cu")
		(net "GND")
	)
	(segment
		(start 28.6512 -61.48324)
		(end 28.6512 -62.07252)
		(width 0.254)
		(layer "F.Cu")
		(net "GND")
	)
	(segment
		(start 54.494938 -46.571154)
		(end 54.099714 -46.17593)
		(width 0.3556)
		(layer "F.Cu")
		(net "GND")
	)
	(segment
		(start 24.724614 -72.03186)
		(end 24.74976 -72.03186)
		(width 0.254)
		(layer "F.Cu")
		(net "GND")
	)
	(segment
		(start 10.3378 -61.468)
		(end 10.050018 -61.755782)
		(width 0.381)
		(layer "F.Cu")
		(net "GND")
	)
	(segment
		(start 52.094892 -43.371262)
		(end 51.699668 -42.976038)
		(width 0.3556)
		(layer "F.Cu")
		(net "GND")
	)
	(segment
		(start 64.094868 -50.571146)
		(end 64.490092 -50.96637)
		(width 0.3556)
		(layer "F.Cu")
		(net "GND")
	)
	(segment
		(start 38.91915 -74.31405)
		(end 38.7096 -74.5236)
		(width 0.3556)
		(layer "F.Cu")
		(net "GND")
	)
	(segment
		(start 61.299852 -54.166516)
		(end 61.695076 -53.771292)
		(width 0.381)
		(layer "F.Cu")
		(net "GND")
	)
	(segment
		(start 73.6981 -92.204032)
		(end 73.5965 -92.305632)
		(width 0.381)
		(layer "F.Cu")
		(net "GND")
	)
	(segment
		(start 13.10005 -53.6448)
		(end 12.92225 -53.8226)
		(width 0.254)
		(layer "F.Cu")
		(net "GND")
	)
	(segment
		(start 59.690254 -55.766462)
		(end 59.699652 -55.766462)
		(width 0.381)
		(layer "F.Cu")
		(net "GND")
	)
	(segment
		(start 50.099722 -51.76647)
		(end 50.494946 -51.371246)
		(width 0.3556)
		(layer "F.Cu")
		(net "GND")
	)
	(segment
		(start 58.6232 -31.541212)
		(end 58.6232 -30.993588)
		(width 0.254)
		(layer "F.Cu")
		(net "GND")
	)
	(segment
		(start 8.830564 -48.779938)
		(end 9.296146 -48.314356)
		(width 0.1778)
		(layer "F.Cu")
		(net "GND")
	)
	(segment
		(start 61.2902 -54.166516)
		(end 61.299852 -54.166516)
		(width 0.381)
		(layer "F.Cu")
		(net "GND")
	)
	(segment
		(start 34.407348 -79.686658)
		(end 34.12109 -79.4004)
		(width 0.254)
		(layer "F.Cu")
		(net "GND")
	)
	(segment
		(start 57.695084 -48.9712)
		(end 58.090308 -48.575976)
		(width 0.3556)
		(layer "F.Cu")
		(net "GND")
	)
	(segment
		(start 38.718236 -39.18331)
		(end 38.337236 -39.56431)
		(width 0.381)
		(layer "F.Cu")
		(net "GND")
	)
	(segment
		(start 12.012676 -46.860714)
		(end 11.192002 -46.860714)
		(width 0.254)
		(layer "F.Cu")
		(net "GND")
	)
	(segment
		(start 86.0806 -47.221394)
		(end 86.3092 -47.221394)
		(width 0.381)
		(layer "F.Cu")
		(net "GND")
	)
	(segment
		(start 32.312864 -79.701136)
		(end 31.500064 -79.701136)
		(width 0.254)
		(layer "F.Cu")
		(net "GND")
	)
	(segment
		(start 29.99994 -79.76108)
		(end 29.9466 -79.70774)
		(width 0.254)
		(layer "F.Cu")
		(net "GND")
	)
	(segment
		(start 9.37895 -9.558528)
		(end 9.37895 -9.652)
		(width 0.381)
		(layer "F.Cu")
		(net "GND")
	)
	(segment
		(start 76.492354 -27.825954)
		(end 76.492354 -27.596846)
		(width 0.381)
		(layer "F.Cu")
		(net "GND")
	)
	(segment
		(start 48.593248 -20.835112)
		(end 48.593248 -21.466048)
		(width 0.381)
		(layer "F.Cu")
		(net "GND")
	)
	(segment
		(start 59.027822 -29.625798)
		(end 60.1726 -28.48102)
		(width 0.254)
		(layer "F.Cu")
		(net "GND")
	)
	(segment
		(start 40.854884 -118.25986)
		(end 40.854884 -116.871496)
		(width 0.381)
		(layer "F.Cu")
		(net "GND")
	)
	(segment
		(start 73.852278 -51.50739)
		(end 73.429114 -51.900074)
		(width 0.3556)
		(layer "F.Cu")
		(net "GND")
	)
	(segment
		(start 15.24 -18.200878)
		(end 13.822172 -16.78305)
		(width 0.381)
		(layer "F.Cu")
		(net "GND")
	)
	(segment
		(start 42.346626 -18.598896)
		(end 42.346626 -19.271996)
		(width 0.381)
		(layer "F.Cu")
		(net "GND")
	)
	(segment
		(start 53.70449 -55.371238)
		(end 54.099714 -55.766462)
		(width 0.381)
		(layer "F.Cu")
		(net "GND")
	)
	(segment
		(start 66.18605 -25.6794)
		(end 66.56705 -26.0604)
		(width 0.381)
		(layer "F.Cu")
		(net "GND")
	)
	(segment
		(start 62.494922 -46.571154)
		(end 62.890146 -46.17593)
		(width 0.3556)
		(layer "F.Cu")
		(net "GND")
	)
	(segment
		(start 57.5818 -76.3524)
		(end 58.1152 -76.8858)
		(width 0.381)
		(layer "F.Cu")
		(net "GND")
	)
	(segment
		(start 28.575 -10.68705)
		(end 28.194 -11.06805)
		(width 0.381)
		(layer "F.Cu")
		(net "GND")
	)
	(segment
		(start 71.760842 -62.376558)
		(end 72.644 -61.4934)
		(width 0.381)
		(layer "F.Cu")
		(net "GND")
	)
	(segment
		(start 58.064908 -116.713508)
		(end 58.064908 -118.25986)
		(width 0.3556)
		(layer "F.Cu")
		(net "GND")
	)
	(segment
		(start 58.49493 -53.771292)
		(end 58.606182 -53.882544)
		(width 0.3556)
		(layer "F.Cu")
		(net "GND")
	)
	(segment
		(start 61.8998 -26.62301)
		(end 62.226698 -26.296112)
		(width 0.381)
		(layer "F.Cu")
		(net "GND")
	)
	(segment
		(start 60.579 -84.30895)
		(end 60.579 -83.7184)
		(width 0.381)
		(layer "F.Cu")
		(net "GND")
	)
	(segment
		(start 9.2964 -104.07015)
		(end 9.2964 -103.7844)
		(width 0.381)
		(layer "F.Cu")
		(net "GND")
	)
	(segment
		(start 23.854664 -95.982282)
		(end 23.45944 -95.587058)
		(width 0.381)
		(layer "F.Cu")
		(net "GND")
	)
	(segment
		(start 5.750052 -6.99008)
		(end 6.51383 -6.99008)
		(width 0.381)
		(layer "F.Cu")
		(net "GND")
	)
	(segment
		(start 18.542 -82.1436)
		(end 18.6182 -82.1436)
		(width 0.254)
		(layer "F.Cu")
		(net "GND")
	)
	(segment
		(start 52.094892 -47.371254)
		(end 52.894992 -47.371254)
		(width 0.3556)
		(layer "F.Cu")
		(net "GND")
	)
	(segment
		(start 53.537612 -27.627326)
		(end 53.537612 -27.20848)
		(width 0.381)
		(layer "F.Cu")
		(net "GND")
	)
	(segment
		(start 76.981558 -74.876406)
		(end 76.981558 -75.569826)
		(width 0.381)
		(layer "F.Cu")
		(net "GND")
	)
	(segment
		(start 59.29503 -53.771292)
		(end 59.410854 -53.887116)
		(width 0.381)
		(layer "F.Cu")
		(net "GND")
	)
	(segment
		(start 59.29503 -55.371238)
		(end 59.690254 -55.766462)
		(width 0.3556)
		(layer "F.Cu")
		(net "GND")
	)
	(segment
		(start 62.701932 -99.076002)
		(end 59.39917 -99.076002)
		(width 0.381)
		(layer "F.Cu")
		(net "GND")
	)
	(segment
		(start 29.60624 -24.1046)
		(end 29.60624 -24.59736)
		(width 0.381)
		(layer "F.Cu")
		(net "GND")
	)
	(segment
		(start 60.490608 -54.571138)
		(end 60.094876 -54.96687)
		(width 0.381)
		(layer "F.Cu")
		(net "GND")
	)
	(segment
		(start 52.616862 -29.147262)
		(end 54.852316 -29.147262)
		(width 0.254)
		(layer "F.Cu")
		(net "GND")
	)
	(segment
		(start 35.719258 -79.686658)
		(end 35.999928 -79.967328)
		(width 0.254)
		(layer "F.Cu")
		(net "GND")
	)
	(segment
		(start 52.826412 -26.954988)
		(end 51.9938 -27.7876)
		(width 0.254)
		(layer "F.Cu")
		(net "GND")
	)
	(segment
		(start 20.66417 -94.382336)
		(end 21.059394 -93.987112)
		(width 0.381)
		(layer "F.Cu")
		(net "GND")
	)
	(segment
		(start 8.459724 -49.579784)
		(end 9.242044 -49.579784)
		(width 0.2032)
		(layer "F.Cu")
		(net "GND")
	)
	(segment
		(start 34.407348 -79.686658)
		(end 35.719258 -79.686658)
		(width 0.254)
		(layer "F.Cu")
		(net "GND")
	)
	(segment
		(start 53.695092 -51.371246)
		(end 53.695092 -51.361594)
		(width 0.3556)
		(layer "F.Cu")
		(net "GND")
	)
	(segment
		(start 77.326744 -34.873438)
		(end 77.326744 -34.517838)
		(width 0.3556)
		(layer "F.Cu")
		(net "GND")
	)
	(segment
		(start 80.293972 -72.930512)
		(end 79.60995 -72.930512)
		(width 0.254)
		(layer "F.Cu")
		(net "GND")
	)
	(segment
		(start 56.894984 -40.17137)
		(end 57.290208 -39.776146)
		(width 0.3556)
		(layer "F.Cu")
		(net "GND")
	)
	(segment
		(start 24.500078 -80.910176)
		(end 24.500078 -82.091276)
		(width 0.254)
		(layer "F.Cu")
		(net "GND")
	)
	(segment
		(start 21.026374 -106.94416)
		(end 21.102574 -106.94416)
		(width 0.381)
		(layer "F.Cu")
		(net "GND")
	)
	(segment
		(start 76.581 -83.976972)
		(end 76.581 -82.931)
		(width 0.381)
		(layer "F.Cu")
		(net "GND")
	)
	(segment
		(start 78.65237 -51.50739)
		(end 79.034132 -51.889152)
		(width 0.3556)
		(layer "F.Cu")
		(net "GND")
	)
	(segment
		(start 73.152 -74.69505)
		(end 72.028304 -74.69505)
		(width 0.381)
		(layer "F.Cu")
		(net "GND")
	)
	(segment
		(start 19.064224 -95.982282)
		(end 19.459448 -95.587058)
		(width 0.381)
		(layer "F.Cu")
		(net "GND")
	)
	(segment
		(start 22.999954 -80.910176)
		(end 22.999954 -81.963768)
		(width 0.254)
		(layer "F.Cu")
		(net "GND")
	)
	(segment
		(start 10.739374 -52.408582)
		(end 11.761978 -52.408582)
		(width 0.3556)
		(layer "F.Cu")
		(net "GND")
	)
	(segment
		(start 79.452216 -52.30749)
		(end 79.833978 -52.689252)
		(width 0.3556)
		(layer "F.Cu")
		(net "GND")
	)
	(segment
		(start 74.01052 -28.402534)
		(end 74.650854 -27.7622)
		(width 0.381)
		(layer "F.Cu")
		(net "GND")
	)
	(segment
		(start 14.29385 -106.21645)
		(end 16.8275 -106.21645)
		(width 0.381)
		(layer "F.Cu")
		(net "GND")
	)
	(segment
		(start 19.744944 -118.460012)
		(end 19.744944 -116.925344)
		(width 0.381)
		(layer "F.Cu")
		(net "GND")
	)
	(segment
		(start 39.505636 -45.411644)
		(end 39.532814 -45.384466)
		(width 0.381)
		(layer "F.Cu")
		(net "GND")
	)
	(segment
		(start 55.24373 -24.887936)
		(end 55.24373 -24.55418)
		(width 0.381)
		(layer "F.Cu")
		(net "GND")
	)
	(segment
		(start 25.11806 -82.091276)
		(end 24.500078 -82.091276)
		(width 0.254)
		(layer "F.Cu")
		(net "GND")
	)
	(segment
		(start 14.605 -19.177)
		(end 14.605 -18.542)
		(width 0.381)
		(layer "F.Cu")
		(net "GND")
	)
	(segment
		(start 76.417424 -26.430986)
		(end 75.646534 -27.201876)
		(width 0.381)
		(layer "F.Cu")
		(net "GND")
	)
	(segment
		(start 26.127964 -60.95619)
		(end 25.718262 -60.95619)
		(width 0.254)
		(layer "F.Cu")
		(net "GND")
	)
	(segment
		(start 27.41295 -27.305)
		(end 26.902664 -27.815286)
		(width 0.381)
		(layer "F.Cu")
		(net "GND")
	)
	(segment
		(start 47.567088 -20.835112)
		(end 47.567088 -21.455888)
		(width 0.381)
		(layer "F.Cu")
		(net "GND")
	)
	(segment
		(start 11.500104 -25.015952)
		(end 11.673078 -25.015952)
		(width 0.381)
		(layer "F.Cu")
		(net "GND")
	)
	(segment
		(start 73.052432 -44.307506)
		(end 72.67067 -43.925744)
		(width 0.3556)
		(layer "F.Cu")
		(net "GND")
	)
	(segment
		(start 26.9113 -32.1945)
		(end 27.7368 -31.369)
		(width 0.381)
		(layer "F.Cu")
		(net "GND")
	)
	(segment
		(start 59.182 -11.32205)
		(end 59.182 -11.9634)
		(width 0.381)
		(layer "F.Cu")
		(net "GND")
	)
	(segment
		(start 11.547094 -48.64989)
		(end 11.547094 -48.824134)
		(width 0.381)
		(layer "F.Cu")
		(net "GND")
	)
	(segment
		(start 43.095926 -101.452426)
		(end 42.675048 -101.873304)
		(width 0.381)
		(layer "F.Cu")
		(net "GND")
	)
	(segment
		(start 41.121076 -68.149978)
		(end 40.781986 -68.489068)
		(width 0.381)
		(layer "F.Cu")
		(net "GND")
	)
	(segment
		(start 25.6794 -107.061)
		(end 26.0604 -106.68)
		(width 0.381)
		(layer "F.Cu")
		(net "GND")
	)
	(segment
		(start 9.852914 -47.453296)
		(end 9.296146 -48.010064)
		(width 0.254)
		(layer "F.Cu")
		(net "GND")
	)
	(segment
		(start 61.8744 -83.3374)
		(end 61.3156 -83.3374)
		(width 0.381)
		(layer "F.Cu")
		(net "GND")
	)
	(segment
		(start 49.6951 -55.371238)
		(end 49.704498 -55.371238)
		(width 0.3556)
		(layer "F.Cu")
		(net "GND")
	)
	(segment
		(start 59.29503 -50.571146)
		(end 58.495184 -49.7713)
		(width 0.3556)
		(layer "F.Cu")
		(net "GND")
	)
	(segment
		(start 51.295046 -43.371262)
		(end 50.899822 -42.976038)
		(width 0.3556)
		(layer "F.Cu")
		(net "GND")
	)
	(segment
		(start 52.904644 -47.371254)
		(end 53.299868 -46.97603)
		(width 0.3556)
		(layer "F.Cu")
		(net "GND")
	)
	(segment
		(start 29.60624 -24.59736)
		(end 29.2608 -24.9428)
		(width 0.381)
		(layer "F.Cu")
		(net "GND")
	)
	(segment
		(start 23.344886 -118.460012)
		(end 23.344886 -116.40185)
		(width 0.381)
		(layer "F.Cu")
		(net "GND")
	)
	(segment
		(start 82.296 -18.556986)
		(end 81.9404 -18.912586)
		(width 0.3556)
		(layer "F.Cu")
		(net "GND")
	)
	(segment
		(start 52.316126 -23.450804)
		(end 53.213 -23.450804)
		(width 0.381)
		(layer "F.Cu")
		(net "GND")
	)
	(segment
		(start 70.42785 -29.44495)
		(end 70.8914 -28.9814)
		(width 0.381)
		(layer "F.Cu")
		(net "GND")
	)
	(segment
		(start 31.337504 -31.115)
		(end 30.918404 -31.115)
		(width 0.381)
		(layer "F.Cu")
		(net "GND")
	)
	(segment
		(start 64.894968 -55.371238)
		(end 65.290192 -55.766462)
		(width 0.3556)
		(layer "F.Cu")
		(net "GND")
	)
	(segment
		(start 60.894976 -54.56174)
		(end 61.2902 -54.166516)
		(width 0.3556)
		(layer "F.Cu")
		(net "GND")
	)
	(segment
		(start 57.695084 -48.180752)
		(end 58.090308 -48.575976)
		(width 0.3556)
		(layer "F.Cu")
		(net "GND")
	)
	(segment
		(start 85.6996 -48.237394)
		(end 86.3092 -48.237394)
		(width 0.3556)
		(layer "F.Cu")
		(net "GND")
	)
	(segment
		(start 44.895008 -59.37123)
		(end 44.676822 -59.589416)
		(width 0.3556)
		(layer "F.Cu")
		(net "GND")
	)
	(via
		(at 16.839438 -109.982508)
		(size 0.508)
		(drill 0.254)
		(layers "F.Cu" "B.Cu")
		(net "GND")
	)
	(via
		(at 8.901176 -9.080754)
		(size 0.508)
		(drill 0.254)
		(layers "F.Cu" "B.Cu")
		(net "GND")
	)
	(via
		(at 2.667 -62.3316)
		(size 0.762)
		(drill 0.381)
		(layers "F.Cu" "B.Cu")
		(net "GND")
	)
	(via
		(at 59.182 -11.9634)
		(size 0.508)
		(drill 0.254)
		(layers "F.Cu" "B.Cu")
		(net "GND")
	)
	(via
		(at 24.20112 -104.775)
		(size 0.508)
		(drill 0.254)
		(layers "F.Cu" "B.Cu")
		(net "GND")
	)
	(via
		(at 81.178654 -51.08956)
		(size 0.508)
		(drill 0.254)
		(layers "F.Cu" "B.Cu")
		(net "GND")
	)
	(via
		(at 84.17687 -47.602394)
		(size 0.508)
		(drill 0.254)
		(layers "F.Cu" "B.Cu")
		(net "GND")
	)
	(via
		(at 16.745712 -19.431)
		(size 0.508)
		(drill 0.254)
		(layers "F.Cu" "B.Cu")
		(net "GND")
	)
	(via
		(at 71.4502 -106.5022)
		(size 0.508)
		(drill 0.254)
		(layers "F.Cu" "B.Cu")
		(net "GND")
	)
	(via
		(at 6.025642 -30.680914)
		(size 0.508)
		(drill 0.254)
		(layers "F.Cu" "B.Cu")
		(net "GND")
	)
	(via
		(at 40.5638 -28.448)
		(size 0.508)
		(drill 0.254)
		(layers "F.Cu" "B.Cu")
		(net "GND")
	)
	(via
		(at 62.890146 -47.77613)
		(size 0.4572)
		(drill 0.254)
		(layers "F.Cu" "B.Cu")
		(net "GND")
	)
	(via
		(at 50.899822 -48.575976)
		(size 0.4572)
		(drill 0.254)
		(layers "F.Cu" "B.Cu")
		(net "GND")
	)
	(via
		(at 23.368254 -114.402108)
		(size 0.508)
		(drill 0.254)
		(layers "F.Cu" "B.Cu")
		(net "GND")
	)
	(via
		(at 9.48944 -49.2887)
		(size 0.508)
		(drill 0.254)
		(layers "F.Cu" "B.Cu")
		(net "GND")
	)
	(via
		(at 18.796 -68.7832)
		(size 0.508)
		(drill 0.254)
		(layers "F.Cu" "B.Cu")
		(net "GND")
	)
	(via
		(at 86.131654 -30.766512)
		(size 0.508)
		(drill 0.254)
		(layers "F.Cu" "B.Cu")
		(net "GND")
	)
	(via
		(at 15.803372 -0.762)
		(size 0.508)
		(drill 0.254)
		(layers "F.Cu" "B.Cu")
		(net "GND")
	)
	(via
		(at 50.099722 -39.776146)
		(size 0.4572)
		(drill 0.254)
		(layers "F.Cu" "B.Cu")
		(net "GND")
	)
	(via
		(at 70.501002 -116.847112)
		(size 0.508)
		(drill 0.254)
		(layers "F.Cu" "B.Cu")
		(net "GND")
	)
	(via
		(at 89.238074 -51.000152)
		(size 0.508)
		(drill 0.254)
		(layers "F.Cu" "B.Cu")
		(net "GND")
	)
	(via
		(at 51.699668 -58.966354)
		(size 0.4572)
		(drill 0.254)
		(layers "F.Cu" "B.Cu")
		(net "GND")
	)
	(via
		(at 4.223004 -51.167792)
		(size 0.508)
		(drill 0.254)
		(layers "F.Cu" "B.Cu")
		(net "GND")
	)
	(via
		(at 33.4518 -33.274)
		(size 0.508)
		(drill 0.254)
		(layers "F.Cu" "B.Cu")
		(net "GND")
	)
	(via
		(at 62.5348 -76.1238)
		(size 0.508)
		(drill 0.254)
		(layers "F.Cu" "B.Cu")
		(net "GND")
	)
	(via
		(at 0.762 -97.060004)
		(size 0.508)
		(drill 0.254)
		(layers "F.Cu" "B.Cu")
		(net "GND")
	)
	(via
		(at 56.4134 -28.4734)
		(size 0.6604)
		(drill 0.3302)
		(layers "F.Cu" "B.Cu")
		(net "GND")
	)
	(via
		(at 78.618334 -58.365644)
		(size 0.508)
		(drill 0.254)
		(layers "F.Cu" "B.Cu")
		(net "GND")
	)
	(via
		(at 9.7028 -92.67317)
		(size 0.508)
		(drill 0.254)
		(layers "F.Cu" "B.Cu")
		(net "GND")
	)
	(via
		(at 32.0802 -44.85005)
		(size 0.508)
		(drill 0.254)
		(layers "F.Cu" "B.Cu")
		(net "GND")
	)
	(via
		(at 12.502642 -31.442914)
		(size 0.508)
		(drill 0.254)
		(layers "F.Cu" "B.Cu")
		(net "GND")
	)
	(via
		(at 36.068 -37.084)
		(size 0.508)
		(drill 0.254)
		(layers "F.Cu" "B.Cu")
		(net "GND")
	)
	(via
		(at 52.92344 -97.76206)
		(size 0.508)
		(drill 0.254)
		(layers "F.Cu" "B.Cu")
		(net "GND")
	)
	(via
		(at 29.60624 -22.517354)
		(size 0.508)
		(drill 0.254)
		(layers "F.Cu" "B.Cu")
		(net "GND")
	)
	(via
		(at 4.223004 -49.745392)
		(size 0.508)
		(drill 0.254)
		(layers "F.Cu" "B.Cu")
		(net "GND")
	)
	(via
		(at 45.299884 -50.96637)
		(size 0.4572)
		(drill 0.254)
		(layers "F.Cu" "B.Cu")
		(net "GND")
	)
	(via
		(at 54.099714 -52.56657)
		(size 0.4572)
		(drill 0.254)
		(layers "F.Cu" "B.Cu")
		(net "GND")
	)
	(via
		(at 46.89983 -58.966354)
		(size 0.4572)
		(drill 0.254)
		(layers "F.Cu" "B.Cu")
		(net "GND")
	)
	(via
		(at 50.8 -115.7732)
		(size 0.508)
		(drill 0.254)
		(layers "F.Cu" "B.Cu")
		(net "GND")
	)
	(via
		(at 5.36829 -60.093098)
		(size 0.508)
		(drill 0.254)
		(layers "F.Cu" "B.Cu")
		(net "GND")
	)
	(via
		(at 12.012676 -46.860714)
		(size 0.508)
		(drill 0.254)
		(layers "F.Cu" "B.Cu")
		(net "GND")
	)
	(via
		(at 4.858766 -51.878992)
		(size 0.508)
		(drill 0.254)
		(layers "F.Cu" "B.Cu")
		(net "GND")
	)
	(via
		(at 42.242232 -57.198006)
		(size 0.508)
		(drill 0.254)
		(layers "F.Cu" "B.Cu")
		(net "GND")
	)
	(via
		(at 70.6628 -103.8098)
		(size 0.508)
		(drill 0.254)
		(layers "F.Cu" "B.Cu")
		(net "GND")
	)
	(via
		(at 56.4388 -116.5098)
		(size 0.508)
		(drill 0.254)
		(layers "F.Cu" "B.Cu")
		(net "GND")
	)
	(via
		(at 35.6362 -100.3554)
		(size 0.508)
		(drill 0.254)
		(layers "F.Cu" "B.Cu")
		(net "GND")
	)
	(via
		(at 44.158662 -23.873714)
		(size 0.508)
		(drill 0.254)
		(layers "F.Cu" "B.Cu")
		(net "GND")
	)
	(via
		(at 6.27126 -62.602618)
		(size 0.508)
		(drill 0.254)
		(layers "F.Cu" "B.Cu")
		(net "GND")
	)
	(via
		(at 89.238074 -56.080152)
		(size 0.508)
		(drill 0.254)
		(layers "F.Cu" "B.Cu")
		(net "GND")
	)
	(via
		(at 51.699668 -48.575976)
		(size 0.4572)
		(drill 0.254)
		(layers "F.Cu" "B.Cu")
		(net "GND")
	)
	(via
		(at 50.099722 -50.96637)
		(size 0.4572)
		(drill 0.254)
		(layers "F.Cu" "B.Cu")
		(net "GND")
	)
	(via
		(at 6.985 -51.308)
		(size 0.6604)
		(drill 0.3302)
		(layers "F.Cu" "B.Cu")
		(net "GND")
	)
	(via
		(at 57.290208 -39.776146)
		(size 0.4572)
		(drill 0.254)
		(layers "F.Cu" "B.Cu")
		(net "GND")
	)
	(via
		(at 70.14337 -83.819746)
		(size 0.508)
		(drill 0.254)
		(layers "F.Cu" "B.Cu")
		(net "GND")
	)
	(via
		(at 79.80172 -76.05776)
		(size 0.508)
		(drill 0.254)
		(layers "F.Cu" "B.Cu")
		(net "GND")
	)
	(via
		(at 78.359 -97.0534)
		(size 0.508)
		(drill 0.254)
		(layers "F.Cu" "B.Cu")
		(net "GND")
	)
	(via
		(at 66.80962 -38.314884)
		(size 0.508)
		(drill 0.254)
		(layers "F.Cu" "B.Cu")
		(net "GND")
	)
	(via
		(at 37.578538 -2.4892)
		(size 0.508)
		(drill 0.254)
		(layers "F.Cu" "B.Cu")
		(net "GND")
	)
	(via
		(at 85.619082 -50.038)
		(size 0.508)
		(drill 0.254)
		(layers "F.Cu" "B.Cu")
		(net "GND")
	)
	(via
		(at 64.490092 -46.97603)
		(size 0.4572)
		(drill 0.254)
		(layers "F.Cu" "B.Cu")
		(net "GND")
	)
	(via
		(at 5.4356 -45.2374)
		(size 0.6604)
		(drill 0.3302)
		(layers "F.Cu" "B.Cu")
		(net "GND")
	)
	(via
		(at 26.56205 -15.841726)
		(size 0.508)
		(drill 0.254)
		(layers "F.Cu" "B.Cu")
		(net "GND")
	)
	(via
		(at 64.360552 -69.50837)
		(size 0.508)
		(drill 0.254)
		(layers "F.Cu" "B.Cu")
		(net "GND")
	)
	(via
		(at 89.238074 -30.680152)
		(size 0.508)
		(drill 0.254)
		(layers "F.Cu" "B.Cu")
		(net "GND")
	)
	(via
		(at 64.490092 -52.56657)
		(size 0.4572)
		(drill 0.254)
		(layers "F.Cu" "B.Cu")
		(net "GND")
	)
	(via
		(at 73.369424 -3.090164)
		(size 0.508)
		(drill 0.254)
		(layers "F.Cu" "B.Cu")
		(net "GND")
	)
	(via
		(at 63.690246 -40.575992)
		(size 0.4572)
		(drill 0.254)
		(layers "F.Cu" "B.Cu")
		(net "GND")
	)
	(via
		(at 33.909 -37.94379)
		(size 0.508)
		(drill 0.254)
		(layers "F.Cu" "B.Cu")
		(net "GND")
	)
	(via
		(at 80.752188 -58.359548)
		(size 0.508)
		(drill 0.254)
		(layers "F.Cu" "B.Cu")
		(net "GND")
	)
	(via
		(at 63.690246 -58.966354)
		(size 0.4572)
		(drill 0.254)
		(layers "F.Cu" "B.Cu")
		(net "GND")
	)
	(via
		(at 78.618334 -57.504838)
		(size 0.508)
		(drill 0.254)
		(layers "F.Cu" "B.Cu")
		(net "GND")
	)
	(via
		(at 70.9168 -28.9814)
		(size 0.508)
		(drill 0.254)
		(layers "F.Cu" "B.Cu")
		(net "GND")
	)
	(via
		(at 40.856408 -116.869972)
		(size 0.508)
		(drill 0.254)
		(layers "F.Cu" "B.Cu")
		(net "GND")
	)
	(via
		(at 55.7784 -18.796)
		(size 0.508)
		(drill 0.254)
		(layers "F.Cu" "B.Cu")
		(net "GND")
	)
	(via
		(at 59.3852 -99.089972)
		(size 0.508)
		(drill 0.254)
		(layers "F.Cu" "B.Cu")
		(net "GND")
	)
	(via
		(at 72.061578 -116.687092)
		(size 0.508)
		(drill 0.254)
		(layers "F.Cu" "B.Cu")
		(net "GND")
	)
	(via
		(at 50.099722 -50.166524)
		(size 0.4572)
		(drill 0.254)
		(layers "F.Cu" "B.Cu")
		(net "GND")
	)
	(via
		(at 46.4185 -108.3945)
		(size 0.508)
		(drill 0.254)
		(layers "F.Cu" "B.Cu")
		(net "GND")
	)
	(via
		(at 73.8632 -111.3282)
		(size 0.508)
		(drill 0.254)
		(layers "F.Cu" "B.Cu")
		(net "GND")
	)
	(via
		(at 3.2766 -26.797)
		(size 0.508)
		(drill 0.254)
		(layers "F.Cu" "B.Cu")
		(net "GND")
	)
	(via
		(at 5.36829 -61.129418)
		(size 0.508)
		(drill 0.254)
		(layers "F.Cu" "B.Cu")
		(net "GND")
	)
	(via
		(at 80.00619 -100.238306)
		(size 0.508)
		(drill 0.254)
		(layers "F.Cu" "B.Cu")
		(net "GND")
	)
	(via
		(at 75.881992 -99.089972)
		(size 0.508)
		(drill 0.254)
		(layers "F.Cu" "B.Cu")
		(net "GND")
	)
	(via
		(at 63.083186 -11.825986)
		(size 0.508)
		(drill 0.254)
		(layers "F.Cu" "B.Cu")
		(net "GND")
	)
	(via
		(at 20.66417 -94.382336)
		(size 0.4572)
		(drill 0.254)
		(layers "F.Cu" "B.Cu")
		(net "GND")
	)
	(via
		(at 5.36829 -61.909198)
		(size 0.508)
		(drill 0.254)
		(layers "F.Cu" "B.Cu")
		(net "GND")
	)
	(via
		(at 15.268448 -28.953968)
		(size 0.508)
		(drill 0.254)
		(layers "F.Cu" "B.Cu")
		(net "GND")
	)
	(via
		(at 24.677624 -114.410998)
		(size 0.508)
		(drill 0.254)
		(layers "F.Cu" "B.Cu")
		(net "GND")
	)
	(via
		(at 4.318 -54.791102)
		(size 0.508)
		(drill 0.254)
		(layers "F.Cu" "B.Cu")
		(net "GND")
	)
	(via
		(at 79.833978 -52.689252)
		(size 0.4572)
		(drill 0.254)
		(layers "F.Cu" "B.Cu")
		(net "GND")
	)
	(via
		(at 78.105 -31.91129)
		(size 0.508)
		(drill 0.254)
		(layers "F.Cu" "B.Cu")
		(net "GND")
	)
	(via
		(at 80.002126 -115.957858)
		(size 0.508)
		(drill 0.254)
		(layers "F.Cu" "B.Cu")
		(net "GND")
	)
	(via
		(at 0.762 -68.197476)
		(size 0.508)
		(drill 0.254)
		(layers "F.Cu" "B.Cu")
		(net "GND")
	)
	(via
		(at 51.699668 -50.166524)
		(size 0.4572)
		(drill 0.254)
		(layers "F.Cu" "B.Cu")
		(net "GND")
	)
	(via
		(at 65.978786 -26.327354)
		(size 0.508)
		(drill 0.254)
		(layers "F.Cu" "B.Cu")
		(net "GND")
	)
	(via
		(at 26.289 -61.117226)
		(size 0.508)
		(drill 0.254)
		(layers "F.Cu" "B.Cu")
		(net "GND")
	)
	(via
		(at 9.607042 -50.379884)
		(size 0.508)
		(drill 0.254)
		(layers "F.Cu" "B.Cu")
		(net "GND")
	)
	(via
		(at 19.054572 -96.782382)
		(size 0.4572)
		(drill 0.254)
		(layers "F.Cu" "B.Cu")
		(net "GND")
	)
	(via
		(at 64.9605 -19.6469)
		(size 0.508)
		(drill 0.254)
		(layers "F.Cu" "B.Cu")
		(net "GND")
	)
	(via
		(at 46.46295 -21.4122)
		(size 0.508)
		(drill 0.254)
		(layers "F.Cu" "B.Cu")
		(net "GND")
	)
	(via
		(at 80.00619 -101.000306)
		(size 0.508)
		(drill 0.254)
		(layers "F.Cu" "B.Cu")
		(net "GND")
	)
	(via
		(at 15.24 -19.177)
		(size 0.508)
		(drill 0.254)
		(layers "F.Cu" "B.Cu")
		(net "GND")
	)
	(via
		(at 5.36829 -62.696598)
		(size 0.508)
		(drill 0.254)
		(layers "F.Cu" "B.Cu")
		(net "GND")
	)
	(via
		(at 51.699668 -42.976038)
		(size 0.4572)
		(drill 0.254)
		(layers "F.Cu" "B.Cu")
		(net "GND")
	)
	(via
		(at 0.762 -78.357476)
		(size 0.508)
		(drill 0.254)
		(layers "F.Cu" "B.Cu")
		(net "GND")
	)
	(via
		(at 56.44515 -103.5431)
		(size 0.508)
		(drill 0.254)
		(layers "F.Cu" "B.Cu")
		(net "GND")
	)
	(via
		(at 2.7432 -59.4868)
		(size 0.762)
		(drill 0.381)
		(layers "F.Cu" "B.Cu")
		(net "GND")
	)
	(via
		(at 64.490092 -48.575976)
		(size 0.4572)
		(drill 0.254)
		(layers "F.Cu" "B.Cu")
		(net "GND")
	)
	(via
		(at 53.299868 -39.776146)
		(size 0.4572)
		(drill 0.254)
		(layers "F.Cu" "B.Cu")
		(net "GND")
	)
	(via
		(at 45.8089 -93.6371)
		(size 0.508)
		(drill 0.254)
		(layers "F.Cu" "B.Cu")
		(net "GND")
	)
	(via
		(at 68.20154 -45.488352)
		(size 0.4572)
		(drill 0.254)
		(layers "F.Cu" "B.Cu")
		(net "GND")
	)
	(via
		(at 81.07045 -15.2908)
		(size 0.508)
		(drill 0.254)
		(layers "F.Cu" "B.Cu")
		(net "GND")
	)
	(via
		(at 87.021416 -80.968342)
		(size 0.508)
		(drill 0.254)
		(layers "F.Cu" "B.Cu")
		(net "GND")
	)
	(via
		(at 32.9946 -105.558082)
		(size 0.508)
		(drill 0.254)
		(layers "F.Cu" "B.Cu")
		(net "GND")
	)
	(via
		(at 35.179 -116.1415)
		(size 0.508)
		(drill 0.254)
		(layers "F.Cu" "B.Cu")
		(net "GND")
	)
	(via
		(at 52.7558 -15.0114)
		(size 0.508)
		(drill 0.254)
		(layers "F.Cu" "B.Cu")
		(net "GND")
	)
	(via
		(at 54.099714 -46.17593)
		(size 0.4572)
		(drill 0.254)
		(layers "F.Cu" "B.Cu")
		(net "GND")
	)
	(via
		(at 66.04 -53.5686)
		(size 0.6604)
		(drill 0.3302)
		(layers "F.Cu" "B.Cu")
		(net "GND")
	)
	(via
		(at 81.604104 -34.171128)
		(size 0.508)
		(drill 0.254)
		(layers "F.Cu" "B.Cu")
		(net "GND")
	)
	(via
		(at 71.0184 -33.3756)
		(size 0.508)
		(drill 0.254)
		(layers "F.Cu" "B.Cu")
		(net "GND")
	)
	(via
		(at 82.139536 -44.038012)
		(size 0.508)
		(drill 0.254)
		(layers "F.Cu" "B.Cu")
		(net "GND")
	)
	(via
		(at 89.238074 -100.972874)
		(size 0.508)
		(drill 0.254)
		(layers "F.Cu" "B.Cu")
		(net "GND")
	)
	(via
		(at 31.115 -14.732)
		(size 0.508)
		(drill 0.254)
		(layers "F.Cu" "B.Cu")
		(net "GND")
	)
	(via
		(at 75.032108 -12.204954)
		(size 0.508)
		(drill 0.254)
		(layers "F.Cu" "B.Cu")
		(net "GND")
	)
	(via
		(at 66.362326 -54.522878)
		(size 0.4572)
		(drill 0.254)
		(layers "F.Cu" "B.Cu")
		(net "GND")
	)
	(via
		(at 36.123372 -0.762)
		(size 0.508)
		(drill 0.254)
		(layers "F.Cu" "B.Cu")
		(net "GND")
	)
	(via
		(at 15.9004 -114.4778)
		(size 0.508)
		(drill 0.254)
		(layers "F.Cu" "B.Cu")
		(net "GND")
	)
	(via
		(at 9.2964 -103.7844)
		(size 0.508)
		(drill 0.254)
		(layers "F.Cu" "B.Cu")
		(net "GND")
	)
	(via
		(at 1.5748 -79.4766)
		(size 0.508)
		(drill 0.254)
		(layers "F.Cu" "B.Cu")
		(net "GND")
	)
	(via
		(at 64.894968 -38.83787)
		(size 0.4572)
		(drill 0.254)
		(layers "F.Cu" "B.Cu")
		(net "GND")
	)
	(via
		(at 87.0966 -16.7894)
		(size 0.508)
		(drill 0.254)
		(layers "F.Cu" "B.Cu")
		(net "GND")
	)
	(via
		(at 73.885806 -38.688772)
		(size 0.508)
		(drill 0.254)
		(layers "F.Cu" "B.Cu")
		(net "GND")
	)
	(via
		(at 2.54 -31.369)
		(size 0.762)
		(drill 0.381)
		(layers "F.Cu" "B.Cu")
		(net "GND")
	)
	(via
		(at 52.499768 -45.376084)
		(size 0.4572)
		(drill 0.254)
		(layers "F.Cu" "B.Cu")
		(net "GND")
	)
	(via
		(at 31.043372 -0.762)
		(size 0.508)
		(drill 0.254)
		(layers "F.Cu" "B.Cu")
		(net "GND")
	)
	(via
		(at 38.7096 -74.5236)
		(size 0.508)
		(drill 0.254)
		(layers "F.Cu" "B.Cu")
		(net "GND")
	)
	(via
		(at 2.0828 -76.9112)
		(size 0.6604)
		(drill 0.3302)
		(layers "F.Cu" "B.Cu")
		(net "GND")
	)
	(via
		(at 73.470516 -53.489098)
		(size 0.4572)
		(drill 0.254)
		(layers "F.Cu" "B.Cu")
		(net "GND")
	)
	(via
		(at 21.760688 -72.13219)
		(size 0.508)
		(drill 0.254)
		(layers "F.Cu" "B.Cu")
		(net "GND")
	)
	(via
		(at 14.344904 -116.8654)
		(size 0.508)
		(drill 0.254)
		(layers "F.Cu" "B.Cu")
		(net "GND")
	)
	(via
		(at 26.945082 -116.40185)
		(size 0.508)
		(drill 0.254)
		(layers "F.Cu" "B.Cu")
		(net "GND")
	)
	(via
		(at 5.648198 -79.116174)
		(size 0.508)
		(drill 0.254)
		(layers "F.Cu" "B.Cu")
		(net "GND")
	)
	(via
		(at 9.915906 -78.497176)
		(size 0.508)
		(drill 0.254)
		(layers "F.Cu" "B.Cu")
		(net "GND")
	)
	(via
		(at 72.291956 -98.332544)
		(size 0.508)
		(drill 0.254)
		(layers "F.Cu" "B.Cu")
		(net "GND")
	)
	(via
		(at 25.45461 -89.591896)
		(size 0.4572)
		(drill 0.254)
		(layers "F.Cu" "B.Cu")
		(net "GND")
	)
	(via
		(at 59.690254 -52.56657)
		(size 0.4572)
		(drill 0.254)
		(layers "F.Cu" "B.Cu")
		(net "GND")
	)
	(via
		(at 65.913 -25.6794)
		(size 0.508)
		(drill 0.254)
		(layers "F.Cu" "B.Cu")
		(net "GND")
	)
	(via
		(at 56.490108 -42.976038)
		(size 0.4572)
		(drill 0.254)
		(layers "F.Cu" "B.Cu")
		(net "GND")
	)
	(via
		(at 9.7282 -27.7368)
		(size 0.508)
		(drill 0.254)
		(layers "F.Cu" "B.Cu")
		(net "GND")
	)
	(via
		(at 42.346626 -19.271996)
		(size 0.508)
		(drill 0.254)
		(layers "F.Cu" "B.Cu")
		(net "GND")
	)
	(via
		(at 76.581 -82.931)
		(size 0.508)
		(drill 0.254)
		(layers "F.Cu" "B.Cu")
		(net "GND")
	)
	(via
		(at 82.6008 -97.5106)
		(size 0.508)
		(drill 0.254)
		(layers "F.Cu" "B.Cu")
		(net "GND")
	)
	(via
		(at 51.7144 -29.718)
		(size 0.508)
		(drill 0.254)
		(layers "F.Cu" "B.Cu")
		(net "GND")
	)
	(via
		(at 60.4901 -55.766462)
		(size 0.4572)
		(drill 0.254)
		(layers "F.Cu" "B.Cu")
		(net "GND")
	)
	(via
		(at 41.6052 -90.6272)
		(size 0.508)
		(drill 0.254)
		(layers "F.Cu" "B.Cu")
		(net "GND")
	)
	(via
		(at 39.116 -105.3465)
		(size 0.508)
		(drill 0.254)
		(layers "F.Cu" "B.Cu")
		(net "GND")
	)
	(via
		(at 44.541186 -38.934644)
		(size 0.4572)
		(drill 0.254)
		(layers "F.Cu" "B.Cu")
		(net "GND")
	)
	(via
		(at 11.500104 -25.015952)
		(size 0.508)
		(drill 0.254)
		(layers "F.Cu" "B.Cu")
		(net "GND")
	)
	(via
		(at 61.6712 -33.5788)
		(size 0.508)
		(drill 0.254)
		(layers "F.Cu" "B.Cu")
		(net "GND")
	)
	(via
		(at 17.382236 -37.974524)
		(size 0.508)
		(drill 0.254)
		(layers "F.Cu" "B.Cu")
		(net "GND")
	)
	(via
		(at 25.71242 -32.26054)
		(size 0.508)
		(drill 0.254)
		(layers "F.Cu" "B.Cu")
		(net "GND")
	)
	(via
		(at 4.318 -55.699152)
		(size 0.508)
		(drill 0.254)
		(layers "F.Cu" "B.Cu")
		(net "GND")
	)
	(via
		(at 86.3092 -39.347394)
		(size 0.508)
		(drill 0.254)
		(layers "F.Cu" "B.Cu")
		(net "GND")
	)
	(via
		(at 62.890146 -46.17593)
		(size 0.4572)
		(drill 0.254)
		(layers "F.Cu" "B.Cu")
		(net "GND")
	)
	(via
		(at 55.295038 -44.412408)
		(size 0.4572)
		(drill 0.254)
		(layers "F.Cu" "B.Cu")
		(net "GND")
	)
	(via
		(at 24.654764 -96.782382)
		(size 0.4572)
		(drill 0.254)
		(layers "F.Cu" "B.Cu")
		(net "GND")
	)
	(via
		(at 26.56205 -17.165574)
		(size 0.508)
		(drill 0.254)
		(layers "F.Cu" "B.Cu")
		(net "GND")
	)
	(via
		(at 86.3092 -48.237394)
		(size 0.508)
		(drill 0.254)
		(layers "F.Cu" "B.Cu")
		(net "GND")
	)
	(via
		(at 48.494188 -89.15146)
		(size 0.508)
		(drill 0.254)
		(layers "F.Cu" "B.Cu")
		(net "GND")
	)
	(via
		(at 75.532488 -49.940464)
		(size 0.4572)
		(drill 0.254)
		(layers "F.Cu" "B.Cu")
		(net "GND")
	)
	(via
		(at 79.070454 -46.32579)
		(size 0.4572)
		(drill 0.254)
		(layers "F.Cu" "B.Cu")
		(net "GND")
	)
	(via
		(at 48.593248 -21.466048)
		(size 0.508)
		(drill 0.254)
		(layers "F.Cu" "B.Cu")
		(net "GND")
	)
	(via
		(at 61.2902 -58.966354)
		(size 0.4572)
		(drill 0.254)
		(layers "F.Cu" "B.Cu")
		(net "GND")
	)
	(via
		(at 17.36725 -36.6014)
		(size 0.508)
		(drill 0.254)
		(layers "F.Cu" "B.Cu")
		(net "GND")
	)
	(via
		(at 55.04815 -103.5431)
		(size 0.508)
		(drill 0.254)
		(layers "F.Cu" "B.Cu")
		(net "GND")
	)
	(via
		(at 65.9892 -56.5404)
		(size 0.6604)
		(drill 0.3302)
		(layers "F.Cu" "B.Cu")
		(net "GND")
	)
	(via
		(at 70.1294 -95.4786)
		(size 0.508)
		(drill 0.254)
		(layers "F.Cu" "B.Cu")
		(net "GND")
	)
	(via
		(at 74.259694 -50.28438)
		(size 0.4572)
		(drill 0.254)
		(layers "F.Cu" "B.Cu")
		(net "GND")
	)
	(via
		(at 47.58944 -33.63595)
		(size 0.508)
		(drill 0.254)
		(layers "F.Cu" "B.Cu")
		(net "GND")
	)
	(via
		(at 66.108326 -52.668932)
		(size 0.4572)
		(drill 0.254)
		(layers "F.Cu" "B.Cu")
		(net "GND")
	)
	(via
		(at 60.26912 -27.30754)
		(size 0.508)
		(drill 0.254)
		(layers "F.Cu" "B.Cu")
		(net "GND")
	)
	(via
		(at 78.34884 -54.401212)
		(size 0.4572)
		(drill 0.254)
		(layers "F.Cu" "B.Cu")
		(net "GND")
	)
	(via
		(at 35.780726 -22.61997)
		(size 0.508)
		(drill 0.254)
		(layers "F.Cu" "B.Cu")
		(net "GND")
	)
	(via
		(at 67.6402 -110.7186)
		(size 0.508)
		(drill 0.254)
		(layers "F.Cu" "B.Cu")
		(net "GND")
	)
	(via
		(at 51.699668 -53.366416)
		(size 0.4572)
		(drill 0.254)
		(layers "F.Cu" "B.Cu")
		(net "GND")
	)
	(via
		(at 79.79918 -77.98308)
		(size 0.508)
		(drill 0.254)
		(layers "F.Cu" "B.Cu")
		(net "GND")
	)
	(via
		(at 20.883372 -0.762)
		(size 0.508)
		(drill 0.254)
		(layers "F.Cu" "B.Cu")
		(net "GND")
	)
	(via
		(at 17.653 -78.4098)
		(size 0.508)
		(drill 0.254)
		(layers "F.Cu" "B.Cu")
		(net "GND")
	)
	(via
		(at 3.937 -64.008)
		(size 0.762)
		(drill 0.381)
		(layers "F.Cu" "B.Cu")
		(net "GND")
	)
	(via
		(at 84.652612 -38.386766)
		(size 0.508)
		(drill 0.254)
		(layers "F.Cu" "B.Cu")
		(net "GND")
	)
	(via
		(at 10.287 -60.1726)
		(size 0.508)
		(drill 0.254)
		(layers "F.Cu" "B.Cu")
		(net "GND")
	)
	(via
		(at 48.662082 -66.386202)
		(size 0.508)
		(drill 0.254)
		(layers "F.Cu" "B.Cu")
		(net "GND")
	)
	(via
		(at 0.762 -112.300004)
		(size 0.508)
		(drill 0.254)
		(layers "F.Cu" "B.Cu")
		(net "GND")
	)
	(via
		(at 16.713454 -64.29883)
		(size 0.508)
		(drill 0.254)
		(layers "F.Cu" "B.Cu")
		(net "GND")
	)
	(via
		(at 6.940042 -6.563868)
		(size 0.508)
		(drill 0.254)
		(layers "F.Cu" "B.Cu")
		(net "GND")
	)
	(via
		(at 54.099714 -53.366416)
		(size 0.4572)
		(drill 0.254)
		(layers "F.Cu" "B.Cu")
		(net "GND")
	)
	(via
		(at 58.1152 -76.8858)
		(size 0.508)
		(drill 0.254)
		(layers "F.Cu" "B.Cu")
		(net "GND")
	)
	(via
		(at 14.346428 -114.387376)
		(size 0.508)
		(drill 0.254)
		(layers "F.Cu" "B.Cu")
		(net "GND")
	)
	(via
		(at 79.276956 -73.263506)
		(size 0.508)
		(drill 0.254)
		(layers "F.Cu" "B.Cu")
		(net "GND")
	)
	(via
		(at 36.3982 -100.6856)
		(size 0.508)
		(drill 0.254)
		(layers "F.Cu" "B.Cu")
		(net "GND")
	)
	(via
		(at 4.223004 -51.878992)
		(size 0.508)
		(drill 0.254)
		(layers "F.Cu" "B.Cu")
		(net "GND")
	)
	(via
		(at 16.586454 -47.691548)
		(size 0.508)
		(drill 0.254)
		(layers "F.Cu" "B.Cu")
		(net "GND")
	)
	(via
		(at 67.860672 -23.817072)
		(size 0.508)
		(drill 0.254)
		(layers "F.Cu" "B.Cu")
		(net "GND")
	)
	(via
		(at 59.300872 -86.625684)
		(size 0.508)
		(drill 0.254)
		(layers "F.Cu" "B.Cu")
		(net "GND")
	)
	(via
		(at 74.089006 -116.055648)
		(size 0.508)
		(drill 0.254)
		(layers "F.Cu" "B.Cu")
		(net "GND")
	)
	(via
		(at 70.65137 -44.72559)
		(size 0.508)
		(drill 0.254)
		(layers "F.Cu" "B.Cu")
		(net "GND")
	)
	(via
		(at 15.09395 -13.48105)
		(size 0.508)
		(drill 0.254)
		(layers "F.Cu" "B.Cu")
		(net "GND")
	)
	(via
		(at 4.572 -61.1886)
		(size 0.508)
		(drill 0.254)
		(layers "F.Cu" "B.Cu")
		(net "GND")
	)
	(via
		(at 85.599016 -53.368702)
		(size 0.762)
		(drill 0.254)
		(layers "F.Cu" "B.Cu")
		(net "GND")
	)
	(via
		(at 56.490108 -52.56657)
		(size 0.4572)
		(drill 0.254)
		(layers "F.Cu" "B.Cu")
		(net "GND")
	)
	(via
		(at 25.4 -25.019)
		(size 0.508)
		(drill 0.254)
		(layers "F.Cu" "B.Cu")
		(net "GND")
	)
	(via
		(at 70.358 -10.663428)
		(size 0.508)
		(drill 0.254)
		(layers "F.Cu" "B.Cu")
		(net "GND")
	)
	(via
		(at 89.238074 -76.400152)
		(size 0.508)
		(drill 0.254)
		(layers "F.Cu" "B.Cu")
		(net "GND")
	)
	(via
		(at 58.166 -25.654)
		(size 0.508)
		(drill 0.254)
		(layers "F.Cu" "B.Cu")
		(net "GND")
	)
	(via
		(at 85.217 -92.2528)
		(size 0.508)
		(drill 0.254)
		(layers "F.Cu" "B.Cu")
		(net "GND")
	)
	(via
		(at 10.559796 -65.007998)
		(size 0.508)
		(drill 0.254)
		(layers "F.Cu" "B.Cu")
		(net "GND")
	)
	(via
		(at 49.299876 -58.966354)
		(size 0.4572)
		(drill 0.254)
		(layers "F.Cu" "B.Cu")
		(net "GND")
	)
	(via
		(at 12.04976 -78.407514)
		(size 0.508)
		(drill 0.254)
		(layers "F.Cu" "B.Cu")
		(net "GND")
	)
	(via
		(at 26.67 -79.2226)
		(size 0.508)
		(drill 0.254)
		(layers "F.Cu" "B.Cu")
		(net "GND")
	)
	(via
		(at 20.66417 -92.791788)
		(size 0.4572)
		(drill 0.254)
		(layers "F.Cu" "B.Cu")
		(net "GND")
	)
	(via
		(at 61.2902 -54.166516)
		(size 0.4572)
		(drill 0.254)
		(layers "F.Cu" "B.Cu")
		(net "GND")
	)
	(via
		(at 34.407348 -79.686658)
		(size 0.508)
		(drill 0.254)
		(layers "F.Cu" "B.Cu")
		(net "GND")
	)
	(via
		(at 79.305404 -97.222564)
		(size 0.508)
		(drill 0.254)
		(layers "F.Cu" "B.Cu")
		(net "GND")
	)
	(via
		(at 62.226698 -26.296112)
		(size 0.508)
		(drill 0.254)
		(layers "F.Cu" "B.Cu")
		(net "GND")
	)
	(via
		(at 17.050004 -32.5374)
		(size 0.508)
		(drill 0.254)
		(layers "F.Cu" "B.Cu")
		(net "GND")
	)
	(via
		(at 76.492354 -27.596846)
		(size 0.508)
		(drill 0.254)
		(layers "F.Cu" "B.Cu")
		(net "GND")
	)
	(via
		(at 76.763372 -0.762)
		(size 0.508)
		(drill 0.254)
		(layers "F.Cu" "B.Cu")
		(net "GND")
	)
	(via
		(at 23.854664 -95.982282)
		(size 0.4572)
		(drill 0.254)
		(layers "F.Cu" "B.Cu")
		(net "GND")
	)
	(via
		(at 46.89983 -52.56657)
		(size 0.4572)
		(drill 0.254)
		(layers "F.Cu" "B.Cu")
		(net "GND")
	)
	(via
		(at 4.572 -63.4746)
		(size 0.508)
		(drill 0.254)
		(layers "F.Cu" "B.Cu")
		(net "GND")
	)
	(via
		(at 6.604 -53.213)
		(size 0.6604)
		(drill 0.3302)
		(layers "F.Cu" "B.Cu")
		(net "GND")
	)
	(via
		(at 34.29 -52.5526)
		(size 0.508)
		(drill 0.254)
		(layers "F.Cu" "B.Cu")
		(net "GND")
	)
	(via
		(at 53.299868 -50.96637)
		(size 0.4572)
		(drill 0.254)
		(layers "F.Cu" "B.Cu")
		(net "GND")
	)
	(via
		(at 66.28638 -10.780014)
		(size 0.508)
		(drill 0.254)
		(layers "F.Cu" "B.Cu")
		(net "GND")
	)
	(via
		(at 7.5946 -58.7756)
		(size 0.6604)
		(drill 0.3302)
		(layers "F.Cu" "B.Cu")
		(net "GND")
	)
	(via
		(at 86.3092 -40.617394)
		(size 0.508)
		(drill 0.254)
		(layers "F.Cu" "B.Cu")
		(net "GND")
	)
	(via
		(at 23.5966 -87.0712)
		(size 0.6604)
		(drill 0.3302)
		(layers "F.Cu" "B.Cu")
		(net "GND")
	)
	(via
		(at 83.641438 -32.99206)
		(size 0.508)
		(drill 0.254)
		(layers "F.Cu" "B.Cu")
		(net "GND")
	)
	(via
		(at 1.983486 -61.822838)
		(size 0.6604)
		(drill 0.3302)
		(layers "F.Cu" "B.Cu")
		(net "GND")
	)
	(via
		(at 16.145002 -116.8654)
		(size 0.508)
		(drill 0.254)
		(layers "F.Cu" "B.Cu")
		(net "GND")
	)
	(via
		(at 79.034132 -49.489106)
		(size 0.4572)
		(drill 0.254)
		(layers "F.Cu" "B.Cu")
		(net "GND")
	)
	(via
		(at 61.82614 -96.856042)
		(size 0.508)
		(drill 0.254)
		(layers "F.Cu" "B.Cu")
		(net "GND")
	)
	(via
		(at 89.238074 -45.920152)
		(size 0.508)
		(drill 0.254)
		(layers "F.Cu" "B.Cu")
		(net "GND")
	)
	(via
		(at 23.344886 -116.40185)
		(size 0.508)
		(drill 0.254)
		(layers "F.Cu" "B.Cu")
		(net "GND")
	)
	(via
		(at 4.572 -59.563)
		(size 0.6604)
		(drill 0.3302)
		(layers "F.Cu" "B.Cu")
		(net "GND")
	)
	(via
		(at 29.21 -93.853)
		(size 0.508)
		(drill 0.254)
		(layers "F.Cu" "B.Cu")
		(net "GND")
	)
	(via
		(at 83.8708 -77.1144)
		(size 0.6604)
		(drill 0.3302)
		(layers "F.Cu" "B.Cu")
		(net "GND")
	)
	(via
		(at 68.425314 -54.506622)
		(size 0.4572)
		(drill 0.254)
		(layers "F.Cu" "B.Cu")
		(net "GND")
	)
	(via
		(at 14.605 -19.177)
		(size 0.508)
		(drill 0.254)
		(layers "F.Cu" "B.Cu")
		(net "GND")
	)
	(via
		(at 18.542 -82.1436)
		(size 0.508)
		(drill 0.254)
		(layers "F.Cu" "B.Cu")
		(net "GND")
	)
	(via
		(at 8.1534 -64.2112)
		(size 0.6604)
		(drill 0.3302)
		(layers "F.Cu" "B.Cu")
		(net "GND")
	)
	(via
		(at 41.764966 -23.873714)
		(size 0.508)
		(drill 0.254)
		(layers "F.Cu" "B.Cu")
		(net "GND")
	)
	(via
		(at 53.213 -23.450804)
		(size 0.508)
		(drill 0.254)
		(layers "F.Cu" "B.Cu")
		(net "GND")
	)
	(via
		(at 17.59839 -33.609534)
		(size 0.508)
		(drill 0.254)
		(layers "F.Cu" "B.Cu")
		(net "GND")
	)
	(via
		(at 82.886042 -58.353452)
		(size 0.508)
		(drill 0.254)
		(layers "F.Cu" "B.Cu")
		(net "GND")
	)
	(via
		(at 52.63388 -76.49972)
		(size 0.508)
		(drill 0.254)
		(layers "F.Cu" "B.Cu")
		(net "GND")
	)
	(via
		(at 16.664178 -88.791796)
		(size 0.4572)
		(drill 0.254)
		(layers "F.Cu" "B.Cu")
		(net "GND")
	)
	(via
		(at 45.804582 -29.030168)
		(size 0.508)
		(drill 0.254)
		(layers "F.Cu" "B.Cu")
		(net "GND")
	)
	(via
		(at 53.81371 -112.90808)
		(size 0.508)
		(drill 0.254)
		(layers "F.Cu" "B.Cu")
		(net "GND")
	)
	(via
		(at 72.512428 -48.307498)
		(size 0.4572)
		(drill 0.254)
		(layers "F.Cu" "B.Cu")
		(net "GND")
	)
	(via
		(at 23.2918 -16.891)
		(size 0.508)
		(drill 0.254)
		(layers "F.Cu" "B.Cu")
		(net "GND")
	)
	(via
		(at 19.064224 -95.982282)
		(size 0.4572)
		(drill 0.254)
		(layers "F.Cu" "B.Cu")
		(net "GND")
	)
	(via
		(at 0.762 -86.900004)
		(size 0.508)
		(drill 0.254)
		(layers "F.Cu" "B.Cu")
		(net "GND")
	)
	(via
		(at 86.3092 -45.697394)
		(size 0.508)
		(drill 0.254)
		(layers "F.Cu" "B.Cu")
		(net "GND")
	)
	(via
		(at 37.6936 -39.56431)
		(size 0.508)
		(drill 0.254)
		(layers "F.Cu" "B.Cu")
		(net "GND")
	)
	(via
		(at 15.010638 -110.109508)
		(size 0.508)
		(drill 0.254)
		(layers "F.Cu" "B.Cu")
		(net "GND")
	)
	(via
		(at 20.8788 -78.4098)
		(size 0.508)
		(drill 0.254)
		(layers "F.Cu" "B.Cu")
		(net "GND")
	)
	(via
		(at 15.2146 -50.7746)
		(size 0.508)
		(drill 0.254)
		(layers "F.Cu" "B.Cu")
		(net "GND")
	)
	(via
		(at 32.7406 -64.998092)
		(size 0.508)
		(drill 0.254)
		(layers "F.Cu" "B.Cu")
		(net "GND")
	)
	(via
		(at 86.131654 -29.801312)
		(size 0.508)
		(drill 0.254)
		(layers "F.Cu" "B.Cu")
		(net "GND")
	)
	(via
		(at 42.9768 -88.7476)
		(size 0.508)
		(drill 0.254)
		(layers "F.Cu" "B.Cu")
		(net "GND")
	)
	(via
		(at 17.464278 -89.591896)
		(size 0.4572)
		(drill 0.254)
		(layers "F.Cu" "B.Cu")
		(net "GND")
	)
	(via
		(at 50.099722 -48.575976)
		(size 0.4572)
		(drill 0.254)
		(layers "F.Cu" "B.Cu")
		(net "GND")
	)
	(via
		(at 84.17687 -45.062394)
		(size 0.508)
		(drill 0.254)
		(layers "F.Cu" "B.Cu")
		(net "GND")
	)
	(via
		(at 37.856414 -116.5225)
		(size 0.508)
		(drill 0.254)
		(layers "F.Cu" "B.Cu")
		(net "GND")
	)
	(via
		(at 3.512058 -82.62874)
		(size 0.508)
		(drill 0.254)
		(layers "F.Cu" "B.Cu")
		(net "GND")
	)
	(via
		(at 67.823588 -3.090164)
		(size 0.508)
		(drill 0.254)
		(layers "F.Cu" "B.Cu")
		(net "GND")
	)
	(via
		(at 41.736772 -98.831908)
		(size 0.508)
		(drill 0.254)
		(layers "F.Cu" "B.Cu")
		(net "GND")
	)
	(via
		(at 72.63892 -41.525698)
		(size 0.4572)
		(drill 0.254)
		(layers "F.Cu" "B.Cu")
		(net "GND")
	)
	(via
		(at 36.056316 -56.965596)
		(size 0.508)
		(drill 0.254)
		(layers "F.Cu" "B.Cu")
		(net "GND")
	)
	(via
		(at 53.299868 -53.366416)
		(size 0.4572)
		(drill 0.254)
		(layers "F.Cu" "B.Cu")
		(net "GND")
	)
	(via
		(at 89.238074 -20.520152)
		(size 0.508)
		(drill 0.254)
		(layers "F.Cu" "B.Cu")
		(net "GND")
	)
	(via
		(at 15.864332 -99.182174)
		(size 0.4572)
		(drill 0.254)
		(layers "F.Cu" "B.Cu")
		(net "GND")
	)
	(via
		(at 77.10805 -13.847064)
		(size 0.508)
		(drill 0.254)
		(layers "F.Cu" "B.Cu")
		(net "GND")
	)
	(via
		(at 37.18306 -56.90616)
		(size 0.508)
		(drill 0.254)
		(layers "F.Cu" "B.Cu")
		(net "GND")
	)
	(via
		(at 4.572 -61.9506)
		(size 0.508)
		(drill 0.254)
		(layers "F.Cu" "B.Cu")
		(net "GND")
	)
	(via
		(at 80.62722 -75.09891)
		(size 0.508)
		(drill 0.254)
		(layers "F.Cu" "B.Cu")
		(net "GND")
	)
	(via
		(at 16.400018 -77.89291)
		(size 0.508)
		(drill 0.254)
		(layers "F.Cu" "B.Cu")
		(net "GND")
	)
	(via
		(at 84.17687 -39.982394)
		(size 0.508)
		(drill 0.254)
		(layers "F.Cu" "B.Cu")
		(net "GND")
	)
	(via
		(at 72.67067 -46.32579)
		(size 0.4572)
		(drill 0.254)
		(layers "F.Cu" "B.Cu")
		(net "GND")
	)
	(via
		(at 46.322488 -82.794094)
		(size 0.508)
		(drill 0.254)
		(layers "F.Cu" "B.Cu")
		(net "GND")
	)
	(via
		(at 78.105 -65.151)
		(size 0.508)
		(drill 0.254)
		(layers "F.Cu" "B.Cu")
		(net "GND")
	)
	(via
		(at 53.66131 -67.8942)
		(size 0.508)
		(drill 0.254)
		(layers "F.Cu" "B.Cu")
		(net "GND")
	)
	(via
		(at 45.299884 -41.376092)
		(size 0.4572)
		(drill 0.254)
		(layers "F.Cu" "B.Cu")
		(net "GND")
	)
	(via
		(at 47.699676 -46.17593)
		(size 0.4572)
		(drill 0.254)
		(layers "F.Cu" "B.Cu")
		(net "GND")
	)
	(via
		(at 58.890154 -58.966354)
		(size 0.4572)
		(drill 0.254)
		(layers "F.Cu" "B.Cu")
		(net "GND")
	)
	(via
		(at 44.216066 -59.589416)
		(size 0.4572)
		(drill 0.254)
		(layers "F.Cu" "B.Cu")
		(net "GND")
	)
	(via
		(at 24.500078 -82.091276)
		(size 0.508)
		(drill 0.254)
		(layers "F.Cu" "B.Cu")
		(net "GND")
	)
	(via
		(at 54.099714 -42.976038)
		(size 0.4572)
		(drill 0.254)
		(layers "F.Cu" "B.Cu")
		(net "GND")
	)
	(via
		(at 1.983486 -69.442838)
		(size 0.6604)
		(drill 0.3302)
		(layers "F.Cu" "B.Cu")
		(net "GND")
	)
	(via
		(at 73.406 -62.2046)
		(size 0.6604)
		(drill 0.3302)
		(layers "F.Cu" "B.Cu")
		(net "GND")
	)
	(via
		(at 65.290192 -57.37606)
		(size 0.4572)
		(drill 0.254)
		(layers "F.Cu" "B.Cu")
		(net "GND")
	)
	(via
		(at 89.238074 -66.240152)
		(size 0.508)
		(drill 0.254)
		(layers "F.Cu" "B.Cu")
		(net "GND")
	)
	(via
		(at 1.983486 -50.392838)
		(size 0.6604)
		(drill 0.3302)
		(layers "F.Cu" "B.Cu")
		(net "GND")
	)
	(via
		(at 56.812688 -73.84669)
		(size 0.508)
		(drill 0.254)
		(layers "F.Cu" "B.Cu")
		(net "GND")
	)
	(via
		(at 30.639004 -31.369)
		(size 0.508)
		(drill 0.254)
		(layers "F.Cu" "B.Cu")
		(net "GND")
	)
	(via
		(at 0.762 -47.877476)
		(size 0.508)
		(drill 0.254)
		(layers "F.Cu" "B.Cu")
		(net "GND")
	)
	(via
		(at 44.16552 -79.35722)
		(size 0.508)
		(drill 0.254)
		(layers "F.Cu" "B.Cu")
		(net "GND")
	)
	(via
		(at 0.762 -7.237476)
		(size 0.508)
		(drill 0.254)
		(layers "F.Cu" "B.Cu")
		(net "GND")
	)
	(via
		(at 68.18249 -30.854904)
		(size 0.508)
		(drill 0.254)
		(layers "F.Cu" "B.Cu")
		(net "GND")
	)
	(via
		(at 13.24737 -30.789372)
		(size 0.508)
		(drill 0.254)
		(layers "F.Cu" "B.Cu")
		(net "GND")
	)
	(via
		(at 80.752188 -57.498742)
		(size 0.508)
		(drill 0.254)
		(layers "F.Cu" "B.Cu")
		(net "GND")
	)
	(via
		(at 50.363374 -25.726644)
		(size 0.508)
		(drill 0.254)
		(layers "F.Cu" "B.Cu")
		(net "GND")
	)
	(via
		(at 67.3354 -107.696)
		(size 0.508)
		(drill 0.254)
		(layers "F.Cu" "B.Cu")
		(net "GND")
	)
	(via
		(at 5.34289 -63.483998)
		(size 0.508)
		(drill 0.254)
		(layers "F.Cu" "B.Cu")
		(net "GND")
	)
	(via
		(at 89.238074 -10.360152)
		(size 0.508)
		(drill 0.254)
		(layers "F.Cu" "B.Cu")
		(net "GND")
	)
	(via
		(at 39.8526 -97.9678)
		(size 0.508)
		(drill 0.254)
		(layers "F.Cu" "B.Cu")
		(net "GND")
	)
	(via
		(at 19.49958 -108.341922)
		(size 0.508)
		(drill 0.254)
		(layers "F.Cu" "B.Cu")
		(net "GND")
	)
	(via
		(at 21.9202 -100.9904)
		(size 0.508)
		(drill 0.254)
		(layers "F.Cu" "B.Cu")
		(net "GND")
	)
	(via
		(at 4.223004 -50.456592)
		(size 0.508)
		(drill 0.254)
		(layers "F.Cu" "B.Cu")
		(net "GND")
	)
	(via
		(at 68.24345 -18.8976)
		(size 0.508)
		(drill 0.254)
		(layers "F.Cu" "B.Cu")
		(net "GND")
	)
	(via
		(at 26.259282 -98.3869)
		(size 0.4572)
		(drill 0.254)
		(layers "F.Cu" "B.Cu")
		(net "GND")
	)
	(via
		(at 40.954198 -47.19701)
		(size 0.508)
		(drill 0.254)
		(layers "F.Cu" "B.Cu")
		(net "GND")
	)
	(via
		(at 88.71966 -85.762084)
		(size 0.508)
		(drill 0.254)
		(layers "F.Cu" "B.Cu")
		(net "GND")
	)
	(via
		(at 29.2608 -24.9428)
		(size 0.508)
		(drill 0.254)
		(layers "F.Cu" "B.Cu")
		(net "GND")
	)
	(via
		(at 47.699676 -54.166516)
		(size 0.4572)
		(drill 0.254)
		(layers "F.Cu" "B.Cu")
		(net "GND")
	)
	(via
		(at 32.849312 -31.115)
		(size 0.508)
		(drill 0.254)
		(layers "F.Cu" "B.Cu")
		(net "GND")
	)
	(via
		(at 2.389378 -2.680716)
		(size 0.508)
		(drill 0.254)
		(layers "F.Cu" "B.Cu")
		(net "GND")
	)
	(via
		(at 45.299884 -57.366408)
		(size 0.4572)
		(drill 0.254)
		(layers "F.Cu" "B.Cu")
		(net "GND")
	)
	(via
		(at 62.099698 -58.166508)
		(size 0.4572)
		(drill 0.254)
		(layers "F.Cu" "B.Cu")
		(net "GND")
	)
	(via
		(at 6.025642 -31.442914)
		(size 0.508)
		(drill 0.254)
		(layers "F.Cu" "B.Cu")
		(net "GND")
	)
	(via
		(at 22.254718 -92.791788)
		(size 0.4572)
		(drill 0.254)
		(layers "F.Cu" "B.Cu")
		(net "GND")
	)
	(via
		(at 16.664178 -98.382328)
		(size 0.4572)
		(drill 0.254)
		(layers "F.Cu" "B.Cu")
		(net "GND")
	)
	(via
		(at 26.2636 -106.68)
		(size 0.508)
		(drill 0.254)
		(layers "F.Cu" "B.Cu")
		(net "GND")
	)
	(via
		(at 0.762 -52.957476)
		(size 0.508)
		(drill 0.254)
		(layers "F.Cu" "B.Cu")
		(net "GND")
	)
	(via
		(at 62.0903 -40.575992)
		(size 0.4572)
		(drill 0.254)
		(layers "F.Cu" "B.Cu")
		(net "GND")
	)
	(via
		(at 20.833588 -77.0509)
		(size 0.508)
		(drill 0.254)
		(layers "F.Cu" "B.Cu")
		(net "GND")
	)
	(via
		(at 4.858766 -49.745392)
		(size 0.508)
		(drill 0.254)
		(layers "F.Cu" "B.Cu")
		(net "GND")
	)
	(via
		(at 10.343642 -30.680914)
		(size 0.508)
		(drill 0.254)
		(layers "F.Cu" "B.Cu")
		(net "GND")
	)
	(via
		(at 59.2582 -90.65006)
		(size 0.508)
		(drill 0.254)
		(layers "F.Cu" "B.Cu")
		(net "GND")
	)
	(via
		(at 84.44738 -100.099368)
		(size 0.508)
		(drill 0.254)
		(layers "F.Cu" "B.Cu")
		(net "GND")
	)
	(via
		(at 12.20089 -48.64989)
		(size 0.508)
		(drill 0.254)
		(layers "F.Cu" "B.Cu")
		(net "GND")
	)
	(via
		(at 5.38607 -59.122818)
		(size 0.508)
		(drill 0.254)
		(layers "F.Cu" "B.Cu")
		(net "GND")
	)
	(via
		(at 72.67067 -50.289206)
		(size 0.4572)
		(drill 0.254)
		(layers "F.Cu" "B.Cu")
		(net "GND")
	)
	(via
		(at 6.555994 -81.1276)
		(size 0.508)
		(drill 0.254)
		(layers "F.Cu" "B.Cu")
		(net "GND")
	)
	(via
		(at 54.8132 -17.6022)
		(size 0.508)
		(drill 0.254)
		(layers "F.Cu" "B.Cu")
		(net "GND")
	)
	(via
		(at 24.792432 -85.225636)
		(size 0.508)
		(drill 0.254)
		(layers "F.Cu" "B.Cu")
		(net "GND")
	)
	(via
		(at 78.613 -80.01)
		(size 0.508)
		(drill 0.254)
		(layers "F.Cu" "B.Cu")
		(net "GND")
	)
	(via
		(at 71.944992 -36.079684)
		(size 0.508)
		(drill 0.254)
		(layers "F.Cu" "B.Cu")
		(net "GND")
	)
	(via
		(at 58.6232 -14.633702)
		(size 0.508)
		(drill 0.254)
		(layers "F.Cu" "B.Cu")
		(net "GND")
	)
	(via
		(at 55.39359 -112.90808)
		(size 0.508)
		(drill 0.254)
		(layers "F.Cu" "B.Cu")
		(net "GND")
	)
	(via
		(at 60.794138 -20.182078)
		(size 0.508)
		(drill 0.254)
		(layers "F.Cu" "B.Cu")
		(net "GND")
	)
	(via
		(at 35.780726 -28.619958)
		(size 0.508)
		(drill 0.254)
		(layers "F.Cu" "B.Cu")
		(net "GND")
	)
	(via
		(at 68.35013 -8.79475)
		(size 0.508)
		(drill 0.254)
		(layers "F.Cu" "B.Cu")
		(net "GND")
	)
	(via
		(at 71.599806 -73.059544)
		(size 0.762)
		(drill 0.254)
		(layers "F.Cu" "B.Cu")
		(net "GND")
	)
	(via
		(at 20.0152 -107.6452)
		(size 0.508)
		(drill 0.254)
		(layers "F.Cu" "B.Cu")
		(net "GND")
	)
	(via
		(at 49.994058 -61.048646)
		(size 0.508)
		(drill 0.254)
		(layers "F.Cu" "B.Cu")
		(net "GND")
	)
	(via
		(at 4.318 -52.836318)
		(size 0.508)
		(drill 0.254)
		(layers "F.Cu" "B.Cu")
		(net "GND")
	)
	(via
		(at 53.299868 -50.166524)
		(size 0.4572)
		(drill 0.254)
		(layers "F.Cu" "B.Cu")
		(net "GND")
	)
	(via
		(at 0.762 -32.637476)
		(size 0.508)
		(drill 0.254)
		(layers "F.Cu" "B.Cu")
		(net "GND")
	)
	(via
		(at 0.762 -2.157476)
		(size 0.508)
		(drill 0.254)
		(layers "F.Cu" "B.Cu")
		(net "GND")
	)
	(via
		(at 0.762 -107.220004)
		(size 0.508)
		(drill 0.254)
		(layers "F.Cu" "B.Cu")
		(net "GND")
	)
	(via
		(at 8.4074 -99.5934)
		(size 0.508)
		(drill 0.254)
		(layers "F.Cu" "B.Cu")
		(net "GND")
	)
	(via
		(at 17.464278 -97.582228)
		(size 0.4572)
		(drill 0.254)
		(layers "F.Cu" "B.Cu")
		(net "GND")
	)
	(via
		(at 79.96428 -75.216512)
		(size 0.508)
		(drill 0.254)
		(layers "F.Cu" "B.Cu")
		(net "GND")
	)
	(via
		(at 73.470516 -54.289198)
		(size 0.4572)
		(drill 0.254)
		(layers "F.Cu" "B.Cu")
		(net "GND")
	)
	(via
		(at 51.868578 -70.6628)
		(size 0.762)
		(drill 0.254)
		(layers "F.Cu" "B.Cu")
		(net "GND")
	)
	(via
		(at 51.363372 -0.762)
		(size 0.508)
		(drill 0.254)
		(layers "F.Cu" "B.Cu")
		(net "GND")
	)
	(via
		(at 56.490108 -54.166516)
		(size 0.4572)
		(drill 0.254)
		(layers "F.Cu" "B.Cu")
		(net "GND")
	)
	(via
		(at 84.44738 -100.861368)
		(size 0.508)
		(drill 0.254)
		(layers "F.Cu" "B.Cu")
		(net "GND")
	)
	(via
		(at 72.644 -17.26565)
		(size 0.508)
		(drill 0.254)
		(layers "F.Cu" "B.Cu")
		(net "GND")
	)
	(via
		(at 25.144984 -116.40185)
		(size 0.508)
		(drill 0.254)
		(layers "F.Cu" "B.Cu")
		(net "GND")
	)
	(via
		(at 36.8554 -53.0352)
		(size 0.6604)
		(drill 0.3302)
		(layers "F.Cu" "B.Cu")
		(net "GND")
	)
	(via
		(at 13.529818 -27.709876)
		(size 0.508)
		(drill 0.254)
		(layers "F.Cu" "B.Cu")
		(net "GND")
	)
	(via
		(at 81.340706 -38.37305)
		(size 0.508)
		(drill 0.254)
		(layers "F.Cu" "B.Cu")
		(net "GND")
	)
	(via
		(at 12.5476 -41.0972)
		(size 0.6604)
		(drill 0.3302)
		(layers "F.Cu" "B.Cu")
		(net "GND")
	)
	(via
		(at 89.238074 -15.440152)
		(size 0.508)
		(drill 0.254)
		(layers "F.Cu" "B.Cu")
		(net "GND")
	)
	(via
		(at 25.963372 -0.762)
		(size 0.508)
		(drill 0.254)
		(layers "F.Cu" "B.Cu")
		(net "GND")
	)
	(via
		(at 53.299868 -46.17593)
		(size 0.4572)
		(drill 0.254)
		(layers "F.Cu" "B.Cu")
		(net "GND")
	)
	(via
		(at 66.876676 -38.954964)
		(size 0.508)
		(drill 0.254)
		(layers "F.Cu" "B.Cu")
		(net "GND")
	)
	(via
		(at 85.1916 -33.8836)
		(size 0.6604)
		(drill 0.3302)
		(layers "F.Cu" "B.Cu")
		(net "GND")
	)
	(via
		(at 58.890154 -48.575976)
		(size 0.4572)
		(drill 0.254)
		(layers "F.Cu" "B.Cu")
		(net "GND")
	)
	(via
		(at 87.2744 -30.2006)
		(size 0.762)
		(drill 0.381)
		(layers "F.Cu" "B.Cu")
		(net "GND")
	)
	(via
		(at 63.782702 -26.141426)
		(size 0.508)
		(drill 0.254)
		(layers "F.Cu" "B.Cu")
		(net "GND")
	)
	(via
		(at 55.69966 -48.566578)
		(size 0.4572)
		(drill 0.254)
		(layers "F.Cu" "B.Cu")
		(net "GND")
	)
	(via
		(at 55.690262 -58.966354)
		(size 0.4572)
		(drill 0.254)
		(layers "F.Cu" "B.Cu")
		(net "GND")
	)
	(via
		(at 83.641438 -34.186876)
		(size 0.508)
		(drill 0.254)
		(layers "F.Cu" "B.Cu")
		(net "GND")
	)
	(via
		(at 31.500064 -79.701136)
		(size 0.508)
		(drill 0.254)
		(layers "F.Cu" "B.Cu")
		(net "GND")
	)
	(via
		(at 39.949628 -98.831908)
		(size 0.508)
		(drill 0.254)
		(layers "F.Cu" "B.Cu")
		(net "GND")
	)
	(via
		(at 82.63128 -99.089972)
		(size 0.508)
		(drill 0.254)
		(layers "F.Cu" "B.Cu")
		(net "GND")
	)
	(via
		(at 0.762 -73.277476)
		(size 0.508)
		(drill 0.254)
		(layers "F.Cu" "B.Cu")
		(net "GND")
	)
	(via
		(at 57.97042 -99.15906)
		(size 0.508)
		(drill 0.254)
		(layers "F.Cu" "B.Cu")
		(net "GND")
	)
	(via
		(at 74.2188 -39.3446)
		(size 0.6604)
		(drill 0.3302)
		(layers "F.Cu" "B.Cu")
		(net "GND")
	)
	(via
		(at 66.77152 -45.460158)
		(size 0.4572)
		(drill 0.254)
		(layers "F.Cu" "B.Cu")
		(net "GND")
	)
	(via
		(at 35.780726 -30.619954)
		(size 0.508)
		(drill 0.254)
		(layers "F.Cu" "B.Cu")
		(net "GND")
	)
	(via
		(at 4.572 -60.4266)
		(size 0.508)
		(drill 0.254)
		(layers "F.Cu" "B.Cu")
		(net "GND")
	)
	(via
		(at 29.974286 -79.0448)
		(size 0.508)
		(drill 0.254)
		(layers "F.Cu" "B.Cu")
		(net "GND")
	)
	(via
		(at 41.85666 -86.6394)
		(size 0.508)
		(drill 0.254)
		(layers "F.Cu" "B.Cu")
		(net "GND")
	)
	(via
		(at 60.499752 -57.366408)
		(size 0.4572)
		(drill 0.254)
		(layers "F.Cu" "B.Cu")
		(net "GND")
	)
	(via
		(at 31.568898 -103.190548)
		(size 0.508)
		(drill 0.254)
		(layers "F.Cu" "B.Cu")
		(net "GND")
	)
	(via
		(at 47.567088 -21.455888)
		(size 0.508)
		(drill 0.254)
		(layers "F.Cu" "B.Cu")
		(net "GND")
	)
	(via
		(at 61.523372 -0.762)
		(size 0.508)
		(drill 0.254)
		(layers "F.Cu" "B.Cu")
		(net "GND")
	)
	(via
		(at 13.208 -58.5216)
		(size 0.508)
		(drill 0.254)
		(layers "F.Cu" "B.Cu")
		(net "GND")
	)
	(via
		(at 82.139536 -40.990012)
		(size 0.508)
		(drill 0.254)
		(layers "F.Cu" "B.Cu")
		(net "GND")
	)
	(via
		(at 79.034132 -51.889152)
		(size 0.4572)
		(drill 0.254)
		(layers "F.Cu" "B.Cu")
		(net "GND")
	)
	(via
		(at 53.1622 -116.2558)
		(size 0.508)
		(drill 0.254)
		(layers "F.Cu" "B.Cu")
		(net "GND")
	)
	(via
		(at 17.540478 -106.6038)
		(size 0.508)
		(drill 0.254)
		(layers "F.Cu" "B.Cu")
		(net "GND")
	)
	(via
		(at 86.3092 -43.157394)
		(size 0.508)
		(drill 0.254)
		(layers "F.Cu" "B.Cu")
		(net "GND")
	)
	(via
		(at 47.217838 -63.483744)
		(size 0.508)
		(drill 0.254)
		(layers "F.Cu" "B.Cu")
		(net "GND")
	)
	(via
		(at 19.376136 -71.23938)
		(size 0.508)
		(drill 0.254)
		(layers "F.Cu" "B.Cu")
		(net "GND")
	)
	(via
		(at 47.17415 -78.05928)
		(size 0.508)
		(drill 0.254)
		(layers "F.Cu" "B.Cu")
		(net "GND")
	)
	(via
		(at 41.57726 -68.22694)
		(size 0.508)
		(drill 0.254)
		(layers "F.Cu" "B.Cu")
		(net "GND")
	)
	(via
		(at 48.3108 -25.527)
		(size 0.508)
		(drill 0.254)
		(layers "F.Cu" "B.Cu")
		(net "GND")
	)
	(via
		(at 4.858766 -51.167792)
		(size 0.508)
		(drill 0.254)
		(layers "F.Cu" "B.Cu")
		(net "GND")
	)
	(via
		(at 82.139536 -43.022012)
		(size 0.508)
		(drill 0.254)
		(layers "F.Cu" "B.Cu")
		(net "GND")
	)
	(via
		(at 37.2872 -20.066)
		(size 0.508)
		(drill 0.254)
		(layers "F.Cu" "B.Cu")
		(net "GND")
	)
	(via
		(at 82.139536 -39.974012)
		(size 0.508)
		(drill 0.254)
		(layers "F.Cu" "B.Cu")
		(net "GND")
	)
	(via
		(at 16.7132 -66.26225)
		(size 0.508)
		(drill 0.254)
		(layers "F.Cu" "B.Cu")
		(net "GND")
	)
	(via
		(at 9.915906 -79.230982)
		(size 0.508)
		(drill 0.254)
		(layers "F.Cu" "B.Cu")
		(net "GND")
	)
	(via
		(at 40.353742 -23.869904)
		(size 0.508)
		(drill 0.254)
		(layers "F.Cu" "B.Cu")
		(net "GND")
	)
	(via
		(at 44.2976 -63.280544)
		(size 0.508)
		(drill 0.254)
		(layers "F.Cu" "B.Cu")
		(net "GND")
	)
	(via
		(at 50.899822 -42.976038)
		(size 0.4572)
		(drill 0.254)
		(layers "F.Cu" "B.Cu")
		(net "GND")
	)
	(via
		(at 54.25694 -78.4352)
		(size 0.508)
		(drill 0.254)
		(layers "F.Cu" "B.Cu")
		(net "GND")
	)
	(via
		(at 7.782052 -79.237078)
		(size 0.508)
		(drill 0.254)
		(layers "F.Cu" "B.Cu")
		(net "GND")
	)
	(via
		(at 55.5244 -17.6022)
		(size 0.508)
		(drill 0.254)
		(layers "F.Cu" "B.Cu")
		(net "GND")
	)
	(via
		(at 67.544188 -89.976452)
		(size 0.508)
		(drill 0.254)
		(layers "F.Cu" "B.Cu")
		(net "GND")
	)
	(via
		(at 32.4866 -11.43)
		(size 0.508)
		(drill 0.254)
		(layers "F.Cu" "B.Cu")
		(net "GND")
	)
	(via
		(at 11.157204 -15.810992)
		(size 0.508)
		(drill 0.254)
		(layers "F.Cu" "B.Cu")
		(net "GND")
	)
	(via
		(at 1.983486 -54.202838)
		(size 0.6604)
		(drill 0.3302)
		(layers "F.Cu" "B.Cu")
		(net "GND")
	)
	(via
		(at 85.811868 -32.647382)
		(size 0.508)
		(drill 0.254)
		(layers "F.Cu" "B.Cu")
		(net "GND")
	)
	(via
		(at 54.1274 -17.6022)
		(size 0.508)
		(drill 0.254)
		(layers "F.Cu" "B.Cu")
		(net "GND")
	)
	(via
		(at 12.04976 -79.26832)
		(size 0.508)
		(drill 0.254)
		(layers "F.Cu" "B.Cu")
		(net "GND")
	)
	(via
		(at 18.28038 -34.516822)
		(size 0.508)
		(drill 0.254)
		(layers "F.Cu" "B.Cu")
		(net "GND")
	)
	(via
		(at 69.723 -33.433766)
		(size 0.508)
		(drill 0.254)
		(layers "F.Cu" "B.Cu")
		(net "GND")
	)
	(via
		(at 8.128 -82.8802)
		(size 0.508)
		(drill 0.254)
		(layers "F.Cu" "B.Cu")
		(net "GND")
	)
	(via
		(at 32.3342 -99.7204)
		(size 0.508)
		(drill 0.254)
		(layers "F.Cu" "B.Cu")
		(net "GND")
	)
	(via
		(at 74.089006 -115.293648)
		(size 0.508)
		(drill 0.254)
		(layers "F.Cu" "B.Cu")
		(net "GND")
	)
	(via
		(at 63.7286 -23.0886)
		(size 0.508)
		(drill 0.254)
		(layers "F.Cu" "B.Cu")
		(net "GND")
	)
	(via
		(at 76.48448 -57.510934)
		(size 0.508)
		(drill 0.254)
		(layers "F.Cu" "B.Cu")
		(net "GND")
	)
	(via
		(at 24.4856 -34.91865)
		(size 0.508)
		(drill 0.254)
		(layers "F.Cu" "B.Cu")
		(net "GND")
	)
	(via
		(at 85.423248 -72.733408)
		(size 0.508)
		(drill 0.254)
		(layers "F.Cu" "B.Cu")
		(net "GND")
	)
	(via
		(at 71.73976 -13.193014)
		(size 0.508)
		(drill 0.254)
		(layers "F.Cu" "B.Cu")
		(net "GND")
	)
	(via
		(at 59.690254 -42.175938)
		(size 0.4572)
		(drill 0.254)
		(layers "F.Cu" "B.Cu")
		(net "GND")
	)
	(via
		(at 20.793456 -75.6666)
		(size 0.508)
		(drill 0.254)
		(layers "F.Cu" "B.Cu")
		(net "GND")
	)
	(via
		(at 0.762 -17.397476)
		(size 0.508)
		(drill 0.254)
		(layers "F.Cu" "B.Cu")
		(net "GND")
	)
	(via
		(at 89.238074 -111.132874)
		(size 0.508)
		(drill 0.254)
		(layers "F.Cu" "B.Cu")
		(net "GND")
	)
	(via
		(at 32.15005 -28.299664)
		(size 0.508)
		(drill 0.254)
		(layers "F.Cu" "B.Cu")
		(net "GND")
	)
	(via
		(at 59.690254 -55.766462)
		(size 0.4572)
		(drill 0.254)
		(layers "F.Cu" "B.Cu")
		(net "GND")
	)
	(via
		(at 71.308976 -36.08578)
		(size 0.508)
		(drill 0.254)
		(layers "F.Cu" "B.Cu")
		(net "GND")
	)
	(via
		(at 20.893024 -113.176558)
		(size 0.508)
		(drill 0.254)
		(layers "F.Cu" "B.Cu")
		(net "GND")
	)
	(via
		(at 42.0878 -2.8194)
		(size 0.508)
		(drill 0.254)
		(layers "F.Cu" "B.Cu")
		(net "GND")
	)
	(via
		(at 82.139536 -45.054012)
		(size 0.508)
		(drill 0.254)
		(layers "F.Cu" "B.Cu")
		(net "GND")
	)
	(via
		(at 73.08215 -92.322142)
		(size 0.508)
		(drill 0.254)
		(layers "F.Cu" "B.Cu")
		(net "GND")
	)
	(via
		(at 69.651626 -13.116814)
		(size 0.508)
		(drill 0.254)
		(layers "F.Cu" "B.Cu")
		(net "GND")
	)
	(via
		(at 59.124342 -68.461128)
		(size 0.508)
		(drill 0.254)
		(layers "F.Cu" "B.Cu")
		(net "GND")
	)
	(via
		(at 58.090308 -42.976038)
		(size 0.4572)
		(drill 0.254)
		(layers "F.Cu" "B.Cu")
		(net "GND")
	)
	(via
		(at 19.064224 -91.191842)
		(size 0.4572)
		(drill 0.254)
		(layers "F.Cu" "B.Cu")
		(net "GND")
	)
	(via
		(at 58.090308 -48.575976)
		(size 0.4572)
		(drill 0.254)
		(layers "F.Cu" "B.Cu")
		(net "GND")
	)
	(via
		(at 76.691744 -34.492438)
		(size 0.508)
		(drill 0.254)
		(layers "F.Cu" "B.Cu")
		(net "GND")
	)
	(via
		(at 20.7264 -61.341)
		(size 0.508)
		(drill 0.254)
		(layers "F.Cu" "B.Cu")
		(net "GND")
	)
	(via
		(at 36.26612 -67.77482)
		(size 0.508)
		(drill 0.254)
		(layers "F.Cu" "B.Cu")
		(net "GND")
	)
	(via
		(at 64.616838 -26.339038)
		(size 0.508)
		(drill 0.254)
		(layers "F.Cu" "B.Cu")
		(net "GND")
	)
	(via
		(at 21.660104 -113.1697)
		(size 0.508)
		(drill 0.254)
		(layers "F.Cu" "B.Cu")
		(net "GND")
	)
	(via
		(at 17.9451 -116.8654)
		(size 0.508)
		(drill 0.254)
		(layers "F.Cu" "B.Cu")
		(net "GND")
	)
	(via
		(at 23.854664 -91.191842)
		(size 0.4572)
		(drill 0.254)
		(layers "F.Cu" "B.Cu")
		(net "GND")
	)
	(via
		(at 54.8386 -18.7452)
		(size 0.762)
		(drill 0.381)
		(layers "F.Cu" "B.Cu")
		(net "GND")
	)
	(via
		(at 55.690262 -45.376084)
		(size 0.4572)
		(drill 0.254)
		(layers "F.Cu" "B.Cu")
		(net "GND")
	)
	(via
		(at 24.892 -19.177)
		(size 0.508)
		(drill 0.254)
		(layers "F.Cu" "B.Cu")
		(net "GND")
	)
	(via
		(at 47.21225 -105.422954)
		(size 0.508)
		(drill 0.254)
		(layers "F.Cu" "B.Cu")
		(net "GND")
	)
	(via
		(at 0.762 -22.477476)
		(size 0.508)
		(drill 0.254)
		(layers "F.Cu" "B.Cu")
		(net "GND")
	)
	(via
		(at 68.961 -113.4872)
		(size 0.508)
		(drill 0.254)
		(layers "F.Cu" "B.Cu")
		(net "GND")
	)
	(via
		(at 84.297774 -28.602432)
		(size 0.508)
		(drill 0.254)
		(layers "F.Cu" "B.Cu")
		(net "GND")
	)
	(via
		(at 68.171314 -52.644548)
		(size 0.4572)
		(drill 0.254)
		(layers "F.Cu" "B.Cu")
		(net "GND")
	)
	(via
		(at 46.765972 -98.400108)
		(size 0.508)
		(drill 0.254)
		(layers "F.Cu" "B.Cu")
		(net "GND")
	)
	(via
		(at 64.0842 -27.346656)
		(size 0.508)
		(drill 0.254)
		(layers "F.Cu" "B.Cu")
		(net "GND")
	)
	(via
		(at 21.5392 -87.4014)
		(size 0.6604)
		(drill 0.3302)
		(layers "F.Cu" "B.Cu")
		(net "GND")
	)
	(via
		(at 85.019642 -58.353452)
		(size 0.508)
		(drill 0.254)
		(layers "F.Cu" "B.Cu")
		(net "GND")
	)
	(via
		(at 61.3156 -83.3374)
		(size 0.508)
		(drill 0.254)
		(layers "F.Cu" "B.Cu")
		(net "GND")
	)
	(via
		(at 53.295296 -26.954988)
		(size 0.508)
		(drill 0.254)
		(layers "F.Cu" "B.Cu")
		(net "GND")
	)
	(via
		(at 86.2838 -75.1586)
		(size 0.508)
		(drill 0.254)
		(layers "F.Cu" "B.Cu")
		(net "GND")
	)
	(via
		(at 61.2902 -48.575976)
		(size 0.4572)
		(drill 0.254)
		(layers "F.Cu" "B.Cu")
		(net "GND")
	)
	(via
		(at 17.92732 -42.463466)
		(size 0.508)
		(drill 0.254)
		(layers "F.Cu" "B.Cu")
		(net "GND")
	)
	(via
		(at 69.1134 -100.6602)
		(size 0.508)
		(drill 0.254)
		(layers "F.Cu" "B.Cu")
		(net "GND")
	)
	(via
		(at 64.490092 -45.376084)
		(size 0.4572)
		(drill 0.254)
		(layers "F.Cu" "B.Cu")
		(net "GND")
	)
	(via
		(at 24.74976 -72.03186)
		(size 0.508)
		(drill 0.254)
		(layers "F.Cu" "B.Cu")
		(net "GND")
	)
	(via
		(at 22.225 -60.2742)
		(size 0.508)
		(drill 0.254)
		(layers "F.Cu" "B.Cu")
		(net "GND")
	)
	(via
		(at 36.195 -87.8332)
		(size 0.508)
		(drill 0.254)
		(layers "F.Cu" "B.Cu")
		(net "GND")
	)
	(via
		(at 62.890146 -51.76647)
		(size 0.4572)
		(drill 0.254)
		(layers "F.Cu" "B.Cu")
		(net "GND")
	)
	(via
		(at 21.7424 -75.7174)
		(size 0.508)
		(drill 0.254)
		(layers "F.Cu" "B.Cu")
		(net "GND")
	)
	(via
		(at 84.238084 -118.500144)
		(size 0.508)
		(drill 0.254)
		(layers "F.Cu" "B.Cu")
		(net "GND")
	)
	(via
		(at 84.864448 -113.707672)
		(size 0.508)
		(drill 0.254)
		(layers "F.Cu" "B.Cu")
		(net "GND")
	)
	(via
		(at 10.343642 -31.442914)
		(size 0.508)
		(drill 0.254)
		(layers "F.Cu" "B.Cu")
		(net "GND")
	)
	(via
		(at 62.0903 -39.776146)
		(size 0.4572)
		(drill 0.254)
		(layers "F.Cu" "B.Cu")
		(net "GND")
	)
	(via
		(at 56.261 -31.7754)
		(size 0.508)
		(drill 0.254)
		(layers "F.Cu" "B.Cu")
		(net "GND")
	)
	(via
		(at 8.184642 -30.680914)
		(size 0.508)
		(drill 0.254)
		(layers "F.Cu" "B.Cu")
		(net "GND")
	)
	(via
		(at 84.9884 -97.3582)
		(size 0.508)
		(drill 0.254)
		(layers "F.Cu" "B.Cu")
		(net "GND")
	)
	(via
		(at 25.45715 -112.554258)
		(size 0.508)
		(drill 0.254)
		(layers "F.Cu" "B.Cu")
		(net "GND")
	)
	(via
		(at 4.572 -62.7126)
		(size 0.508)
		(drill 0.254)
		(layers "F.Cu" "B.Cu")
		(net "GND")
	)
	(via
		(at 74.7268 -32.7152)
		(size 0.508)
		(drill 0.254)
		(layers "F.Cu" "B.Cu")
		(net "GND")
	)
	(via
		(at 54.61 -116.4844)
		(size 0.508)
		(drill 0.254)
		(layers "F.Cu" "B.Cu")
		(net "GND")
	)
	(via
		(at 84.297774 -27.582622)
		(size 0.508)
		(drill 0.254)
		(layers "F.Cu" "B.Cu")
		(net "GND")
	)
	(via
		(at 86.3092 -44.935394)
		(size 0.508)
		(drill 0.254)
		(layers "F.Cu" "B.Cu")
		(net "GND")
	)
	(via
		(at 45.299884 -43.776138)
		(size 0.4572)
		(drill 0.254)
		(layers "F.Cu" "B.Cu")
		(net "GND")
	)
	(via
		(at 81.9658 -75.2094)
		(size 0.6604)
		(drill 0.3302)
		(layers "F.Cu" "B.Cu")
		(net "GND")
	)
	(via
		(at 18.288 -59.92495)
		(size 0.508)
		(drill 0.254)
		(layers "F.Cu" "B.Cu")
		(net "GND")
	)
	(via
		(at 17.381728 -38.645338)
		(size 0.508)
		(drill 0.254)
		(layers "F.Cu" "B.Cu")
		(net "GND")
	)
	(via
		(at 52.10302 -71.628)
		(size 0.508)
		(drill 0.254)
		(layers "F.Cu" "B.Cu")
		(net "GND")
	)
	(via
		(at 0.762 -58.037476)
		(size 0.508)
		(drill 0.254)
		(layers "F.Cu" "B.Cu")
		(net "GND")
	)
	(via
		(at 85.599016 -51.336702)
		(size 0.762)
		(drill 0.254)
		(layers "F.Cu" "B.Cu")
		(net "GND")
	)
	(via
		(at 19.431 -16.891)
		(size 0.508)
		(drill 0.254)
		(layers "F.Cu" "B.Cu")
		(net "GND")
	)
	(via
		(at 1.9812 -49.3776)
		(size 0.762)
		(drill 0.381)
		(layers "F.Cu" "B.Cu")
		(net "GND")
	)
	(via
		(at 72.67067 -51.089306)
		(size 0.4572)
		(drill 0.254)
		(layers "F.Cu" "B.Cu")
		(net "GND")
	)
	(via
		(at 79.789528 -78.785212)
		(size 0.508)
		(drill 0.254)
		(layers "F.Cu" "B.Cu")
		(net "GND")
	)
	(via
		(at 59.690254 -50.96637)
		(size 0.4572)
		(drill 0.254)
		(layers "F.Cu" "B.Cu")
		(net "GND")
	)
	(via
		(at 19.431 -68.7578)
		(size 0.508)
		(drill 0.254)
		(layers "F.Cu" "B.Cu")
		(net "GND")
	)
	(via
		(at 89.238074 -71.320152)
		(size 0.508)
		(drill 0.254)
		(layers "F.Cu" "B.Cu")
		(net "GND")
	)
	(via
		(at 14.898116 -73.81367)
		(size 0.508)
		(drill 0.254)
		(layers "F.Cu" "B.Cu")
		(net "GND")
	)
	(via
		(at 57.262014 -71.695818)
		(size 0.508)
		(drill 0.254)
		(layers "F.Cu" "B.Cu")
		(net "GND")
	)
	(via
		(at 58.090308 -55.766462)
		(size 0.4572)
		(drill 0.254)
		(layers "F.Cu" "B.Cu")
		(net "GND")
	)
	(via
		(at 30.664404 -26.67)
		(size 0.508)
		(drill 0.254)
		(layers "F.Cu" "B.Cu")
		(net "GND")
	)
	(via
		(at 46.023276 -74.694796)
		(size 0.508)
		(drill 0.254)
		(layers "F.Cu" "B.Cu")
		(net "GND")
	)
	(via
		(at 54.7624 -80.4672)
		(size 0.508)
		(drill 0.254)
		(layers "F.Cu" "B.Cu")
		(net "GND")
	)
	(via
		(at 89.238074 -90.812874)
		(size 0.508)
		(drill 0.254)
		(layers "F.Cu" "B.Cu")
		(net "GND")
	)
	(via
		(at 4.699 -41.4782)
		(size 0.6604)
		(drill 0.3302)
		(layers "F.Cu" "B.Cu")
		(net "GND")
	)
	(via
		(at 78.234032 -41.525698)
		(size 0.4572)
		(drill 0.254)
		(layers "F.Cu" "B.Cu")
		(net "GND")
	)
	(via
		(at 47.699676 -40.575992)
		(size 0.4572)
		(drill 0.254)
		(layers "F.Cu" "B.Cu")
		(net "GND")
	)
	(via
		(at 65.290192 -59.766454)
		(size 0.4572)
		(drill 0.254)
		(layers "F.Cu" "B.Cu")
		(net "GND")
	)
	(via
		(at 21.717 -82.1436)
		(size 0.508)
		(drill 0.254)
		(layers "F.Cu" "B.Cu")
		(net "GND")
	)
	(via
		(at 37.084 -54.9529)
		(size 0.508)
		(drill 0.254)
		(layers "F.Cu" "B.Cu")
		(net "GND")
	)
	(via
		(at 1.983486 -65.632838)
		(size 0.6604)
		(drill 0.3302)
		(layers "F.Cu" "B.Cu")
		(net "GND")
	)
	(via
		(at 7.112 -56.769)
		(size 0.6604)
		(drill 0.3302)
		(layers "F.Cu" "B.Cu")
		(net "GND")
	)
	(via
		(at 53.6448 -35.690302)
		(size 0.508)
		(drill 0.254)
		(layers "F.Cu" "B.Cu")
		(net "GND")
	)
	(via
		(at 1.983486 -46.582838)
		(size 0.6604)
		(drill 0.3302)
		(layers "F.Cu" "B.Cu")
		(net "GND")
	)
	(via
		(at 17.141444 -47.349156)
		(size 0.508)
		(drill 0.254)
		(layers "F.Cu" "B.Cu")
		(net "GND")
	)
	(via
		(at 0.762 -27.557476)
		(size 0.508)
		(drill 0.254)
		(layers "F.Cu" "B.Cu")
		(net "GND")
	)
	(via
		(at 82.139536 -42.006012)
		(size 0.508)
		(drill 0.254)
		(layers "F.Cu" "B.Cu")
		(net "GND")
	)
	(via
		(at 18.299176 -33.607248)
		(size 0.508)
		(drill 0.254)
		(layers "F.Cu" "B.Cu")
		(net "GND")
	)
	(via
		(at 46.283372 -0.762)
		(size 0.508)
		(drill 0.254)
		(layers "F.Cu" "B.Cu")
		(net "GND")
	)
	(via
		(at 66.226182 -39.243)
		(size 0.6604)
		(drill 0.3302)
		(layers "F.Cu" "B.Cu")
		(net "GND")
	)
	(via
		(at 60.61202 -59.856116)
		(size 0.4572)
		(drill 0.254)
		(layers "F.Cu" "B.Cu")
		(net "GND")
	)
	(via
		(at 28.85186 -62.27318)
		(size 0.508)
		(drill 0.254)
		(layers "F.Cu" "B.Cu")
		(net "GND")
	)
	(via
		(at 5.13715 -113.708434)
		(size 0.508)
		(drill 0.254)
		(layers "F.Cu" "B.Cu")
		(net "GND")
	)
	(via
		(at 30.24124 -50.72253)
		(size 0.508)
		(drill 0.254)
		(layers "F.Cu" "B.Cu")
		(net "GND")
	)
	(via
		(at 76.882498 -69.976238)
		(size 0.508)
		(drill 0.254)
		(layers "F.Cu" "B.Cu")
		(net "GND")
	)
	(via
		(at 4.7752 -31.0134)
		(size 0.6604)
		(drill 0.3302)
		(layers "F.Cu" "B.Cu")
		(net "GND")
	)
	(via
		(at 77.216 -77.47)
		(size 0.508)
		(drill 0.254)
		(layers "F.Cu" "B.Cu")
		(net "GND")
	)
	(via
		(at 28.238958 -74.541634)
		(size 0.508)
		(drill 0.254)
		(layers "F.Cu" "B.Cu")
		(net "GND")
	)
	(via
		(at 17.8943 -35.20694)
		(size 0.6604)
		(drill 0.3302)
		(layers "F.Cu" "B.Cu")
		(net "GND")
	)
	(via
		(at 73.72223 -11.932412)
		(size 0.508)
		(drill 0.254)
		(layers "F.Cu" "B.Cu")
		(net "GND")
	)
	(via
		(at 89.238074 -95.892874)
		(size 0.508)
		(drill 0.254)
		(layers "F.Cu" "B.Cu")
		(net "GND")
	)
	(via
		(at 8.184642 -31.442914)
		(size 0.508)
		(drill 0.254)
		(layers "F.Cu" "B.Cu")
		(net "GND")
	)
	(via
		(at 57.139332 -27.237944)
		(size 0.508)
		(drill 0.254)
		(layers "F.Cu" "B.Cu")
		(net "GND")
	)
	(via
		(at 89.238074 -25.600152)
		(size 0.508)
		(drill 0.254)
		(layers "F.Cu" "B.Cu")
		(net "GND")
	)
	(via
		(at 24.2316 -16.891)
		(size 0.508)
		(drill 0.254)
		(layers "F.Cu" "B.Cu")
		(net "GND")
	)
	(via
		(at 2.1082 -79.9338)
		(size 0.508)
		(drill 0.254)
		(layers "F.Cu" "B.Cu")
		(net "GND")
	)
	(via
		(at 4.318 -53.731414)
		(size 0.508)
		(drill 0.254)
		(layers "F.Cu" "B.Cu")
		(net "GND")
	)
	(via
		(at 33.8074 -91.1606)
		(size 0.508)
		(drill 0.254)
		(layers "F.Cu" "B.Cu")
		(net "GND")
	)
	(via
		(at 1.983486 -58.012838)
		(size 0.6604)
		(drill 0.3302)
		(layers "F.Cu" "B.Cu")
		(net "GND")
	)
	(via
		(at 79.034132 -47.125636)
		(size 0.4572)
		(drill 0.254)
		(layers "F.Cu" "B.Cu")
		(net "GND")
	)
	(via
		(at 85.7758 -57.8866)
		(size 0.6604)
		(drill 0.3302)
		(layers "F.Cu" "B.Cu")
		(net "GND")
	)
	(via
		(at 60.4901 -42.976038)
		(size 0.4572)
		(drill 0.254)
		(layers "F.Cu" "B.Cu")
		(net "GND")
	)
	(via
		(at 6.604 -54.991)
		(size 0.6604)
		(drill 0.3302)
		(layers "F.Cu" "B.Cu")
		(net "GND")
	)
	(via
		(at 89.238074 -5.280152)
		(size 0.508)
		(drill 0.254)
		(layers "F.Cu" "B.Cu")
		(net "GND")
	)
	(via
		(at 0.762 -91.980004)
		(size 0.508)
		(drill 0.254)
		(layers "F.Cu" "B.Cu")
		(net "GND")
	)
	(via
		(at 61.98108 -59.821572)
		(size 0.4572)
		(drill 0.254)
		(layers "F.Cu" "B.Cu")
		(net "GND")
	)
	(via
		(at 21.971 -19.05)
		(size 0.508)
		(drill 0.254)
		(layers "F.Cu" "B.Cu")
		(net "GND")
	)
	(via
		(at 50.899822 -53.366416)
		(size 0.4572)
		(drill 0.254)
		(layers "F.Cu" "B.Cu")
		(net "GND")
	)
	(via
		(at 81.9658 -73.3044)
		(size 0.6604)
		(drill 0.3302)
		(layers "F.Cu" "B.Cu")
		(net "GND")
	)
	(via
		(at 8.10768 -47.39894)
		(size 0.508)
		(drill 0.254)
		(layers "F.Cu" "B.Cu")
		(net "GND")
	)
	(via
		(at 22.254718 -94.382336)
		(size 0.4572)
		(drill 0.254)
		(layers "F.Cu" "B.Cu")
		(net "GND")
	)
	(via
		(at 81.843372 -0.762)
		(size 0.508)
		(drill 0.254)
		(layers "F.Cu" "B.Cu")
		(net "GND")
	)
	(via
		(at 4.858766 -49.034192)
		(size 0.508)
		(drill 0.254)
		(layers "F.Cu" "B.Cu")
		(net "GND")
	)
	(via
		(at 44.978828 -98.400108)
		(size 0.508)
		(drill 0.254)
		(layers "F.Cu" "B.Cu")
		(net "GND")
	)
	(via
		(at 52.7685 -93.091)
		(size 0.508)
		(drill 0.254)
		(layers "F.Cu" "B.Cu")
		(net "GND")
	)
	(via
		(at 20.2184 -79.248)
		(size 0.508)
		(drill 0.254)
		(layers "F.Cu" "B.Cu")
		(net "GND")
	)
	(via
		(at 80.02905 -93.091)
		(size 0.508)
		(drill 0.254)
		(layers "F.Cu" "B.Cu")
		(net "GND")
	)
	(via
		(at 9.296146 -48.010064)
		(size 0.508)
		(drill 0.254)
		(layers "F.Cu" "B.Cu")
		(net "GND")
	)
	(via
		(at 21.336 -66.38925)
		(size 0.508)
		(drill 0.254)
		(layers "F.Cu" "B.Cu")
		(net "GND")
	)
	(via
		(at 77.326744 -34.517838)
		(size 0.508)
		(drill 0.254)
		(layers "F.Cu" "B.Cu")
		(net "GND")
	)
	(via
		(at 38.174422 -80.135222)
		(size 0.508)
		(drill 0.254)
		(layers "F.Cu" "B.Cu")
		(net "GND")
	)
	(via
		(at 79.32801 -74.474578)
		(size 0.508)
		(drill 0.254)
		(layers "F.Cu" "B.Cu")
		(net "GND")
	)
	(via
		(at 8.7122 -95.25)
		(size 0.508)
		(drill 0.254)
		(layers "F.Cu" "B.Cu")
		(net "GND")
	)
	(via
		(at 17.1196 -39.5224)
		(size 0.762)
		(drill 0.381)
		(layers "F.Cu" "B.Cu")
		(net "GND")
	)
	(via
		(at 4.223004 -49.034192)
		(size 0.508)
		(drill 0.254)
		(layers "F.Cu" "B.Cu")
		(net "GND")
	)
	(via
		(at 86.3092 -47.221394)
		(size 0.508)
		(drill 0.254)
		(layers "F.Cu" "B.Cu")
		(net "GND")
	)
	(via
		(at 27.616658 -25.184862)
		(size 0.508)
		(drill 0.254)
		(layers "F.Cu" "B.Cu")
		(net "GND")
	)
	(via
		(at 58.099706 -54.166516)
		(size 0.4572)
		(drill 0.254)
		(layers "F.Cu" "B.Cu")
		(net "GND")
	)
	(via
		(at 50.099722 -51.76647)
		(size 0.4572)
		(drill 0.254)
		(layers "F.Cu" "B.Cu")
		(net "GND")
	)
	(via
		(at 28.194 -11.3284)
		(size 0.508)
		(drill 0.254)
		(layers "F.Cu" "B.Cu")
		(net "GND")
	)
	(via
		(at 85.019642 -57.492646)
		(size 0.508)
		(drill 0.254)
		(layers "F.Cu" "B.Cu")
		(net "GND")
	)
	(via
		(at 26.902664 -27.927808)
		(size 0.508)
		(drill 0.254)
		(layers "F.Cu" "B.Cu")
		(net "GND")
	)
	(via
		(at 15.875 -69.215)
		(size 0.508)
		(drill 0.254)
		(layers "F.Cu" "B.Cu")
		(net "GND")
	)
	(via
		(at 45.299884 -54.166516)
		(size 0.4572)
		(drill 0.254)
		(layers "F.Cu" "B.Cu")
		(net "GND")
	)
	(via
		(at 66.603372 -0.762)
		(size 0.508)
		(drill 0.254)
		(layers "F.Cu" "B.Cu")
		(net "GND")
	)
	(via
		(at 35.2806 -55.753)
		(size 0.6604)
		(drill 0.3302)
		(layers "F.Cu" "B.Cu")
		(net "GND")
	)
	(via
		(at 10.050018 -61.755782)
		(size 0.508)
		(drill 0.254)
		(layers "F.Cu" "B.Cu")
		(net "GND")
	)
	(via
		(at 18.04289 -108.341922)
		(size 0.508)
		(drill 0.254)
		(layers "F.Cu" "B.Cu")
		(net "GND")
	)
	(via
		(at 15.344394 -33.0708)
		(size 0.508)
		(drill 0.254)
		(layers "F.Cu" "B.Cu")
		(net "GND")
	)
	(via
		(at 50.099722 -45.376084)
		(size 0.4572)
		(drill 0.254)
		(layers "F.Cu" "B.Cu")
		(net "GND")
	)
	(via
		(at 43.095926 -101.452426)
		(size 0.508)
		(drill 0.254)
		(layers "F.Cu" "B.Cu")
		(net "GND")
	)
	(via
		(at 32.91205 -14.57325)
		(size 0.508)
		(drill 0.254)
		(layers "F.Cu" "B.Cu")
		(net "GND")
	)
	(via
		(at 62.890146 -50.166524)
		(size 0.4572)
		(drill 0.254)
		(layers "F.Cu" "B.Cu")
		(net "GND")
	)
	(via
		(at 77.20076 -54.016656)
		(size 0.4572)
		(drill 0.254)
		(layers "F.Cu" "B.Cu")
		(net "GND")
	)
	(via
		(at 65.89268 -87.86622)
		(size 0.508)
		(drill 0.254)
		(layers "F.Cu" "B.Cu")
		(net "GND")
	)
	(via
		(at 12.119356 -53.905658)
		(size 0.508)
		(drill 0.254)
		(layers "F.Cu" "B.Cu")
		(net "GND")
	)
	(via
		(at 89.238074 -106.052874)
		(size 0.508)
		(drill 0.254)
		(layers "F.Cu" "B.Cu")
		(net "GND")
	)
	(via
		(at 74.598022 -38.666928)
		(size 0.508)
		(drill 0.254)
		(layers "F.Cu" "B.Cu")
		(net "GND")
	)
	(via
		(at 66.073528 -23.817072)
		(size 0.508)
		(drill 0.254)
		(layers "F.Cu" "B.Cu")
		(net "GND")
	)
	(via
		(at 36.1442 -54.9402)
		(size 0.508)
		(drill 0.254)
		(layers "F.Cu" "B.Cu")
		(net "GND")
	)
	(via
		(at 42.291 -24.4856)
		(size 0.508)
		(drill 0.254)
		(layers "F.Cu" "B.Cu")
		(net "GND")
	)
	(via
		(at 57.290208 -45.376084)
		(size 0.4572)
		(drill 0.254)
		(layers "F.Cu" "B.Cu")
		(net "GND")
	)
	(via
		(at 40.23868 -29.61894)
		(size 0.508)
		(drill 0.254)
		(layers "F.Cu" "B.Cu")
		(net "GND")
	)
	(via
		(at 86.923372 -0.762)
		(size 0.508)
		(drill 0.254)
		(layers "F.Cu" "B.Cu")
		(net "GND")
	)
	(via
		(at 50.54346 -62.943994)
		(size 0.508)
		(drill 0.254)
		(layers "F.Cu" "B.Cu")
		(net "GND")
	)
	(via
		(at 30.0482 -60.325)
		(size 0.508)
		(drill 0.254)
		(layers "F.Cu" "B.Cu")
		(net "GND")
	)
	(via
		(at 30.91688 -67.39382)
		(size 0.508)
		(drill 0.254)
		(layers "F.Cu" "B.Cu")
		(net "GND")
	)
	(via
		(at 13.462 -10.541)
		(size 0.508)
		(drill 0.254)
		(layers "F.Cu" "B.Cu")
		(net "GND")
	)
	(via
		(at 84.17687 -48.872394)
		(size 0.508)
		(drill 0.254)
		(layers "F.Cu" "B.Cu")
		(net "GND")
	)
	(via
		(at 62.890146 -44.575984)
		(size 0.4572)
		(drill 0.254)
		(layers "F.Cu" "B.Cu")
		(net "GND")
	)
	(via
		(at 79.034132 -51.089306)
		(size 0.4572)
		(drill 0.254)
		(layers "F.Cu" "B.Cu")
		(net "GND")
	)
	(via
		(at 68.461636 -116.601494)
		(size 0.508)
		(drill 0.254)
		(layers "F.Cu" "B.Cu")
		(net "GND")
	)
	(via
		(at 11.303 -90.297)
		(size 0.508)
		(drill 0.254)
		(layers "F.Cu" "B.Cu")
		(net "GND")
	)
	(via
		(at 80.68818 -74.02322)
		(size 0.508)
		(drill 0.254)
		(layers "F.Cu" "B.Cu")
		(net "GND")
	)
	(via
		(at 42.255694 -53.287676)
		(size 0.508)
		(drill 0.254)
		(layers "F.Cu" "B.Cu")
		(net "GND")
	)
	(via
		(at 82.559652 -90.65006)
		(size 0.508)
		(drill 0.254)
		(layers "F.Cu" "B.Cu")
		(net "GND")
	)
	(via
		(at 0.762 -12.317476)
		(size 0.508)
		(drill 0.254)
		(layers "F.Cu" "B.Cu")
		(net "GND")
	)
	(via
		(at 37.2364 -104.2924)
		(size 0.508)
		(drill 0.254)
		(layers "F.Cu" "B.Cu")
		(net "GND")
	)
	(via
		(at 5.763768 -118.495572)
		(size 0.508)
		(drill 0.254)
		(layers "F.Cu" "B.Cu")
		(net "GND")
	)
	(via
		(at 64.490092 -50.96637)
		(size 0.4572)
		(drill 0.254)
		(layers "F.Cu" "B.Cu")
		(net "GND")
	)
	(via
		(at 38.6334 -108.1278)
		(size 0.508)
		(drill 0.254)
		(layers "F.Cu" "B.Cu")
		(net "GND")
	)
	(via
		(at 12.502642 -30.807914)
		(size 0.508)
		(drill 0.254)
		(layers "F.Cu" "B.Cu")
		(net "GND")
	)
	(via
		(at 85.599016 -52.352702)
		(size 0.508)
		(drill 0.254)
		(layers "F.Cu" "B.Cu")
		(net "GND")
	)
	(via
		(at 10.375392 -113.90376)
		(size 0.508)
		(drill 0.254)
		(layers "F.Cu" "B.Cu")
		(net "GND")
	)
	(via
		(at 86.3092 -42.141394)
		(size 0.508)
		(drill 0.254)
		(layers "F.Cu" "B.Cu")
		(net "GND")
	)
	(via
		(at 76.981558 -75.569826)
		(size 0.508)
		(drill 0.254)
		(layers "F.Cu" "B.Cu")
		(net "GND")
	)
	(via
		(at 12.829032 -14.594586)
		(size 0.508)
		(drill 0.254)
		(layers "F.Cu" "B.Cu")
		(net "GND")
	)
	(via
		(at 13.08989 -108.342176)
		(size 0.508)
		(drill 0.254)
		(layers "F.Cu" "B.Cu")
		(net "GND")
	)
	(via
		(at 5.97789 -83.81746)
		(size 0.508)
		(drill 0.254)
		(layers "F.Cu" "B.Cu")
		(net "GND")
	)
	(via
		(at 52.499768 -42.976038)
		(size 0.4572)
		(drill 0.254)
		(layers "F.Cu" "B.Cu")
		(net "GND")
	)
	(via
		(at 57.9628 -116.6114)
		(size 0.508)
		(drill 0.254)
		(layers "F.Cu" "B.Cu")
		(net "GND")
	)
	(via
		(at 11.43 -31.115)
		(size 0.6604)
		(drill 0.3302)
		(layers "F.Cu" "B.Cu")
		(net "GND")
	)
	(via
		(at 21.545042 -116.8654)
		(size 0.508)
		(drill 0.254)
		(layers "F.Cu" "B.Cu")
		(net "GND")
	)
	(via
		(at 89.238074 -40.840152)
		(size 0.508)
		(drill 0.254)
		(layers "F.Cu" "B.Cu")
		(net "GND")
	)
	(via
		(at 51.699668 -50.96637)
		(size 0.4572)
		(drill 0.254)
		(layers "F.Cu" "B.Cu")
		(net "GND")
	)
	(via
		(at 59.690254 -46.97603)
		(size 0.4572)
		(drill 0.254)
		(layers "F.Cu" "B.Cu")
		(net "GND")
	)
	(via
		(at 79.833978 -48.68926)
		(size 0.4572)
		(drill 0.254)
		(layers "F.Cu" "B.Cu")
		(net "GND")
	)
	(via
		(at 57.290208 -46.97603)
		(size 0.4572)
		(drill 0.254)
		(layers "F.Cu" "B.Cu")
		(net "GND")
	)
	(via
		(at 5.643372 -0.762)
		(size 0.508)
		(drill 0.254)
		(layers "F.Cu" "B.Cu")
		(net "GND")
	)
	(via
		(at 1.983486 -73.252838)
		(size 0.6604)
		(drill 0.3302)
		(layers "F.Cu" "B.Cu")
		(net "GND")
	)
	(via
		(at 89.238074 -35.760152)
		(size 0.508)
		(drill 0.254)
		(layers "F.Cu" "B.Cu")
		(net "GND")
	)
	(via
		(at 5.3975 -52.37988)
		(size 0.508)
		(drill 0.254)
		(layers "F.Cu" "B.Cu")
		(net "GND")
	)
	(via
		(at 78.994 -81.407)
		(size 0.508)
		(drill 0.254)
		(layers "F.Cu" "B.Cu")
		(net "GND")
	)
	(via
		(at 1.67386 -67.18808)
		(size 0.762)
		(drill 0.381)
		(layers "F.Cu" "B.Cu")
		(net "GND")
	)
	(via
		(at 56.68264 -92.1004)
		(size 0.508)
		(drill 0.254)
		(layers "F.Cu" "B.Cu")
		(net "GND")
	)
	(via
		(at 19.685 -116.8654)
		(size 0.508)
		(drill 0.254)
		(layers "F.Cu" "B.Cu")
		(net "GND")
	)
	(via
		(at 12.43076 -52.037234)
		(size 0.508)
		(drill 0.254)
		(layers "F.Cu" "B.Cu")
		(net "GND")
	)
	(via
		(at 17.35709 -35.907726)
		(size 0.508)
		(drill 0.254)
		(layers "F.Cu" "B.Cu")
		(net "GND")
	)
	(via
		(at 23.622 -80.01)
		(size 0.6604)
		(drill 0.3302)
		(layers "F.Cu" "B.Cu")
		(net "GND")
	)
	(via
		(at 14.513814 -53.172614)
		(size 0.508)
		(drill 0.254)
		(layers "F.Cu" "B.Cu")
		(net "GND")
	)
	(via
		(at 50.869596 -104.38384)
		(size 0.762)
		(drill 0.254)
		(layers "F.Cu" "B.Cu")
		(net "GND")
	)
	(via
		(at 62.329314 -25.295606)
		(size 0.508)
		(drill 0.254)
		(layers "F.Cu" "B.Cu")
		(net "GND")
	)
	(via
		(at 24.654764 -90.391742)
		(size 0.4572)
		(drill 0.254)
		(layers "F.Cu" "B.Cu")
		(net "GND")
	)
	(via
		(at 25.45461 -97.582228)
		(size 0.4572)
		(drill 0.254)
		(layers "F.Cu" "B.Cu")
		(net "GND")
	)
	(via
		(at 84.297774 -26.562558)
		(size 0.508)
		(drill 0.254)
		(layers "F.Cu" "B.Cu")
		(net "GND")
	)
	(via
		(at 61.674248 -29.845254)
		(size 0.508)
		(drill 0.254)
		(layers "F.Cu" "B.Cu")
		(net "GND")
	)
	(via
		(at 6.27126 -63.313818)
		(size 0.508)
		(drill 0.254)
		(layers "F.Cu" "B.Cu")
		(net "GND")
	)
	(via
		(at 39.5732 -59.6138)
		(size 0.508)
		(drill 0.254)
		(layers "F.Cu" "B.Cu")
		(net "GND")
	)
	(via
		(at 65.290192 -55.766462)
		(size 0.4572)
		(drill 0.254)
		(layers "F.Cu" "B.Cu")
		(net "GND")
	)
	(via
		(at 40.95496 -48.381158)
		(size 0.508)
		(drill 0.254)
		(layers "F.Cu" "B.Cu")
		(net "GND")
	)
	(via
		(at 43.8277 -101.26726)
		(size 0.508)
		(drill 0.254)
		(layers "F.Cu" "B.Cu")
		(net "GND")
	)
	(via
		(at 53.7972 -23.84298)
		(size 0.508)
		(drill 0.254)
		(layers "F.Cu" "B.Cu")
		(net "GND")
	)
	(via
		(at 36.92271 -108.2167)
		(size 0.508)
		(drill 0.254)
		(layers "F.Cu" "B.Cu")
		(net "GND")
	)
	(via
		(at 63.1698 -19.2786)
		(size 0.508)
		(drill 0.254)
		(layers "F.Cu" "B.Cu")
		(net "GND")
	)
	(via
		(at 33.328864 -71.167498)
		(size 0.508)
		(drill 0.254)
		(layers "F.Cu" "B.Cu")
		(net "GND")
	)
	(via
		(at 21.368004 -79.19466)
		(size 0.508)
		(drill 0.254)
		(layers "F.Cu" "B.Cu")
		(net "GND")
	)
	(via
		(at 82.886042 -57.492646)
		(size 0.508)
		(drill 0.254)
		(layers "F.Cu" "B.Cu")
		(net "GND")
	)
	(via
		(at 59.3344 -94.361)
		(size 0.508)
		(drill 0.254)
		(layers "F.Cu" "B.Cu")
		(net "GND")
	)
	(via
		(at 67.6148 -76.327)
		(size 0.508)
		(drill 0.254)
		(layers "F.Cu" "B.Cu")
		(net "GND")
	)
	(via
		(at 20.7772 -47.879)
		(size 0.508)
		(drill 0.254)
		(layers "F.Cu" "B.Cu")
		(net "GND")
	)
	(via
		(at 73.429114 -51.900074)
		(size 0.4572)
		(drill 0.254)
		(layers "F.Cu" "B.Cu")
		(net "GND")
	)
	(via
		(at 52.499768 -48.575976)
		(size 0.4572)
		(drill 0.254)
		(layers "F.Cu" "B.Cu")
		(net "GND")
	)
	(via
		(at 57.290208 -50.175922)
		(size 0.4572)
		(drill 0.254)
		(layers "F.Cu" "B.Cu")
		(net "GND")
	)
	(via
		(at 51.80838 -31.877)
		(size 0.508)
		(drill 0.254)
		(layers "F.Cu" "B.Cu")
		(net "GND")
	)
	(via
		(at 17.57553 -34.492946)
		(size 0.508)
		(drill 0.254)
		(layers "F.Cu" "B.Cu")
		(net "GND")
	)
	(via
		(at 0.762 -42.797476)
		(size 0.508)
		(drill 0.254)
		(layers "F.Cu" "B.Cu")
		(net "GND")
	)
	(via
		(at 83.8708 -75.2094)
		(size 0.6604)
		(drill 0.3302)
		(layers "F.Cu" "B.Cu")
		(net "GND")
	)
	(via
		(at 10.723372 -0.762)
		(size 0.508)
		(drill 0.254)
		(layers "F.Cu" "B.Cu")
		(net "GND")
	)
	(via
		(at 72.644 -61.4934)
		(size 0.508)
		(drill 0.254)
		(layers "F.Cu" "B.Cu")
		(net "GND")
	)
	(via
		(at 58.6994 -31.9024)
		(size 0.508)
		(drill 0.254)
		(layers "F.Cu" "B.Cu")
		(net "GND")
	)
	(via
		(at 35.7378 -94.044008)
		(size 0.508)
		(drill 0.254)
		(layers "F.Cu" "B.Cu")
		(net "GND")
	)
	(via
		(at 69.6976 -22.864826)
		(size 0.508)
		(drill 0.254)
		(layers "F.Cu" "B.Cu")
		(net "GND")
	)
	(via
		(at 0.762 -63.117476)
		(size 0.508)
		(drill 0.254)
		(layers "F.Cu" "B.Cu")
		(net "GND")
	)
	(via
		(at 22.479 -32.512)
		(size 0.508)
		(drill 0.254)
		(layers "F.Cu" "B.Cu")
		(net "GND")
	)
	(via
		(at 84.0486 -79.9338)
		(size 0.508)
		(drill 0.254)
		(layers "F.Cu" "B.Cu")
		(net "GND")
	)
	(via
		(at 7.782052 -78.503272)
		(size 0.508)
		(drill 0.254)
		(layers "F.Cu" "B.Cu")
		(net "GND")
	)
	(via
		(at 64.102996 -33.568386)
		(size 0.508)
		(drill 0.254)
		(layers "F.Cu" "B.Cu")
		(net "GND")
	)
	(via
		(at 28.448 -31.369)
		(size 0.508)
		(drill 0.254)
		(layers "F.Cu" "B.Cu")
		(net "GND")
	)
	(via
		(at 53.299868 -46.97603)
		(size 0.4572)
		(drill 0.254)
		(layers "F.Cu" "B.Cu")
		(net "GND")
	)
	(via
		(at 16.0782 -60.3504)
		(size 0.508)
		(drill 0.254)
		(layers "F.Cu" "B.Cu")
		(net "GND")
	)
	(via
		(at 19.431 -34.29)
		(size 0.6604)
		(drill 0.3302)
		(layers "F.Cu" "B.Cu")
		(net "GND")
	)
	(via
		(at 50.099722 -55.766462)
		(size 0.4572)
		(drill 0.254)
		(layers "F.Cu" "B.Cu")
		(net "GND")
	)
	(via
		(at 24.01824 -112.594898)
		(size 0.508)
		(drill 0.254)
		(layers "F.Cu" "B.Cu")
		(net "GND")
	)
	(via
		(at 57.796938 -18.86585)
		(size 0.762)
		(drill 0.254)
		(layers "F.Cu" "B.Cu")
		(net "GND")
	)
	(via
		(at 87.2744 -34.0106)
		(size 0.6604)
		(drill 0.3302)
		(layers "F.Cu" "B.Cu")
		(net "GND")
	)
	(via
		(at 1.983486 -42.772838)
		(size 0.6604)
		(drill 0.3302)
		(layers "F.Cu" "B.Cu")
		(net "GND")
	)
	(via
		(at 18.264124 -90.391742)
		(size 0.4572)
		(drill 0.254)
		(layers "F.Cu" "B.Cu")
		(net "GND")
	)
	(via
		(at 41.203372 -0.762)
		(size 0.508)
		(drill 0.254)
		(layers "F.Cu" "B.Cu")
		(net "GND")
	)
	(via
		(at 48.1584 -116.7892)
		(size 0.508)
		(drill 0.254)
		(layers "F.Cu" "B.Cu")
		(net "GND")
	)
	(via
		(at 29.974286 -79.70774)
		(size 0.508)
		(drill 0.254)
		(layers "F.Cu" "B.Cu")
		(net "GND")
	)
	(via
		(at 79.034132 -54.289198)
		(size 0.4572)
		(drill 0.254)
		(layers "F.Cu" "B.Cu")
		(net "GND")
	)
	(via
		(at 21.7424 -85.09)
		(size 0.508)
		(drill 0.254)
		(layers "F.Cu" "B.Cu")
		(net "GND")
	)
	(via
		(at 33.94456 -99.193096)
		(size 0.508)
		(drill 0.254)
		(layers "F.Cu" "B.Cu")
		(net "GND")
	)
	(via
		(at 42.747438 -23.869904)
		(size 0.508)
		(drill 0.254)
		(layers "F.Cu" "B.Cu")
		(net "GND")
	)
	(via
		(at 74.089006 -116.817648)
		(size 0.508)
		(drill 0.254)
		(layers "F.Cu" "B.Cu")
		(net "GND")
	)
	(via
		(at 89.238074 -61.160152)
		(size 0.508)
		(drill 0.254)
		(layers "F.Cu" "B.Cu")
		(net "GND")
	)
	(via
		(at 80.21574 -74.5363)
		(size 0.508)
		(drill 0.254)
		(layers "F.Cu" "B.Cu")
		(net "GND")
	)
	(via
		(at 75.539346 -100.935028)
		(size 0.508)
		(drill 0.254)
		(layers "F.Cu" "B.Cu")
		(net "GND")
	)
	(via
		(at 81.9658 -77.1144)
		(size 0.6604)
		(drill 0.3302)
		(layers "F.Cu" "B.Cu")
		(net "GND")
	)
	(via
		(at 54.099714 -55.766462)
		(size 0.4572)
		(drill 0.254)
		(layers "F.Cu" "B.Cu")
		(net "GND")
	)
	(via
		(at 85.69325 -19.4564)
		(size 0.508)
		(drill 0.254)
		(layers "F.Cu" "B.Cu")
		(net "GND")
	)
	(via
		(at 41.959276 -108.886752)
		(size 0.508)
		(drill 0.254)
		(layers "F.Cu" "B.Cu")
		(net "GND")
	)
	(via
		(at 45.299884 -46.97603)
		(size 0.4572)
		(drill 0.254)
		(layers "F.Cu" "B.Cu")
		(net "GND")
	)
	(via
		(at 56.443372 -0.762)
		(size 0.508)
		(drill 0.254)
		(layers "F.Cu" "B.Cu")
		(net "GND")
	)
	(via
		(at 70.1294 -96.901)
		(size 0.508)
		(drill 0.254)
		(layers "F.Cu" "B.Cu")
		(net "GND")
	)
	(via
		(at 85.2678 -95.6056)
		(size 0.508)
		(drill 0.254)
		(layers "F.Cu" "B.Cu")
		(net "GND")
	)
	(via
		(at 81.9404 -19.3294)
		(size 0.508)
		(drill 0.254)
		(layers "F.Cu" "B.Cu")
		(net "GND")
	)
	(via
		(at 79.750158 -8.4836)
		(size 0.508)
		(drill 0.254)
		(layers "F.Cu" "B.Cu")
		(net "GND")
	)
	(via
		(at 76.417424 -26.430986)
		(size 0.508)
		(drill 0.254)
		(layers "F.Cu" "B.Cu")
		(net "GND")
	)
	(via
		(at 76.582778 -49.64049)
		(size 0.508)
		(drill 0.254)
		(layers "F.Cu" "B.Cu")
		(net "GND")
	)
	(via
		(at 29.5148 -29.2354)
		(size 0.508)
		(drill 0.254)
		(layers "F.Cu" "B.Cu")
		(net "GND")
	)
	(via
		(at 48.063912 -71.28637)
		(size 0.508)
		(drill 0.254)
		(layers "F.Cu" "B.Cu")
		(net "GND")
	)
	(via
		(at 19.1262 -77.5081)
		(size 0.508)
		(drill 0.254)
		(layers "F.Cu" "B.Cu")
		(net "GND")
	)
	(via
		(at 6.27126 -63.999618)
		(size 0.508)
		(drill 0.254)
		(layers "F.Cu" "B.Cu")
		(net "GND")
	)
	(via
		(at 51.60772 -105.758234)
		(size 0.508)
		(drill 0.254)
		(layers "F.Cu" "B.Cu")
		(net "GND")
	)
	(via
		(at 14.59738 -108.342176)
		(size 0.508)
		(drill 0.254)
		(layers "F.Cu" "B.Cu")
		(net "GND")
	)
	(via
		(at 0.762 -37.717476)
		(size 0.508)
		(drill 0.254)
		(layers "F.Cu" "B.Cu")
		(net "GND")
	)
	(via
		(at 63.690246 -55.766462)
		(size 0.4572)
		(drill 0.254)
		(layers "F.Cu" "B.Cu")
		(net "GND")
	)
	(via
		(at 71.683372 -0.762)
		(size 0.508)
		(drill 0.254)
		(layers "F.Cu" "B.Cu")
		(net "GND")
	)
	(via
		(at 81.622646 -33.031176)
		(size 0.508)
		(drill 0.254)
		(layers "F.Cu" "B.Cu")
		(net "GND")
	)
	(via
		(at 75.422252 -82.7278)
		(size 0.508)
		(drill 0.254)
		(layers "F.Cu" "B.Cu")
		(net "GND")
	)
	(via
		(at 35.780726 -26.619962)
		(size 0.508)
		(drill 0.254)
		(layers "F.Cu" "B.Cu")
		(net "GND")
	)
	(via
		(at 62.3062 -113.2332)
		(size 0.508)
		(drill 0.254)
		(layers "F.Cu" "B.Cu")
		(net "GND")
	)
	(via
		(at 76.48448 -58.37174)
		(size 0.508)
		(drill 0.254)
		(layers "F.Cu" "B.Cu")
		(net "GND")
	)
	(via
		(at 35.9918 -24.619966)
		(size 0.508)
		(drill 0.254)
		(layers "F.Cu" "B.Cu")
		(net "GND")
	)
	(via
		(at 5.648198 -78.382368)
		(size 0.508)
		(drill 0.254)
		(layers "F.Cu" "B.Cu")
		(net "GND")
	)
	(via
		(at 31.623 -42.4434)
		(size 0.508)
		(drill 0.254)
		(layers "F.Cu" "B.Cu")
		(net "GND")
	)
	(via
		(at 3.984752 -65.802002)
		(size 0.508)
		(drill 0.254)
		(layers "F.Cu" "B.Cu")
		(net "GND")
	)
	(via
		(at 15.382494 -79.970122)
		(size 0.508)
		(drill 0.254)
		(layers "F.Cu" "B.Cu")
		(net "GND")
	)
	(via
		(at 64.490092 -43.776138)
		(size 0.4572)
		(drill 0.254)
		(layers "F.Cu" "B.Cu")
		(net "GND")
	)
	(via
		(at 23.0886 -56.6039)
		(size 0.508)
		(drill 0.254)
		(layers "F.Cu" "B.Cu")
		(net "GND")
	)
	(via
		(at 79.807054 -76.799694)
		(size 0.508)
		(drill 0.254)
		(layers "F.Cu" "B.Cu")
		(net "GND")
	)
	(via
		(at 83.8708 -73.3044)
		(size 0.6604)
		(drill 0.3302)
		(layers "F.Cu" "B.Cu")
		(net "GND")
	)
	(via
		(at 4.858766 -50.456592)
		(size 0.508)
		(drill 0.254)
		(layers "F.Cu" "B.Cu")
		(net "GND")
	)
	(via
		(at 26.259282 -88.787224)
		(size 0.4572)
		(drill 0.254)
		(layers "F.Cu" "B.Cu")
		(net "GND")
	)
	(via
		(at 76.3524 -2.690114)
		(size 0.508)
		(drill 0.254)
		(layers "F.Cu" "B.Cu")
		(net "GND")
	)
	(via
		(at 0.762 -102.140004)
		(size 0.508)
		(drill 0.254)
		(layers "F.Cu" "B.Cu")
		(net "GND")
	)
	(via
		(at 38.896036 -45.357288)
		(size 0.508)
		(drill 0.254)
		(layers "F.Cu" "B.Cu")
		(net "GND")
	)
	(via
		(at 66.78422 -82.6262)
		(size 0.508)
		(drill 0.254)
		(layers "F.Cu" "B.Cu")
		(net "GND")
	)
	(via
		(at 72.67067 -43.925744)
		(size 0.4572)
		(drill 0.254)
		(layers "F.Cu" "B.Cu")
		(net "GND")
	)
	(arc
		(start 60.4901 -42.976038)
		(mid 60.499043 -42.977817)
		(end 60.50661 -42.982896)
		(width 0.3556)
		(layer "F.Cu")
		(net "GND")
	)
	(segment
		(start 58.50255 -24.65705)
		(end 59.309 -24.65705)
		(width 0.381)
		(layer "B.Cu")
		(net "GND")
	)
	(segment
		(start 31.369 -31.73095)
		(end 31.000954 -31.73095)
		(width 0.381)
		(layer "B.Cu")
		(net "GND")
	)
	(segment
		(start 29.97835 -95.38335)
		(end 29.97835 -95.7072)
		(width 0.381)
		(layer "B.Cu")
		(net "GND")
	)
	(segment
		(start 72.539606 -48.307498)
		(end 73.116948 -47.730156)
		(width 0.3556)
		(layer "B.Cu")
		(net "GND")
	)
	(segment
		(start 57.679844 -44.806362)
		(end 57.673494 -44.812712)
		(width 0.381)
		(layer "B.Cu")
		(net "GND")
	)
	(segment
		(start 15.113 -20.04695)
		(end 15.24 -19.91995)
		(width 0.381)
		(layer "B.Cu")
		(net "GND")
	)
	(segment
		(start 47.649384 -48.554386)
		(end 47.649384 -48.36414)
		(width 0.3556)
		(layer "B.Cu")
		(net "GND")
	)
	(segment
		(start 54.480968 -54.87162)
		(end 54.099714 -55.252874)
		(width 0.381)
		(layer "B.Cu")
		(net "GND")
	)
	(segment
		(start 60.930536 -49.314354)
		(end 60.757816 -49.728882)
		(width 0.3556)
		(layer "B.Cu")
		(net "GND")
	)
	(segment
		(start 72.528176 -51.2318)
		(end 72.67067 -51.089306)
		(width 0.381)
		(layer "B.Cu")
		(net "GND")
	)
	(segment
		(start 70.942454 -51.2318)
		(end 71.676768 -51.2318)
		(width 0.381)
		(layer "B.Cu")
		(net "GND")
	)
	(segment
		(start 40.503856 -56.836056)
		(end 40.427656 -56.836056)
		(width 0.381)
		(layer "B.Cu")
		(net "GND")
	)
	(segment
		(start 72.63892 -41.983914)
		(end 72.63892 -41.525698)
		(width 0.381)
		(layer "B.Cu")
		(net "GND")
	)
	(segment
		(start 46.0756 -92.93225)
		(end 45.085 -92.93225)
		(width 0.381)
		(layer "B.Cu")
		(net "GND")
	)
	(segment
		(start 81.529936 -39.974012)
		(end 82.139536 -39.974012)
		(width 0.381)
		(layer "B.Cu")
		(net "GND")
	)
	(segment
		(start 14.344904 -118.460012)
		(end 14.344904 -116.8654)
		(width 0.381)
		(layer "B.Cu")
		(net "GND")
	)
	(segment
		(start 83.82127 -48.872394)
		(end 84.17687 -48.872394)
		(width 0.381)
		(layer "B.Cu")
		(net "GND")
	)
	(segment
		(start 46.96206 -63.227966)
		(end 47.217838 -63.483744)
		(width 0.381)
		(layer "B.Cu")
		(net "GND")
	)
	(segment
		(start 42.9768 -88.47455)
		(end 42.9768 -88.7476)
		(width 0.381)
		(layer "B.Cu")
		(net "GND")
	)
	(segment
		(start 60.499752 -43.630342)
		(end 60.499752 -42.98569)
		(width 0.381)
		(layer "B.Cu")
		(net "GND")
	)
	(segment
		(start 81.529936 -42.006012)
		(end 82.139536 -42.006012)
		(width 0.381)
		(layer "B.Cu")
		(net "GND")
	)
	(segment
		(start 62.992 -24.65705)
		(end 62.96787 -24.65705)
		(width 0.381)
		(layer "B.Cu")
		(net "GND")
	)
	(segment
		(start 59.151266 -49.314354)
		(end 59.151266 -48.837088)
		(width 0.3556)
		(layer "B.Cu")
		(net "GND")
	)
	(segment
		(start 18.659348 -89.18702)
		(end 18.659348 -89.586816)
		(width 0.127)
		(layer "B.Cu")
		(net "GND")
	)
	(segment
		(start 78.42377 -51.000406)
		(end 78.945232 -51.000406)
		(width 0.381)
		(layer "B.Cu")
		(net "GND")
	)
	(segment
		(start 13.574014 -23.18004)
		(end 13.574014 -23.806404)
		(width 0.381)
		(layer "B.Cu")
		(net "GND")
	)
	(segment
		(start 68.18249 -30.854904)
		(end 68.18249 -29.810964)
		(width 0.381)
		(layer "B.Cu")
		(net "GND")
	)
	(segment
		(start 14.600174 -27.709876)
		(end 15.24 -27.07005)
		(width 0.381)
		(layer "B.Cu")
		(net "GND")
	)
	(segment
		(start 65.171066 -40.299386)
		(end 65.171066 -39.755318)
		(width 0.381)
		(layer "B.Cu")
		(net "GND")
	)
	(segment
		(start 57.785 -24.892)
		(end 57.785 -24.53005)
		(width 0.381)
		(layer "B.Cu")
		(net "GND")
	)
	(segment
		(start 29.3624 -30.7594)
		(end 28.3464 -30.7594)
		(width 0.381)
		(layer "B.Cu")
		(net "GND")
	)
	(segment
		(start 17.50695 -19.431)
		(end 16.745712 -19.431)
		(width 0.381)
		(layer "B.Cu")
		(net "GND")
	)
	(segment
		(start 57.673494 -44.812712)
		(end 57.673494 -44.992798)
		(width 0.381)
		(layer "B.Cu")
		(net "GND")
	)
	(segment
		(start 62.96787 -24.65705)
		(end 62.329314 -25.295606)
		(width 0.381)
		(layer "B.Cu")
		(net "GND")
	)
	(segment
		(start 29.21 -93.853)
		(end 29.21 -94.615)
		(width 0.381)
		(layer "B.Cu")
		(net "GND")
	)
	(segment
		(start 60.499752 -42.98569)
		(end 60.4901 -42.976038)
		(width 0.381)
		(layer "B.Cu")
		(net "GND")
	)
	(segment
		(start 70.5104 -51.663854)
		(end 70.942454 -51.2318)
		(width 0.381)
		(layer "B.Cu")
		(net "GND")
	)
	(segment
		(start 65.194434 -40.322754)
		(end 65.171066 -40.299386)
		(width 0.381)
		(layer "B.Cu")
		(net "GND")
	)
	(segment
		(start 48.25492 -73.94956)
		(end 48.246792 -73.957688)
		(width 0.381)
		(layer "B.Cu")
		(net "GND")
	)
	(segment
		(start 30.37205 -101.77145)
		(end 30.7086 -102.108)
		(width 0.381)
		(layer "B.Cu")
		(net "GND")
	)
	(segment
		(start 40.854884 -116.871496)
		(end 40.856408 -116.869972)
		(width 0.381)
		(layer "B.Cu")
		(net "GND")
	)
	(segment
		(start 23.573486 -106.10977)
		(end 23.573486 -105.402634)
		(width 0.381)
		(layer "B.Cu")
		(net "GND")
	)
	(segment
		(start 42.242232 -57.958482)
		(end 42.242232 -57.198006)
		(width 0.381)
		(layer "B.Cu")
		(net "GND")
	)
	(segment
		(start 56.4388 -116.5098)
		(end 56.4388 -116.7892)
		(width 0.3302)
		(layer "B.Cu")
		(net "GND")
	)
	(segment
		(start 70.634606 -54.23662)
		(end 70.634606 -53.215794)
		(width 0.381)
		(layer "B.Cu")
		(net "GND")
	)
	(segment
		(start 64.894968 -39.47922)
		(end 64.894968 -38.83787)
		(width 0.381)
		(layer "B.Cu")
		(net "GND")
	)
	(segment
		(start 84.272628 -28.627578)
		(end 83.683602 -28.627578)
		(width 0.381)
		(layer "B.Cu")
		(net "GND")
	)
	(segment
		(start 16.713454 -64.29883)
		(end 16.017494 -64.29883)
		(width 0.3556)
		(layer "B.Cu")
		(net "GND")
	)
	(segment
		(start 30.5435 -41.81475)
		(end 31.623 -41.81475)
		(width 0.381)
		(layer "B.Cu")
		(net "GND")
	)
	(segment
		(start 83.683602 -27.607768)
		(end 84.272628 -27.607768)
		(width 0.381)
		(layer "B.Cu")
		(net "GND")
	)
	(segment
		(start 48.00092 -24.51989)
		(end 48.3108 -24.82977)
		(width 0.381)
		(layer "B.Cu")
		(net "GND")
	)
	(segment
		(start 53.738018 -43.761406)
		(end 53.738018 -43.337734)
		(width 0.381)
		(layer "B.Cu")
		(net "GND")
	)
	(segment
		(start 41.266618 -57.198006)
		(end 40.964612 -56.896)
		(width 0.381)
		(layer "B.Cu")
		(net "GND")
	)
	(segment
		(start 41.6052 -90.6272)
		(end 41.6052 -90.7542)
		(width 0.254)
		(layer "B.Cu")
		(net "GND")
	)
	(segment
		(start 56.265064 -116.962936)
		(end 56.265064 -118.460012)
		(width 0.3302)
		(layer "B.Cu")
		(net "GND")
	)
	(segment
		(start 30.37205 -100.838)
		(end 30.37205 -101.77145)
		(width 0.381)
		(layer "B.Cu")
		(net "GND")
	)
	(segment
		(start 68.460112 -116.603018)
		(end 68.461636 -116.601494)
		(width 0.381)
		(layer "B.Cu")
		(net "GND")
	)
	(segment
		(start 59.956192 -50.700432)
		(end 59.690254 -50.96637)
		(width 0.3556)
		(layer "B.Cu")
		(net "GND")
	)
	(segment
		(start 83.56727 -40.363394)
		(end 83.94827 -39.982394)
		(width 0.381)
		(layer "B.Cu")
		(net "GND")
	)
	(segment
		(start 70.669658 -30.253178)
		(end 70.669658 -29.817314)
		(width 0.381)
		(layer "B.Cu")
		(net "GND")
	)
	(segment
		(start 69.424296 -19.28495)
		(end 69.036946 -18.8976)
		(width 0.381)
		(layer "B.Cu")
		(net "GND")
	)
	(segment
		(start 42.1894 -2.921)
		(end 42.49166 -2.921)
		(width 0.381)
		(layer "B.Cu")
		(net "GND")
	)
	(segment
		(start 69.651626 -13.116814)
		(end 69.651626 -12.755626)
		(width 0.381)
		(layer "B.Cu")
		(net "GND")
	)
	(segment
		(start 80.547464 -51.44135)
		(end 80.826864 -51.44135)
		(width 0.381)
		(layer "B.Cu")
		(net "GND")
	)
	(segment
		(start 26.386536 -88.925146)
		(end 26.50236 -89.104724)
		(width 0.254)
		(layer "B.Cu")
		(net "GND")
	)
	(segment
		(start 34.05886 -98.304096)
		(end 33.94456 -98.418396)
		(width 0.381)
		(layer "B.Cu")
		(net "GND")
	)
	(segment
		(start 60.768484 -49.754536)
		(end 60.537598 -50.311812)
		(width 0.3556)
		(layer "B.Cu")
		(net "GND")
	)
	(segment
		(start 46.940724 -49.263046)
		(end 47.649384 -48.554386)
		(width 0.3556)
		(layer "B.Cu")
		(net "GND")
	)
	(segment
		(start 61.2648 -42.79265)
		(end 60.673488 -42.79265)
		(width 0.381)
		(layer "B.Cu")
		(net "GND")
	)
	(segment
		(start 29.5148 -28.9052)
		(end 29.5148 -29.2354)
		(width 0.381)
		(layer "B.Cu")
		(net "GND")
	)
	(segment
		(start 30.2514 -60.5282)
		(end 30.0482 -60.325)
		(width 0.381)
		(layer "B.Cu")
		(net "GND")
	)
	(segment
		(start 11.303 -53.95595)
		(end 11.335766 -53.988716)
		(width 0.381)
		(layer "B.Cu")
		(net "GND")
	)
	(segment
		(start 64.920622 -91.661742)
		(end 64.919352 -91.665298)
		(width 0.381)
		(layer "B.Cu")
		(net "GND")
	)
	(segment
		(start 23.573486 -105.402634)
		(end 24.20112 -104.775)
		(width 0.381)
		(layer "B.Cu")
		(net "GND")
	)
	(segment
		(start 70.397878 -30.8356)
		(end 70.397878 -30.524958)
		(width 0.381)
		(layer "B.Cu")
		(net "GND")
	)
	(segment
		(start 33.001712 -35.339528)
		(end 33.001712 -34.206688)
		(width 0.381)
		(layer "B.Cu")
		(net "GND")
	)
	(segment
		(start 40.0304 -105.97515)
		(end 39.40175 -105.3465)
		(width 0.381)
		(layer "B.Cu")
		(net "GND")
	)
	(segment
		(start 57.78754 -14.633702)
		(end 58.6232 -14.633702)
		(width 0.381)
		(layer "B.Cu")
		(net "GND")
	)
	(segment
		(start 43.1038 -62.57925)
		(end 43.1038 -62.763146)
		(width 0.3048)
		(layer "B.Cu")
		(net "GND")
	)
	(segment
		(start 37.6047 -92.65285)
		(end 36.63315 -92.65285)
		(width 0.381)
		(layer "B.Cu")
		(net "GND")
	)
	(segment
		(start 58.166 -25.273)
		(end 57.785 -24.892)
		(width 0.381)
		(layer "B.Cu")
		(net "GND")
	)
	(segment
		(start 44.209716 -92.748862)
		(end 44.393104 -92.93225)
		(width 0.254)
		(layer "B.Cu")
		(net "GND")
	)
	(segment
		(start 51.7144 -29.718)
		(end 51.816 -29.8196)
		(width 0.381)
		(layer "B.Cu")
		(net "GND")
	)
	(segment
		(start 75.539346 -100.935028)
		(end 76.87945 -100.935028)
		(width 0.381)
		(layer "B.Cu")
		(net "GND")
	)
	(segment
		(start 25.57145 -89.591896)
		(end 25.859486 -89.30386)
		(width 0.254)
		(layer "B.Cu")
		(net "GND")
	)
	(segment
		(start 79.305404 -98.119184)
		(end 79.305404 -97.222564)
		(width 0.381)
		(layer "B.Cu")
		(net "GND")
	)
	(segment
		(start 37.00145 -104.05745)
		(end 37.00145 -103.632)
		(width 0.381)
		(layer "B.Cu")
		(net "GND")
	)
	(segment
		(start 48.25492 -71.92137)
		(end 48.25492 -71.477378)
		(width 0.381)
		(layer "B.Cu")
		(net "GND")
	)
	(segment
		(start 53.738018 -43.337734)
		(end 54.099714 -42.976038)
		(width 0.381)
		(layer "B.Cu")
		(net "GND")
	)
	(segment
		(start 70.65772 -53.19268)
		(end 70.65772 -52.648358)
		(width 0.381)
		(layer "B.Cu")
		(net "GND")
	)
	(segment
		(start 36.29025 -19.9898)
		(end 37.211 -19.9898)
		(width 0.381)
		(layer "B.Cu")
		(net "GND")
	)
	(segment
		(start 16.017494 -64.29883)
		(end 15.661894 -63.94323)
		(width 0.3556)
		(layer "B.Cu")
		(net "GND")
	)
	(segment
		(start 35.687 -65.8876)
		(end 35.687 -67.411346)
		(width 0.254)
		(layer "B.Cu")
		(net "GND")
	)
	(segment
		(start 84.297774 -28.602432)
		(end 84.272628 -28.627578)
		(width 0.381)
		(layer "B.Cu")
		(net "GND")
	)
	(segment
		(start 78.945232 -51.000406)
		(end 79.034132 -51.089306)
		(width 0.381)
		(layer "B.Cu")
		(net "GND")
	)
	(segment
		(start 27.07005 -90.805)
		(end 27.07005 -90.397584)
		(width 0.254)
		(layer "B.Cu")
		(net "GND")
	)
	(segment
		(start 68.6054 -96.4946)
		(end 69.6214 -95.4786)
		(width 0.381)
		(layer "B.Cu")
		(net "GND")
	)
	(segment
		(start 43.8912 -88.09355)
		(end 43.3578 -88.09355)
		(width 0.381)
		(layer "B.Cu")
		(net "GND")
	)
	(segment
		(start 64.919352 -91.665298)
		(end 64.35725 -92.2274)
		(width 0.381)
		(layer "B.Cu")
		(net "GND")
	)
	(segment
		(start 42.88917 -53.856382)
		(end 42.88917 -53.747416)
		(width 0.381)
		(layer "B.Cu")
		(net "GND")
	)
	(segment
		(start 71.821548 -48.495458)
		(end 72.324468 -48.495458)
		(width 0.3556)
		(layer "B.Cu")
		(net "GND")
	)
	(segment
		(start 84.853018 -98.20529)
		(end 84.853018 -99.238054)
		(width 0.381)
		(layer "B.Cu")
		(net "GND")
	)
	(segment
		(start 11.500104 -25.015952)
		(end 11.960098 -25.015952)
		(width 0.381)
		(layer "B.Cu")
		(net "GND")
	)
	(segment
		(start 19.376136 -71.23938)
		(end 19.376136 -70.988936)
		(width 0.381)
		(layer "B.Cu")
		(net "GND")
	)
	(segment
		(start 44.393104 -92.93225)
		(end 45.085 -92.93225)
		(width 0.254)
		(layer "B.Cu")
		(net "GND")
	)
	(segment
		(start 58.166 -25.654)
		(end 58.166 -25.273)
		(width 0.381)
		(layer "B.Cu")
		(net "GND")
	)
	(segment
		(start 42.242232 -57.198006)
		(end 41.266618 -57.198006)
		(width 0.381)
		(layer "B.Cu")
		(net "GND")
	)
	(segment
		(start 54.099714 -55.766462)
		(end 53.532024 -55.766462)
		(width 0.381)
		(layer "B.Cu")
		(net "GND")
	)
	(segment
		(start 79.222346 -65.151)
		(end 79.85125 -65.779904)
		(width 0.3048)
		(layer "B.Cu")
		(net "GND")
	)
	(segment
		(start 48.25492 -72.954134)
		(end 48.25492 -71.92137)
		(width 0.381)
		(layer "B.Cu")
		(net "GND")
	)
	(segment
		(start 40.666416 -68.22694)
		(end 40.460676 -68.0212)
		(width 0.381)
		(layer "B.Cu")
		(net "GND")
	)
	(segment
		(start 24.2316 -17.40535)
		(end 24.003 -17.63395)
		(width 0.381)
		(layer "B.Cu")
		(net "GND")
	)
	(segment
		(start 41.6052 -90.7542)
		(end 41.679876 -90.828876)
		(width 0.254)
		(layer "B.Cu")
		(net "GND")
	)
	(segment
		(start 41.566084 -48.44415)
		(end 41.503092 -48.381158)
		(width 0.254)
		(layer "B.Cu")
		(net "GND")
	)
	(segment
		(start 60.19165 -94.889828)
		(end 59.662822 -94.361)
		(width 0.381)
		(layer "B.Cu")
		(net "GND")
	)
	(segment
		(start 84.086446 -45.041566)
		(end 84.17687 -45.062394)
		(width 0.381)
		(layer "B.Cu")
		(net "GND")
	)
	(segment
		(start 53.66131 -67.8942)
		(end 53.683408 -67.8942)
		(width 0.381)
		(layer "B.Cu")
		(net "GND")
	)
	(segment
		(start 4.32435 -26.797)
		(end 3.2766 -26.797)
		(width 0.381)
		(layer "B.Cu")
		(net "GND")
	)
	(segment
		(start 38.82009 -39.56431)
		(end 39.452042 -38.932358)
		(width 0.381)
		(layer "B.Cu")
		(net "GND")
	)
	(segment
		(start 18.659348 -89.18702)
		(end 19.06778 -89.18702)
		(width 0.127)
		(layer "B.Cu")
		(net "GND")
	)
	(segment
		(start 50.8 -115.7732)
		(end 50.8 -117.1448)
		(width 0.381)
		(layer "B.Cu")
		(net "GND")
	)
	(segment
		(start 39.452042 -38.932358)
		(end 39.75735 -38.932358)
		(width 0.381)
		(layer "B.Cu")
		(net "GND")
	)
	(segment
		(start 67.544188 -89.976452)
		(end 65.956688 -89.976452)
		(width 0.381)
		(layer "B.Cu")
		(net "GND")
	)
	(segment
		(start 56.583326 -53.376322)
		(end 56.583326 -54.073298)
		(width 0.3556)
		(layer "B.Cu")
		(net "GND")
	)
	(segment
		(start 53.4924 -78.30185)
		(end 54.12359 -78.30185)
		(width 0.381)
		(layer "B.Cu")
		(net "GND")
	)
	(segment
		(start 56.54929 -52.507388)
		(end 56.490108 -52.56657)
		(width 0.3556)
		(layer "B.Cu")
		(net "GND")
	)
	(segment
		(start 71.599806 -72.447658)
		(end 71.599806 -73.059544)
		(width 0.381)
		(layer "B.Cu")
		(net "GND")
	)
	(segment
		(start 57.97042 -99.15906)
		(end 57.97042 -99.544378)
		(width 0.381)
		(layer "B.Cu")
		(net "GND")
	)
	(segment
		(start 80.006444 -48.861726)
		(end 79.833978 -48.68926)
		(width 0.381)
		(layer "B.Cu")
		(net "GND")
	)
	(segment
		(start 79.85125 -68.26885)
		(end 80.431386 -68.848986)
		(width 0.3048)
		(layer "B.Cu")
		(net "GND")
	)
	(segment
		(start 46.05401 -62.37986)
		(end 46.96206 -62.37986)
		(width 0.381)
		(layer "B.Cu")
		(net "GND")
	)
	(segment
		(start 54.723284 -54.87162)
		(end 54.480968 -54.87162)
		(width 0.381)
		(layer "B.Cu")
		(net "GND")
	)
	(segment
		(start 50.038254 -43.586654)
		(end 49.1617 -43.586654)
		(width 0.381)
		(layer "B.Cu")
		(net "GND")
	)
	(segment
		(start 53.424582 -55.65902)
		(end 53.424582 -55.53202)
		(width 0.381)
		(layer "B.Cu")
		(net "GND")
	)
	(segment
		(start 56.54929 -51.424078)
		(end 56.54929 -51.95697)
		(width 0.3556)
		(layer "B.Cu")
		(net "GND")
	)
	(segment
		(start 85.6996 -42.395394)
		(end 86.0552 -42.395394)
		(width 0.381)
		(layer "B.Cu")
		(net "GND")
	)
	(segment
		(start 83.418934 -38.13556)
		(end 84.401406 -38.13556)
		(width 0.381)
		(layer "B.Cu")
		(net "GND")
	)
	(segment
		(start 57.97042 -99.544378)
		(end 58.436002 -100.00996)
		(width 0.381)
		(layer "B.Cu")
		(net "GND")
	)
	(segment
		(start 56.583326 -54.073298)
		(end 56.490108 -54.166516)
		(width 0.3556)
		(layer "B.Cu")
		(net "GND")
	)
	(segment
		(start 40.460676 -68.0212)
		(end 39.294054 -68.0212)
		(width 0.381)
		(layer "B.Cu")
		(net "GND")
	)
	(segment
		(start 75.535028 -100.93071)
		(end 75.539346 -100.935028)
		(width 0.381)
		(layer "B.Cu")
		(net "GND")
	)
	(segment
		(start 57.864756 -50.175922)
		(end 57.290208 -50.175922)
		(width 0.3556)
		(layer "B.Cu")
		(net "GND")
	)
	(segment
		(start 79.17942 -54.434486)
		(end 79.034132 -54.289198)
		(width 0.381)
		(layer "B.Cu")
		(net "GND")
	)
	(segment
		(start 42.0878 -2.8194)
		(end 42.1894 -2.921)
		(width 0.381)
		(layer "B.Cu")
		(net "GND")
	)
	(segment
		(start 56.64581 -50.94097)
		(end 56.64581 -51.327558)
		(width 0.3556)
		(layer "B.Cu")
		(net "GND")
	)
	(segment
		(start 69.651626 -12.755626)
		(end 69.342 -12.446)
		(width 0.381)
		(layer "B.Cu")
		(net "GND")
	)
	(segment
		(start 31.000954 -31.73095)
		(end 30.639004 -31.369)
		(width 0.381)
		(layer "B.Cu")
		(net "GND")
	)
	(segment
		(start 45.30217 -22.2123)
		(end 44.4881 -22.2123)
		(width 0.381)
		(layer "B.Cu")
		(net "GND")
	)
	(segment
		(start 54.295548 -67.967352)
		(end 54.313582 -67.949318)
		(width 0.381)
		(layer "B.Cu")
		(net "GND")
	)
	(segment
		(start 40.854884 -118.25986)
		(end 40.854884 -116.871496)
		(width 0.381)
		(layer "B.Cu")
		(net "GND")
	)
	(segment
		(start 51.55946 -62.252098)
		(end 50.54346 -62.252098)
		(width 0.381)
		(layer "B.Cu")
		(net "GND")
	)
	(segment
		(start 60.673488 -42.79265)
		(end 60.4901 -42.976038)
		(width 0.381)
		(layer "B.Cu")
		(net "GND")
	)
	(segment
		(start 60.263278 -52.136294)
		(end 60.12053 -52.136294)
		(width 0.3556)
		(layer "B.Cu")
		(net "GND")
	)
	(segment
		(start 84.401406 -38.13556)
		(end 84.652612 -38.386766)
		(width 0.381)
		(layer "B.Cu")
		(net "GND")
	)
	(segment
		(start 52.494688 -53.964586)
		(end 52.398422 -53.964586)
		(width 0.3556)
		(layer "B.Cu")
		(net "GND")
	)
	(segment
		(start 22.96795 -19.05)
		(end 22.987 -19.06905)
		(width 0.381)
		(layer "B.Cu")
		(net "GND")
	)
	(segment
		(start 19.064224 -96.085914)
		(end 19.39036 -96.41205)
		(width 0.254)
		(layer "B.Cu")
		(net "GND")
	)
	(segment
		(start 54.12359 -78.30185)
		(end 54.25694 -78.4352)
		(width 0.381)
		(layer "B.Cu")
		(net "GND")
	)
	(segment
		(start 37.578538 -3.214878)
		(end 37.578538 -2.4892)
		(width 0.381)
		(layer "B.Cu")
		(net "GND")
	)
	(segment
		(start 36.021264 -67.74561)
		(end 36.23691 -67.74561)
		(width 0.254)
		(layer "B.Cu")
		(net "GND")
	)
	(segment
		(start 42.88917 -53.747416)
		(end 42.42943 -53.287676)
		(width 0.381)
		(layer "B.Cu")
		(net "GND")
	)
	(segment
		(start 32.23895 -31.115)
		(end 32.849312 -31.115)
		(width 0.381)
		(layer "B.Cu")
		(net "GND")
	)
	(segment
		(start 15.661894 -63.94323)
		(end 15.661894 -62.916054)
		(width 0.3556)
		(layer "B.Cu")
		(net "GND")
	)
	(segment
		(start 68.460112 -118.460012)
		(end 68.460112 -116.603018)
		(width 0.381)
		(layer "B.Cu")
		(net "GND")
	)
	(segment
		(start 29.21 -94.615)
		(end 29.97835 -95.38335)
		(width 0.381)
		(layer "B.Cu")
		(net "GND")
	)
	(segment
		(start 84.9884 -97.6376)
		(end 84.853018 -97.772982)
		(width 0.381)
		(layer "B.Cu")
		(net "GND")
	)
	(segment
		(start 76.582778 -49.03089)
		(end 76.582778 -49.64049)
		(width 0.381)
		(layer "B.Cu")
		(net "GND")
	)
	(segment
		(start 31.568898 -103.190548)
		(end 31.333948 -103.190548)
		(width 0.381)
		(layer "B.Cu")
		(net "GND")
	)
	(segment
		(start 44.2214 -63.356744)
		(end 44.2976 -63.280544)
		(width 0.3048)
		(layer "B.Cu")
		(net "GND")
	)
	(segment
		(start 83.56727 -45.570394)
		(end 83.56727 -45.365924)
		(width 0.381)
		(layer "B.Cu")
		(net "GND")
	)
	(segment
		(start 11.960098 -25.015952)
		(end 12.192 -24.78405)
		(width 0.381)
		(layer "B.Cu")
		(net "GND")
	)
	(segment
		(start 49.231296 -66.390774)
		(end 48.666654 -66.390774)
		(width 0.381)
		(layer "B.Cu")
		(net "GND")
	)
	(segment
		(start 38.608 -67.335146)
		(end 38.608 -66.82105)
		(width 0.381)
		(layer "B.Cu")
		(net "GND")
	)
	(segment
		(start 72.799194 -54.999636)
		(end 73.240646 -54.999636)
		(width 0.381)
		(layer "B.Cu")
		(net "GND")
	)
	(segment
		(start 57.673494 -44.992798)
		(end 57.290208 -45.376084)
		(width 0.381)
		(layer "B.Cu")
		(net "GND")
	)
	(segment
		(start 56.54929 -51.95697)
		(end 56.54929 -52.507388)
		(width 0.3556)
		(layer "B.Cu")
		(net "GND")
	)
	(segment
		(start 53.532024 -55.766462)
		(end 53.424582 -55.65902)
		(width 0.381)
		(layer "B.Cu")
		(net "GND")
	)
	(segment
		(start 41.503092 -48.381158)
		(end 40.95496 -48.381158)
		(width 0.254)
		(layer "B.Cu")
		(net "GND")
	)
	(segment
		(start 84.272628 -26.587704)
		(end 83.683602 -26.587704)
		(width 0.381)
		(layer "B.Cu")
		(net "GND")
	)
	(segment
		(start 84.9884 -97.3582)
		(end 84.9884 -97.6376)
		(width 0.381)
		(layer "B.Cu")
		(net "GND")
	)
	(segment
		(start 30.7086 -102.5652)
		(end 30.7086 -102.108)
		(width 0.381)
		(layer "B.Cu")
		(net "GND")
	)
	(segment
		(start 39.40175 -105.3465)
		(end 39.116 -105.3465)
		(width 0.381)
		(layer "B.Cu")
		(net "GND")
	)
	(segment
		(start 31.89605 -70.358)
		(end 33.25495 -70.358)
		(width 0.381)
		(layer "B.Cu")
		(net "GND")
	)
	(segment
		(start 47.167546 -105.37825)
		(end 47.21225 -105.422954)
		(width 0.381)
		(layer "B.Cu")
		(net "GND")
	)
	(segment
		(start 71.72833 -50.289206)
		(end 72.67067 -50.289206)
		(width 0.381)
		(layer "B.Cu")
		(net "GND")
	)
	(segment
		(start 31.623 -41.81475)
		(end 31.623 -42.4434)
		(width 0.381)
		(layer "B.Cu")
		(net "GND")
	)
	(segment
		(start 33.4518 -90.805)
		(end 33.8074 -91.1606)
		(width 0.381)
		(layer "B.Cu")
		(net "GND")
	)
	(segment
		(start 83.94827 -39.982394)
		(end 84.17687 -39.982394)
		(width 0.381)
		(layer "B.Cu")
		(net "GND")
	)
	(segment
		(start 37.6936 -39.56431)
		(end 38.82009 -39.56431)
		(width 0.381)
		(layer "B.Cu")
		(net "GND")
	)
	(segment
		(start 64.102996 -34.237676)
		(end 64.102996 -33.568386)
		(width 0.254)
		(layer "B.Cu")
		(net "GND")
	)
	(segment
		(start 52.424584 -54.93258)
		(end 52.424584 -54.656482)
		(width 0.381)
		(layer "B.Cu")
		(net "GND")
	)
	(segment
		(start 72.324468 -48.495458)
		(end 72.512428 -48.307498)
		(width 0.3556)
		(layer "B.Cu")
		(net "GND")
	)
	(segment
		(start 33.94456 -98.418396)
		(end 33.94456 -99.193096)
		(width 0.381)
		(layer "B.Cu")
		(net "GND")
	)
	(segment
		(start 12.036298 -53.988716)
		(end 12.119356 -53.905658)
		(width 0.381)
		(layer "B.Cu")
		(net "GND")
	)
	(segment
		(start 45.96765 -22.2123)
		(end 45.30217 -22.2123)
		(width 0.381)
		(layer "B.Cu")
		(net "GND")
	)
	(segment
		(start 76.562204 -52.286916)
		(end 76.562204 -53.3781)
		(width 0.381)
		(layer "B.Cu")
		(net "GND")
	)
	(segment
		(start 50.869596 -104.38384)
		(end 50.689256 -104.2035)
		(width 0.381)
		(layer "B.Cu")
		(net "GND")
	)
	(segment
		(start 16.145002 -118.460012)
		(end 16.145002 -116.8654)
		(width 0.381)
		(layer "B.Cu")
		(net "GND")
	)
	(segment
		(start 48.494188 -89.15146)
		(end 48.04029 -89.15146)
		(width 0.381)
		(layer "B.Cu")
		(net "GND")
	)
	(segment
		(start 60.19165 -95.0214)
		(end 60.19165 -94.889828)
		(width 0.381)
		(layer "B.Cu")
		(net "GND")
	)
	(segment
		(start 41.531286 -47.19701)
		(end 40.954198 -47.19701)
		(width 0.381)
		(layer "B.Cu")
		(net "GND")
	)
	(segment
		(start 70.65772 -52.648358)
		(end 70.5104 -52.501038)
		(width 0.381)
		(layer "B.Cu")
		(net "GND")
	)
	(segment
		(start 41.566084 -47.231808)
		(end 41.531286 -47.19701)
		(width 0.381)
		(layer "B.Cu")
		(net "GND")
	)
	(segment
		(start 84.17687 -47.602394)
		(end 84.7852 -47.602394)
		(width 0.381)
		(layer "B.Cu")
		(net "GND")
	)
	(segment
		(start 68.6054 -97.49155)
		(end 68.6054 -96.4946)
		(width 0.381)
		(layer "B.Cu")
		(net "GND")
	)
	(segment
		(start 46.0756 -93.3704)
		(end 46.0756 -92.93225)
		(width 0.381)
		(layer "B.Cu")
		(net "GND")
	)
	(segment
		(start 13.529818 -27.709876)
		(end 14.600174 -27.709876)
		(width 0.381)
		(layer "B.Cu")
		(net "GND")
	)
	(segment
		(start 79.85125 -65.779904)
		(end 79.85125 -66.1162)
		(width 0.3048)
		(layer "B.Cu")
		(net "GND")
	)
	(segment
		(start 35.3822 -65.5828)
		(end 35.687 -65.8876)
		(width 0.254)
		(layer "B.Cu")
		(net "GND")
	)
	(segment
		(start 81.529936 -40.990012)
		(end 82.139536 -40.990012)
		(width 0.381)
		(layer "B.Cu")
		(net "GND")
	)
	(segment
		(start 57.796938 -20.182078)
		(end 57.796938 -18.86585)
		(width 0.381)
		(layer "B.Cu")
		(net "GND")
	)
	(segment
		(start 81.529936 -45.054012)
		(end 82.139536 -45.054012)
		(width 0.381)
		(layer "B.Cu")
		(net "GND")
	)
	(segment
		(start 70.9168 -28.9814)
		(end 70.669658 -29.228542)
		(width 0.381)
		(layer "B.Cu")
		(net "GND")
	)
	(segment
		(start 39.294054 -68.0212)
		(end 38.608 -67.335146)
		(width 0.381)
		(layer "B.Cu")
		(net "GND")
	)
	(segment
		(start 19.431 -17.50695)
		(end 19.431 -16.891)
		(width 0.381)
		(layer "B.Cu")
		(net "GND")
	)
	(segment
		(start 84.272628 -27.607768)
		(end 84.297774 -27.582622)
		(width 0.381)
		(layer "B.Cu")
		(net "GND")
	)
	(segment
		(start 33.001712 -34.206688)
		(end 33.4518 -33.7566)
		(width 0.381)
		(layer "B.Cu")
		(net "GND")
	)
	(segment
		(start 59.109102 -49.356518)
		(end 59.151266 -49.314354)
		(width 0.3556)
		(layer "B.Cu")
		(net "GND")
	)
	(segment
		(start 35.455098 -118.460012)
		(end 35.456622 -118.458488)
		(width 0.3556)
		(layer "B.Cu")
		(net "GND")
	)
	(segment
		(start 59.781186 -86.14537)
		(end 59.300872 -86.625684)
		(width 0.381)
		(layer "B.Cu")
		(net "GND")
	)
	(segment
		(start 60.757816 -49.728882)
		(end 60.768484 -49.754536)
		(width 0.3556)
		(layer "B.Cu")
		(net "GND")
	)
	(segment
		(start 18.664428 -96.382078)
		(end 18.664428 -96.386904)
		(width 0.254)
		(layer "B.Cu")
		(net "GND")
	)
	(segment
		(start 61.479938 -20.182078)
		(end 60.794138 -20.182078)
		(width 0.381)
		(layer "B.Cu")
		(net "GND")
	)
	(segment
		(start 79.85125 -66.1162)
		(end 79.85125 -68.26885)
		(width 0.381)
		(layer "B.Cu")
		(net "GND")
	)
	(segment
		(start 76.66355 -26.18486)
		(end 78.72349 -26.18486)
		(width 0.381)
		(layer "B.Cu")
		(net "GND")
	)
	(segment
		(start 28.78455 -28.17495)
		(end 29.5148 -28.9052)
		(width 0.381)
		(layer "B.Cu")
		(net "GND")
	)
	(segment
		(start 65.956688 -89.976452)
		(end 64.9224 -91.01074)
		(width 0.381)
		(layer "B.Cu")
		(net "GND")
	)
	(segment
		(start 57.785 -24.53005)
		(end 57.808114 -24.506936)
		(width 0.381)
		(layer "B.Cu")
		(net "GND")
	)
	(segment
		(start 43.530012 -92.748862)
		(end 44.209716 -92.748862)
		(width 0.254)
		(layer "B.Cu")
		(net "GND")
	)
	(segment
		(start 64.35725 -89.2048)
		(end 64.5541 -89.2048)
		(width 0.381)
		(layer "B.Cu")
		(net "GND")
	)
	(segment
		(start 35.456622 -116.419122)
		(end 35.179 -116.1415)
		(width 0.3556)
		(layer "B.Cu")
		(net "GND")
	)
	(segment
		(start 69.6214 -95.4786)
		(end 70.1294 -95.4786)
		(width 0.381)
		(layer "B.Cu")
		(net "GND")
	)
	(segment
		(start 18.91665 -70.52945)
		(end 18.8722 -70.52945)
		(width 0.381)
		(layer "B.Cu")
		(net "GND")
	)
	(segment
		(start 43.8277 -100.8126)
		(end 43.8277 -101.26726)
		(width 0.381)
		(layer "B.Cu")
		(net "GND")
	)
	(segment
		(start 56.64581 -51.327558)
		(end 56.54929 -51.424078)
		(width 0.3556)
		(layer "B.Cu")
		(net "GND")
	)
	(segment
		(start 25.859486 -89.30386)
		(end 25.859486 -89.18702)
		(width 0.254)
		(layer "B.Cu")
		(net "GND")
	)
	(segment
		(start 19.376136 -70.988936)
		(end 18.91665 -70.52945)
		(width 0.381)
		(layer "B.Cu")
		(net "GND")
	)
	(segment
		(start 80.02905 -93.726)
		(end 80.02905 -93.091)
		(width 0.381)
		(layer "B.Cu")
		(net "GND")
	)
	(segment
		(start 53.75656 -67.967352)
		(end 54.295548 -67.967352)
		(width 0.381)
		(layer "B.Cu")
		(net "GND")
	)
	(segment
		(start 26.50236 -89.104724)
		(end 26.576782 -89.104724)
		(width 0.254)
		(layer "B.Cu")
		(net "GND")
	)
	(segment
		(start 50.865024 -117.209824)
		(end 50.865024 -118.460012)
		(width 0.381)
		(layer "B.Cu")
		(net "GND")
	)
	(segment
		(start 36.63315 -92.65285)
		(end 35.7378 -93.5482)
		(width 0.381)
		(layer "B.Cu")
		(net "GND")
	)
	(segment
		(start 34.163 -66.437002)
		(end 34.163 -65.988184)
		(width 0.254)
		(layer "B.Cu")
		(net "GND")
	)
	(segment
		(start 72.512428 -48.307498)
		(end 72.539606 -48.307498)
		(width 0.3556)
		(layer "B.Cu")
		(net "GND")
	)
	(segment
		(start 58.352436 -24.506936)
		(end 58.50255 -24.65705)
		(width 0.381)
		(layer "B.Cu")
		(net "GND")
	)
	(segment
		(start 52.384452 -59.734196)
		(end 52.384452 -59.651138)
		(width 0.381)
		(layer "B.Cu")
		(net "GND")
	)
	(segment
		(start 83.56727 -48.618394)
		(end 83.82127 -48.872394)
		(width 0.381)
		(layer "B.Cu")
		(net "GND")
	)
	(segment
		(start 57.808114 -24.506936)
		(end 58.352436 -24.506936)
		(width 0.381)
		(layer "B.Cu")
		(net "GND")
	)
	(segment
		(start 60.12053 -52.136294)
		(end 59.690254 -52.56657)
		(width 0.3556)
		(layer "B.Cu")
		(net "GND")
	)
	(segment
		(start 36.23691 -67.74561)
		(end 36.26612 -67.77482)
		(width 0.254)
		(layer "B.Cu")
		(net "GND")
	)
	(segment
		(start 81.529936 -43.022012)
		(end 82.139536 -43.022012)
		(width 0.381)
		(layer "B.Cu")
		(net "GND")
	)
	(segment
		(start 53.1622 -116.2558)
		(end 52.665122 -116.752878)
		(width 0.3302)
		(layer "B.Cu")
		(net "GND")
	)
	(segment
		(start 73.470516 -54.769766)
		(end 73.470516 -54.289198)
		(width 0.381)
		(layer "B.Cu")
		(net "GND")
	)
	(segment
		(start 19.744944 -118.460012)
		(end 19.744944 -116.925344)
		(width 0.381)
		(layer "B.Cu")
		(net "GND")
	)
	(segment
		(start 46.811184 -99.427792)
		(end 46.063408 -99.427792)
		(width 0.381)
		(layer "B.Cu")
		(net "GND")
	)
	(segment
		(start 26.659332 -89.34069)
		(end 26.659332 -89.187274)
		(width 0.254)
		(layer "B.Cu")
		(net "GND")
	)
	(segment
		(start 65.405 -69.57695)
		(end 65.33642 -69.50837)
		(width 0.381)
		(layer "B.Cu")
		(net "GND")
	)
	(segment
		(start 76.562204 -53.3781)
		(end 77.20076 -54.016656)
		(width 0.381)
		(layer "B.Cu")
		(net "GND")
	)
	(segment
		(start 52.384452 -59.651138)
		(end 51.699668 -58.966354)
		(width 0.381)
		(layer "B.Cu")
		(net "GND")
	)
	(segment
		(start 46.111414 -54.154324)
		(end 45.312076 -54.154324)
		(width 0.381)
		(layer "B.Cu")
		(net "GND")
	)
	(segment
		(start 58.092848 -49.94783)
		(end 57.864756 -50.175922)
		(width 0.3556)
		(layer "B.Cu")
		(net "GND")
	)
	(segment
		(start 50.54346 -62.252098)
		(end 50.54346 -62.943994)
		(width 0.381)
		(layer "B.Cu")
		(net "GND")
	)
	(segment
		(start 70.634606 -53.215794)
		(end 70.65772 -53.19268)
		(width 0.381)
		(layer "B.Cu")
		(net "GND")
	)
	(segment
		(start 32.893 -31.071312)
		(end 32.849312 -31.115)
		(width 0.381)
		(layer "B.Cu")
		(net "GND")
	)
	(segment
		(start 46.0502 -62.37605)
		(end 46.05401 -62.37986)
		(width 0.381)
		(layer "B.Cu")
		(net "GND")
	)
	(segment
		(start 49.553114 -60.607702)
		(end 49.994058 -61.048646)
		(width 0.381)
		(layer "B.Cu")
		(net "GND")
	)
	(segment
		(start 35.687 -67.411346)
		(end 36.021264 -67.74561)
		(width 0.254)
		(layer "B.Cu")
		(net "GND")
	)
	(segment
		(start 52.424584 -54.656482)
		(end 52.494688 -54.586378)
		(width 0.381)
		(layer "B.Cu")
		(net "GND")
	)
	(segment
		(start 70.397878 -30.524958)
		(end 70.669658 -30.253178)
		(width 0.381)
		(layer "B.Cu")
		(net "GND")
	)
	(segment
		(start 76.417424 -26.430986)
		(end 76.66355 -26.18486)
		(width 0.381)
		(layer "B.Cu")
		(net "GND")
	)
	(segment
		(start 68.95338 -54.953916)
		(end 68.872608 -54.953916)
		(width 0.381)
		(layer "B.Cu")
		(net "GND")
	)
	(segment
		(start 39.329868 -92.748862)
		(end 37.700712 -92.748862)
		(width 0.254)
		(layer "B.Cu")
		(net "GND")
	)
	(segment
		(start 60.537598 -50.311812)
		(end 59.956192 -50.700432)
		(width 0.3556)
		(layer "B.Cu")
		(net "GND")
	)
	(segment
		(start 33.33369 -70.43674)
		(end 33.25495 -70.358)
		(width 0.381)
		(layer "B.Cu")
		(net "GND")
	)
	(segment
		(start 52.665122 -116.752878)
		(end 52.665122 -118.460012)
		(width 0.3302)
		(layer "B.Cu")
		(net "GND")
	)
	(segment
		(start 18.669 -95.587058)
		(end 19.064224 -95.982282)
		(width 0.254)
		(layer "B.Cu")
		(net "GND")
	)
	(segment
		(start 52.398422 -53.964586)
		(end 51.800252 -53.366416)
		(width 0.3556)
		(layer "B.Cu")
		(net "GND")
	)
	(segment
		(start 33.33369 -71.162672)
		(end 33.33369 -70.43674)
		(width 0.381)
		(layer "B.Cu")
		(net "GND")
	)
	(segment
		(start 44.4881 -22.2123)
		(end 42.926 -20.6502)
		(width 0.381)
		(layer "B.Cu")
		(net "GND")
	)
	(segment
		(start 28.3464 -30.7594)
		(end 28.3464 -30.7975)
		(width 0.381)
		(layer "B.Cu")
		(net "GND")
	)
	(segment
		(start 48.943006 -21.11629)
		(end 48.593248 -21.466048)
		(width 0.381)
		(layer "B.Cu")
		(net "GND")
	)
	(segment
		(start 42.42943 -53.287676)
		(end 42.255694 -53.287676)
		(width 0.381)
		(layer "B.Cu")
		(net "GND")
	)
	(segment
		(start 54.61 -116.84)
		(end 54.464966 -116.985034)
		(width 0.3302)
		(layer "B.Cu")
		(net "GND")
	)
	(segment
		(start 49.48682 -21.11629)
		(end 48.943006 -21.11629)
		(width 0.381)
		(layer "B.Cu")
		(net "GND")
	)
	(segment
		(start 70.5104 -52.501038)
		(end 70.5104 -51.663854)
		(width 0.381)
		(layer "B.Cu")
		(net "GND")
	)
	(segment
		(start 56.4388 -116.7892)
		(end 56.265064 -116.962936)
		(width 0.3302)
		(layer "B.Cu")
		(net "GND")
	)
	(segment
		(start 48.25492 -71.477378)
		(end 48.063912 -71.28637)
		(width 0.381)
		(layer "B.Cu")
		(net "GND")
	)
	(segment
		(start 58.04408 -48.529748)
		(end 58.090308 -48.575976)
		(width 0.3556)
		(layer "B.Cu")
		(net "GND")
	)
	(segment
		(start 37.700712 -92.748862)
		(end 37.6047 -92.65285)
		(width 0.254)
		(layer "B.Cu")
		(net "GND")
	)
	(segment
		(start 28.575 -31.98495)
		(end 28.575 -31.496)
		(width 0.381)
		(layer "B.Cu")
		(net "GND")
	)
	(segment
		(start 40.5638 -56.896)
		(end 40.503856 -56.836056)
		(width 0.381)
		(layer "B.Cu")
		(net "GND")
	)
	(segment
		(start 30.988 -67.3227)
		(end 30.91688 -67.39382)
		(width 0.381)
		(layer "B.Cu")
		(net "GND")
	)
	(segment
		(start 35.7378 -93.5482)
		(end 35.7378 -94.044008)
		(width 0.381)
		(layer "B.Cu")
		(net "GND")
	)
	(segment
		(start 51.800252 -53.366416)
		(end 51.699668 -53.366416)
		(width 0.3556)
		(layer "B.Cu")
		(net "GND")
	)
	(segment
		(start 19.39036 -96.41205)
		(end 19.472656 -96.41205)
		(width 0.254)
		(layer "B.Cu")
		(net "GND")
	)
	(segment
		(start 36.6776 -100.965)
		(end 36.3982 -100.6856)
		(width 0.381)
		(layer "B.Cu")
		(net "GND")
	)
	(segment
		(start 70.832472 -47.506382)
		(end 71.821548 -48.495458)
		(width 0.3556)
		(layer "B.Cu")
		(net "GND")
	)
	(segment
		(start 8.92556 -27.7368)
		(end 9.7282 -27.7368)
		(width 0.381)
		(layer "B.Cu")
		(net "GND")
	)
	(segment
		(start 45.8089 -93.6371)
		(end 46.0756 -93.3704)
		(width 0.381)
		(layer "B.Cu")
		(net "GND")
	)
	(segment
		(start 42.926 -20.6502)
		(end 42.926 -19.83105)
		(width 0.381)
		(layer "B.Cu")
		(net "GND")
	)
	(segment
		(start 31.55315 -60.5282)
		(end 31.55315 -59.6392)
		(width 0.381)
		(layer "B.Cu")
		(net "GND")
	)
	(segment
		(start 21.971 -19.05)
		(end 22.96795 -19.05)
		(width 0.381)
		(layer "B.Cu")
		(net "GND")
	)
	(segment
		(start 19.064224 -95.982282)
		(end 18.664428 -96.382078)
		(width 0.254)
		(layer "B.Cu")
		(net "GND")
	)
	(segment
		(start 19.064224 -95.982282)
		(end 19.064224 -96.085914)
		(width 0.254)
		(layer "B.Cu")
		(net "GND")
	)
	(segment
		(start 31.55315 -60.5282)
		(end 30.2514 -60.5282)
		(width 0.381)
		(layer "B.Cu")
		(net "GND")
	)
	(segment
		(start 15.24 -18.68805)
		(end 15.24 -19.177)
		(width 0.381)
		(layer "B.Cu")
		(net "GND")
	)
	(segment
		(start 42.49166 -2.921)
		(end 42.785538 -3.214878)
		(width 0.381)
		(layer "B.Cu")
		(net "GND")
	)
	(segment
		(start 84.853018 -97.772982)
		(end 84.853018 -98.20529)
		(width 0.381)
		(layer "B.Cu")
		(net "GND")
	)
	(segment
		(start 80.431386 -68.848986)
		(end 80.431386 -69.618606)
		(width 0.3048)
		(layer "B.Cu")
		(net "GND")
	)
	(segment
		(start 56.68264 -92.1004)
		(end 55.886858 -92.896182)
		(width 0.381)
		(layer "B.Cu")
		(net "GND")
	)
	(segment
		(start 83.56727 -47.602394)
		(end 84.17687 -47.602394)
		(width 0.381)
		(layer "B.Cu")
		(net "GND")
	)
	(segment
		(start 40.964612 -56.896)
		(end 40.5638 -56.896)
		(width 0.381)
		(layer "B.Cu")
		(net "GND")
	)
	(segment
		(start 13.574014 -23.806404)
		(end 12.596368 -24.78405)
		(width 0.381)
		(layer "B.Cu")
		(net "GND")
	)
	(segment
		(start 15.113 -18.56105)
		(end 15.24 -18.68805)
		(width 0.381)
		(layer "B.Cu")
		(net "GND")
	)
	(segment
		(start 44.2087 -100.4316)
		(end 43.8277 -100.8126)
		(width 0.381)
		(layer "B.Cu")
		(net "GND")
	)
	(segment
		(start 80.086962 -52.942236)
		(end 79.833978 -52.689252)
		(width 0.381)
		(layer "B.Cu")
		(net "GND")
	)
	(segment
		(start 68.872608 -54.953916)
		(end 68.425314 -54.506622)
		(width 0.381)
		(layer "B.Cu")
		(net "GND")
	)
	(segment
		(start 46.063408 -99.427792)
		(end 45.0596 -100.4316)
		(width 0.381)
		(layer "B.Cu")
		(net "GND")
	)
	(segment
		(start 28.78455 -27.7622)
		(end 28.78455 -28.17495)
		(width 0.381)
		(layer "B.Cu")
		(net "GND")
	)
	(segment
		(start 73.240646 -54.999636)
		(end 73.470516 -54.769766)
		(width 0.381)
		(layer "B.Cu")
		(net "GND")
	)
	(segment
		(start 32.893 -30.37205)
		(end 32.893 -31.071312)
		(width 0.381)
		(layer "B.Cu")
		(net "GND")
	)
	(segment
		(start 21.545042 -118.460012)
		(end 21.545042 -116.8654)
		(width 0.381)
		(layer "B.Cu")
		(net "GND")
	)
	(segment
		(start 19.744944 -116.925344)
		(end 19.685 -116.8654)
		(width 0.381)
		(layer "B.Cu")
		(net "GND")
	)
	(segment
		(start 12.596368 -24.78405)
		(end 12.192 -24.78405)
		(width 0.381)
		(layer "B.Cu")
		(net "GND")
	)
	(segment
		(start 80.546194 -52.942236)
		(end 80.086962 -52.942236)
		(width 0.381)
		(layer "B.Cu")
		(net "GND")
	)
	(segment
		(start 33.16605 -90.805)
		(end 33.4518 -90.805)
		(width 0.381)
		(layer "B.Cu")
		(net "GND")
	)
	(segment
		(start 80.826864 -51.44135)
		(end 81.178654 -51.08956)
		(width 0.381)
		(layer "B.Cu")
		(net "GND")
	)
	(segment
		(start 54.099714 -42.976038)
		(end 54.117748 -42.958004)
		(width 0.381)
		(layer "B.Cu")
		(net "GND")
	)
	(segment
		(start 70.76567 -44.61129)
		(end 70.65137 -44.72559)
		(width 0.3048)
		(layer "B.Cu")
		(net "GND")
	)
	(segment
		(start 53.683408 -67.8942)
		(end 53.75656 -67.967352)
		(width 0.381)
		(layer "B.Cu")
		(net "GND")
	)
	(segment
		(start 33.4518 -33.7566)
		(end 33.4518 -33.274)
		(width 0.381)
		(layer "B.Cu")
		(net "GND")
	)
	(segment
		(start 48.04029 -89.15146)
		(end 47.55388 -88.66505)
		(width 0.381)
		(layer "B.Cu")
		(net "GND")
	)
	(segment
		(start 78.105 -65.151)
		(end 79.222346 -65.151)
		(width 0.3048)
		(layer "B.Cu")
		(net "GND")
	)
	(segment
		(start 17.864328 -97.182178)
		(end 17.464278 -97.582228)
		(width 0.254)
		(layer "B.Cu")
		(net "GND")
	)
	(segment
		(start 37.211 -19.9898)
		(end 37.2872 -20.066)
		(width 0.381)
		(layer "B.Cu")
		(net "GND")
	)
	(segment
		(start 42.29735 -58.0136)
		(end 42.242232 -57.958482)
		(width 0.381)
		(layer "B.Cu")
		(net "GND")
	)
	(segment
		(start 84.7852 -47.602394)
		(end 84.8995 -47.488094)
		(width 0.381)
		(layer "B.Cu")
		(net "GND")
	)
	(segment
		(start 34.568384 -65.5828)
		(end 35.3822 -65.5828)
		(width 0.254)
		(layer "B.Cu")
		(net "GND")
	)
	(segment
		(start 51.816 -29.8196)
		(end 51.816 -30.46095)
		(width 0.381)
		(layer "B.Cu")
		(net "GND")
	)
	(segment
		(start 69.342 -12.446)
		(end 68.98005 -12.446)
		(width 0.381)
		(layer "B.Cu")
		(net "GND")
	)
	(segment
		(start 59.662822 -94.361)
		(end 59.3344 -94.361)
		(width 0.381)
		(layer "B.Cu")
		(net "GND")
	)
	(segment
		(start 49.3014 -66.32067)
		(end 49.231296 -66.390774)
		(width 0.381)
		(layer "B.Cu")
		(net "GND")
	)
	(segment
		(start 28.575 -31.496)
		(end 28.448 -31.369)
		(width 0.381)
		(layer "B.Cu")
		(net "GND")
	)
	(segment
		(start 64.5541 -89.2048)
		(end 65.89268 -87.86622)
		(width 0.381)
		(layer "B.Cu")
		(net "GND")
	)
	(segment
		(start 79.17942 -54.898798)
		(end 79.17942 -54.434486)
		(width 0.381)
		(layer "B.Cu")
		(net "GND")
	)
	(segment
		(start 68.67525 -97.5614)
		(end 68.6054 -97.49155)
		(width 0.381)
		(layer "B.Cu")
		(net "GND")
	)
	(segment
		(start 48.3108 -24.82977)
		(end 48.3108 -25.527)
		(width 0.381)
		(layer "B.Cu")
		(net "GND")
	)
	(segment
		(start 69.036946 -18.8976)
		(end 68.24345 -18.8976)
		(width 0.381)
		(layer "B.Cu")
		(net "GND")
	)
	(segment
		(start 59.109102 -50.31359)
		(end 59.109102 -49.356518)
		(width 0.3556)
		(layer "B.Cu")
		(net "GND")
	)
	(segment
		(start 28.448 -30.8991)
		(end 28.448 -31.369)
		(width 0.381)
		(layer "B.Cu")
		(net "GND")
	)
	(segment
		(start 46.46295 -21.4122)
		(end 46.46295 -21.717)
		(width 0.381)
		(layer "B.Cu")
		(net "GND")
	)
	(segment
		(start 17.9451 -118.460012)
		(end 17.9451 -116.8654)
		(width 0.381)
		(layer "B.Cu")
		(net "GND")
	)
	(segment
		(start 72.621394 -72.447658)
		(end 71.599806 -72.447658)
		(width 0.381)
		(layer "B.Cu")
		(net "GND")
	)
	(segment
		(start 44.2976 -62.60465)
		(end 44.0944 -62.40145)
		(width 0.3048)
		(layer "B.Cu")
		(net "GND")
	)
	(segment
		(start 44.2976 -63.280544)
		(end 44.2976 -62.60465)
		(width 0.3048)
		(layer "B.Cu")
		(net "GND")
	)
	(segment
		(start 34.163 -65.988184)
		(end 34.568384 -65.5828)
		(width 0.254)
		(layer "B.Cu")
		(net "GND")
	)
	(segment
		(start 11.335766 -53.988716)
		(end 12.036298 -53.988716)
		(width 0.381)
		(layer "B.Cu")
		(net "GND")
	)
	(segment
		(start 59.151266 -48.837088)
		(end 58.890154 -48.575976)
		(width 0.3556)
		(layer "B.Cu")
		(net "GND")
	)
	(segment
		(start 70.669658 -29.228542)
		(end 70.669658 -29.817314)
		(width 0.381)
		(layer "B.Cu")
		(net "GND")
	)
	(segment
		(start 56.511698 -52.58816)
		(end 56.490108 -52.56657)
		(width 0.3556)
		(layer "B.Cu")
		(net "GND")
	)
	(segment
		(start 26.659586 -89.98712)
		(end 26.59761 -89.925144)
		(width 0.254)
		(layer "B.Cu")
		(net "GND")
	)
	(segment
		(start 50.689256 -104.2035)
		(end 50.19675 -104.2035)
		(width 0.381)
		(layer "B.Cu")
		(net "GND")
	)
	(segment
		(start 79.618586 -47.71009)
		(end 79.034132 -47.125636)
		(width 0.381)
		(layer "B.Cu")
		(net "GND")
	)
	(segment
		(start 58.326782 -52.58816)
		(end 56.511698 -52.58816)
		(width 0.3556)
		(layer "B.Cu")
		(net "GND")
	)
	(segment
		(start 65.33642 -69.50837)
		(end 64.360552 -69.50837)
		(width 0.381)
		(layer "B.Cu")
		(net "GND")
	)
	(segment
		(start 74.495406 -100.93071)
		(end 75.535028 -100.93071)
		(width 0.381)
		(layer "B.Cu")
		(net "GND")
	)
	(segment
		(start 43.1038 -62.763146)
		(end 43.697398 -63.356744)
		(width 0.3048)
		(layer "B.Cu")
		(net "GND")
	)
	(segment
		(start 54.464966 -116.985034)
		(end 54.464966 -118.460012)
		(width 0.3302)
		(layer "B.Cu")
		(net "GND")
	)
	(segment
		(start 25.45461 -89.591896)
		(end 25.57145 -89.591896)
		(width 0.254)
		(layer "B.Cu")
		(net "GND")
	)
	(segment
		(start 46.96206 -62.37986)
		(end 46.96206 -63.227966)
		(width 0.381)
		(layer "B.Cu")
		(net "GND")
	)
	(segment
		(start 71.68896 -50.249836)
		(end 71.72833 -50.289206)
		(width 0.381)
		(layer "B.Cu")
		(net "GND")
	)
	(segment
		(start 26.576782 -89.104724)
		(end 26.659332 -89.187274)
		(width 0.254)
		(layer "B.Cu")
		(net "GND")
	)
	(segment
		(start 33.328864 -71.167498)
		(end 33.33369 -71.162672)
		(width 0.381)
		(layer "B.Cu")
		(net "GND")
	)
	(segment
		(start 45.312076 -54.154324)
		(end 45.299884 -54.166516)
		(width 0.381)
		(layer "B.Cu")
		(net "GND")
	)
	(segment
		(start 52.494688 -54.586378)
		(end 52.494688 -53.964586)
		(width 0.381)
		(layer "B.Cu")
		(net "GND")
	)
	(segment
		(start 33.16605 -90.805)
		(end 33.16605 -89.789)
		(width 0.381)
		(layer "B.Cu")
		(net "GND")
	)
	(segment
		(start 70.358 -19.28495)
		(end 69.424296 -19.28495)
		(width 0.381)
		(layer "B.Cu")
		(net "GND")
	)
	(segment
		(start 81.529936 -44.038012)
		(end 82.139536 -44.038012)
		(width 0.381)
		(layer "B.Cu")
		(net "GND")
	)
	(segment
		(start 35.456622 -118.458488)
		(end 35.456622 -116.419122)
		(width 0.3556)
		(layer "B.Cu")
		(net "GND")
	)
	(segment
		(start 17.653 -59.92495)
		(end 18.288 -59.92495)
		(width 0.381)
		(layer "B.Cu")
		(net "GND")
	)
	(segment
		(start 30.988 -66.437002)
		(end 30.988 -67.3227)
		(width 0.381)
		(layer "B.Cu")
		(net "GND")
	)
	(segment
		(start 45.0596 -100.4316)
		(end 44.2087 -100.4316)
		(width 0.381)
		(layer "B.Cu")
		(net "GND")
	)
	(segment
		(start 43.697398 -63.356744)
		(end 44.2214 -63.356744)
		(width 0.3048)
		(layer "B.Cu")
		(net "GND")
	)
	(segment
		(start 58.702194 -44.806362)
		(end 57.679844 -44.806362)
		(width 0.381)
		(layer "B.Cu")
		(net "GND")
	)
	(segment
		(start 64.9224 -91.01074)
		(end 64.9224 -91.644724)
		(width 0.381)
		(layer "B.Cu")
		(net "GND")
	)
	(segment
		(start 26.59761 -89.925144)
		(end 26.59761 -89.402412)
		(width 0.254)
		(layer "B.Cu")
		(net "GND")
	)
	(segment
		(start 28.3464 -30.7975)
		(end 28.448 -30.8991)
		(width 0.381)
		(layer "B.Cu")
		(net "GND")
	)
	(segment
		(start 27.07005 -90.397584)
		(end 26.659586 -89.98712)
		(width 0.254)
		(layer "B.Cu")
		(net "GND")
	)
	(segment
		(start 71.26097 -44.61129)
		(end 70.76567 -44.61129)
		(width 0.3048)
		(layer "B.Cu")
		(net "GND")
	)
	(segment
		(start 71.374 -19.28495)
		(end 70.358 -19.28495)
		(width 0.381)
		(layer "B.Cu")
		(net "GND")
	)
	(segment
		(start 72.39 -19.28495)
		(end 71.374 -19.28495)
		(width 0.381)
		(layer "B.Cu")
		(net "GND")
	)
	(segment
		(start 37.2364 -104.2924)
		(end 37.00145 -104.05745)
		(width 0.381)
		(layer "B.Cu")
		(net "GND")
	)
	(segment
		(start 60.55868 -86.14537)
		(end 59.781186 -86.14537)
		(width 0.381)
		(layer "B.Cu")
		(net "GND")
	)
	(segment
		(start 79.618586 -47.846488)
		(end 79.618586 -47.71009)
		(width 0.381)
		(layer "B.Cu")
		(net "GND")
	)
	(segment
		(start 58.04408 -47.990252)
		(end 58.04408 -48.529748)
		(width 0.3556)
		(layer "B.Cu")
		(net "GND")
	)
	(segment
		(start 43.3578 -88.09355)
		(end 42.9768 -88.47455)
		(width 0.381)
		(layer "B.Cu")
		(net "GND")
	)
	(segment
		(start 48.25492 -72.954134)
		(end 48.25492 -73.94956)
		(width 0.381)
		(layer "B.Cu")
		(net "GND")
	)
	(segment
		(start 55.886858 -92.896182)
		(end 55.886858 -94.520766)
		(width 0.381)
		(layer "B.Cu")
		(net "GND")
	)
	(segment
		(start 83.56727 -45.365924)
		(end 84.086446 -45.041566)
		(width 0.381)
		(layer "B.Cu")
		(net "GND")
	)
	(segment
		(start 26.386536 -88.914478)
		(end 26.386536 -88.925146)
		(width 0.254)
		(layer "B.Cu")
		(net "GND")
	)
	(segment
		(start 80.512666 -48.861726)
		(end 80.006444 -48.861726)
		(width 0.381)
		(layer "B.Cu")
		(net "GND")
	)
	(segment
		(start 50.8 -117.1448)
		(end 50.865024 -117.209824)
		(width 0.381)
		(layer "B.Cu")
		(net "GND")
	)
	(segment
		(start 54.117748 -42.958004)
		(end 54.736492 -42.958004)
		(width 0.381)
		(layer "B.Cu")
		(net "GND")
	)
	(segment
		(start 48.666654 -66.390774)
		(end 48.662082 -66.386202)
		(width 0.381)
		(layer "B.Cu")
		(net "GND")
	)
	(segment
		(start 46.940724 -49.363122)
		(end 46.940724 -49.263046)
		(width 0.3556)
		(layer "B.Cu")
		(net "GND")
	)
	(segment
		(start 49.39919 -60.607702)
		(end 49.553114 -60.607702)
		(width 0.381)
		(layer "B.Cu")
		(net "GND")
	)
	(segment
		(start 46.46295 -21.717)
		(end 45.96765 -22.2123)
		(width 0.381)
		(layer "B.Cu")
		(net "GND")
	)
	(segment
		(start 31.877 -30.75305)
		(end 32.23895 -31.115)
		(width 0.381)
		(layer "B.Cu")
		(net "GND")
	)
	(segment
		(start 26.59761 -89.402412)
		(end 26.659332 -89.34069)
		(width 0.254)
		(layer "B.Cu")
		(net "GND")
	)
	(segment
		(start 54.099714 -55.252874)
		(end 54.099714 -55.766462)
		(width 0.381)
		(layer "B.Cu")
		(net "GND")
	)
	(segment
		(start 64.9224 -91.644724)
		(end 64.920622 -91.661742)
		(width 0.381)
		(layer "B.Cu")
		(net "GND")
	)
	(segment
		(start 41.57726 -68.22694)
		(end 40.666416 -68.22694)
		(width 0.381)
		(layer "B.Cu")
		(net "GND")
	)
	(segment
		(start 15.24 -19.91995)
		(end 15.24 -19.177)
		(width 0.381)
		(layer "B.Cu")
		(net "GND")
	)
	(segment
		(start 86.0552 -42.395394)
		(end 86.3092 -42.141394)
		(width 0.381)
		(layer "B.Cu")
		(net "GND")
	)
	(segment
		(start 83.56727 -40.490394)
		(end 83.56727 -40.363394)
		(width 0.381)
		(layer "B.Cu")
		(net "GND")
	)
	(segment
		(start 54.61 -116.4844)
		(end 54.61 -116.84)
		(width 0.3302)
		(layer "B.Cu")
		(net "GND")
	)
	(segment
		(start 37.00145 -100.965)
		(end 36.6776 -100.965)
		(width 0.381)
		(layer "B.Cu")
		(net "GND")
	)
	(segment
		(start 72.509126 -42.113708)
		(end 72.63892 -41.983914)
		(width 0.381)
		(layer "B.Cu")
		(net "GND")
	)
	(segment
		(start 65.171066 -39.755318)
		(end 64.894968 -39.47922)
		(width 0.381)
		(layer "B.Cu")
		(net "GND")
	)
	(segment
		(start 26.259282 -88.787224)
		(end 26.386536 -88.914478)
		(width 0.254)
		(layer "B.Cu")
		(net "GND")
	)
	(segment
		(start 46.3804 -105.37825)
		(end 47.167546 -105.37825)
		(width 0.381)
		(layer "B.Cu")
		(net "GND")
	)
	(segment
		(start 71.676768 -51.2318)
		(end 72.528176 -51.2318)
		(width 0.381)
		(layer "B.Cu")
		(net "GND")
	)
	(segment
		(start 18.659348 -95.587058)
		(end 18.669 -95.587058)
		(width 0.254)
		(layer "B.Cu")
		(net "GND")
	)
	(segment
		(start 31.333948 -103.190548)
		(end 30.7086 -102.5652)
		(width 0.381)
		(layer "B.Cu")
		(net "GND")
	)
	(segment
		(start 84.297774 -26.562558)
		(end 84.272628 -26.587704)
		(width 0.381)
		(layer "B.Cu")
		(net "GND")
	)
	(segment
		(start 50.155602 -43.704002)
		(end 50.038254 -43.586654)
		(width 0.381)
		(layer "B.Cu")
		(net "GND")
	)
	(segment
		(start 41.679876 -90.828876)
		(end 41.679876 -91.398852)
		(width 0.254)
		(layer "B.Cu")
		(net "GND")
	)
	(segment
		(start 24.2316 -16.891)
		(end 24.2316 -17.40535)
		(width 0.381)
		(layer "B.Cu")
		(net "GND")
	)
	(segment
		(start 47.014638 -63.280544)
		(end 44.2976 -63.280544)
		(width 0.381)
		(layer "In2.Cu")
		(net "GND")
	)
	(segment
		(start 29.1338 -65.5066)
		(end 28.829 -65.8114)
		(width 0.381)
		(layer "In2.Cu")
		(net "GND")
	)
	(segment
		(start 25.4635 -68.065396)
		(end 25.813004 -68.4149)
		(width 0.381)
		(layer "In2.Cu")
		(net "GND")
	)
	(segment
		(start 26.924 -65.8114)
		(end 26.4668 -66.2686)
		(width 0.381)
		(layer "In2.Cu")
		(net "GND")
	)
	(segment
		(start 48.662082 -66.386202)
		(end 48.29048 -66.0146)
		(width 0.381)
		(layer "In2.Cu")
		(net "GND")
	)
	(segment
		(start 36.34359 -67.77482)
		(end 36.26612 -67.77482)
		(width 0.381)
		(layer "In2.Cu")
		(net "GND")
	)
	(segment
		(start 31.6738 -65.5066)
		(end 29.1338 -65.5066)
		(width 0.381)
		(layer "In2.Cu")
		(net "GND")
	)
	(segment
		(start 41.301924 -68.149978)
		(end 40.842946 -67.691)
		(width 0.381)
		(layer "In2.Cu")
		(net "GND")
	)
	(segment
		(start 41.500298 -68.149978)
		(end 41.301924 -68.149978)
		(width 0.381)
		(layer "In2.Cu")
		(net "GND")
	)
	(segment
		(start 48.662082 -66.613278)
		(end 48.662082 -66.386202)
		(width 0.381)
		(layer "In2.Cu")
		(net "GND")
	)
	(segment
		(start 41.90492 -68.5546)
		(end 42.189146 -68.5546)
		(width 0.381)
		(layer "In2.Cu")
		(net "GND")
	)
	(segment
		(start 47.217838 -63.483744)
		(end 47.014638 -63.280544)
		(width 0.381)
		(layer "In2.Cu")
		(net "GND")
	)
	(segment
		(start 32.893508 -64.998092)
		(end 32.7406 -64.998092)
		(width 0.381)
		(layer "In2.Cu")
		(net "GND")
	)
	(segment
		(start 42.189146 -68.5546)
		(end 43.214798 -67.528948)
		(width 0.381)
		(layer "In2.Cu")
		(net "GND")
	)
	(segment
		(start 25.4635 -67.570604)
		(end 25.4635 -68.065396)
		(width 0.381)
		(layer "In2.Cu")
		(net "GND")
	)
	(segment
		(start 26.4668 -66.567304)
		(end 25.4635 -67.570604)
		(width 0.381)
		(layer "In2.Cu")
		(net "GND")
	)
	(segment
		(start 32.7406 -64.998092)
		(end 32.182308 -64.998092)
		(width 0.381)
		(layer "In2.Cu")
		(net "GND")
	)
	(segment
		(start 43.517312 -63.45301)
		(end 38.82009 -63.45301)
		(width 0.381)
		(layer "In2.Cu")
		(net "GND")
	)
	(segment
		(start 48.29048 -64.556386)
		(end 47.217838 -63.483744)
		(width 0.381)
		(layer "In2.Cu")
		(net "GND")
	)
	(segment
		(start 39.116 -67.691)
		(end 38.5318 -67.1068)
		(width 0.381)
		(layer "In2.Cu")
		(net "GND")
	)
	(segment
		(start 36.37661 -67.7418)
		(end 36.34359 -67.77482)
		(width 0.381)
		(layer "In2.Cu")
		(net "GND")
	)
	(segment
		(start 43.689778 -63.280544)
		(end 43.517312 -63.45301)
		(width 0.381)
		(layer "In2.Cu")
		(net "GND")
	)
	(segment
		(start 25.813004 -68.4149)
		(end 27.2161 -68.4149)
		(width 0.381)
		(layer "In2.Cu")
		(net "GND")
	)
	(segment
		(start 33.7312 -68.9102)
		(end 34.89579 -67.74561)
		(width 0.381)
		(layer "In2.Cu")
		(net "GND")
	)
	(segment
		(start 41.57726 -68.22694)
		(end 41.90492 -68.5546)
		(width 0.381)
		(layer "In2.Cu")
		(net "GND")
	)
	(segment
		(start 34.89579 -67.74561)
		(end 36.23691 -67.74561)
		(width 0.381)
		(layer "In2.Cu")
		(net "GND")
	)
	(segment
		(start 48.29048 -66.0146)
		(end 48.29048 -64.556386)
		(width 0.381)
		(layer "In2.Cu")
		(net "GND")
	)
	(segment
		(start 43.214798 -67.528948)
		(end 45.557948 -67.528948)
		(width 0.381)
		(layer "In2.Cu")
		(net "GND")
	)
	(segment
		(start 28.829 -65.8114)
		(end 26.924 -65.8114)
		(width 0.381)
		(layer "In2.Cu")
		(net "GND")
	)
	(segment
		(start 36.23691 -67.74561)
		(end 36.26612 -67.77482)
		(width 0.381)
		(layer "In2.Cu")
		(net "GND")
	)
	(segment
		(start 27.2161 -68.4149)
		(end 27.7114 -68.9102)
		(width 0.381)
		(layer "In2.Cu")
		(net "GND")
	)
	(segment
		(start 33.86201 -64.02959)
		(end 32.893508 -64.998092)
		(width 0.381)
		(layer "In2.Cu")
		(net "GND")
	)
	(segment
		(start 32.182308 -64.998092)
		(end 31.6738 -65.5066)
		(width 0.381)
		(layer "In2.Cu")
		(net "GND")
	)
	(segment
		(start 40.842946 -67.691)
		(end 39.116 -67.691)
		(width 0.381)
		(layer "In2.Cu")
		(net "GND")
	)
	(segment
		(start 45.557948 -67.528948)
		(end 46.1518 -68.1228)
		(width 0.381)
		(layer "In2.Cu")
		(net "GND")
	)
	(segment
		(start 44.2976 -63.280544)
		(end 43.689778 -63.280544)
		(width 0.381)
		(layer "In2.Cu")
		(net "GND")
	)
	(segment
		(start 41.57726 -68.22694)
		(end 41.500298 -68.149978)
		(width 0.381)
		(layer "In2.Cu")
		(net "GND")
	)
	(segment
		(start 27.7114 -68.9102)
		(end 33.7312 -68.9102)
		(width 0.381)
		(layer "In2.Cu")
		(net "GND")
	)
	(segment
		(start 26.4668 -66.2686)
		(end 26.4668 -66.567304)
		(width 0.381)
		(layer "In2.Cu")
		(net "GND")
	)
	(segment
		(start 38.24351 -64.02959)
		(end 33.86201 -64.02959)
		(width 0.381)
		(layer "In2.Cu")
		(net "GND")
	)
	(segment
		(start 37.5666 -67.1068)
		(end 36.9316 -67.7418)
		(width 0.381)
		(layer "In2.Cu")
		(net "GND")
	)
	(segment
		(start 38.82009 -63.45301)
		(end 38.24351 -64.02959)
		(width 0.381)
		(layer "In2.Cu")
		(net "GND")
	)
	(segment
		(start 36.9316 -67.7418)
		(end 36.37661 -67.7418)
		(width 0.381)
		(layer "In2.Cu")
		(net "GND")
	)
	(segment
		(start 38.5318 -67.1068)
		(end 37.5666 -67.1068)
		(width 0.381)
		(layer "In2.Cu")
		(net "GND")
	)
	(segment
		(start 46.1518 -68.1228)
		(end 47.15256 -68.1228)
		(width 0.381)
		(layer "In2.Cu")
		(net "GND")
	)
	(segment
		(start 47.15256 -68.1228)
		(end 48.662082 -66.613278)
		(width 0.381)
		(layer "In2.Cu")
		(net "GND")
	)
	(segment
		(start 22.225 -60.2742)
		(end 22.225 -59.65444)
		(width 0.381)
		(layer "In9.Cu")
		(net "GND")
	)
	(segment
		(start 28.85186 -61.62294)
		(end 29.435806 -61.038994)
		(width 0.381)
		(layer "In9.Cu")
		(net "GND")
	)
	(segment
		(start 20.28444 -50.51044)
		(end 20.28444 -49.833784)
		(width 0.381)
		(layer "In9.Cu")
		(net "GND")
	)
	(segment
		(start 25.0952 -32.87776)
		(end 25.71242 -32.26054)
		(width 0.381)
		(layer "In9.Cu")
		(net "GND")
	)
	(segment
		(start 28.448 -31.369)
		(end 28.6258 -31.1912)
		(width 0.381)
		(layer "In9.Cu")
		(net "GND")
	)
	(segment
		(start 27.8892 -68.58)
		(end 25.8445 -68.58)
		(width 0.381)
		(layer "In9.Cu")
		(net "GND")
	)
	(segment
		(start 23.0886 -56.6039)
		(end 23.0886 -52.832)
		(width 0.381)
		(layer "In9.Cu")
		(net "GND")
	)
	(segment
		(start 29.37383 -66.477134)
		(end 28.936442 -67.532758)
		(width 0.381)
		(layer "In9.Cu")
		(net "GND")
	)
	(segment
		(start 20.58924 -58.01868)
		(end 20.58924 -50.81524)
		(width 0.381)
		(layer "In9.Cu")
		(net "GND")
	)
	(segment
		(start 28.85186 -62.40018)
		(end 29.37383 -62.92215)
		(width 0.381)
		(layer "In9.Cu")
		(net "GND")
	)
	(segment
		(start 20.58924 -50.81524)
		(end 20.28444 -50.51044)
		(width 0.381)
		(layer "In9.Cu")
		(net "GND")
	)
	(segment
		(start 21.1074 -45.433488)
		(end 21.90242 -43.514264)
		(width 0.381)
		(layer "In9.Cu")
		(net "GND")
	)
	(segment
		(start 29.37383 -62.92215)
		(end 29.37383 -66.477134)
		(width 0.381)
		(layer "In9.Cu")
		(net "GND")
	)
	(segment
		(start 23.0886 -52.832)
		(end 23.527512 -52.393088)
		(width 0.381)
		(layer "In9.Cu")
		(net "GND")
	)
	(segment
		(start 23.527512 -52.393088)
		(end 23.527512 -46.169072)
		(width 0.381)
		(layer "In9.Cu")
		(net "GND")
	)
	(segment
		(start 21.117052 -48.218852)
		(end 20.7772 -47.879)
		(width 0.381)
		(layer "In9.Cu")
		(net "GND")
	)
	(segment
		(start 23.06828 -61.11748)
		(end 26.288746 -61.11748)
		(width 0.381)
		(layer "In9.Cu")
		(net "GND")
	)
	(segment
		(start 25.4635 -67.3735)
		(end 25.98928 -66.84772)
		(width 0.381)
		(layer "In9.Cu")
		(net "GND")
	)
	(segment
		(start 28.156662 -27.927808)
		(end 26.902664 -27.927808)
		(width 0.381)
		(layer "In9.Cu")
		(net "GND")
	)
	(segment
		(start 28.1051 -36.0045)
		(end 28.6512 -35.4584)
		(width 0.381)
		(layer "In9.Cu")
		(net "GND")
	)
	(segment
		(start 28.85186 -62.27318)
		(end 28.85186 -61.62294)
		(width 0.381)
		(layer "In9.Cu")
		(net "GND")
	)
	(segment
		(start 27.55646 -57.75706)
		(end 24.24176 -57.75706)
		(width 0.381)
		(layer "In9.Cu")
		(net "GND")
	)
	(segment
		(start 23.959312 -44.867068)
		(end 28.1051 -40.72128)
		(width 0.381)
		(layer "In9.Cu")
		(net "GND")
	)
	(segment
		(start 22.225 -60.2742)
		(end 23.06828 -61.11748)
		(width 0.381)
		(layer "In9.Cu")
		(net "GND")
	)
	(segment
		(start 28.1051 -40.72128)
		(end 28.1051 -36.0045)
		(width 0.381)
		(layer "In9.Cu")
		(net "GND")
	)
	(segment
		(start 29.435806 -59.636406)
		(end 27.55646 -57.75706)
		(width 0.381)
		(layer "In9.Cu")
		(net "GND")
	)
	(segment
		(start 25.8445 -68.58)
		(end 25.4635 -68.199)
		(width 0.381)
		(layer "In9.Cu")
		(net "GND")
	)
	(segment
		(start 25.71242 -32.083756)
		(end 25.71242 -32.26054)
		(width 0.381)
		(layer "In9.Cu")
		(net "GND")
	)
	(segment
		(start 25.0952 -36.085018)
		(end 25.0952 -32.87776)
		(width 0.381)
		(layer "In9.Cu")
		(net "GND")
	)
	(segment
		(start 25.69464 -39.722044)
		(end 25.69464 -36.684458)
		(width 0.381)
		(layer "In9.Cu")
		(net "GND")
	)
	(segment
		(start 26.53157 -28.298902)
		(end 26.53157 -31.264606)
		(width 0.381)
		(layer "In9.Cu")
		(net "GND")
	)
	(segment
		(start 20.7772 -47.879)
		(end 21.1074 -47.5488)
		(width 0.381)
		(layer "In9.Cu")
		(net "GND")
	)
	(segment
		(start 26.288746 -61.11748)
		(end 26.289 -61.117226)
		(width 0.381)
		(layer "In9.Cu")
		(net "GND")
	)
	(segment
		(start 21.1074 -47.5488)
		(end 21.1074 -45.433488)
		(width 0.381)
		(layer "In9.Cu")
		(net "GND")
	)
	(segment
		(start 20.28444 -49.833784)
		(end 21.117052 -49.001172)
		(width 0.381)
		(layer "In9.Cu")
		(net "GND")
	)
	(segment
		(start 21.90242 -43.514264)
		(end 25.69464 -39.722044)
		(width 0.381)
		(layer "In9.Cu")
		(net "GND")
	)
	(segment
		(start 22.225 -59.65444)
		(end 20.58924 -58.01868)
		(width 0.381)
		(layer "In9.Cu")
		(net "GND")
	)
	(segment
		(start 25.98928 -66.84772)
		(end 25.98928 -62.1411)
		(width 0.381)
		(layer "In9.Cu")
		(net "GND")
	)
	(segment
		(start 28.6512 -35.4584)
		(end 28.6512 -31.5722)
		(width 0.381)
		(layer "In9.Cu")
		(net "GND")
	)
	(segment
		(start 23.527512 -46.169072)
		(end 23.626826 -45.670216)
		(width 0.381)
		(layer "In9.Cu")
		(net "GND")
	)
	(segment
		(start 26.289 -61.84138)
		(end 26.289 -61.117226)
		(width 0.381)
		(layer "In9.Cu")
		(net "GND")
	)
	(segment
		(start 25.69464 -36.684458)
		(end 25.0952 -36.085018)
		(width 0.381)
		(layer "In9.Cu")
		(net "GND")
	)
	(segment
		(start 28.6512 -31.5722)
		(end 28.448 -31.369)
		(width 0.381)
		(layer "In9.Cu")
		(net "GND")
	)
	(segment
		(start 26.53157 -31.264606)
		(end 25.71242 -32.083756)
		(width 0.381)
		(layer "In9.Cu")
		(net "GND")
	)
	(segment
		(start 23.626826 -45.670216)
		(end 23.959312 -44.867068)
		(width 0.381)
		(layer "In9.Cu")
		(net "GND")
	)
	(segment
		(start 26.902664 -27.927808)
		(end 26.53157 -28.298902)
		(width 0.381)
		(layer "In9.Cu")
		(net "GND")
	)
	(segment
		(start 28.6258 -28.396946)
		(end 28.156662 -27.927808)
		(width 0.381)
		(layer "In9.Cu")
		(net "GND")
	)
	(segment
		(start 29.435806 -61.038994)
		(end 29.435806 -59.636406)
		(width 0.381)
		(layer "In9.Cu")
		(net "GND")
	)
	(segment
		(start 28.85186 -62.27318)
		(end 28.85186 -62.40018)
		(width 0.381)
		(layer "In9.Cu")
		(net "GND")
	)
	(segment
		(start 28.6258 -31.1912)
		(end 28.6258 -28.396946)
		(width 0.381)
		(layer "In9.Cu")
		(net "GND")
	)
	(segment
		(start 24.24176 -57.75706)
		(end 23.0886 -56.6039)
		(width 0.381)
		(layer "In9.Cu")
		(net "GND")
	)
	(segment
		(start 25.98928 -62.1411)
		(end 26.289 -61.84138)
		(width 0.381)
		(layer "In9.Cu")
		(net "GND")
	)
	(segment
		(start 28.936442 -67.532758)
		(end 27.8892 -68.58)
		(width 0.381)
		(layer "In9.Cu")
		(net "GND")
	)
	(segment
		(start 25.4635 -68.199)
		(end 25.4635 -67.3735)
		(width 0.381)
		(layer "In9.Cu")
		(net "GND")
	)
	(segment
		(start 21.117052 -49.001172)
		(end 21.117052 -48.218852)
		(width 0.381)
		(layer "In9.Cu")
		(net "GND")
	)
	(via
		(at 81.915 -26.1366)
		(size 0.762)
		(drill 0.254)
		(layers "F.Cu" "B.Cu")
		(net "FRU_E2")
	)
	(segment
		(start 78.72349 -26.834846)
		(end 79.7179 -26.834846)
		(width 0.11684)
		(layer "B.Cu")
		(net "FRU_E2")
	)
	(segment
		(start 80.416146 -26.1366)
		(end 81.915 -26.1366)
		(width 0.11684)
		(layer "B.Cu")
		(net "FRU_E2")
	)
	(segment
		(start 82.883502 -26.587704)
		(end 82.945478 -26.587704)
		(width 0.11684)
		(layer "B.Cu")
		(net "FRU_E2")
	)
	(segment
		(start 79.7179 -26.834846)
		(end 80.416146 -26.1366)
		(width 0.11684)
		(layer "B.Cu")
		(net "FRU_E2")
	)
	(segment
		(start 82.432398 -26.1366)
		(end 82.883502 -26.587704)
		(width 0.11684)
		(layer "B.Cu")
		(net "FRU_E2")
	)
	(segment
		(start 81.915 -26.1366)
		(end 82.432398 -26.1366)
		(width 0.11684)
		(layer "B.Cu")
		(net "FRU_E2")
	)
	(segment
		(start 84.92236 -26.965656)
		(end 84.92236 -26.587704)
		(width 0.11684)
		(layer "B.Cu")
		(net "FRU_E2")
	)
	(segment
		(start 82.945478 -26.587704)
		(end 83.43773 -27.079956)
		(width 0.11684)
		(layer "B.Cu")
		(net "FRU_E2")
	)
	(segment
		(start 84.80806 -27.079956)
		(end 84.92236 -26.965656)
		(width 0.11684)
		(layer "B.Cu")
		(net "FRU_E2")
	)
	(segment
		(start 83.43773 -27.079956)
		(end 84.80806 -27.079956)
		(width 0.11684)
		(layer "B.Cu")
		(net "FRU_E2")
	)
	(via
		(at 81.7372 -27.686)
		(size 0.6604)
		(drill 0.3302)
		(layers "F.Cu" "B.Cu")
		(net "FRU_E1")
	)
	(segment
		(start 78.72349 -27.485086)
		(end 79.673196 -27.485086)
		(width 0.11684)
		(layer "B.Cu")
		(net "FRU_E1")
	)
	(segment
		(start 82.086958 -27.686)
		(end 82.16519 -27.607768)
		(width 0.11684)
		(layer "B.Cu")
		(net "FRU_E1")
	)
	(segment
		(start 79.673196 -27.485086)
		(end 80.107282 -27.051)
		(width 0.11684)
		(layer "B.Cu")
		(net "FRU_E1")
	)
	(segment
		(start 82.883502 -27.607768)
		(end 82.923888 -27.607768)
		(width 0.11684)
		(layer "B.Cu")
		(net "FRU_E1")
	)
	(segment
		(start 81.7372 -27.686)
		(end 82.086958 -27.686)
		(width 0.11684)
		(layer "B.Cu")
		(net "FRU_E1")
	)
	(segment
		(start 84.92236 -27.992324)
		(end 84.92236 -27.607768)
		(width 0.11684)
		(layer "B.Cu")
		(net "FRU_E1")
	)
	(segment
		(start 84.80806 -28.106624)
		(end 84.92236 -27.992324)
		(width 0.11684)
		(layer "B.Cu")
		(net "FRU_E1")
	)
	(segment
		(start 83.422744 -28.106624)
		(end 84.80806 -28.106624)
		(width 0.11684)
		(layer "B.Cu")
		(net "FRU_E1")
	)
	(segment
		(start 81.1022 -27.051)
		(end 81.7372 -27.686)
		(width 0.11684)
		(layer "B.Cu")
		(net "FRU_E1")
	)
	(segment
		(start 80.107282 -27.051)
		(end 81.1022 -27.051)
		(width 0.11684)
		(layer "B.Cu")
		(net "FRU_E1")
	)
	(segment
		(start 82.923888 -27.607768)
		(end 83.422744 -28.106624)
		(width 0.11684)
		(layer "B.Cu")
		(net "FRU_E1")
	)
	(segment
		(start 82.16519 -27.607768)
		(end 82.883502 -27.607768)
		(width 0.11684)
		(layer "B.Cu")
		(net "FRU_E1")
	)
	(via
		(at 80.518 -28.321)
		(size 0.6604)
		(drill 0.3302)
		(layers "F.Cu" "B.Cu")
		(net "FRU_E0")
	)
	(segment
		(start 82.93735 -28.627578)
		(end 83.572604 -29.262832)
		(width 0.11684)
		(layer "B.Cu")
		(net "FRU_E0")
	)
	(segment
		(start 83.572604 -29.262832)
		(end 84.584032 -29.262832)
		(width 0.11684)
		(layer "B.Cu")
		(net "FRU_E0")
	)
	(segment
		(start 82.883502 -28.627578)
		(end 82.93735 -28.627578)
		(width 0.11684)
		(layer "B.Cu")
		(net "FRU_E0")
	)
	(segment
		(start 84.92236 -28.924504)
		(end 84.92236 -28.627832)
		(width 0.11684)
		(layer "B.Cu")
		(net "FRU_E0")
	)
	(segment
		(start 80.010254 -28.321)
		(end 79.824326 -28.135072)
		(width 0.11684)
		(layer "B.Cu")
		(net "FRU_E0")
	)
	(segment
		(start 80.824578 -28.627578)
		(end 80.518 -28.321)
		(width 0.11684)
		(layer "B.Cu")
		(net "FRU_E0")
	)
	(segment
		(start 80.518 -28.321)
		(end 80.010254 -28.321)
		(width 0.11684)
		(layer "B.Cu")
		(net "FRU_E0")
	)
	(segment
		(start 82.883502 -28.627578)
		(end 80.824578 -28.627578)
		(width 0.11684)
		(layer "B.Cu")
		(net "FRU_E0")
	)
	(segment
		(start 79.824326 -28.135072)
		(end 78.72349 -28.135072)
		(width 0.11684)
		(layer "B.Cu")
		(net "FRU_E0")
	)
	(segment
		(start 84.584032 -29.262832)
		(end 84.92236 -28.924504)
		(width 0.11684)
		(layer "B.Cu")
		(net "FRU_E0")
	)
	(segment
		(start 12.389104 -10.380472)
		(end 11.551666 -11.21791)
		(width 0.11684)
		(layer "F.Cu")
		(net "REAR_PWR_BTN_N")
	)
	(segment
		(start 10.261854 -8.166862)
		(end 10.17905 -8.249666)
		(width 0.11684)
		(layer "F.Cu")
		(net "REAR_PWR_BTN_N")
	)
	(segment
		(start 12.389104 -9.331452)
		(end 12.389104 -10.380472)
		(width 0.11684)
		(layer "F.Cu")
		(net "REAR_PWR_BTN_N")
	)
	(segment
		(start 11.933936 -9.628886)
		(end 11.933936 -9.216644)
		(width 0.11684)
		(layer "F.Cu")
		(net "REAR_PWR_BTN_N")
	)
	(segment
		(start 12.292838 -8.857742)
		(end 12.862814 -8.857742)
		(width 0.11684)
		(layer "F.Cu")
		(net "REAR_PWR_BTN_N")
	)
	(segment
		(start 10.249916 -6.99008)
		(end 10.261854 -7.002018)
		(width 0.11684)
		(layer "F.Cu")
		(net "REAR_PWR_BTN_N")
	)
	(segment
		(start 11.551666 -11.21791)
		(end 11.551666 -11.657838)
		(width 0.11684)
		(layer "F.Cu")
		(net "REAR_PWR_BTN_N")
	)
	(segment
		(start 10.261854 -7.002018)
		(end 10.261854 -8.166862)
		(width 0.11684)
		(layer "F.Cu")
		(net "REAR_PWR_BTN_N")
	)
	(segment
		(start 11.933936 -9.628886)
		(end 11.368786 -9.063736)
		(width 0.11684)
		(layer "F.Cu")
		(net "REAR_PWR_BTN_N")
	)
	(segment
		(start 10.17905 -8.249666)
		(end 10.17905 -9.652)
		(width 0.11684)
		(layer "F.Cu")
		(net "REAR_PWR_BTN_N")
	)
	(segment
		(start 12.862814 -8.857742)
		(end 12.389104 -9.331452)
		(width 0.11684)
		(layer "F.Cu")
		(net "REAR_PWR_BTN_N")
	)
	(segment
		(start 11.933936 -9.216644)
		(end 12.292838 -8.857742)
		(width 0.11684)
		(layer "F.Cu")
		(net "REAR_PWR_BTN_N")
	)
	(segment
		(start 10.767314 -9.063736)
		(end 10.17905 -9.652)
		(width 0.11684)
		(layer "F.Cu")
		(net "REAR_PWR_BTN_N")
	)
	(segment
		(start 11.95705 -9.652)
		(end 11.933936 -9.628886)
		(width 0.11684)
		(layer "F.Cu")
		(net "REAR_PWR_BTN_N")
	)
	(segment
		(start 11.368786 -9.063736)
		(end 10.767314 -9.063736)
		(width 0.11684)
		(layer "F.Cu")
		(net "REAR_PWR_BTN_N")
	)
	(segment
		(start 30.2514 -101.44125)
		(end 31.12135 -101.44125)
		(width 0.11684)
		(layer "F.Cu")
		(net "FM_THROTTLE_N")
	)
	(segment
		(start 52.894992 -40.17137)
		(end 52.499768 -39.776146)
		(width 0.11684)
		(layer "F.Cu")
		(net "FM_THROTTLE_N")
	)
	(segment
		(start 31.12135 -101.44125)
		(end 31.794196 -100.768404)
		(width 0.11684)
		(layer "F.Cu")
		(net "FM_THROTTLE_N")
	)
	(segment
		(start 29.591 -102.36835)
		(end 29.939996 -102.36835)
		(width 0.11684)
		(layer "F.Cu")
		(net "FM_THROTTLE_N")
	)
	(segment
		(start 30.2514 -102.056946)
		(end 30.2514 -101.44125)
		(width 0.11684)
		(layer "F.Cu")
		(net "FM_THROTTLE_N")
	)
	(segment
		(start 29.939996 -102.36835)
		(end 30.2514 -102.056946)
		(width 0.11684)
		(layer "F.Cu")
		(net "FM_THROTTLE_N")
	)
	(segment
		(start 31.794196 -100.768404)
		(end 31.794196 -100.054664)
		(width 0.11684)
		(layer "F.Cu")
		(net "FM_THROTTLE_N")
	)
	(via
		(at 52.499768 -39.776146)
		(size 0.4572)
		(drill 0.254)
		(layers "F.Cu" "B.Cu")
		(net "FM_THROTTLE_N")
	)
	(via
		(at 36.04006 -78.88478)
		(size 0.508)
		(drill 0.254)
		(layers "F.Cu" "B.Cu")
		(net "FM_THROTTLE_N")
	)
	(via
		(at 31.794196 -100.054664)
		(size 0.508)
		(drill 0.254)
		(layers "F.Cu" "B.Cu")
		(net "FM_THROTTLE_N")
	)
	(segment
		(start 34.798 -56.801512)
		(end 34.798 -57.9628)
		(width 0.10668)
		(layer "In4.Cu")
		(net "FM_THROTTLE_N")
	)
	(segment
		(start 36.682426 -71.778876)
		(end 35.328352 -73.132442)
		(width 0.10668)
		(layer "In4.Cu")
		(net "FM_THROTTLE_N")
	)
	(segment
		(start 44.373546 -39.359586)
		(end 44.0944 -39.638732)
		(width 0.10668)
		(layer "In4.Cu")
		(net "FM_THROTTLE_N")
	)
	(segment
		(start 44.0944 -40.809164)
		(end 39.089584 -45.81398)
		(width 0.10668)
		(layer "In4.Cu")
		(net "FM_THROTTLE_N")
	)
	(segment
		(start 36.34486 -64.91224)
		(end 36.34486 -65.501266)
		(width 0.10668)
		(layer "In4.Cu")
		(net "FM_THROTTLE_N")
	)
	(segment
		(start 34.286952 -73.132442)
		(end 33.32734 -74.092054)
		(width 0.10668)
		(layer "In4.Cu")
		(net "FM_THROTTLE_N")
	)
	(segment
		(start 36.907724 -71.298816)
		(end 36.682426 -71.778876)
		(width 0.10668)
		(layer "In4.Cu")
		(net "FM_THROTTLE_N")
	)
	(segment
		(start 35.51174 -59.97194)
		(end 35.51174 -64.07912)
		(width 0.10668)
		(layer "In4.Cu")
		(net "FM_THROTTLE_N")
	)
	(segment
		(start 33.32734 -76.50734)
		(end 35.70478 -78.88478)
		(width 0.10668)
		(layer "In4.Cu")
		(net "FM_THROTTLE_N")
	)
	(segment
		(start 35.08502 -56.514492)
		(end 34.798 -56.801512)
		(width 0.10668)
		(layer "In4.Cu")
		(net "FM_THROTTLE_N")
	)
	(segment
		(start 33.32734 -74.092054)
		(end 33.32734 -76.50734)
		(width 0.10668)
		(layer "In4.Cu")
		(net "FM_THROTTLE_N")
	)
	(segment
		(start 44.883324 -39.13505)
		(end 44.658788 -39.359586)
		(width 0.10668)
		(layer "In4.Cu")
		(net "FM_THROTTLE_N")
	)
	(segment
		(start 34.921952 -58.086752)
		(end 34.921952 -59.382152)
		(width 0.10668)
		(layer "In4.Cu")
		(net "FM_THROTTLE_N")
	)
	(segment
		(start 35.328352 -73.132442)
		(end 34.286952 -73.132442)
		(width 0.10668)
		(layer "In4.Cu")
		(net "FM_THROTTLE_N")
	)
	(segment
		(start 36.6268 -46.0756)
		(end 35.881564 -46.820836)
		(width 0.10668)
		(layer "In4.Cu")
		(net "FM_THROTTLE_N")
	)
	(segment
		(start 36.34486 -65.501266)
		(end 36.72586 -65.882266)
		(width 0.10668)
		(layer "In4.Cu")
		(net "FM_THROTTLE_N")
	)
	(segment
		(start 35.881564 -46.820836)
		(end 35.881564 -47.17161)
		(width 0.10668)
		(layer "In4.Cu")
		(net "FM_THROTTLE_N")
	)
	(segment
		(start 35.203638 -52.773834)
		(end 34.45256 -53.524912)
		(width 0.10668)
		(layer "In4.Cu")
		(net "FM_THROTTLE_N")
	)
	(segment
		(start 44.658788 -39.359586)
		(end 44.373546 -39.359586)
		(width 0.10668)
		(layer "In4.Cu")
		(net "FM_THROTTLE_N")
	)
	(segment
		(start 44.883324 -39.123112)
		(end 44.883324 -39.13505)
		(width 0.10668)
		(layer "In4.Cu")
		(net "FM_THROTTLE_N")
	)
	(segment
		(start 36.907724 -69.295772)
		(end 36.907724 -71.298816)
		(width 0.10668)
		(layer "In4.Cu")
		(net "FM_THROTTLE_N")
	)
	(segment
		(start 34.45256 -53.524912)
		(end 34.45256 -55.15356)
		(width 0.10668)
		(layer "In4.Cu")
		(net "FM_THROTTLE_N")
	)
	(segment
		(start 34.798 -57.9628)
		(end 34.921952 -58.086752)
		(width 0.10668)
		(layer "In4.Cu")
		(net "FM_THROTTLE_N")
	)
	(segment
		(start 34.921952 -59.382152)
		(end 35.51174 -59.97194)
		(width 0.10668)
		(layer "In4.Cu")
		(net "FM_THROTTLE_N")
	)
	(segment
		(start 39.089584 -45.81398)
		(end 38.45814 -46.0756)
		(width 0.10668)
		(layer "In4.Cu")
		(net "FM_THROTTLE_N")
	)
	(segment
		(start 35.08502 -55.78602)
		(end 35.08502 -56.514492)
		(width 0.10668)
		(layer "In4.Cu")
		(net "FM_THROTTLE_N")
	)
	(segment
		(start 45.91304 -38.093396)
		(end 44.883324 -39.123112)
		(width 0.10668)
		(layer "In4.Cu")
		(net "FM_THROTTLE_N")
	)
	(segment
		(start 52.499768 -39.776146)
		(end 50.817018 -38.093396)
		(width 0.10668)
		(layer "In4.Cu")
		(net "FM_THROTTLE_N")
	)
	(segment
		(start 35.881564 -47.17161)
		(end 35.203638 -48.80864)
		(width 0.10668)
		(layer "In4.Cu")
		(net "FM_THROTTLE_N")
	)
	(segment
		(start 38.45814 -46.0756)
		(end 36.6268 -46.0756)
		(width 0.10668)
		(layer "In4.Cu")
		(net "FM_THROTTLE_N")
	)
	(segment
		(start 36.72586 -65.882266)
		(end 36.72586 -68.856352)
		(width 0.10668)
		(layer "In4.Cu")
		(net "FM_THROTTLE_N")
	)
	(segment
		(start 36.72586 -68.856352)
		(end 36.907724 -69.295772)
		(width 0.10668)
		(layer "In4.Cu")
		(net "FM_THROTTLE_N")
	)
	(segment
		(start 44.0944 -39.638732)
		(end 44.0944 -40.809164)
		(width 0.10668)
		(layer "In4.Cu")
		(net "FM_THROTTLE_N")
	)
	(segment
		(start 50.817018 -38.093396)
		(end 45.91304 -38.093396)
		(width 0.10668)
		(layer "In4.Cu")
		(net "FM_THROTTLE_N")
	)
	(segment
		(start 35.51174 -64.07912)
		(end 36.34486 -64.91224)
		(width 0.10668)
		(layer "In4.Cu")
		(net "FM_THROTTLE_N")
	)
	(segment
		(start 35.203638 -48.80864)
		(end 35.203638 -52.773834)
		(width 0.10668)
		(layer "In4.Cu")
		(net "FM_THROTTLE_N")
	)
	(segment
		(start 35.70478 -78.88478)
		(end 36.04006 -78.88478)
		(width 0.10668)
		(layer "In4.Cu")
		(net "FM_THROTTLE_N")
	)
	(segment
		(start 34.45256 -55.15356)
		(end 35.08502 -55.78602)
		(width 0.10668)
		(layer "In4.Cu")
		(net "FM_THROTTLE_N")
	)
	(segment
		(start 34.56813 -92.188284)
		(end 34.19475 -92.561664)
		(width 0.08382)
		(layer "In9.Cu")
		(net "FM_THROTTLE_N")
	)
	(segment
		(start 34.53003 -90.61577)
		(end 34.56813 -90.65387)
		(width 0.08382)
		(layer "In9.Cu")
		(net "FM_THROTTLE_N")
	)
	(segment
		(start 34.56813 -90.65387)
		(end 34.56813 -92.188284)
		(width 0.08382)
		(layer "In9.Cu")
		(net "FM_THROTTLE_N")
	)
	(segment
		(start 33.94837 -95.550736)
		(end 33.94837 -98.12528)
		(width 0.08382)
		(layer "In9.Cu")
		(net "FM_THROTTLE_N")
	)
	(segment
		(start 35.64255 -83.25485)
		(end 35.64255 -86.374732)
		(width 0.08382)
		(layer "In9.Cu")
		(net "FM_THROTTLE_N")
	)
	(segment
		(start 34.75355 -87.263732)
		(end 34.75355 -89.50325)
		(width 0.08382)
		(layer "In9.Cu")
		(net "FM_THROTTLE_N")
	)
	(segment
		(start 33.94837 -98.12528)
		(end 32.98952 -99.08413)
		(width 0.08382)
		(layer "In9.Cu")
		(net "FM_THROTTLE_N")
	)
	(segment
		(start 32.98952 -99.08413)
		(end 32.056324 -99.08413)
		(width 0.08382)
		(layer "In9.Cu")
		(net "FM_THROTTLE_N")
	)
	(segment
		(start 34.19475 -94.955868)
		(end 33.94837 -95.550736)
		(width 0.08382)
		(layer "In9.Cu")
		(net "FM_THROTTLE_N")
	)
	(segment
		(start 34.19475 -92.561664)
		(end 34.19475 -94.955868)
		(width 0.08382)
		(layer "In9.Cu")
		(net "FM_THROTTLE_N")
	)
	(segment
		(start 36.04006 -78.88478)
		(end 36.04006 -82.85734)
		(width 0.08382)
		(layer "In9.Cu")
		(net "FM_THROTTLE_N")
	)
	(segment
		(start 32.056324 -99.08413)
		(end 31.794196 -99.346258)
		(width 0.08382)
		(layer "In9.Cu")
		(net "FM_THROTTLE_N")
	)
	(segment
		(start 34.53003 -89.72677)
		(end 34.53003 -90.61577)
		(width 0.08382)
		(layer "In9.Cu")
		(net "FM_THROTTLE_N")
	)
	(segment
		(start 34.75355 -89.50325)
		(end 34.53003 -89.72677)
		(width 0.08382)
		(layer "In9.Cu")
		(net "FM_THROTTLE_N")
	)
	(segment
		(start 35.64255 -86.374732)
		(end 34.75355 -87.263732)
		(width 0.08382)
		(layer "In9.Cu")
		(net "FM_THROTTLE_N")
	)
	(segment
		(start 31.794196 -99.346258)
		(end 31.794196 -100.054664)
		(width 0.08382)
		(layer "In9.Cu")
		(net "FM_THROTTLE_N")
	)
	(segment
		(start 36.04006 -82.85734)
		(end 35.64255 -83.25485)
		(width 0.08382)
		(layer "In9.Cu")
		(net "FM_THROTTLE_N")
	)
	(segment
		(start 51.11877 -68.08343)
		(end 50.88382 -68.08343)
		(width 0.11684)
		(layer "F.Cu")
		(net "FM_SLPS3_GF_N")
	)
	(segment
		(start 51.384962 -67.817238)
		(end 51.11877 -68.08343)
		(width 0.11684)
		(layer "F.Cu")
		(net "FM_SLPS3_GF_N")
	)
	(segment
		(start 50.88382 -68.08343)
		(end 50.71745 -68.2498)
		(width 0.11684)
		(layer "F.Cu")
		(net "FM_SLPS3_GF_N")
	)
	(segment
		(start 51.907948 -66.55562)
		(end 51.384962 -67.817238)
		(width 0.11684)
		(layer "F.Cu")
		(net "FM_SLPS3_GF_N")
	)
	(segment
		(start 52.43576 -66.337434)
		(end 51.907948 -66.55562)
		(width 0.11684)
		(layer "F.Cu")
		(net "FM_SLPS3_GF_N")
	)
	(segment
		(start 52.43576 -66.337434)
		(end 52.6796 -66.093594)
		(width 0.11684)
		(layer "F.Cu")
		(net "FM_SLPS3_GF_N")
	)
	(segment
		(start 52.6796 -66.093594)
		(end 52.6796 -65.17259)
		(width 0.11684)
		(layer "F.Cu")
		(net "FM_SLPS3_GF_N")
	)
	(segment
		(start 52.6796 -65.17259)
		(end 52.3748 -64.86779)
		(width 0.11684)
		(layer "F.Cu")
		(net "FM_SLPS3_GF_N")
	)
	(via
		(at 50.1523 -90.56624)
		(size 0.508)
		(drill 0.254)
		(layers "F.Cu" "B.Cu")
		(net "FM_SLPS3_GF_N")
	)
	(via
		(at 32.963104 -95.123)
		(size 0.508)
		(drill 0.254)
		(layers "F.Cu" "B.Cu")
		(net "FM_SLPS3_GF_N")
	)
	(via
		(at 52.3748 -64.86779)
		(size 0.508)
		(drill 0.254)
		(layers "F.Cu" "B.Cu")
		(net "FM_SLPS3_GF_N")
	)
	(via
		(at 52.43576 -66.337434)
		(size 0.762)
		(drill 0.381)
		(layers "F.Cu" "B.Cu")
		(net "FM_SLPS3_GF_N")
	)
	(segment
		(start 50.84445 -90.4875)
		(end 50.76571 -90.56624)
		(width 0.11684)
		(layer "B.Cu")
		(net "FM_SLPS3_GF_N")
	)
	(segment
		(start 53.98262 -64.505586)
		(end 53.98262 -63.70447)
		(width 0.11684)
		(layer "B.Cu")
		(net "FM_SLPS3_GF_N")
	)
	(segment
		(start 52.3748 -64.86779)
		(end 53.013864 -64.86779)
		(width 0.11684)
		(layer "B.Cu")
		(net "FM_SLPS3_GF_N")
	)
	(segment
		(start 29.88945 -93.1164)
		(end 30.45587 -93.68282)
		(width 0.11684)
		(layer "B.Cu")
		(net "FM_SLPS3_GF_N")
	)
	(segment
		(start 30.45587 -93.68282)
		(end 30.89402 -93.68282)
		(width 0.11684)
		(layer "B.Cu")
		(net "FM_SLPS3_GF_N")
	)
	(segment
		(start 53.104034 -64.77762)
		(end 53.710586 -64.77762)
		(width 0.11684)
		(layer "B.Cu")
		(net "FM_SLPS3_GF_N")
	)
	(segment
		(start 50.76571 -90.56624)
		(end 50.1523 -90.56624)
		(width 0.11684)
		(layer "B.Cu")
		(net "FM_SLPS3_GF_N")
	)
	(segment
		(start 53.710586 -64.77762)
		(end 53.98262 -64.505586)
		(width 0.11684)
		(layer "B.Cu")
		(net "FM_SLPS3_GF_N")
	)
	(segment
		(start 32.3342 -95.123)
		(end 32.963104 -95.123)
		(width 0.11684)
		(layer "B.Cu")
		(net "FM_SLPS3_GF_N")
	)
	(segment
		(start 30.89402 -93.68282)
		(end 32.3342 -95.123)
		(width 0.11684)
		(layer "B.Cu")
		(net "FM_SLPS3_GF_N")
	)
	(segment
		(start 53.98262 -63.70447)
		(end 53.8734 -63.59525)
		(width 0.11684)
		(layer "B.Cu")
		(net "FM_SLPS3_GF_N")
	)
	(segment
		(start 53.013864 -64.86779)
		(end 53.104034 -64.77762)
		(width 0.11684)
		(layer "B.Cu")
		(net "FM_SLPS3_GF_N")
	)
	(segment
		(start 34.537904 -93.5482)
		(end 44.247308 -93.5482)
		(width 0.08382)
		(layer "In2.Cu")
		(net "FM_SLPS3_GF_N")
	)
	(segment
		(start 44.247308 -93.5482)
		(end 45.037248 -94.33814)
		(width 0.08382)
		(layer "In2.Cu")
		(net "FM_SLPS3_GF_N")
	)
	(segment
		(start 50.38598 -92.08262)
		(end 50.38598 -90.79992)
		(width 0.08382)
		(layer "In2.Cu")
		(net "FM_SLPS3_GF_N")
	)
	(segment
		(start 45.037248 -94.33814)
		(end 48.13046 -94.33814)
		(width 0.08382)
		(layer "In2.Cu")
		(net "FM_SLPS3_GF_N")
	)
	(segment
		(start 50.38598 -90.79992)
		(end 50.1523 -90.56624)
		(width 0.08382)
		(layer "In2.Cu")
		(net "FM_SLPS3_GF_N")
	)
	(segment
		(start 48.13046 -94.33814)
		(end 50.38598 -92.08262)
		(width 0.08382)
		(layer "In2.Cu")
		(net "FM_SLPS3_GF_N")
	)
	(segment
		(start 32.963104 -95.123)
		(end 34.537904 -93.5482)
		(width 0.08382)
		(layer "In2.Cu")
		(net "FM_SLPS3_GF_N")
	)
	(segment
		(start 50.40757 -73.47712)
		(end 48.70958 -73.47712)
		(width 0.10668)
		(layer "In4.Cu")
		(net "FM_SLPS3_GF_N")
	)
	(segment
		(start 51.11242 -68.481448)
		(end 51.358038 -69.073776)
		(width 0.10668)
		(layer "In4.Cu")
		(net "FM_SLPS3_GF_N")
	)
	(segment
		(start 48.422052 -80.197452)
		(end 49.276 -81.0514)
		(width 0.10668)
		(layer "In4.Cu")
		(net "FM_SLPS3_GF_N")
	)
	(segment
		(start 51.358038 -69.073776)
		(end 51.358038 -72.526652)
		(width 0.10668)
		(layer "In4.Cu")
		(net "FM_SLPS3_GF_N")
	)
	(segment
		(start 47.88916 -87.00008)
		(end 47.88916 -89.299796)
		(width 0.10668)
		(layer "In4.Cu")
		(net "FM_SLPS3_GF_N")
	)
	(segment
		(start 48.225964 -89.6366)
		(end 49.22266 -89.6366)
		(width 0.10668)
		(layer "In4.Cu")
		(net "FM_SLPS3_GF_N")
	)
	(segment
		(start 52.3748 -64.86779)
		(end 52.67452 -65.16751)
		(width 0.10668)
		(layer "In4.Cu")
		(net "FM_SLPS3_GF_N")
	)
	(segment
		(start 48.27016 -74.50836)
		(end 49.4538 -75.692)
		(width 0.10668)
		(layer "In4.Cu")
		(net "FM_SLPS3_GF_N")
	)
	(segment
		(start 48.70958 -73.47712)
		(end 48.27016 -73.91654)
		(width 0.10668)
		(layer "In4.Cu")
		(net "FM_SLPS3_GF_N")
	)
	(segment
		(start 49.4538 -76.714858)
		(end 48.422052 -77.746606)
		(width 0.10668)
		(layer "In4.Cu")
		(net "FM_SLPS3_GF_N")
	)
	(segment
		(start 52.67452 -66.08826)
		(end 51.953668 -66.809112)
		(width 0.10668)
		(layer "In4.Cu")
		(net "FM_SLPS3_GF_N")
	)
	(segment
		(start 52.67452 -65.16751)
		(end 52.67452 -66.08826)
		(width 0.10668)
		(layer "In4.Cu")
		(net "FM_SLPS3_GF_N")
	)
	(segment
		(start 49.276 -85.61324)
		(end 47.88916 -87.00008)
		(width 0.10668)
		(layer "In4.Cu")
		(net "FM_SLPS3_GF_N")
	)
	(segment
		(start 51.11242 -68.15074)
		(end 51.11242 -68.481448)
		(width 0.10668)
		(layer "In4.Cu")
		(net "FM_SLPS3_GF_N")
	)
	(segment
		(start 49.22266 -89.6366)
		(end 50.1523 -90.56624)
		(width 0.10668)
		(layer "In4.Cu")
		(net "FM_SLPS3_GF_N")
	)
	(segment
		(start 48.27016 -73.91654)
		(end 48.27016 -74.50836)
		(width 0.10668)
		(layer "In4.Cu")
		(net "FM_SLPS3_GF_N")
	)
	(segment
		(start 49.276 -81.0514)
		(end 49.276 -85.61324)
		(width 0.10668)
		(layer "In4.Cu")
		(net "FM_SLPS3_GF_N")
	)
	(segment
		(start 51.953668 -66.809112)
		(end 51.599592 -67.663568)
		(width 0.10668)
		(layer "In4.Cu")
		(net "FM_SLPS3_GF_N")
	)
	(segment
		(start 49.4538 -75.692)
		(end 49.4538 -76.714858)
		(width 0.10668)
		(layer "In4.Cu")
		(net "FM_SLPS3_GF_N")
	)
	(segment
		(start 51.358038 -72.526652)
		(end 50.40757 -73.47712)
		(width 0.10668)
		(layer "In4.Cu")
		(net "FM_SLPS3_GF_N")
	)
	(segment
		(start 47.88916 -89.299796)
		(end 48.225964 -89.6366)
		(width 0.10668)
		(layer "In4.Cu")
		(net "FM_SLPS3_GF_N")
	)
	(segment
		(start 51.599592 -67.663568)
		(end 51.11242 -68.15074)
		(width 0.10668)
		(layer "In4.Cu")
		(net "FM_SLPS3_GF_N")
	)
	(segment
		(start 48.422052 -77.746606)
		(end 48.422052 -80.197452)
		(width 0.10668)
		(layer "In4.Cu")
		(net "FM_SLPS3_GF_N")
	)
	(segment
		(start 46.736 -35.04565)
		(end 46.736 -35.687)
		(width 0.11684)
		(layer "F.Cu")
		(net "FM_PLT_BMC_THERMTRIP_N_R")
	)
	(segment
		(start 44.895008 -40.971216)
		(end 44.499784 -40.575992)
		(width 0.11684)
		(layer "F.Cu")
		(net "FM_PLT_BMC_THERMTRIP_N_R")
	)
	(via
		(at 46.736 -35.687)
		(size 0.508)
		(drill 0.254)
		(layers "F.Cu" "B.Cu")
		(net "FM_PLT_BMC_THERMTRIP_N_R")
	)
	(via
		(at 44.499784 -40.575992)
		(size 0.4572)
		(drill 0.254)
		(layers "F.Cu" "B.Cu")
		(net "FM_PLT_BMC_THERMTRIP_N_R")
	)
	(segment
		(start 44.410376 -40.6654)
		(end 44.499784 -40.575992)
		(width 0.08382)
		(layer "In2.Cu")
		(net "FM_PLT_BMC_THERMTRIP_N_R")
	)
	(segment
		(start 40.309292 -33.5788)
		(end 38.1 -33.5788)
		(width 0.08382)
		(layer "In2.Cu")
		(net "FM_PLT_BMC_THERMTRIP_N_R")
	)
	(segment
		(start 40.548306 -40.26916)
		(end 40.944546 -40.6654)
		(width 0.08382)
		(layer "In2.Cu")
		(net "FM_PLT_BMC_THERMTRIP_N_R")
	)
	(segment
		(start 46.736 -35.687)
		(end 46.736 -35.35172)
		(width 0.08382)
		(layer "In2.Cu")
		(net "FM_PLT_BMC_THERMTRIP_N_R")
	)
	(segment
		(start 41.442132 -34.71164)
		(end 40.309292 -33.5788)
		(width 0.08382)
		(layer "In2.Cu")
		(net "FM_PLT_BMC_THERMTRIP_N_R")
	)
	(segment
		(start 37.0586 -39.56812)
		(end 37.75964 -40.26916)
		(width 0.08382)
		(layer "In2.Cu")
		(net "FM_PLT_BMC_THERMTRIP_N_R")
	)
	(segment
		(start 46.736 -35.35172)
		(end 46.09592 -34.71164)
		(width 0.08382)
		(layer "In2.Cu")
		(net "FM_PLT_BMC_THERMTRIP_N_R")
	)
	(segment
		(start 46.09592 -34.71164)
		(end 41.442132 -34.71164)
		(width 0.08382)
		(layer "In2.Cu")
		(net "FM_PLT_BMC_THERMTRIP_N_R")
	)
	(segment
		(start 37.75964 -40.26916)
		(end 40.548306 -40.26916)
		(width 0.08382)
		(layer "In2.Cu")
		(net "FM_PLT_BMC_THERMTRIP_N_R")
	)
	(segment
		(start 37.0586 -34.6202)
		(end 37.0586 -39.56812)
		(width 0.08382)
		(layer "In2.Cu")
		(net "FM_PLT_BMC_THERMTRIP_N_R")
	)
	(segment
		(start 38.1 -33.5788)
		(end 37.0586 -34.6202)
		(width 0.08382)
		(layer "In2.Cu")
		(net "FM_PLT_BMC_THERMTRIP_N_R")
	)
	(segment
		(start 40.944546 -40.6654)
		(end 44.410376 -40.6654)
		(width 0.08382)
		(layer "In2.Cu")
		(net "FM_PLT_BMC_THERMTRIP_N_R")
	)
	(segment
		(start 43.848528 -31.267654)
		(end 44.088812 -31.847536)
		(width 0.11684)
		(layer "F.Cu")
		(net "FM_PCH_BMC_THERMTRIP_N")
	)
	(segment
		(start 22.254718 -89.591896)
		(end 21.859494 -89.98712)
		(width 0.11684)
		(layer "F.Cu")
		(net "FM_PCH_BMC_THERMTRIP_N")
	)
	(segment
		(start 44.950634 -32.26816)
		(end 45.106336 -32.203644)
		(width 0.11684)
		(layer "F.Cu")
		(net "FM_PCH_BMC_THERMTRIP_N")
	)
	(segment
		(start 46.254162 -33.763712)
		(end 46.254162 -33.602676)
		(width 0.11684)
		(layer "F.Cu")
		(net "FM_PCH_BMC_THERMTRIP_N")
	)
	(segment
		(start 45.106336 -32.203644)
		(end 45.641514 -32.203644)
		(width 0.11684)
		(layer "F.Cu")
		(net "FM_PCH_BMC_THERMTRIP_N")
	)
	(segment
		(start 44.416472 -32.175196)
		(end 44.641008 -32.26816)
		(width 0.11684)
		(layer "F.Cu")
		(net "FM_PCH_BMC_THERMTRIP_N")
	)
	(segment
		(start 44.641008 -32.26816)
		(end 44.950634 -32.26816)
		(width 0.11684)
		(layer "F.Cu")
		(net "FM_PCH_BMC_THERMTRIP_N")
	)
	(segment
		(start 46.736 -34.24555)
		(end 46.254162 -33.763712)
		(width 0.11684)
		(layer "F.Cu")
		(net "FM_PCH_BMC_THERMTRIP_N")
	)
	(segment
		(start 45.758354 -32.320484)
		(end 45.758354 -33.238694)
		(width 0.11684)
		(layer "F.Cu")
		(net "FM_PCH_BMC_THERMTRIP_N")
	)
	(segment
		(start 45.758354 -33.238694)
		(end 46.122336 -33.602676)
		(width 0.11684)
		(layer "F.Cu")
		(net "FM_PCH_BMC_THERMTRIP_N")
	)
	(segment
		(start 46.122336 -33.602676)
		(end 46.254162 -33.602676)
		(width 0.11684)
		(layer "F.Cu")
		(net "FM_PCH_BMC_THERMTRIP_N")
	)
	(segment
		(start 45.641514 -32.203644)
		(end 45.758354 -32.320484)
		(width 0.11684)
		(layer "F.Cu")
		(net "FM_PCH_BMC_THERMTRIP_N")
	)
	(segment
		(start 44.088812 -31.847536)
		(end 44.416472 -32.175196)
		(width 0.11684)
		(layer "F.Cu")
		(net "FM_PCH_BMC_THERMTRIP_N")
	)
	(via
		(at 46.254162 -33.602676)
		(size 0.508)
		(drill 0.254)
		(layers "F.Cu" "B.Cu")
		(net "FM_PCH_BMC_THERMTRIP_N")
	)
	(via
		(at 22.254718 -89.591896)
		(size 0.4572)
		(drill 0.254)
		(layers "F.Cu" "B.Cu")
		(net "FM_PCH_BMC_THERMTRIP_N")
	)
	(via
		(at 34.1376 -32.423608)
		(size 0.508)
		(drill 0.254)
		(layers "F.Cu" "B.Cu")
		(net "FM_PCH_BMC_THERMTRIP_N")
	)
	(segment
		(start 42.729658 -30.790388)
		(end 37.230558 -30.790388)
		(width 0.08382)
		(layer "In2.Cu")
		(net "FM_PCH_BMC_THERMTRIP_N")
	)
	(segment
		(start 37.230558 -30.790388)
		(end 35.897058 -32.123888)
		(width 0.08382)
		(layer "In2.Cu")
		(net "FM_PCH_BMC_THERMTRIP_N")
	)
	(segment
		(start 43.85564 -32.87522)
		(end 43.85564 -31.91637)
		(width 0.08382)
		(layer "In2.Cu")
		(net "FM_PCH_BMC_THERMTRIP_N")
	)
	(segment
		(start 35.897058 -32.123888)
		(end 34.43732 -32.123888)
		(width 0.08382)
		(layer "In2.Cu")
		(net "FM_PCH_BMC_THERMTRIP_N")
	)
	(segment
		(start 43.85564 -31.91637)
		(end 42.729658 -30.790388)
		(width 0.08382)
		(layer "In2.Cu")
		(net "FM_PCH_BMC_THERMTRIP_N")
	)
	(segment
		(start 34.43732 -32.123888)
		(end 34.1376 -32.423608)
		(width 0.08382)
		(layer "In2.Cu")
		(net "FM_PCH_BMC_THERMTRIP_N")
	)
	(segment
		(start 46.254162 -33.602676)
		(end 46.165516 -33.602676)
		(width 0.08382)
		(layer "In2.Cu")
		(net "FM_PCH_BMC_THERMTRIP_N")
	)
	(segment
		(start 46.165516 -33.602676)
		(end 45.732446 -33.169606)
		(width 0.08382)
		(layer "In2.Cu")
		(net "FM_PCH_BMC_THERMTRIP_N")
	)
	(segment
		(start 44.150026 -33.169606)
		(end 43.85564 -32.87522)
		(width 0.08382)
		(layer "In2.Cu")
		(net "FM_PCH_BMC_THERMTRIP_N")
	)
	(segment
		(start 45.732446 -33.169606)
		(end 44.150026 -33.169606)
		(width 0.08382)
		(layer "In2.Cu")
		(net "FM_PCH_BMC_THERMTRIP_N")
	)
	(segment
		(start 18.766282 -45.466)
		(end 17.611344 -46.620938)
		(width 0.10668)
		(layer "In4.Cu")
		(net "FM_PCH_BMC_THERMTRIP_N")
	)
	(segment
		(start 18.288 -68.596256)
		(end 18.288 -69.469)
		(width 0.10668)
		(layer "In4.Cu")
		(net "FM_PCH_BMC_THERMTRIP_N")
	)
	(segment
		(start 26.837132 -37.57422)
		(end 19.666204 -44.745148)
		(width 0.10668)
		(layer "In4.Cu")
		(net "FM_PCH_BMC_THERMTRIP_N")
	)
	(segment
		(start 27.1907 -37.57422)
		(end 26.837132 -37.57422)
		(width 0.10668)
		(layer "In4.Cu")
		(net "FM_PCH_BMC_THERMTRIP_N")
	)
	(segment
		(start 18.81124 -49.44364)
		(end 18.81124 -52.218082)
		(width 0.10668)
		(layer "In4.Cu")
		(net "FM_PCH_BMC_THERMTRIP_N")
	)
	(segment
		(start 20.1422 -65.024)
		(end 20.1422 -66.918078)
		(width 0.10668)
		(layer "In4.Cu")
		(net "FM_PCH_BMC_THERMTRIP_N")
	)
	(segment
		(start 20.8534 -81.1022)
		(end 21.209 -81.4578)
		(width 0.10668)
		(layer "In4.Cu")
		(net "FM_PCH_BMC_THERMTRIP_N")
	)
	(segment
		(start 20.42414 -72.748394)
		(end 20.91436 -73.238614)
		(width 0.10668)
		(layer "In4.Cu")
		(net "FM_PCH_BMC_THERMTRIP_N")
	)
	(segment
		(start 21.50872 -63.65748)
		(end 20.1422 -65.024)
		(width 0.10668)
		(layer "In4.Cu")
		(net "FM_PCH_BMC_THERMTRIP_N")
	)
	(segment
		(start 18.288 -69.469)
		(end 20.42414 -71.60514)
		(width 0.10668)
		(layer "In4.Cu")
		(net "FM_PCH_BMC_THERMTRIP_N")
	)
	(segment
		(start 29.29128 -35.47364)
		(end 27.1907 -37.57422)
		(width 0.10668)
		(layer "In4.Cu")
		(net "FM_PCH_BMC_THERMTRIP_N")
	)
	(segment
		(start 19.666204 -44.745148)
		(end 19.520154 -45.097446)
		(width 0.10668)
		(layer "In4.Cu")
		(net "FM_PCH_BMC_THERMTRIP_N")
	)
	(segment
		(start 18.81124 -52.218082)
		(end 17.435322 -53.594)
		(width 0.10668)
		(layer "In4.Cu")
		(net "FM_PCH_BMC_THERMTRIP_N")
	)
	(segment
		(start 19.16684 -58.538618)
		(end 19.16684 -58.793126)
		(width 0.10668)
		(layer "In4.Cu")
		(net "FM_PCH_BMC_THERMTRIP_N")
	)
	(segment
		(start 19.16684 -58.793126)
		(end 21.50872 -61.135006)
		(width 0.10668)
		(layer "In4.Cu")
		(net "FM_PCH_BMC_THERMTRIP_N")
	)
	(segment
		(start 17.15516 -78.60792)
		(end 17.67586 -79.12862)
		(width 0.10668)
		(layer "In4.Cu")
		(net "FM_PCH_BMC_THERMTRIP_N")
	)
	(segment
		(start 19.859498 -67.20078)
		(end 19.683476 -67.20078)
		(width 0.10668)
		(layer "In4.Cu")
		(net "FM_PCH_BMC_THERMTRIP_N")
	)
	(segment
		(start 20.42795 -74.75728)
		(end 18.907506 -74.75728)
		(width 0.10668)
		(layer "In4.Cu")
		(net "FM_PCH_BMC_THERMTRIP_N")
	)
	(segment
		(start 21.209 -81.4578)
		(end 21.209 -85.3948)
		(width 0.10668)
		(layer "In4.Cu")
		(net "FM_PCH_BMC_THERMTRIP_N")
	)
	(segment
		(start 17.949418 -75.715368)
		(end 17.15516 -77.63383)
		(width 0.10668)
		(layer "In4.Cu")
		(net "FM_PCH_BMC_THERMTRIP_N")
	)
	(segment
		(start 21.871178 -86.056978)
		(end 21.871178 -89.208356)
		(width 0.10668)
		(layer "In4.Cu")
		(net "FM_PCH_BMC_THERMTRIP_N")
	)
	(segment
		(start 17.67586 -79.12862)
		(end 17.67586 -80.88122)
		(width 0.10668)
		(layer "In4.Cu")
		(net "FM_PCH_BMC_THERMTRIP_N")
	)
	(segment
		(start 21.209 -85.3948)
		(end 21.871178 -86.056978)
		(width 0.10668)
		(layer "In4.Cu")
		(net "FM_PCH_BMC_THERMTRIP_N")
	)
	(segment
		(start 20.91436 -73.238614)
		(end 20.91436 -74.27087)
		(width 0.10668)
		(layer "In4.Cu")
		(net "FM_PCH_BMC_THERMTRIP_N")
	)
	(segment
		(start 17.611344 -48.243744)
		(end 18.81124 -49.44364)
		(width 0.10668)
		(layer "In4.Cu")
		(net "FM_PCH_BMC_THERMTRIP_N")
	)
	(segment
		(start 17.611344 -46.620938)
		(end 17.611344 -48.243744)
		(width 0.10668)
		(layer "In4.Cu")
		(net "FM_PCH_BMC_THERMTRIP_N")
	)
	(segment
		(start 17.67586 -80.88122)
		(end 17.89684 -81.1022)
		(width 0.10668)
		(layer "In4.Cu")
		(net "FM_PCH_BMC_THERMTRIP_N")
	)
	(segment
		(start 30.5181 -32.4231)
		(end 29.29128 -33.64992)
		(width 0.10668)
		(layer "In4.Cu")
		(net "FM_PCH_BMC_THERMTRIP_N")
	)
	(segment
		(start 29.29128 -33.64992)
		(end 29.29128 -35.47364)
		(width 0.10668)
		(layer "In4.Cu")
		(net "FM_PCH_BMC_THERMTRIP_N")
	)
	(segment
		(start 17.435322 -56.8071)
		(end 19.16684 -58.538618)
		(width 0.10668)
		(layer "In4.Cu")
		(net "FM_PCH_BMC_THERMTRIP_N")
	)
	(segment
		(start 17.435322 -53.594)
		(end 17.435322 -56.8071)
		(width 0.10668)
		(layer "In4.Cu")
		(net "FM_PCH_BMC_THERMTRIP_N")
	)
	(segment
		(start 21.50872 -61.135006)
		(end 21.50872 -63.65748)
		(width 0.10668)
		(layer "In4.Cu")
		(net "FM_PCH_BMC_THERMTRIP_N")
	)
	(segment
		(start 19.683476 -67.20078)
		(end 18.288 -68.596256)
		(width 0.10668)
		(layer "In4.Cu")
		(net "FM_PCH_BMC_THERMTRIP_N")
	)
	(segment
		(start 19.520154 -45.097446)
		(end 19.15414 -45.46346)
		(width 0.10668)
		(layer "In4.Cu")
		(net "FM_PCH_BMC_THERMTRIP_N")
	)
	(segment
		(start 18.907506 -74.75728)
		(end 17.949418 -75.715368)
		(width 0.10668)
		(layer "In4.Cu")
		(net "FM_PCH_BMC_THERMTRIP_N")
	)
	(segment
		(start 21.871178 -89.208356)
		(end 22.254718 -89.591896)
		(width 0.10668)
		(layer "In4.Cu")
		(net "FM_PCH_BMC_THERMTRIP_N")
	)
	(segment
		(start 19.15414 -45.46346)
		(end 18.931636 -45.46346)
		(width 0.10668)
		(layer "In4.Cu")
		(net "FM_PCH_BMC_THERMTRIP_N")
	)
	(segment
		(start 20.91436 -74.27087)
		(end 20.42795 -74.75728)
		(width 0.10668)
		(layer "In4.Cu")
		(net "FM_PCH_BMC_THERMTRIP_N")
	)
	(segment
		(start 33.81883 -32.4231)
		(end 30.5181 -32.4231)
		(width 0.10668)
		(layer "In4.Cu")
		(net "FM_PCH_BMC_THERMTRIP_N")
	)
	(segment
		(start 18.929096 -45.466)
		(end 18.766282 -45.466)
		(width 0.10668)
		(layer "In4.Cu")
		(net "FM_PCH_BMC_THERMTRIP_N")
	)
	(segment
		(start 17.15516 -77.63383)
		(end 17.15516 -78.60792)
		(width 0.10668)
		(layer "In4.Cu")
		(net "FM_PCH_BMC_THERMTRIP_N")
	)
	(segment
		(start 20.1422 -66.918078)
		(end 19.859498 -67.20078)
		(width 0.10668)
		(layer "In4.Cu")
		(net "FM_PCH_BMC_THERMTRIP_N")
	)
	(segment
		(start 18.931636 -45.46346)
		(end 18.929096 -45.466)
		(width 0.10668)
		(layer "In4.Cu")
		(net "FM_PCH_BMC_THERMTRIP_N")
	)
	(segment
		(start 34.1376 -32.423608)
		(end 33.81883 -32.4231)
		(width 0.10668)
		(layer "In4.Cu")
		(net "FM_PCH_BMC_THERMTRIP_N")
	)
	(segment
		(start 20.42414 -71.60514)
		(end 20.42414 -72.748394)
		(width 0.10668)
		(layer "In4.Cu")
		(net "FM_PCH_BMC_THERMTRIP_N")
	)
	(segment
		(start 17.89684 -81.1022)
		(end 20.8534 -81.1022)
		(width 0.10668)
		(layer "In4.Cu")
		(net "FM_PCH_BMC_THERMTRIP_N")
	)
	(segment
		(start 53.695092 -43.371262)
		(end 53.299868 -42.976038)
		(width 0.11684)
		(layer "F.Cu")
		(net "FM_JTAG_TCK_MUX_BMC_SEL_R1")
	)
	(via
		(at 35.168332 -37.200332)
		(size 0.508)
		(drill 0.254)
		(layers "F.Cu" "B.Cu")
		(net "FM_JTAG_TCK_MUX_BMC_SEL_R1")
	)
	(via
		(at 53.299868 -42.976038)
		(size 0.4572)
		(drill 0.254)
		(layers "F.Cu" "B.Cu")
		(net "FM_JTAG_TCK_MUX_BMC_SEL_R1")
	)
	(segment
		(start 35.189668 -37.200332)
		(end 35.433 -36.957)
		(width 0.11684)
		(layer "B.Cu")
		(net "FM_JTAG_TCK_MUX_BMC_SEL_R1")
	)
	(segment
		(start 35.168332 -37.200332)
		(end 35.189668 -37.200332)
		(width 0.11684)
		(layer "B.Cu")
		(net "FM_JTAG_TCK_MUX_BMC_SEL_R1")
	)
	(segment
		(start 35.433 -36.957)
		(end 35.433 -36.59505)
		(width 0.11684)
		(layer "B.Cu")
		(net "FM_JTAG_TCK_MUX_BMC_SEL_R1")
	)
	(segment
		(start 41.637458 -33.003998)
		(end 41.76522 -33.312354)
		(width 0.08382)
		(layer "In2.Cu")
		(net "FM_JTAG_TCK_MUX_BMC_SEL_R1")
	)
	(segment
		(start 40.91686 -32.2834)
		(end 41.637458 -33.003998)
		(width 0.08382)
		(layer "In2.Cu")
		(net "FM_JTAG_TCK_MUX_BMC_SEL_R1")
	)
	(segment
		(start 49.74463 -36.3093)
		(end 50.742596 -36.3093)
		(width 0.08382)
		(layer "In2.Cu")
		(net "FM_JTAG_TCK_MUX_BMC_SEL_R1")
	)
	(segment
		(start 38.519862 -32.2834)
		(end 40.91686 -32.2834)
		(width 0.08382)
		(layer "In2.Cu")
		(net "FM_JTAG_TCK_MUX_BMC_SEL_R1")
	)
	(segment
		(start 35.306 -37.062664)
		(end 35.306 -33.9344)
		(width 0.08382)
		(layer "In2.Cu")
		(net "FM_JTAG_TCK_MUX_BMC_SEL_R1")
	)
	(segment
		(start 41.95826 -34.0868)
		(end 46.355 -34.0868)
		(width 0.08382)
		(layer "In2.Cu")
		(net "FM_JTAG_TCK_MUX_BMC_SEL_R1")
	)
	(segment
		(start 38.115494 -32.687768)
		(end 38.519862 -32.2834)
		(width 0.08382)
		(layer "In2.Cu")
		(net "FM_JTAG_TCK_MUX_BMC_SEL_R1")
	)
	(segment
		(start 52.873148 -42.549318)
		(end 53.299868 -42.976038)
		(width 0.08382)
		(layer "In2.Cu")
		(net "FM_JTAG_TCK_MUX_BMC_SEL_R1")
	)
	(segment
		(start 50.742596 -36.3093)
		(end 52.873148 -38.439852)
		(width 0.08382)
		(layer "In2.Cu")
		(net "FM_JTAG_TCK_MUX_BMC_SEL_R1")
	)
	(segment
		(start 36.552632 -32.687768)
		(end 38.115494 -32.687768)
		(width 0.08382)
		(layer "In2.Cu")
		(net "FM_JTAG_TCK_MUX_BMC_SEL_R1")
	)
	(segment
		(start 47.48149 -35.21329)
		(end 48.96485 -35.21329)
		(width 0.08382)
		(layer "In2.Cu")
		(net "FM_JTAG_TCK_MUX_BMC_SEL_R1")
	)
	(segment
		(start 41.76522 -33.89376)
		(end 41.95826 -34.0868)
		(width 0.08382)
		(layer "In2.Cu")
		(net "FM_JTAG_TCK_MUX_BMC_SEL_R1")
	)
	(segment
		(start 52.873148 -38.439852)
		(end 52.873148 -42.549318)
		(width 0.08382)
		(layer "In2.Cu")
		(net "FM_JTAG_TCK_MUX_BMC_SEL_R1")
	)
	(segment
		(start 49.482248 -35.730688)
		(end 49.482248 -36.046918)
		(width 0.08382)
		(layer "In2.Cu")
		(net "FM_JTAG_TCK_MUX_BMC_SEL_R1")
	)
	(segment
		(start 49.482248 -36.046918)
		(end 49.74463 -36.3093)
		(width 0.08382)
		(layer "In2.Cu")
		(net "FM_JTAG_TCK_MUX_BMC_SEL_R1")
	)
	(segment
		(start 35.168332 -37.200332)
		(end 35.306 -37.062664)
		(width 0.08382)
		(layer "In2.Cu")
		(net "FM_JTAG_TCK_MUX_BMC_SEL_R1")
	)
	(segment
		(start 41.76522 -33.312354)
		(end 41.76522 -33.89376)
		(width 0.08382)
		(layer "In2.Cu")
		(net "FM_JTAG_TCK_MUX_BMC_SEL_R1")
	)
	(segment
		(start 46.355 -34.0868)
		(end 47.48149 -35.21329)
		(width 0.08382)
		(layer "In2.Cu")
		(net "FM_JTAG_TCK_MUX_BMC_SEL_R1")
	)
	(segment
		(start 35.306 -33.9344)
		(end 36.552632 -32.687768)
		(width 0.08382)
		(layer "In2.Cu")
		(net "FM_JTAG_TCK_MUX_BMC_SEL_R1")
	)
	(segment
		(start 48.96485 -35.21329)
		(end 49.482248 -35.730688)
		(width 0.08382)
		(layer "In2.Cu")
		(net "FM_JTAG_TCK_MUX_BMC_SEL_R1")
	)
	(segment
		(start 76.2 -72.5932)
		(end 75.7174 -72.1106)
		(width 0.11684)
		(layer "F.Cu")
		(net "FM_JTAG_TCK_MUX_BMC_SEL_R")
	)
	(segment
		(start 75.946 -74.02195)
		(end 74.93 -73.00595)
		(width 0.11684)
		(layer "F.Cu")
		(net "FM_JTAG_TCK_MUX_BMC_SEL_R")
	)
	(segment
		(start 74.93 -72.517)
		(end 75.3364 -72.1106)
		(width 0.11684)
		(layer "F.Cu")
		(net "FM_JTAG_TCK_MUX_BMC_SEL_R")
	)
	(segment
		(start 74.93 -73.00595)
		(end 74.93 -72.517)
		(width 0.11684)
		(layer "F.Cu")
		(net "FM_JTAG_TCK_MUX_BMC_SEL_R")
	)
	(segment
		(start 75.3364 -72.1106)
		(end 75.7174 -72.1106)
		(width 0.11684)
		(layer "F.Cu")
		(net "FM_JTAG_TCK_MUX_BMC_SEL_R")
	)
	(segment
		(start 76.8858 -73.5838)
		(end 76.2 -72.898)
		(width 0.11684)
		(layer "F.Cu")
		(net "FM_JTAG_TCK_MUX_BMC_SEL_R")
	)
	(segment
		(start 76.2 -72.898)
		(end 76.2 -72.5932)
		(width 0.11684)
		(layer "F.Cu")
		(net "FM_JTAG_TCK_MUX_BMC_SEL_R")
	)
	(segment
		(start 77.507592 -73.5838)
		(end 76.8858 -73.5838)
		(width 0.11684)
		(layer "F.Cu")
		(net "FM_JTAG_TCK_MUX_BMC_SEL_R")
	)
	(segment
		(start 78.000098 -74.076306)
		(end 77.507592 -73.5838)
		(width 0.11684)
		(layer "F.Cu")
		(net "FM_JTAG_TCK_MUX_BMC_SEL_R")
	)
	(via
		(at 75.7174 -72.1106)
		(size 0.762)
		(drill 0.381)
		(layers "F.Cu" "B.Cu")
		(net "FM_JTAG_TCK_MUX_BMC_SEL_R")
	)
	(segment
		(start 78.6638 -74.876406)
		(end 78.000098 -74.876406)
		(width 0.11684)
		(layer "F.Cu")
		(net "FM_JTAG_TCK_MUX_BMC_SEL")
	)
	(segment
		(start 77.634846 -74.876406)
		(end 78.000098 -74.876406)
		(width 0.11684)
		(layer "F.Cu")
		(net "FM_JTAG_TCK_MUX_BMC_SEL")
	)
	(segment
		(start 20.701 -101.981)
		(end 20.701 -103.191056)
		(width 0.11684)
		(layer "F.Cu")
		(net "FM_JTAG_TCK_MUX_BMC_SEL")
	)
	(segment
		(start 20.24126 -103.997252)
		(end 20.205954 -104.032558)
		(width 0.11684)
		(layer "F.Cu")
		(net "FM_JTAG_TCK_MUX_BMC_SEL")
	)
	(segment
		(start 77.199998 -74.076306)
		(end 77.520546 -74.396854)
		(width 0.11684)
		(layer "F.Cu")
		(net "FM_JTAG_TCK_MUX_BMC_SEL")
	)
	(segment
		(start 77.520546 -74.396854)
		(end 77.520546 -74.762106)
		(width 0.11684)
		(layer "F.Cu")
		(net "FM_JTAG_TCK_MUX_BMC_SEL")
	)
	(segment
		(start 21.859494 -99.58705)
		(end 21.859494 -100.212906)
		(width 0.11684)
		(layer "F.Cu")
		(net "FM_JTAG_TCK_MUX_BMC_SEL")
	)
	(segment
		(start 21.4884 -101.1936)
		(end 20.701 -101.981)
		(width 0.11684)
		(layer "F.Cu")
		(net "FM_JTAG_TCK_MUX_BMC_SEL")
	)
	(segment
		(start 22.1234 -106.172)
		(end 22.1234 -107.7214)
		(width 0.11684)
		(layer "F.Cu")
		(net "FM_JTAG_TCK_MUX_BMC_SEL")
	)
	(segment
		(start 22.1234 -107.7214)
		(end 21.41728 -108.42752)
		(width 0.11684)
		(layer "F.Cu")
		(net "FM_JTAG_TCK_MUX_BMC_SEL")
	)
	(segment
		(start 20.701 -103.191056)
		(end 20.24126 -103.650796)
		(width 0.11684)
		(layer "F.Cu")
		(net "FM_JTAG_TCK_MUX_BMC_SEL")
	)
	(segment
		(start 20.205954 -104.032558)
		(end 20.205954 -105.72496)
		(width 0.11684)
		(layer "F.Cu")
		(net "FM_JTAG_TCK_MUX_BMC_SEL")
	)
	(segment
		(start 21.859494 -100.212906)
		(end 21.4884 -100.584)
		(width 0.11684)
		(layer "F.Cu")
		(net "FM_JTAG_TCK_MUX_BMC_SEL")
	)
	(segment
		(start 76.981558 -74.076306)
		(end 77.199998 -74.076306)
		(width 0.11684)
		(layer "F.Cu")
		(net "FM_JTAG_TCK_MUX_BMC_SEL")
	)
	(segment
		(start 21.7932 -105.8418)
		(end 22.1234 -106.172)
		(width 0.11684)
		(layer "F.Cu")
		(net "FM_JTAG_TCK_MUX_BMC_SEL")
	)
	(segment
		(start 77.520546 -74.762106)
		(end 77.634846 -74.876406)
		(width 0.11684)
		(layer "F.Cu")
		(net "FM_JTAG_TCK_MUX_BMC_SEL")
	)
	(segment
		(start 21.41728 -108.42752)
		(end 21.41728 -109.34954)
		(width 0.11684)
		(layer "F.Cu")
		(net "FM_JTAG_TCK_MUX_BMC_SEL")
	)
	(segment
		(start 20.322794 -105.8418)
		(end 21.7932 -105.8418)
		(width 0.11684)
		(layer "F.Cu")
		(net "FM_JTAG_TCK_MUX_BMC_SEL")
	)
	(segment
		(start 20.205954 -105.72496)
		(end 20.322794 -105.8418)
		(width 0.11684)
		(layer "F.Cu")
		(net "FM_JTAG_TCK_MUX_BMC_SEL")
	)
	(segment
		(start 21.4884 -100.584)
		(end 21.4884 -101.1936)
		(width 0.11684)
		(layer "F.Cu")
		(net "FM_JTAG_TCK_MUX_BMC_SEL")
	)
	(segment
		(start 20.24126 -103.650796)
		(end 20.24126 -103.997252)
		(width 0.11684)
		(layer "F.Cu")
		(net "FM_JTAG_TCK_MUX_BMC_SEL")
	)
	(via
		(at 12.29868 -81.690464)
		(size 0.508)
		(drill 0.254)
		(layers "F.Cu" "B.Cu")
		(net "FM_JTAG_TCK_MUX_BMC_SEL")
	)
	(via
		(at 25.39746 -79.0448)
		(size 0.508)
		(drill 0.254)
		(layers "F.Cu" "B.Cu")
		(net "FM_JTAG_TCK_MUX_BMC_SEL")
	)
	(via
		(at 73.9902 -80.2386)
		(size 0.508)
		(drill 0.254)
		(layers "F.Cu" "B.Cu")
		(net "FM_JTAG_TCK_MUX_BMC_SEL")
	)
	(via
		(at 78.6638 -74.876406)
		(size 0.508)
		(drill 0.254)
		(layers "F.Cu" "B.Cu")
		(net "FM_JTAG_TCK_MUX_BMC_SEL")
	)
	(via
		(at 34.417 -34.29)
		(size 0.508)
		(drill 0.254)
		(layers "F.Cu" "B.Cu")
		(net "FM_JTAG_TCK_MUX_BMC_SEL")
	)
	(via
		(at 21.41728 -109.34954)
		(size 0.508)
		(drill 0.254)
		(layers "F.Cu" "B.Cu")
		(net "FM_JTAG_TCK_MUX_BMC_SEL")
	)
	(segment
		(start 35.433 -35.79495)
		(end 35.433 -35.306)
		(width 0.11684)
		(layer "B.Cu")
		(net "FM_JTAG_TCK_MUX_BMC_SEL")
	)
	(segment
		(start 35.433 -35.306)
		(end 34.417 -34.29)
		(width 0.11684)
		(layer "B.Cu")
		(net "FM_JTAG_TCK_MUX_BMC_SEL")
	)
	(segment
		(start 48.287178 -79.63154)
		(end 46.359318 -79.63154)
		(width 0.08382)
		(layer "In2.Cu")
		(net "FM_JTAG_TCK_MUX_BMC_SEL")
	)
	(segment
		(start 13.6398 -81.3816)
		(end 14.1478 -81.8896)
		(width 0.08382)
		(layer "In2.Cu")
		(net "FM_JTAG_TCK_MUX_BMC_SEL")
	)
	(segment
		(start 40.084756 -80.0608)
		(end 39.50716 -80.0608)
		(width 0.08382)
		(layer "In2.Cu")
		(net "FM_JTAG_TCK_MUX_BMC_SEL")
	)
	(segment
		(start 37.312346 -80.1624)
		(end 37.271706 -80.1624)
		(width 0.08382)
		(layer "In2.Cu")
		(net "FM_JTAG_TCK_MUX_BMC_SEL")
	)
	(segment
		(start 35.48126 -80.27162)
		(end 35.37204 -80.1624)
		(width 0.08382)
		(layer "In2.Cu")
		(net "FM_JTAG_TCK_MUX_BMC_SEL")
	)
	(segment
		(start 37.896546 -79.5782)
		(end 37.312346 -80.1624)
		(width 0.08382)
		(layer "In2.Cu")
		(net "FM_JTAG_TCK_MUX_BMC_SEL")
	)
	(segment
		(start 12.29868 -81.690464)
		(end 12.822936 -81.690464)
		(width 0.08382)
		(layer "In2.Cu")
		(net "FM_JTAG_TCK_MUX_BMC_SEL")
	)
	(segment
		(start 67.309238 -80.665828)
		(end 64.308228 -80.665828)
		(width 0.08382)
		(layer "In2.Cu")
		(net "FM_JTAG_TCK_MUX_BMC_SEL")
	)
	(segment
		(start 43.025822 -79.80807)
		(end 42.113962 -80.71993)
		(width 0.08382)
		(layer "In2.Cu")
		(net "FM_JTAG_TCK_MUX_BMC_SEL")
	)
	(segment
		(start 62.786514 -79.91729)
		(end 62.524132 -80.179672)
		(width 0.08382)
		(layer "In2.Cu")
		(net "FM_JTAG_TCK_MUX_BMC_SEL")
	)
	(segment
		(start 25.87244 -77.76464)
		(end 25.87244 -78.70698)
		(width 0.08382)
		(layer "In2.Cu")
		(net "FM_JTAG_TCK_MUX_BMC_SEL")
	)
	(segment
		(start 18.1864 -77.4446)
		(end 17.907 -77.1652)
		(width 0.08382)
		(layer "In2.Cu")
		(net "FM_JTAG_TCK_MUX_BMC_SEL")
	)
	(segment
		(start 62.07633 -81.38287)
		(end 60.09767 -81.38287)
		(width 0.08382)
		(layer "In2.Cu")
		(net "FM_JTAG_TCK_MUX_BMC_SEL")
	)
	(segment
		(start 54.733698 -78.752954)
		(end 54.551072 -78.93558)
		(width 0.08382)
		(layer "In2.Cu")
		(net "FM_JTAG_TCK_MUX_BMC_SEL")
	)
	(segment
		(start 59.56046 -80.84566)
		(end 57.28208 -80.84566)
		(width 0.08382)
		(layer "In2.Cu")
		(net "FM_JTAG_TCK_MUX_BMC_SEL")
	)
	(segment
		(start 39.50716 -80.0608)
		(end 39.02456 -79.5782)
		(width 0.08382)
		(layer "In2.Cu")
		(net "FM_JTAG_TCK_MUX_BMC_SEL")
	)
	(segment
		(start 19.18589 -73.3552)
		(end 19.852386 -73.079102)
		(width 0.08382)
		(layer "In2.Cu")
		(net "FM_JTAG_TCK_MUX_BMC_SEL")
	)
	(segment
		(start 52.948586 -78.93558)
		(end 51.516026 -80.36814)
		(width 0.08382)
		(layer "In2.Cu")
		(net "FM_JTAG_TCK_MUX_BMC_SEL")
	)
	(segment
		(start 62.524132 -80.935068)
		(end 62.07633 -81.38287)
		(width 0.08382)
		(layer "In2.Cu")
		(net "FM_JTAG_TCK_MUX_BMC_SEL")
	)
	(segment
		(start 14.1478 -81.8896)
		(end 15.07744 -81.8896)
		(width 0.08382)
		(layer "In2.Cu")
		(net "FM_JTAG_TCK_MUX_BMC_SEL")
	)
	(segment
		(start 25.070054 -77.30744)
		(end 25.41524 -77.30744)
		(width 0.08382)
		(layer "In2.Cu")
		(net "FM_JTAG_TCK_MUX_BMC_SEL")
	)
	(segment
		(start 35.37204 -80.1624)
		(end 26.51506 -80.1624)
		(width 0.08382)
		(layer "In2.Cu")
		(net "FM_JTAG_TCK_MUX_BMC_SEL")
	)
	(segment
		(start 62.524132 -80.179672)
		(end 62.524132 -80.935068)
		(width 0.08382)
		(layer "In2.Cu")
		(net "FM_JTAG_TCK_MUX_BMC_SEL")
	)
	(segment
		(start 60.09767 -81.38287)
		(end 59.56046 -80.84566)
		(width 0.08382)
		(layer "In2.Cu")
		(net "FM_JTAG_TCK_MUX_BMC_SEL")
	)
	(segment
		(start 20.841716 -73.079102)
		(end 25.070054 -77.30744)
		(width 0.08382)
		(layer "In2.Cu")
		(net "FM_JTAG_TCK_MUX_BMC_SEL")
	)
	(segment
		(start 12.822936 -81.690464)
		(end 13.1318 -81.3816)
		(width 0.08382)
		(layer "In2.Cu")
		(net "FM_JTAG_TCK_MUX_BMC_SEL")
	)
	(segment
		(start 43.060112 -79.80807)
		(end 43.025822 -79.80807)
		(width 0.08382)
		(layer "In2.Cu")
		(net "FM_JTAG_TCK_MUX_BMC_SEL")
	)
	(segment
		(start 51.516026 -80.36814)
		(end 49.023778 -80.36814)
		(width 0.08382)
		(layer "In2.Cu")
		(net "FM_JTAG_TCK_MUX_BMC_SEL")
	)
	(segment
		(start 49.023778 -80.36814)
		(end 48.287178 -79.63154)
		(width 0.08382)
		(layer "In2.Cu")
		(net "FM_JTAG_TCK_MUX_BMC_SEL")
	)
	(segment
		(start 40.743886 -80.71993)
		(end 40.084756 -80.0608)
		(width 0.08382)
		(layer "In2.Cu")
		(net "FM_JTAG_TCK_MUX_BMC_SEL")
	)
	(segment
		(start 17.907 -74.295)
		(end 18.8468 -73.3552)
		(width 0.08382)
		(layer "In2.Cu")
		(net "FM_JTAG_TCK_MUX_BMC_SEL")
	)
	(segment
		(start 54.551072 -78.93558)
		(end 52.948586 -78.93558)
		(width 0.08382)
		(layer "In2.Cu")
		(net "FM_JTAG_TCK_MUX_BMC_SEL")
	)
	(segment
		(start 17.907 -77.1652)
		(end 17.907 -74.295)
		(width 0.08382)
		(layer "In2.Cu")
		(net "FM_JTAG_TCK_MUX_BMC_SEL")
	)
	(segment
		(start 25.53462 -79.0448)
		(end 25.39746 -79.0448)
		(width 0.08382)
		(layer "In2.Cu")
		(net "FM_JTAG_TCK_MUX_BMC_SEL")
	)
	(segment
		(start 67.939666 -80.0354)
		(end 67.309238 -80.665828)
		(width 0.08382)
		(layer "In2.Cu")
		(net "FM_JTAG_TCK_MUX_BMC_SEL")
	)
	(segment
		(start 46.359318 -79.63154)
		(end 45.287438 -78.55966)
		(width 0.08382)
		(layer "In2.Cu")
		(net "FM_JTAG_TCK_MUX_BMC_SEL")
	)
	(segment
		(start 19.852386 -73.079102)
		(end 20.841716 -73.079102)
		(width 0.08382)
		(layer "In2.Cu")
		(net "FM_JTAG_TCK_MUX_BMC_SEL")
	)
	(segment
		(start 37.271706 -80.1624)
		(end 37.162486 -80.27162)
		(width 0.08382)
		(layer "In2.Cu")
		(net "FM_JTAG_TCK_MUX_BMC_SEL")
	)
	(segment
		(start 44.445174 -78.423008)
		(end 43.060112 -79.80807)
		(width 0.08382)
		(layer "In2.Cu")
		(net "FM_JTAG_TCK_MUX_BMC_SEL")
	)
	(segment
		(start 25.87244 -78.70698)
		(end 25.53462 -79.0448)
		(width 0.08382)
		(layer "In2.Cu")
		(net "FM_JTAG_TCK_MUX_BMC_SEL")
	)
	(segment
		(start 72.47636 -80.2386)
		(end 72.27316 -80.0354)
		(width 0.08382)
		(layer "In2.Cu")
		(net "FM_JTAG_TCK_MUX_BMC_SEL")
	)
	(segment
		(start 13.1318 -81.3816)
		(end 13.6398 -81.3816)
		(width 0.08382)
		(layer "In2.Cu")
		(net "FM_JTAG_TCK_MUX_BMC_SEL")
	)
	(segment
		(start 72.27316 -80.0354)
		(end 67.939666 -80.0354)
		(width 0.08382)
		(layer "In2.Cu")
		(net "FM_JTAG_TCK_MUX_BMC_SEL")
	)
	(segment
		(start 42.113962 -80.71993)
		(end 40.743886 -80.71993)
		(width 0.08382)
		(layer "In2.Cu")
		(net "FM_JTAG_TCK_MUX_BMC_SEL")
	)
	(segment
		(start 63.55969 -79.91729)
		(end 62.786514 -79.91729)
		(width 0.08382)
		(layer "In2.Cu")
		(net "FM_JTAG_TCK_MUX_BMC_SEL")
	)
	(segment
		(start 37.162486 -80.27162)
		(end 35.48126 -80.27162)
		(width 0.08382)
		(layer "In2.Cu")
		(net "FM_JTAG_TCK_MUX_BMC_SEL")
	)
	(segment
		(start 73.9902 -80.2386)
		(end 72.47636 -80.2386)
		(width 0.08382)
		(layer "In2.Cu")
		(net "FM_JTAG_TCK_MUX_BMC_SEL")
	)
	(segment
		(start 55.189374 -78.752954)
		(end 54.733698 -78.752954)
		(width 0.08382)
		(layer "In2.Cu")
		(net "FM_JTAG_TCK_MUX_BMC_SEL")
	)
	(segment
		(start 26.51506 -80.1624)
		(end 25.39746 -79.0448)
		(width 0.08382)
		(layer "In2.Cu")
		(net "FM_JTAG_TCK_MUX_BMC_SEL")
	)
	(segment
		(start 18.1864 -78.78064)
		(end 18.1864 -77.4446)
		(width 0.08382)
		(layer "In2.Cu")
		(net "FM_JTAG_TCK_MUX_BMC_SEL")
	)
	(segment
		(start 44.957492 -78.423008)
		(end 44.445174 -78.423008)
		(width 0.08382)
		(layer "In2.Cu")
		(net "FM_JTAG_TCK_MUX_BMC_SEL")
	)
	(segment
		(start 25.41524 -77.30744)
		(end 25.87244 -77.76464)
		(width 0.08382)
		(layer "In2.Cu")
		(net "FM_JTAG_TCK_MUX_BMC_SEL")
	)
	(segment
		(start 18.8468 -73.3552)
		(end 19.18589 -73.3552)
		(width 0.08382)
		(layer "In2.Cu")
		(net "FM_JTAG_TCK_MUX_BMC_SEL")
	)
	(segment
		(start 64.308228 -80.665828)
		(end 63.55969 -79.91729)
		(width 0.08382)
		(layer "In2.Cu")
		(net "FM_JTAG_TCK_MUX_BMC_SEL")
	)
	(segment
		(start 39.02456 -79.5782)
		(end 37.896546 -79.5782)
		(width 0.08382)
		(layer "In2.Cu")
		(net "FM_JTAG_TCK_MUX_BMC_SEL")
	)
	(segment
		(start 15.07744 -81.8896)
		(end 18.1864 -78.78064)
		(width 0.08382)
		(layer "In2.Cu")
		(net "FM_JTAG_TCK_MUX_BMC_SEL")
	)
	(segment
		(start 57.28208 -80.84566)
		(end 55.189374 -78.752954)
		(width 0.08382)
		(layer "In2.Cu")
		(net "FM_JTAG_TCK_MUX_BMC_SEL")
	)
	(segment
		(start 45.287438 -78.55966)
		(end 44.957492 -78.423008)
		(width 0.08382)
		(layer "In2.Cu")
		(net "FM_JTAG_TCK_MUX_BMC_SEL")
	)
	(segment
		(start 27.223974 -38.58006)
		(end 27.607514 -38.58006)
		(width 0.10668)
		(layer "In4.Cu")
		(net "FM_JTAG_TCK_MUX_BMC_SEL")
	)
	(segment
		(start 11.3538 -80.0354)
		(end 9.6774 -80.0354)
		(width 0.10668)
		(layer "In4.Cu")
		(net "FM_JTAG_TCK_MUX_BMC_SEL")
	)
	(segment
		(start 14.139418 -110.53064)
		(end 14.764258 -111.15548)
		(width 0.10668)
		(layer "In4.Cu")
		(net "FM_JTAG_TCK_MUX_BMC_SEL")
	)
	(segment
		(start 22.101048 -43.702986)
		(end 27.223974 -38.58006)
		(width 0.10668)
		(layer "In4.Cu")
		(net "FM_JTAG_TCK_MUX_BMC_SEL")
	)
	(segment
		(start 24.86406 -77.426566)
		(end 24.30526 -76.867766)
		(width 0.10668)
		(layer "In4.Cu")
		(net "FM_JTAG_TCK_MUX_BMC_SEL")
	)
	(segment
		(start 23.3172 -60.22086)
		(end 20.69338 -57.59704)
		(width 0.10668)
		(layer "In4.Cu")
		(net "FM_JTAG_TCK_MUX_BMC_SEL")
	)
	(segment
		(start 24.86406 -78.60538)
		(end 24.86406 -77.426566)
		(width 0.10668)
		(layer "In4.Cu")
		(net "FM_JTAG_TCK_MUX_BMC_SEL")
	)
	(segment
		(start 22.903434 -71.806308)
		(end 22.903434 -71.52894)
		(width 0.10668)
		(layer "In4.Cu")
		(net "FM_JTAG_TCK_MUX_BMC_SEL")
	)
	(segment
		(start 74.47153 -79.75727)
		(end 73.9902 -80.2386)
		(width 0.10668)
		(layer "In4.Cu")
		(net "FM_JTAG_TCK_MUX_BMC_SEL")
	)
	(segment
		(start 6.60273 -105.137712)
		(end 9.15416 -107.689142)
		(width 0.10668)
		(layer "In4.Cu")
		(net "FM_JTAG_TCK_MUX_BMC_SEL")
	)
	(segment
		(start 9.15416 -109.281722)
		(end 9.597898 -109.72546)
		(width 0.10668)
		(layer "In4.Cu")
		(net "FM_JTAG_TCK_MUX_BMC_SEL")
	)
	(segment
		(start 20.312888 -50.311812)
		(end 20.312888 -49.022508)
		(width 0.10668)
		(layer "In4.Cu")
		(net "FM_JTAG_TCK_MUX_BMC_SEL")
	)
	(segment
		(start 6.94563 -90.10777)
		(end 6.668262 -90.10777)
		(width 0.10668)
		(layer "In4.Cu")
		(net "FM_JTAG_TCK_MUX_BMC_SEL")
	)
	(segment
		(start 4.9784 -91.817698)
		(end 4.9784 -92.212414)
		(width 0.10668)
		(layer "In4.Cu")
		(net "FM_JTAG_TCK_MUX_BMC_SEL")
	)
	(segment
		(start 4.69392 -102.196138)
		(end 4.9784 -102.480618)
		(width 0.10668)
		(layer "In4.Cu")
		(net "FM_JTAG_TCK_MUX_BMC_SEL")
	)
	(segment
		(start 24.3205 -65.122044)
		(end 24.3205 -63.732664)
		(width 0.10668)
		(layer "In4.Cu")
		(net "FM_JTAG_TCK_MUX_BMC_SEL")
	)
	(segment
		(start 6.668008 -90.107516)
		(end 5.334 -90.107516)
		(width 0.10668)
		(layer "In4.Cu")
		(net "FM_JTAG_TCK_MUX_BMC_SEL")
	)
	(segment
		(start 20.799552 -46.844966)
		(end 22.101048 -43.702986)
		(width 0.10668)
		(layer "In4.Cu")
		(net "FM_JTAG_TCK_MUX_BMC_SEL")
	)
	(segment
		(start 8.5344 -88.519)
		(end 6.94563 -90.10777)
		(width 0.10668)
		(layer "In4.Cu")
		(net "FM_JTAG_TCK_MUX_BMC_SEL")
	)
	(segment
		(start 25.30348 -79.0448)
		(end 24.86406 -78.60538)
		(width 0.10668)
		(layer "In4.Cu")
		(net "FM_JTAG_TCK_MUX_BMC_SEL")
	)
	(segment
		(start 9.597898 -109.72546)
		(end 14.139418 -109.72546)
		(width 0.10668)
		(layer "In4.Cu")
		(net "FM_JTAG_TCK_MUX_BMC_SEL")
	)
	(segment
		(start 77.7113 -79.75727)
		(end 74.47153 -79.75727)
		(width 0.10668)
		(layer "In4.Cu")
		(net "FM_JTAG_TCK_MUX_BMC_SEL")
	)
	(segment
		(start 9.3345 -83.94446)
		(end 10.0203 -84.63026)
		(width 0.10668)
		(layer "In4.Cu")
		(net "FM_JTAG_TCK_MUX_BMC_SEL")
	)
	(segment
		(start 20.312888 -49.022508)
		(end 19.9136 -48.62322)
		(width 0.10668)
		(layer "In4.Cu")
		(net "FM_JTAG_TCK_MUX_BMC_SEL")
	)
	(segment
		(start 19.45132 -111.15548)
		(end 20.21332 -111.15548)
		(width 0.10668)
		(layer "In4.Cu")
		(net "FM_JTAG_TCK_MUX_BMC_SEL")
	)
	(segment
		(start 9.2075 -88.519)
		(end 8.5344 -88.519)
		(width 0.10668)
		(layer "In4.Cu")
		(net "FM_JTAG_TCK_MUX_BMC_SEL")
	)
	(segment
		(start 20.69338 -50.692304)
		(end 20.312888 -50.311812)
		(width 0.10668)
		(layer "In4.Cu")
		(net "FM_JTAG_TCK_MUX_BMC_SEL")
	)
	(segment
		(start 20.21332 -111.15548)
		(end 21.41728 -109.95152)
		(width 0.10668)
		(layer "In4.Cu")
		(net "FM_JTAG_TCK_MUX_BMC_SEL")
	)
	(segment
		(start 18.8976 -111.7092)
		(end 19.45132 -111.15548)
		(width 0.10668)
		(layer "In4.Cu")
		(net "FM_JTAG_TCK_MUX_BMC_SEL")
	)
	(segment
		(start 10.0203 -87.7062)
		(end 9.2075 -88.519)
		(width 0.10668)
		(layer "In4.Cu")
		(net "FM_JTAG_TCK_MUX_BMC_SEL")
	)
	(segment
		(start 4.69392 -100.416106)
		(end 4.69392 -102.196138)
		(width 0.10668)
		(layer "In4.Cu")
		(net "FM_JTAG_TCK_MUX_BMC_SEL")
	)
	(segment
		(start 9.6774 -80.0354)
		(end 9.3345 -80.3783)
		(width 0.10668)
		(layer "In4.Cu")
		(net "FM_JTAG_TCK_MUX_BMC_SEL")
	)
	(segment
		(start 19.9136 -48.62322)
		(end 19.9136 -47.833026)
		(width 0.10668)
		(layer "In4.Cu")
		(net "FM_JTAG_TCK_MUX_BMC_SEL")
	)
	(segment
		(start 5.0546 -91.741498)
		(end 4.9784 -91.817698)
		(width 0.10668)
		(layer "In4.Cu")
		(net "FM_JTAG_TCK_MUX_BMC_SEL")
	)
	(segment
		(start 24.30526 -76.867766)
		(end 24.30526 -73.42886)
		(width 0.10668)
		(layer "In4.Cu")
		(net "FM_JTAG_TCK_MUX_BMC_SEL")
	)
	(segment
		(start 17.579594 -111.15548)
		(end 18.133314 -111.7092)
		(width 0.10668)
		(layer "In4.Cu")
		(net "FM_JTAG_TCK_MUX_BMC_SEL")
	)
	(segment
		(start 22.90318 -72.02678)
		(end 22.90318 -71.806562)
		(width 0.10668)
		(layer "In4.Cu")
		(net "FM_JTAG_TCK_MUX_BMC_SEL")
	)
	(segment
		(start 19.985736 -47.658782)
		(end 20.799552 -46.844966)
		(width 0.10668)
		(layer "In4.Cu")
		(net "FM_JTAG_TCK_MUX_BMC_SEL")
	)
	(segment
		(start 24.3205 -63.732664)
		(end 23.3172 -62.729364)
		(width 0.10668)
		(layer "In4.Cu")
		(net "FM_JTAG_TCK_MUX_BMC_SEL")
	)
	(segment
		(start 11.6078 -81.066894)
		(end 11.6078 -80.2894)
		(width 0.10668)
		(layer "In4.Cu")
		(net "FM_JTAG_TCK_MUX_BMC_SEL")
	)
	(segment
		(start 22.90318 -71.806562)
		(end 22.903434 -71.806308)
		(width 0.10668)
		(layer "In4.Cu")
		(net "FM_JTAG_TCK_MUX_BMC_SEL")
	)
	(segment
		(start 14.139418 -109.72546)
		(end 14.139418 -110.53064)
		(width 0.10668)
		(layer "In4.Cu")
		(net "FM_JTAG_TCK_MUX_BMC_SEL")
	)
	(segment
		(start 19.9136 -47.833026)
		(end 19.985736 -47.658782)
		(width 0.10668)
		(layer "In4.Cu")
		(net "FM_JTAG_TCK_MUX_BMC_SEL")
	)
	(segment
		(start 4.9784 -105.010712)
		(end 5.1054 -105.137712)
		(width 0.10668)
		(layer "In4.Cu")
		(net "FM_JTAG_TCK_MUX_BMC_SEL")
	)
	(segment
		(start 14.764258 -111.15548)
		(end 17.579594 -111.15548)
		(width 0.10668)
		(layer "In4.Cu")
		(net "FM_JTAG_TCK_MUX_BMC_SEL")
	)
	(segment
		(start 5.334 -90.107516)
		(end 5.0546 -90.386916)
		(width 0.10668)
		(layer "In4.Cu")
		(net "FM_JTAG_TCK_MUX_BMC_SEL")
	)
	(segment
		(start 22.3774 -67.065144)
		(end 24.3205 -65.122044)
		(width 0.10668)
		(layer "In4.Cu")
		(net "FM_JTAG_TCK_MUX_BMC_SEL")
	)
	(segment
		(start 12.29868 -81.690464)
		(end 12.23137 -81.690464)
		(width 0.10668)
		(layer "In4.Cu")
		(net "FM_JTAG_TCK_MUX_BMC_SEL")
	)
	(segment
		(start 22.903434 -71.52894)
		(end 22.3774 -71.002906)
		(width 0.10668)
		(layer "In4.Cu")
		(net "FM_JTAG_TCK_MUX_BMC_SEL")
	)
	(segment
		(start 6.668262 -90.10777)
		(end 6.668008 -90.107516)
		(width 0.10668)
		(layer "In4.Cu")
		(net "FM_JTAG_TCK_MUX_BMC_SEL")
	)
	(segment
		(start 18.133314 -111.7092)
		(end 18.8976 -111.7092)
		(width 0.10668)
		(layer "In4.Cu")
		(net "FM_JTAG_TCK_MUX_BMC_SEL")
	)
	(segment
		(start 10.0203 -84.63026)
		(end 10.0203 -87.7062)
		(width 0.10668)
		(layer "In4.Cu")
		(net "FM_JTAG_TCK_MUX_BMC_SEL")
	)
	(segment
		(start 29.415994 -36.77158)
		(end 30.437074 -36.77158)
		(width 0.10668)
		(layer "In4.Cu")
		(net "FM_JTAG_TCK_MUX_BMC_SEL")
	)
	(segment
		(start 9.15416 -107.689142)
		(end 9.15416 -109.281722)
		(width 0.10668)
		(layer "In4.Cu")
		(net "FM_JTAG_TCK_MUX_BMC_SEL")
	)
	(segment
		(start 5.1054 -105.137712)
		(end 6.60273 -105.137712)
		(width 0.10668)
		(layer "In4.Cu")
		(net "FM_JTAG_TCK_MUX_BMC_SEL")
	)
	(segment
		(start 4.28244 -100.004626)
		(end 4.69392 -100.416106)
		(width 0.10668)
		(layer "In4.Cu")
		(net "FM_JTAG_TCK_MUX_BMC_SEL")
	)
	(segment
		(start 5.0546 -90.386916)
		(end 5.0546 -91.741498)
		(width 0.10668)
		(layer "In4.Cu")
		(net "FM_JTAG_TCK_MUX_BMC_SEL")
	)
	(segment
		(start 25.39746 -79.0448)
		(end 25.30348 -79.0448)
		(width 0.10668)
		(layer "In4.Cu")
		(net "FM_JTAG_TCK_MUX_BMC_SEL")
	)
	(segment
		(start 11.6078 -80.2894)
		(end 11.3538 -80.0354)
		(width 0.10668)
		(layer "In4.Cu")
		(net "FM_JTAG_TCK_MUX_BMC_SEL")
	)
	(segment
		(start 4.9784 -102.480618)
		(end 4.9784 -105.010712)
		(width 0.10668)
		(layer "In4.Cu")
		(net "FM_JTAG_TCK_MUX_BMC_SEL")
	)
	(segment
		(start 20.69338 -57.59704)
		(end 20.69338 -50.692304)
		(width 0.10668)
		(layer "In4.Cu")
		(net "FM_JTAG_TCK_MUX_BMC_SEL")
	)
	(segment
		(start 78.6638 -78.80477)
		(end 77.7113 -79.75727)
		(width 0.10668)
		(layer "In4.Cu")
		(net "FM_JTAG_TCK_MUX_BMC_SEL")
	)
	(segment
		(start 30.437074 -36.77158)
		(end 32.918654 -34.29)
		(width 0.10668)
		(layer "In4.Cu")
		(net "FM_JTAG_TCK_MUX_BMC_SEL")
	)
	(segment
		(start 4.28244 -92.908374)
		(end 4.28244 -100.004626)
		(width 0.10668)
		(layer "In4.Cu")
		(net "FM_JTAG_TCK_MUX_BMC_SEL")
	)
	(segment
		(start 23.3172 -62.729364)
		(end 23.3172 -60.22086)
		(width 0.10668)
		(layer "In4.Cu")
		(net "FM_JTAG_TCK_MUX_BMC_SEL")
	)
	(segment
		(start 32.918654 -34.29)
		(end 34.417 -34.29)
		(width 0.10668)
		(layer "In4.Cu")
		(net "FM_JTAG_TCK_MUX_BMC_SEL")
	)
	(segment
		(start 24.30526 -73.42886)
		(end 22.90318 -72.02678)
		(width 0.10668)
		(layer "In4.Cu")
		(net "FM_JTAG_TCK_MUX_BMC_SEL")
	)
	(segment
		(start 22.3774 -71.002906)
		(end 22.3774 -67.065144)
		(width 0.10668)
		(layer "In4.Cu")
		(net "FM_JTAG_TCK_MUX_BMC_SEL")
	)
	(segment
		(start 4.9784 -92.212414)
		(end 4.28244 -92.908374)
		(width 0.10668)
		(layer "In4.Cu")
		(net "FM_JTAG_TCK_MUX_BMC_SEL")
	)
	(segment
		(start 27.607514 -38.58006)
		(end 29.415994 -36.77158)
		(width 0.10668)
		(layer "In4.Cu")
		(net "FM_JTAG_TCK_MUX_BMC_SEL")
	)
	(segment
		(start 21.41728 -109.95152)
		(end 21.41728 -109.34954)
		(width 0.10668)
		(layer "In4.Cu")
		(net "FM_JTAG_TCK_MUX_BMC_SEL")
	)
	(segment
		(start 78.6638 -74.876406)
		(end 78.6638 -78.80477)
		(width 0.10668)
		(layer "In4.Cu")
		(net "FM_JTAG_TCK_MUX_BMC_SEL")
	)
	(segment
		(start 9.3345 -80.3783)
		(end 9.3345 -83.94446)
		(width 0.10668)
		(layer "In4.Cu")
		(net "FM_JTAG_TCK_MUX_BMC_SEL")
	)
	(segment
		(start 12.23137 -81.690464)
		(end 11.6078 -81.066894)
		(width 0.10668)
		(layer "In4.Cu")
		(net "FM_JTAG_TCK_MUX_BMC_SEL")
	)
	(segment
		(start 31.423864 -46.028864)
		(end 33.733486 -46.028864)
		(width 0.11684)
		(layer "F.Cu")
		(net "RST_PCA9548_SENSOR_N")
	)
	(segment
		(start 24.664162 -87.99195)
		(end 25.059386 -88.387174)
		(width 0.11684)
		(layer "F.Cu")
		(net "RST_PCA9548_SENSOR_N")
	)
	(segment
		(start 28.04922 -42.65422)
		(end 31.423864 -46.028864)
		(width 0.11684)
		(layer "F.Cu")
		(net "RST_PCA9548_SENSOR_N")
	)
	(segment
		(start 25.527 -83.450938)
		(end 25.527 -84.02701)
		(width 0.11684)
		(layer "F.Cu")
		(net "RST_PCA9548_SENSOR_N")
	)
	(segment
		(start 25.635712 -84.981288)
		(end 25.635712 -86.242144)
		(width 0.11684)
		(layer "F.Cu")
		(net "RST_PCA9548_SENSOR_N")
	)
	(segment
		(start 22.92223 -44.83481)
		(end 25.10282 -42.65422)
		(width 0.11684)
		(layer "F.Cu")
		(net "RST_PCA9548_SENSOR_N")
	)
	(segment
		(start 25.527 -84.02701)
		(end 25.64384 -84.14385)
		(width 0.11684)
		(layer "F.Cu")
		(net "RST_PCA9548_SENSOR_N")
	)
	(segment
		(start 26.1874 -84.4296)
		(end 25.635712 -84.981288)
		(width 0.11684)
		(layer "F.Cu")
		(net "RST_PCA9548_SENSOR_N")
	)
	(segment
		(start 26.1874 -84.14385)
		(end 26.1874 -84.4296)
		(width 0.11684)
		(layer "F.Cu")
		(net "RST_PCA9548_SENSOR_N")
	)
	(segment
		(start 25.64384 -84.14385)
		(end 26.1874 -84.14385)
		(width 0.11684)
		(layer "F.Cu")
		(net "RST_PCA9548_SENSOR_N")
	)
	(segment
		(start 24.664162 -87.213694)
		(end 24.664162 -87.99195)
		(width 0.11684)
		(layer "F.Cu")
		(net "RST_PCA9548_SENSOR_N")
	)
	(segment
		(start 33.733486 -46.028864)
		(end 33.7566 -46.00575)
		(width 0.11684)
		(layer "F.Cu")
		(net "RST_PCA9548_SENSOR_N")
	)
	(segment
		(start 25.635712 -86.242144)
		(end 24.664162 -87.213694)
		(width 0.11684)
		(layer "F.Cu")
		(net "RST_PCA9548_SENSOR_N")
	)
	(segment
		(start 20.701 -44.83481)
		(end 22.92223 -44.83481)
		(width 0.11684)
		(layer "F.Cu")
		(net "RST_PCA9548_SENSOR_N")
	)
	(segment
		(start 25.10282 -42.65422)
		(end 28.04922 -42.65422)
		(width 0.11684)
		(layer "F.Cu")
		(net "RST_PCA9548_SENSOR_N")
	)
	(via
		(at 20.701 -44.83481)
		(size 0.508)
		(drill 0.254)
		(layers "F.Cu" "B.Cu")
		(net "RST_PCA9548_SENSOR_N")
	)
	(via
		(at 25.527 -83.450938)
		(size 0.508)
		(drill 0.254)
		(layers "F.Cu" "B.Cu")
		(net "RST_PCA9548_SENSOR_N")
	)
	(segment
		(start 22.04212 -71.141844)
		(end 22.04212 -66.982594)
		(width 0.10668)
		(layer "In4.Cu")
		(net "RST_PCA9548_SENSOR_N")
	)
	(segment
		(start 25.30094 -82.241898)
		(end 24.52878 -81.469738)
		(width 0.10668)
		(layer "In4.Cu")
		(net "RST_PCA9548_SENSOR_N")
	)
	(segment
		(start 25.30094 -83.224878)
		(end 25.30094 -82.241898)
		(width 0.10668)
		(layer "In4.Cu")
		(net "RST_PCA9548_SENSOR_N")
	)
	(segment
		(start 22.20468 -66.763646)
		(end 22.20468 -65.289938)
		(width 0.10668)
		(layer "In4.Cu")
		(net "RST_PCA9548_SENSOR_N")
	)
	(segment
		(start 19.977608 -50.45075)
		(end 19.977608 -49.161446)
		(width 0.10668)
		(layer "In4.Cu")
		(net "RST_PCA9548_SENSOR_N")
	)
	(segment
		(start 22.0472 -66.977514)
		(end 22.0472 -66.921126)
		(width 0.10668)
		(layer "In4.Cu")
		(net "RST_PCA9548_SENSOR_N")
	)
	(segment
		(start 22.5679 -72.300846)
		(end 22.5679 -71.667624)
		(width 0.10668)
		(layer "In4.Cu")
		(net "RST_PCA9548_SENSOR_N")
	)
	(segment
		(start 19.977608 -49.161446)
		(end 19.56562 -48.749458)
		(width 0.10668)
		(layer "In4.Cu")
		(net "RST_PCA9548_SENSOR_N")
	)
	(segment
		(start 22.440138 -65.05448)
		(end 23.642066 -65.05448)
		(width 0.10668)
		(layer "In4.Cu")
		(net "RST_PCA9548_SENSOR_N")
	)
	(segment
		(start 19.56562 -47.796704)
		(end 19.70151 -47.46879)
		(width 0.10668)
		(layer "In4.Cu")
		(net "RST_PCA9548_SENSOR_N")
	)
	(segment
		(start 22.98192 -60.359798)
		(end 20.3581 -57.735978)
		(width 0.10668)
		(layer "In4.Cu")
		(net "RST_PCA9548_SENSOR_N")
	)
	(segment
		(start 22.04212 -66.982594)
		(end 22.0472 -66.977514)
		(width 0.10668)
		(layer "In4.Cu")
		(net "RST_PCA9548_SENSOR_N")
	)
	(segment
		(start 20.06473 -47.10557)
		(end 20.701 -45.56887)
		(width 0.10668)
		(layer "In4.Cu")
		(net "RST_PCA9548_SENSOR_N")
	)
	(segment
		(start 19.56562 -48.749458)
		(end 19.56562 -47.796704)
		(width 0.10668)
		(layer "In4.Cu")
		(net "RST_PCA9548_SENSOR_N")
	)
	(segment
		(start 20.3581 -57.735978)
		(end 20.3581 -50.831242)
		(width 0.10668)
		(layer "In4.Cu")
		(net "RST_PCA9548_SENSOR_N")
	)
	(segment
		(start 23.889462 -73.622408)
		(end 22.5679 -72.300846)
		(width 0.10668)
		(layer "In4.Cu")
		(net "RST_PCA9548_SENSOR_N")
	)
	(segment
		(start 22.5679 -71.667624)
		(end 22.04212 -71.141844)
		(width 0.10668)
		(layer "In4.Cu")
		(net "RST_PCA9548_SENSOR_N")
	)
	(segment
		(start 25.527 -83.450938)
		(end 25.30094 -83.224878)
		(width 0.10668)
		(layer "In4.Cu")
		(net "RST_PCA9548_SENSOR_N")
	)
	(segment
		(start 24.52878 -81.469738)
		(end 24.52878 -77.59954)
		(width 0.10668)
		(layer "In4.Cu")
		(net "RST_PCA9548_SENSOR_N")
	)
	(segment
		(start 24.52878 -77.59954)
		(end 23.889462 -76.960222)
		(width 0.10668)
		(layer "In4.Cu")
		(net "RST_PCA9548_SENSOR_N")
	)
	(segment
		(start 22.0472 -66.921126)
		(end 22.20468 -66.763646)
		(width 0.10668)
		(layer "In4.Cu")
		(net "RST_PCA9548_SENSOR_N")
	)
	(segment
		(start 19.70151 -47.46879)
		(end 20.06473 -47.10557)
		(width 0.10668)
		(layer "In4.Cu")
		(net "RST_PCA9548_SENSOR_N")
	)
	(segment
		(start 23.98522 -64.711326)
		(end 23.98522 -63.871602)
		(width 0.10668)
		(layer "In4.Cu")
		(net "RST_PCA9548_SENSOR_N")
	)
	(segment
		(start 23.889462 -76.960222)
		(end 23.889462 -73.622408)
		(width 0.10668)
		(layer "In4.Cu")
		(net "RST_PCA9548_SENSOR_N")
	)
	(segment
		(start 23.642066 -65.05448)
		(end 23.98522 -64.711326)
		(width 0.10668)
		(layer "In4.Cu")
		(net "RST_PCA9548_SENSOR_N")
	)
	(segment
		(start 23.98522 -63.871602)
		(end 22.98192 -62.868302)
		(width 0.10668)
		(layer "In4.Cu")
		(net "RST_PCA9548_SENSOR_N")
	)
	(segment
		(start 22.98192 -62.868302)
		(end 22.98192 -60.359798)
		(width 0.10668)
		(layer "In4.Cu")
		(net "RST_PCA9548_SENSOR_N")
	)
	(segment
		(start 22.20468 -65.289938)
		(end 22.440138 -65.05448)
		(width 0.10668)
		(layer "In4.Cu")
		(net "RST_PCA9548_SENSOR_N")
	)
	(segment
		(start 20.701 -45.56887)
		(end 20.701 -44.83481)
		(width 0.10668)
		(layer "In4.Cu")
		(net "RST_PCA9548_SENSOR_N")
	)
	(segment
		(start 20.3581 -50.831242)
		(end 19.977608 -50.45075)
		(width 0.10668)
		(layer "In4.Cu")
		(net "RST_PCA9548_SENSOR_N")
	)
	(segment
		(start 48.0949 -45.771308)
		(end 47.699676 -45.376084)
		(width 0.11684)
		(layer "F.Cu")
		(net "FM_CPU_RMCA_CATERR_LVT3_R_N")
	)
	(via
		(at 47.699676 -45.376084)
		(size 0.4572)
		(drill 0.254)
		(layers "F.Cu" "B.Cu")
		(net "FM_CPU_RMCA_CATERR_LVT3_R_N")
	)
	(via
		(at 33.909 -37.2872)
		(size 0.508)
		(drill 0.254)
		(layers "F.Cu" "B.Cu")
		(net "FM_CPU_RMCA_CATERR_LVT3_R_N")
	)
	(segment
		(start 33.909 -37.2872)
		(end 34.417 -36.7792)
		(width 0.11684)
		(layer "B.Cu")
		(net "FM_CPU_RMCA_CATERR_LVT3_R_N")
	)
	(segment
		(start 34.417 -36.7792)
		(end 34.417 -36.59505)
		(width 0.11684)
		(layer "B.Cu")
		(net "FM_CPU_RMCA_CATERR_LVT3_R_N")
	)
	(segment
		(start 47.2948 -41.1988)
		(end 47.0662 -40.9702)
		(width 0.08382)
		(layer "In9.Cu")
		(net "FM_CPU_RMCA_CATERR_LVT3_R_N")
	)
	(segment
		(start 47.915576 -45.160184)
		(end 48.342296 -44.9834)
		(width 0.08382)
		(layer "In9.Cu")
		(net "FM_CPU_RMCA_CATERR_LVT3_R_N")
	)
	(segment
		(start 43.207686 -38.269926)
		(end 42.413682 -37.475922)
		(width 0.08382)
		(layer "In9.Cu")
		(net "FM_CPU_RMCA_CATERR_LVT3_R_N")
	)
	(segment
		(start 34.720022 -36.394898)
		(end 34.720022 -36.476178)
		(width 0.08382)
		(layer "In9.Cu")
		(net "FM_CPU_RMCA_CATERR_LVT3_R_N")
	)
	(segment
		(start 44.558966 -38.269926)
		(end 43.207686 -38.269926)
		(width 0.08382)
		(layer "In9.Cu")
		(net "FM_CPU_RMCA_CATERR_LVT3_R_N")
	)
	(segment
		(start 35.453828 -35.661092)
		(end 34.720022 -36.394898)
		(width 0.08382)
		(layer "In9.Cu")
		(net "FM_CPU_RMCA_CATERR_LVT3_R_N")
	)
	(segment
		(start 49.0982 -44.9834)
		(end 49.53 -44.5516)
		(width 0.08382)
		(layer "In9.Cu")
		(net "FM_CPU_RMCA_CATERR_LVT3_R_N")
	)
	(segment
		(start 46.6344 -40.9702)
		(end 46.482 -40.8178)
		(width 0.08382)
		(layer "In9.Cu")
		(net "FM_CPU_RMCA_CATERR_LVT3_R_N")
	)
	(segment
		(start 40.828722 -37.475922)
		(end 39.013892 -35.661092)
		(width 0.08382)
		(layer "In9.Cu")
		(net "FM_CPU_RMCA_CATERR_LVT3_R_N")
	)
	(segment
		(start 39.013892 -35.661092)
		(end 35.453828 -35.661092)
		(width 0.08382)
		(layer "In9.Cu")
		(net "FM_CPU_RMCA_CATERR_LVT3_R_N")
	)
	(segment
		(start 48.9204 -43.1292)
		(end 48.9204 -42.0116)
		(width 0.08382)
		(layer "In9.Cu")
		(net "FM_CPU_RMCA_CATERR_LVT3_R_N")
	)
	(segment
		(start 45.6946 -39.40556)
		(end 44.558966 -38.269926)
		(width 0.08382)
		(layer "In9.Cu")
		(net "FM_CPU_RMCA_CATERR_LVT3_R_N")
	)
	(segment
		(start 48.342296 -44.9834)
		(end 49.0982 -44.9834)
		(width 0.08382)
		(layer "In9.Cu")
		(net "FM_CPU_RMCA_CATERR_LVT3_R_N")
	)
	(segment
		(start 45.6946 -39.9288)
		(end 45.6946 -39.40556)
		(width 0.08382)
		(layer "In9.Cu")
		(net "FM_CPU_RMCA_CATERR_LVT3_R_N")
	)
	(segment
		(start 45.9486 -40.1828)
		(end 45.6946 -39.9288)
		(width 0.08382)
		(layer "In9.Cu")
		(net "FM_CPU_RMCA_CATERR_LVT3_R_N")
	)
	(segment
		(start 48.9204 -42.0116)
		(end 48.6918 -41.783)
		(width 0.08382)
		(layer "In9.Cu")
		(net "FM_CPU_RMCA_CATERR_LVT3_R_N")
	)
	(segment
		(start 46.482 -40.3606)
		(end 46.3042 -40.1828)
		(width 0.08382)
		(layer "In9.Cu")
		(net "FM_CPU_RMCA_CATERR_LVT3_R_N")
	)
	(segment
		(start 47.0662 -40.9702)
		(end 46.6344 -40.9702)
		(width 0.08382)
		(layer "In9.Cu")
		(net "FM_CPU_RMCA_CATERR_LVT3_R_N")
	)
	(segment
		(start 34.720022 -36.476178)
		(end 33.909 -37.2872)
		(width 0.08382)
		(layer "In9.Cu")
		(net "FM_CPU_RMCA_CATERR_LVT3_R_N")
	)
	(segment
		(start 49.53 -43.7388)
		(end 48.9204 -43.1292)
		(width 0.08382)
		(layer "In9.Cu")
		(net "FM_CPU_RMCA_CATERR_LVT3_R_N")
	)
	(segment
		(start 47.5742 -41.783)
		(end 47.2948 -41.5036)
		(width 0.08382)
		(layer "In9.Cu")
		(net "FM_CPU_RMCA_CATERR_LVT3_R_N")
	)
	(segment
		(start 49.53 -44.5516)
		(end 49.53 -43.7388)
		(width 0.08382)
		(layer "In9.Cu")
		(net "FM_CPU_RMCA_CATERR_LVT3_R_N")
	)
	(segment
		(start 46.482 -40.8178)
		(end 46.482 -40.3606)
		(width 0.08382)
		(layer "In9.Cu")
		(net "FM_CPU_RMCA_CATERR_LVT3_R_N")
	)
	(segment
		(start 46.3042 -40.1828)
		(end 45.9486 -40.1828)
		(width 0.08382)
		(layer "In9.Cu")
		(net "FM_CPU_RMCA_CATERR_LVT3_R_N")
	)
	(segment
		(start 42.413682 -37.475922)
		(end 40.828722 -37.475922)
		(width 0.08382)
		(layer "In9.Cu")
		(net "FM_CPU_RMCA_CATERR_LVT3_R_N")
	)
	(segment
		(start 48.6918 -41.783)
		(end 47.5742 -41.783)
		(width 0.08382)
		(layer "In9.Cu")
		(net "FM_CPU_RMCA_CATERR_LVT3_R_N")
	)
	(segment
		(start 47.2948 -41.5036)
		(end 47.2948 -41.1988)
		(width 0.08382)
		(layer "In9.Cu")
		(net "FM_CPU_RMCA_CATERR_LVT3_R_N")
	)
	(segment
		(start 47.699676 -45.376084)
		(end 47.915576 -45.160184)
		(width 0.08382)
		(layer "In9.Cu")
		(net "FM_CPU_RMCA_CATERR_LVT3_R_N")
	)
	(via
		(at 25.5778 -74.5744)
		(size 0.508)
		(drill 0.254)
		(layers "F.Cu" "B.Cu")
		(net "FM_CPU_MSMI_CATERR_LVT3_N")
	)
	(via
		(at 34.417 -35.052)
		(size 0.508)
		(drill 0.254)
		(layers "F.Cu" "B.Cu")
		(net "FM_CPU_MSMI_CATERR_LVT3_N")
	)
	(via
		(at 48.617632 -90.792554)
		(size 0.508)
		(drill 0.254)
		(layers "F.Cu" "B.Cu")
		(net "FM_CPU_MSMI_CATERR_LVT3_N")
	)
	(via
		(at 40.9956 -78.1304)
		(size 0.508)
		(drill 0.254)
		(layers "F.Cu" "B.Cu")
		(net "FM_CPU_MSMI_CATERR_LVT3_N")
	)
	(via
		(at 13.88364 -79.16164)
		(size 0.508)
		(drill 0.254)
		(layers "F.Cu" "B.Cu")
		(net "FM_CPU_MSMI_CATERR_LVT3_N")
	)
	(via
		(at 14.097 -80.01)
		(size 0.6604)
		(drill 0.3302)
		(layers "F.Cu" "B.Cu")
		(net "FM_CPU_MSMI_CATERR_LVT3_N")
	)
	(segment
		(start 48.617632 -90.792554)
		(end 49.054512 -90.792554)
		(width 0.11684)
		(layer "B.Cu")
		(net "FM_CPU_MSMI_CATERR_LVT3_N")
	)
	(segment
		(start 34.417 -35.052)
		(end 34.417 -35.79495)
		(width 0.11684)
		(layer "B.Cu")
		(net "FM_CPU_MSMI_CATERR_LVT3_N")
	)
	(segment
		(start 49.054512 -90.792554)
		(end 49.748186 -90.09888)
		(width 0.11684)
		(layer "B.Cu")
		(net "FM_CPU_MSMI_CATERR_LVT3_N")
	)
	(segment
		(start 15.7734 -83.58505)
		(end 16.2814 -84.09305)
		(width 0.11684)
		(layer "B.Cu")
		(net "FM_CPU_MSMI_CATERR_LVT3_N")
	)
	(segment
		(start 13.88364 -79.79664)
		(end 14.097 -80.01)
		(width 0.11684)
		(layer "B.Cu")
		(net "FM_CPU_MSMI_CATERR_LVT3_N")
	)
	(segment
		(start 16.78051 -85.14588)
		(end 16.78051 -84.571078)
		(width 0.11684)
		(layer "B.Cu")
		(net "FM_CPU_MSMI_CATERR_LVT3_N")
	)
	(segment
		(start 15.7734 -83.11134)
		(end 15.7734 -83.58505)
		(width 0.11684)
		(layer "B.Cu")
		(net "FM_CPU_MSMI_CATERR_LVT3_N")
	)
	(segment
		(start 13.88364 -80.22336)
		(end 13.88364 -81.60004)
		(width 0.11684)
		(layer "B.Cu")
		(net "FM_CPU_MSMI_CATERR_LVT3_N")
	)
	(segment
		(start 14.1732 -81.8896)
		(end 14.55166 -81.8896)
		(width 0.11684)
		(layer "B.Cu")
		(net "FM_CPU_MSMI_CATERR_LVT3_N")
	)
	(segment
		(start 14.097 -80.01)
		(end 13.88364 -80.22336)
		(width 0.11684)
		(layer "B.Cu")
		(net "FM_CPU_MSMI_CATERR_LVT3_N")
	)
	(segment
		(start 16.78051 -84.571078)
		(end 16.302482 -84.09305)
		(width 0.11684)
		(layer "B.Cu")
		(net "FM_CPU_MSMI_CATERR_LVT3_N")
	)
	(segment
		(start 13.88364 -79.16164)
		(end 13.88364 -79.79664)
		(width 0.11684)
		(layer "B.Cu")
		(net "FM_CPU_MSMI_CATERR_LVT3_N")
	)
	(segment
		(start 50.34407 -90.09888)
		(end 50.84445 -89.5985)
		(width 0.11684)
		(layer "B.Cu")
		(net "FM_CPU_MSMI_CATERR_LVT3_N")
	)
	(segment
		(start 16.302482 -84.09305)
		(end 16.2814 -84.09305)
		(width 0.11684)
		(layer "B.Cu")
		(net "FM_CPU_MSMI_CATERR_LVT3_N")
	)
	(segment
		(start 14.55166 -81.8896)
		(end 15.7734 -83.11134)
		(width 0.11684)
		(layer "B.Cu")
		(net "FM_CPU_MSMI_CATERR_LVT3_N")
	)
	(segment
		(start 13.88364 -81.60004)
		(end 14.1732 -81.8896)
		(width 0.11684)
		(layer "B.Cu")
		(net "FM_CPU_MSMI_CATERR_LVT3_N")
	)
	(segment
		(start 49.748186 -90.09888)
		(end 50.34407 -90.09888)
		(width 0.11684)
		(layer "B.Cu")
		(net "FM_CPU_MSMI_CATERR_LVT3_N")
	)
	(segment
		(start 15.5956 -72.7456)
		(end 15.5956 -73.914)
		(width 0.08382)
		(layer "In2.Cu")
		(net "FM_CPU_MSMI_CATERR_LVT3_N")
	)
	(segment
		(start 40.5638 -77.6986)
		(end 40.9956 -78.1304)
		(width 0.08382)
		(layer "In2.Cu")
		(net "FM_CPU_MSMI_CATERR_LVT3_N")
	)
	(segment
		(start 14.82598 -74.68362)
		(end 14.82598 -77.333094)
		(width 0.08382)
		(layer "In2.Cu")
		(net "FM_CPU_MSMI_CATERR_LVT3_N")
	)
	(segment
		(start 14.508226 -78.100174)
		(end 13.88364 -78.72476)
		(width 0.08382)
		(layer "In2.Cu")
		(net "FM_CPU_MSMI_CATERR_LVT3_N")
	)
	(segment
		(start 13.88364 -78.72476)
		(end 13.88364 -79.16164)
		(width 0.08382)
		(layer "In2.Cu")
		(net "FM_CPU_MSMI_CATERR_LVT3_N")
	)
	(segment
		(start 16.262858 -70.42785)
		(end 15.113 -71.577708)
		(width 0.08382)
		(layer "In2.Cu")
		(net "FM_CPU_MSMI_CATERR_LVT3_N")
	)
	(segment
		(start 14.82598 -77.333094)
		(end 14.508226 -78.100174)
		(width 0.08382)
		(layer "In2.Cu")
		(net "FM_CPU_MSMI_CATERR_LVT3_N")
	)
	(segment
		(start 21.71065 -70.55485)
		(end 18.182844 -70.55485)
		(width 0.08382)
		(layer "In2.Cu")
		(net "FM_CPU_MSMI_CATERR_LVT3_N")
	)
	(segment
		(start 18.055844 -70.42785)
		(end 16.262858 -70.42785)
		(width 0.08382)
		(layer "In2.Cu")
		(net "FM_CPU_MSMI_CATERR_LVT3_N")
	)
	(segment
		(start 26.212546 -74.5744)
		(end 29.103066 -77.46492)
		(width 0.08382)
		(layer "In2.Cu")
		(net "FM_CPU_MSMI_CATERR_LVT3_N")
	)
	(segment
		(start 15.09649 -72.24649)
		(end 15.5956 -72.7456)
		(width 0.08382)
		(layer "In2.Cu")
		(net "FM_CPU_MSMI_CATERR_LVT3_N")
	)
	(segment
		(start 18.182844 -70.55485)
		(end 18.055844 -70.42785)
		(width 0.08382)
		(layer "In2.Cu")
		(net "FM_CPU_MSMI_CATERR_LVT3_N")
	)
	(segment
		(start 15.5956 -73.914)
		(end 14.82598 -74.68362)
		(width 0.08382)
		(layer "In2.Cu")
		(net "FM_CPU_MSMI_CATERR_LVT3_N")
	)
	(segment
		(start 25.5778 -74.5744)
		(end 25.5778 -74.422)
		(width 0.08382)
		(layer "In2.Cu")
		(net "FM_CPU_MSMI_CATERR_LVT3_N")
	)
	(segment
		(start 15.113 -71.577962)
		(end 15.09649 -71.594472)
		(width 0.08382)
		(layer "In2.Cu")
		(net "FM_CPU_MSMI_CATERR_LVT3_N")
	)
	(segment
		(start 29.103066 -77.46492)
		(end 32.271208 -77.46492)
		(width 0.08382)
		(layer "In2.Cu")
		(net "FM_CPU_MSMI_CATERR_LVT3_N")
	)
	(segment
		(start 25.5778 -74.5744)
		(end 26.212546 -74.5744)
		(width 0.08382)
		(layer "In2.Cu")
		(net "FM_CPU_MSMI_CATERR_LVT3_N")
	)
	(segment
		(start 15.09649 -71.594472)
		(end 15.09649 -72.24649)
		(width 0.08382)
		(layer "In2.Cu")
		(net "FM_CPU_MSMI_CATERR_LVT3_N")
	)
	(segment
		(start 32.504888 -77.6986)
		(end 40.5638 -77.6986)
		(width 0.08382)
		(layer "In2.Cu")
		(net "FM_CPU_MSMI_CATERR_LVT3_N")
	)
	(segment
		(start 32.271208 -77.46492)
		(end 32.504888 -77.6986)
		(width 0.08382)
		(layer "In2.Cu")
		(net "FM_CPU_MSMI_CATERR_LVT3_N")
	)
	(segment
		(start 25.5778 -74.422)
		(end 21.71065 -70.55485)
		(width 0.08382)
		(layer "In2.Cu")
		(net "FM_CPU_MSMI_CATERR_LVT3_N")
	)
	(segment
		(start 15.113 -71.577708)
		(end 15.113 -71.577962)
		(width 0.08382)
		(layer "In2.Cu")
		(net "FM_CPU_MSMI_CATERR_LVT3_N")
	)
	(segment
		(start 23.94458 -61.396118)
		(end 24.92502 -62.376558)
		(width 0.10668)
		(layer "In4.Cu")
		(net "FM_CPU_MSMI_CATERR_LVT3_N")
	)
	(segment
		(start 21.52904 -46.061122)
		(end 21.52904 -50.32756)
		(width 0.10668)
		(layer "In4.Cu")
		(net "FM_CPU_MSMI_CATERR_LVT3_N")
	)
	(segment
		(start 24.92502 -65.358264)
		(end 23.70074 -66.582544)
		(width 0.10668)
		(layer "In4.Cu")
		(net "FM_CPU_MSMI_CATERR_LVT3_N")
	)
	(segment
		(start 34.417 -35.052)
		(end 34.417 -35.2298)
		(width 0.10668)
		(layer "In4.Cu")
		(net "FM_CPU_MSMI_CATERR_LVT3_N")
	)
	(segment
		(start 31.35884 -38.28796)
		(end 28.373832 -38.28796)
		(width 0.10668)
		(layer "In4.Cu")
		(net "FM_CPU_MSMI_CATERR_LVT3_N")
	)
	(segment
		(start 21.52904 -50.32756)
		(end 21.28774 -50.910236)
		(width 0.10668)
		(layer "In4.Cu")
		(net "FM_CPU_MSMI_CATERR_LVT3_N")
	)
	(segment
		(start 21.28774 -50.910236)
		(end 21.28774 -57.35066)
		(width 0.10668)
		(layer "In4.Cu")
		(net "FM_CPU_MSMI_CATERR_LVT3_N")
	)
	(segment
		(start 27.362912 -38.91534)
		(end 22.456394 -43.821858)
		(width 0.10668)
		(layer "In4.Cu")
		(net "FM_CPU_MSMI_CATERR_LVT3_N")
	)
	(segment
		(start 34.417 -35.2298)
		(end 31.35884 -38.28796)
		(width 0.10668)
		(layer "In4.Cu")
		(net "FM_CPU_MSMI_CATERR_LVT3_N")
	)
	(segment
		(start 21.28774 -57.35066)
		(end 23.94458 -60.0075)
		(width 0.10668)
		(layer "In4.Cu")
		(net "FM_CPU_MSMI_CATERR_LVT3_N")
	)
	(segment
		(start 23.70074 -70.892924)
		(end 24.16302 -71.355204)
		(width 0.10668)
		(layer "In4.Cu")
		(net "FM_CPU_MSMI_CATERR_LVT3_N")
	)
	(segment
		(start 28.373832 -38.28796)
		(end 27.746452 -38.91534)
		(width 0.10668)
		(layer "In4.Cu")
		(net "FM_CPU_MSMI_CATERR_LVT3_N")
	)
	(segment
		(start 24.89962 -74.22642)
		(end 25.2476 -74.5744)
		(width 0.10668)
		(layer "In4.Cu")
		(net "FM_CPU_MSMI_CATERR_LVT3_N")
	)
	(segment
		(start 24.16302 -72.11822)
		(end 24.89962 -72.85482)
		(width 0.10668)
		(layer "In4.Cu")
		(net "FM_CPU_MSMI_CATERR_LVT3_N")
	)
	(segment
		(start 23.94458 -60.0075)
		(end 23.94458 -61.396118)
		(width 0.10668)
		(layer "In4.Cu")
		(net "FM_CPU_MSMI_CATERR_LVT3_N")
	)
	(segment
		(start 24.89962 -72.85482)
		(end 24.89962 -74.22642)
		(width 0.10668)
		(layer "In4.Cu")
		(net "FM_CPU_MSMI_CATERR_LVT3_N")
	)
	(segment
		(start 23.70074 -66.582544)
		(end 23.70074 -70.892924)
		(width 0.10668)
		(layer "In4.Cu")
		(net "FM_CPU_MSMI_CATERR_LVT3_N")
	)
	(segment
		(start 24.92502 -62.376558)
		(end 24.92502 -65.358264)
		(width 0.10668)
		(layer "In4.Cu")
		(net "FM_CPU_MSMI_CATERR_LVT3_N")
	)
	(segment
		(start 22.456394 -43.821858)
		(end 21.52904 -46.061122)
		(width 0.10668)
		(layer "In4.Cu")
		(net "FM_CPU_MSMI_CATERR_LVT3_N")
	)
	(segment
		(start 24.16302 -71.355204)
		(end 24.16302 -72.11822)
		(width 0.10668)
		(layer "In4.Cu")
		(net "FM_CPU_MSMI_CATERR_LVT3_N")
	)
	(segment
		(start 27.746452 -38.91534)
		(end 27.362912 -38.91534)
		(width 0.10668)
		(layer "In4.Cu")
		(net "FM_CPU_MSMI_CATERR_LVT3_N")
	)
	(segment
		(start 25.2476 -74.5744)
		(end 25.5778 -74.5744)
		(width 0.10668)
		(layer "In4.Cu")
		(net "FM_CPU_MSMI_CATERR_LVT3_N")
	)
	(segment
		(start 45.668692 -83.93176)
		(end 46.1772 -83.93176)
		(width 0.10668)
		(layer "In7.Cu")
		(net "FM_CPU_MSMI_CATERR_LVT3_N")
	)
	(segment
		(start 46.1772 -83.93176)
		(end 47.6123 -85.36686)
		(width 0.10668)
		(layer "In7.Cu")
		(net "FM_CPU_MSMI_CATERR_LVT3_N")
	)
	(segment
		(start 48.9458 -87.274654)
		(end 49.740312 -88.069166)
		(width 0.10668)
		(layer "In7.Cu")
		(net "FM_CPU_MSMI_CATERR_LVT3_N")
	)
	(segment
		(start 40.2844 -80.137)
		(end 42.9006 -82.7532)
		(width 0.10668)
		(layer "In7.Cu")
		(net "FM_CPU_MSMI_CATERR_LVT3_N")
	)
	(segment
		(start 42.9006 -82.7532)
		(end 44.490132 -82.7532)
		(width 0.10668)
		(layer "In7.Cu")
		(net "FM_CPU_MSMI_CATERR_LVT3_N")
	)
	(segment
		(start 47.6123 -85.36686)
		(end 48.798734 -85.36686)
		(width 0.10668)
		(layer "In7.Cu")
		(net "FM_CPU_MSMI_CATERR_LVT3_N")
	)
	(segment
		(start 44.490132 -82.7532)
		(end 45.668692 -83.93176)
		(width 0.10668)
		(layer "In7.Cu")
		(net "FM_CPU_MSMI_CATERR_LVT3_N")
	)
	(segment
		(start 49.740312 -88.069166)
		(end 49.740312 -89.669874)
		(width 0.10668)
		(layer "In7.Cu")
		(net "FM_CPU_MSMI_CATERR_LVT3_N")
	)
	(segment
		(start 40.9956 -78.1304)
		(end 40.9956 -78.7146)
		(width 0.10668)
		(layer "In7.Cu")
		(net "FM_CPU_MSMI_CATERR_LVT3_N")
	)
	(segment
		(start 40.2844 -79.4258)
		(end 40.2844 -80.137)
		(width 0.10668)
		(layer "In7.Cu")
		(net "FM_CPU_MSMI_CATERR_LVT3_N")
	)
	(segment
		(start 49.740312 -89.669874)
		(end 48.617632 -90.792554)
		(width 0.10668)
		(layer "In7.Cu")
		(net "FM_CPU_MSMI_CATERR_LVT3_N")
	)
	(segment
		(start 40.9956 -78.7146)
		(end 40.2844 -79.4258)
		(width 0.10668)
		(layer "In7.Cu")
		(net "FM_CPU_MSMI_CATERR_LVT3_N")
	)
	(segment
		(start 48.9458 -85.513926)
		(end 48.9458 -87.274654)
		(width 0.10668)
		(layer "In7.Cu")
		(net "FM_CPU_MSMI_CATERR_LVT3_N")
	)
	(segment
		(start 48.798734 -85.36686)
		(end 48.9458 -85.513926)
		(width 0.10668)
		(layer "In7.Cu")
		(net "FM_CPU_MSMI_CATERR_LVT3_N")
	)
	(segment
		(start 60.094876 -41.771316)
		(end 60.4901 -41.376092)
		(width 0.11684)
		(layer "F.Cu")
		(net "FM_BMC_SSPRST_N")
	)
	(via
		(at 60.4901 -41.376092)
		(size 0.4572)
		(drill 0.254)
		(layers "F.Cu" "B.Cu")
		(net "FM_BMC_SSPRST_N")
	)
	(via
		(at 63.242952 -39.878254)
		(size 0.6604)
		(drill 0.3302)
		(layers "F.Cu" "B.Cu")
		(net "FM_BMC_SSPRST_N")
	)
	(segment
		(start 62.865 -38.766496)
		(end 62.865 -39.500302)
		(width 0.11684)
		(layer "B.Cu")
		(net "FM_BMC_SSPRST_N")
	)
	(segment
		(start 66.486532 -31.140654)
		(end 66.603372 -31.257494)
		(width 0.11684)
		(layer "B.Cu")
		(net "FM_BMC_SSPRST_N")
	)
	(segment
		(start 63.242952 -39.878254)
		(end 62.938406 -40.1828)
		(width 0.11684)
		(layer "B.Cu")
		(net "FM_BMC_SSPRST_N")
	)
	(segment
		(start 66.127884 -31.140654)
		(end 66.486532 -31.140654)
		(width 0.11684)
		(layer "B.Cu")
		(net "FM_BMC_SSPRST_N")
	)
	(segment
		(start 66.603372 -31.257494)
		(end 66.603372 -35.255708)
		(width 0.11684)
		(layer "B.Cu")
		(net "FM_BMC_SSPRST_N")
	)
	(segment
		(start 66.603372 -35.255708)
		(end 66.30416 -35.55492)
		(width 0.11684)
		(layer "B.Cu")
		(net "FM_BMC_SSPRST_N")
	)
	(segment
		(start 61.877702 -40.1828)
		(end 61.688726 -40.371776)
		(width 0.11684)
		(layer "B.Cu")
		(net "FM_BMC_SSPRST_N")
	)
	(segment
		(start 64.96304 -36.59886)
		(end 64.96304 -36.668456)
		(width 0.11684)
		(layer "B.Cu")
		(net "FM_BMC_SSPRST_N")
	)
	(segment
		(start 60.731908 -41.376092)
		(end 60.4901 -41.376092)
		(width 0.11684)
		(layer "B.Cu")
		(net "FM_BMC_SSPRST_N")
	)
	(segment
		(start 61.688726 -40.744648)
		(end 61.463174 -40.9702)
		(width 0.11684)
		(layer "B.Cu")
		(net "FM_BMC_SSPRST_N")
	)
	(segment
		(start 64.96304 -36.668456)
		(end 62.865 -38.766496)
		(width 0.11684)
		(layer "B.Cu")
		(net "FM_BMC_SSPRST_N")
	)
	(segment
		(start 61.463174 -40.9702)
		(end 61.1378 -40.9702)
		(width 0.11684)
		(layer "B.Cu")
		(net "FM_BMC_SSPRST_N")
	)
	(segment
		(start 66.00698 -35.55492)
		(end 64.96304 -36.59886)
		(width 0.11684)
		(layer "B.Cu")
		(net "FM_BMC_SSPRST_N")
	)
	(segment
		(start 61.1378 -40.9702)
		(end 60.731908 -41.376092)
		(width 0.11684)
		(layer "B.Cu")
		(net "FM_BMC_SSPRST_N")
	)
	(segment
		(start 62.865 -39.500302)
		(end 63.242952 -39.878254)
		(width 0.11684)
		(layer "B.Cu")
		(net "FM_BMC_SSPRST_N")
	)
	(segment
		(start 66.30416 -35.55492)
		(end 66.00698 -35.55492)
		(width 0.11684)
		(layer "B.Cu")
		(net "FM_BMC_SSPRST_N")
	)
	(segment
		(start 62.938406 -40.1828)
		(end 61.877702 -40.1828)
		(width 0.11684)
		(layer "B.Cu")
		(net "FM_BMC_SSPRST_N")
	)
	(segment
		(start 61.688726 -40.371776)
		(end 61.688726 -40.744648)
		(width 0.11684)
		(layer "B.Cu")
		(net "FM_BMC_SSPRST_N")
	)
	(segment
		(start 73.08977 -73.034652)
		(end 73.08977 -73.83272)
		(width 0.11684)
		(layer "F.Cu")
		(net "FM_BMC_DISABLE")
	)
	(segment
		(start 73.152 -73.89495)
		(end 74.168 -73.89495)
		(width 0.11684)
		(layer "F.Cu")
		(net "FM_BMC_DISABLE")
	)
	(segment
		(start 73.08977 -73.83272)
		(end 73.152 -73.89495)
		(width 0.11684)
		(layer "F.Cu")
		(net "FM_BMC_DISABLE")
	)
	(via
		(at 73.08977 -73.034652)
		(size 0.508)
		(drill 0.254)
		(layers "F.Cu" "B.Cu")
		(net "FM_BMC_DISABLE")
	)
	(via
		(at 47.64278 -85.74786)
		(size 0.6604)
		(drill 0.3302)
		(layers "F.Cu" "B.Cu")
		(net "FM_BMC_DISABLE")
	)
	(via
		(at 70.485 -88.511126)
		(size 0.508)
		(drill 0.254)
		(layers "F.Cu" "B.Cu")
		(net "FM_BMC_DISABLE")
	)
	(via
		(at 48.37811 -87.484204)
		(size 0.508)
		(drill 0.254)
		(layers "F.Cu" "B.Cu")
		(net "FM_BMC_DISABLE")
	)
	(segment
		(start 47.64278 -86.621874)
		(end 48.37811 -87.357204)
		(width 0.11684)
		(layer "B.Cu")
		(net "FM_BMC_DISABLE")
	)
	(segment
		(start 46.1772 -85.1281)
		(end 44.831 -85.1281)
		(width 0.11684)
		(layer "B.Cu")
		(net "FM_BMC_DISABLE")
	)
	(segment
		(start 47.64278 -85.74786)
		(end 47.64278 -86.621874)
		(width 0.11684)
		(layer "B.Cu")
		(net "FM_BMC_DISABLE")
	)
	(segment
		(start 48.37811 -87.357204)
		(end 48.37811 -87.484204)
		(width 0.11684)
		(layer "B.Cu")
		(net "FM_BMC_DISABLE")
	)
	(segment
		(start 46.79696 -85.74786)
		(end 46.1772 -85.1281)
		(width 0.11684)
		(layer "B.Cu")
		(net "FM_BMC_DISABLE")
	)
	(segment
		(start 43.8658 -84.1629)
		(end 43.075098 -84.1629)
		(width 0.11684)
		(layer "B.Cu")
		(net "FM_BMC_DISABLE")
	)
	(segment
		(start 47.64278 -85.74786)
		(end 46.79696 -85.74786)
		(width 0.11684)
		(layer "B.Cu")
		(net "FM_BMC_DISABLE")
	)
	(segment
		(start 42.183558 -83.27136)
		(end 42.183558 -83.22056)
		(width 0.11684)
		(layer "B.Cu")
		(net "FM_BMC_DISABLE")
	)
	(segment
		(start 43.075098 -84.1629)
		(end 42.183558 -83.27136)
		(width 0.11684)
		(layer "B.Cu")
		(net "FM_BMC_DISABLE")
	)
	(segment
		(start 44.831 -85.1281)
		(end 43.8658 -84.1629)
		(width 0.11684)
		(layer "B.Cu")
		(net "FM_BMC_DISABLE")
	)
	(segment
		(start 48.486314 -87.592408)
		(end 51.360832 -87.592408)
		(width 0.08382)
		(layer "In2.Cu")
		(net "FM_BMC_DISABLE")
	)
	(segment
		(start 48.37811 -87.484204)
		(end 48.486314 -87.592408)
		(width 0.08382)
		(layer "In2.Cu")
		(net "FM_BMC_DISABLE")
	)
	(segment
		(start 51.360832 -87.592408)
		(end 53.735224 -89.9668)
		(width 0.08382)
		(layer "In2.Cu")
		(net "FM_BMC_DISABLE")
	)
	(segment
		(start 69.969126 -89.027)
		(end 70.485 -88.511126)
		(width 0.08382)
		(layer "In2.Cu")
		(net "FM_BMC_DISABLE")
	)
	(segment
		(start 53.735224 -89.9668)
		(end 56.718454 -89.9668)
		(width 0.08382)
		(layer "In2.Cu")
		(net "FM_BMC_DISABLE")
	)
	(segment
		(start 56.718454 -89.9668)
		(end 57.658254 -89.027)
		(width 0.08382)
		(layer "In2.Cu")
		(net "FM_BMC_DISABLE")
	)
	(segment
		(start 57.658254 -89.027)
		(end 69.969126 -89.027)
		(width 0.08382)
		(layer "In2.Cu")
		(net "FM_BMC_DISABLE")
	)
	(segment
		(start 70.9422 -79.6036)
		(end 71.1454 -79.8068)
		(width 0.10668)
		(layer "In7.Cu")
		(net "FM_BMC_DISABLE")
	)
	(segment
		(start 71.656702 -72.352408)
		(end 70.9422 -73.06691)
		(width 0.10668)
		(layer "In7.Cu")
		(net "FM_BMC_DISABLE")
	)
	(segment
		(start 71.1454 -79.8068)
		(end 71.1454 -87.850726)
		(width 0.10668)
		(layer "In7.Cu")
		(net "FM_BMC_DISABLE")
	)
	(segment
		(start 72.407526 -72.352408)
		(end 71.656702 -72.352408)
		(width 0.10668)
		(layer "In7.Cu")
		(net "FM_BMC_DISABLE")
	)
	(segment
		(start 71.1454 -87.850726)
		(end 70.485 -88.511126)
		(width 0.10668)
		(layer "In7.Cu")
		(net "FM_BMC_DISABLE")
	)
	(segment
		(start 73.08977 -73.034652)
		(end 72.407526 -72.352408)
		(width 0.10668)
		(layer "In7.Cu")
		(net "FM_BMC_DISABLE")
	)
	(segment
		(start 70.9422 -73.06691)
		(end 70.9422 -79.6036)
		(width 0.10668)
		(layer "In7.Cu")
		(net "FM_BMC_DISABLE")
	)
	(segment
		(start 61.869066 -79.632556)
		(end 61.872622 -79.629)
		(width 0.11684)
		(layer "F.Cu")
		(net "FM_BMC_DEBUG_SW_N")
	)
	(segment
		(start 61.872622 -79.629)
		(end 62.84595 -79.629)
		(width 0.11684)
		(layer "F.Cu")
		(net "FM_BMC_DEBUG_SW_N")
	)
	(segment
		(start 44.895008 -50.571146)
		(end 44.499784 -50.96637)
		(width 0.11684)
		(layer "F.Cu")
		(net "FM_BMC_DEBUG_SW_N")
	)
	(segment
		(start 61.872622 -78.154022)
		(end 61.872622 -79.629)
		(width 0.11684)
		(layer "F.Cu")
		(net "FM_BMC_DEBUG_SW_N")
	)
	(segment
		(start 61.6458 -77.9272)
		(end 61.872622 -78.154022)
		(width 0.11684)
		(layer "F.Cu")
		(net "FM_BMC_DEBUG_SW_N")
	)
	(via
		(at 61.6458 -77.9272)
		(size 0.508)
		(drill 0.254)
		(layers "F.Cu" "B.Cu")
		(net "FM_BMC_DEBUG_SW_N")
	)
	(via
		(at 31.27248 -54.124352)
		(size 0.508)
		(drill 0.254)
		(layers "F.Cu" "B.Cu")
		(net "FM_BMC_DEBUG_SW_N")
	)
	(via
		(at 22.729698 -103.74249)
		(size 0.508)
		(drill 0.254)
		(layers "F.Cu" "B.Cu")
		(net "FM_BMC_DEBUG_SW_N")
	)
	(via
		(at 44.499784 -50.96637)
		(size 0.4572)
		(drill 0.254)
		(layers "F.Cu" "B.Cu")
		(net "FM_BMC_DEBUG_SW_N")
	)
	(segment
		(start 21.971 -102.38105)
		(end 22.729698 -103.139748)
		(width 0.11684)
		(layer "B.Cu")
		(net "FM_BMC_DEBUG_SW_N")
	)
	(segment
		(start 22.729698 -103.139748)
		(end 22.729698 -103.74249)
		(width 0.11684)
		(layer "B.Cu")
		(net "FM_BMC_DEBUG_SW_N")
	)
	(segment
		(start 14.5796 -51.816)
		(end 12.9794 -51.816)
		(width 0.08382)
		(layer "In2.Cu")
		(net "FM_BMC_DEBUG_SW_N")
	)
	(segment
		(start 40.3098 -52.5018)
		(end 40.2082 -52.6034)
		(width 0.08382)
		(layer "In2.Cu")
		(net "FM_BMC_DEBUG_SW_N")
	)
	(segment
		(start 25.341072 -69.28358)
		(end 26.52903 -69.28358)
		(width 0.08382)
		(layer "In2.Cu")
		(net "FM_BMC_DEBUG_SW_N")
	)
	(segment
		(start 35.002216 -72.6948)
		(end 37.595556 -70.10146)
		(width 0.08382)
		(layer "In2.Cu")
		(net "FM_BMC_DEBUG_SW_N")
	)
	(segment
		(start 19.6596 -67.2084)
		(end 20.69211 -68.24091)
		(width 0.08382)
		(layer "In2.Cu")
		(net "FM_BMC_DEBUG_SW_N")
	)
	(segment
		(start 12.14501 -63.503302)
		(end 15.850108 -67.2084)
		(width 0.08382)
		(layer "In2.Cu")
		(net "FM_BMC_DEBUG_SW_N")
	)
	(segment
		(start 19.600418 -53.788818)
		(end 16.552418 -53.788818)
		(width 0.08382)
		(layer "In2.Cu")
		(net "FM_BMC_DEBUG_SW_N")
	)
	(segment
		(start 40.992552 -70.10146)
		(end 43.707812 -72.81672)
		(width 0.08382)
		(layer "In2.Cu")
		(net "FM_BMC_DEBUG_SW_N")
	)
	(segment
		(start 12.7 -51.5366)
		(end 12.1412 -51.5366)
		(width 0.08382)
		(layer "In2.Cu")
		(net "FM_BMC_DEBUG_SW_N")
	)
	(segment
		(start 33.9852 -51.9938)
		(end 33.526222 -52.452778)
		(width 0.08382)
		(layer "In2.Cu")
		(net "FM_BMC_DEBUG_SW_N")
	)
	(segment
		(start 11.358626 -56.215026)
		(end 12.14501 -58.113676)
		(width 0.08382)
		(layer "In2.Cu")
		(net "FM_BMC_DEBUG_SW_N")
	)
	(segment
		(start 21.394928 -68.24091)
		(end 21.65731 -67.978528)
		(width 0.08382)
		(layer "In2.Cu")
		(net "FM_BMC_DEBUG_SW_N")
	)
	(segment
		(start 35.5346 -51.9938)
		(end 33.9852 -51.9938)
		(width 0.08382)
		(layer "In2.Cu")
		(net "FM_BMC_DEBUG_SW_N")
	)
	(segment
		(start 41.39565 -52.5018)
		(end 40.3098 -52.5018)
		(width 0.08382)
		(layer "In2.Cu")
		(net "FM_BMC_DEBUG_SW_N")
	)
	(segment
		(start 29.405326 -57.210198)
		(end 28.574492 -57.765442)
		(width 0.08382)
		(layer "In2.Cu")
		(net "FM_BMC_DEBUG_SW_N")
	)
	(segment
		(start 44.499784 -51.240182)
		(end 42.90187 -52.838096)
		(width 0.08382)
		(layer "In2.Cu")
		(net "FM_BMC_DEBUG_SW_N")
	)
	(segment
		(start 20.69211 -68.24091)
		(end 21.394928 -68.24091)
		(width 0.08382)
		(layer "In2.Cu")
		(net "FM_BMC_DEBUG_SW_N")
	)
	(segment
		(start 27.588972 -58.17362)
		(end 25.69591 -58.17362)
		(width 0.08382)
		(layer "In2.Cu")
		(net "FM_BMC_DEBUG_SW_N")
	)
	(segment
		(start 41.731946 -52.838096)
		(end 41.39565 -52.5018)
		(width 0.08382)
		(layer "In2.Cu")
		(net "FM_BMC_DEBUG_SW_N")
	)
	(segment
		(start 15.850108 -67.2084)
		(end 19.6596 -67.2084)
		(width 0.08382)
		(layer "In2.Cu")
		(net "FM_BMC_DEBUG_SW_N")
	)
	(segment
		(start 23.89124 -57.0738)
		(end 22.8854 -57.0738)
		(width 0.08382)
		(layer "In2.Cu")
		(net "FM_BMC_DEBUG_SW_N")
	)
	(segment
		(start 42.90187 -52.838096)
		(end 41.731946 -52.838096)
		(width 0.08382)
		(layer "In2.Cu")
		(net "FM_BMC_DEBUG_SW_N")
	)
	(segment
		(start 23.344632 -67.28714)
		(end 25.341072 -69.28358)
		(width 0.08382)
		(layer "In2.Cu")
		(net "FM_BMC_DEBUG_SW_N")
	)
	(segment
		(start 12.1412 -51.5366)
		(end 11.358626 -52.319174)
		(width 0.08382)
		(layer "In2.Cu")
		(net "FM_BMC_DEBUG_SW_N")
	)
	(segment
		(start 50.44313 -72.81672)
		(end 52.73421 -75.1078)
		(width 0.08382)
		(layer "In2.Cu")
		(net "FM_BMC_DEBUG_SW_N")
	)
	(segment
		(start 27.89809 -71.950072)
		(end 27.89809 -72.321928)
		(width 0.08382)
		(layer "In2.Cu")
		(net "FM_BMC_DEBUG_SW_N")
	)
	(segment
		(start 60.452762 -76.20127)
		(end 61.6458 -77.394308)
		(width 0.08382)
		(layer "In2.Cu")
		(net "FM_BMC_DEBUG_SW_N")
	)
	(segment
		(start 28.03398 -71.814182)
		(end 27.89809 -71.950072)
		(width 0.08382)
		(layer "In2.Cu")
		(net "FM_BMC_DEBUG_SW_N")
	)
	(segment
		(start 11.358626 -52.319174)
		(end 11.358626 -56.215026)
		(width 0.08382)
		(layer "In2.Cu")
		(net "FM_BMC_DEBUG_SW_N")
	)
	(segment
		(start 27.89809 -72.321928)
		(end 28.270962 -72.6948)
		(width 0.08382)
		(layer "In2.Cu")
		(net "FM_BMC_DEBUG_SW_N")
	)
	(segment
		(start 37.595556 -70.10146)
		(end 40.992552 -70.10146)
		(width 0.08382)
		(layer "In2.Cu")
		(net "FM_BMC_DEBUG_SW_N")
	)
	(segment
		(start 33.526222 -52.452778)
		(end 31.214822 -52.452778)
		(width 0.08382)
		(layer "In2.Cu")
		(net "FM_BMC_DEBUG_SW_N")
	)
	(segment
		(start 31.272226 -55.343298)
		(end 29.405326 -57.210198)
		(width 0.08382)
		(layer "In2.Cu")
		(net "FM_BMC_DEBUG_SW_N")
	)
	(segment
		(start 44.499784 -50.96637)
		(end 44.499784 -51.240182)
		(width 0.08382)
		(layer "In2.Cu")
		(net "FM_BMC_DEBUG_SW_N")
	)
	(segment
		(start 31.27248 -53.77688)
		(end 31.27248 -54.124352)
		(width 0.08382)
		(layer "In2.Cu")
		(net "FM_BMC_DEBUG_SW_N")
	)
	(segment
		(start 40.2082 -52.6034)
		(end 36.1442 -52.6034)
		(width 0.08382)
		(layer "In2.Cu")
		(net "FM_BMC_DEBUG_SW_N")
	)
	(segment
		(start 21.65731 -67.978528)
		(end 21.65731 -67.78625)
		(width 0.08382)
		(layer "In2.Cu")
		(net "FM_BMC_DEBUG_SW_N")
	)
	(segment
		(start 56.180228 -76.20127)
		(end 60.452762 -76.20127)
		(width 0.08382)
		(layer "In2.Cu")
		(net "FM_BMC_DEBUG_SW_N")
	)
	(segment
		(start 22.15642 -67.28714)
		(end 23.344632 -67.28714)
		(width 0.08382)
		(layer "In2.Cu")
		(net "FM_BMC_DEBUG_SW_N")
	)
	(segment
		(start 24.492712 -57.675272)
		(end 23.89124 -57.0738)
		(width 0.08382)
		(layer "In2.Cu")
		(net "FM_BMC_DEBUG_SW_N")
	)
	(segment
		(start 25.69591 -58.17362)
		(end 24.492712 -57.675272)
		(width 0.08382)
		(layer "In2.Cu")
		(net "FM_BMC_DEBUG_SW_N")
	)
	(segment
		(start 26.52903 -69.28358)
		(end 28.03398 -70.78853)
		(width 0.08382)
		(layer "In2.Cu")
		(net "FM_BMC_DEBUG_SW_N")
	)
	(segment
		(start 30.861 -53.3654)
		(end 31.27248 -53.77688)
		(width 0.08382)
		(layer "In2.Cu")
		(net "FM_BMC_DEBUG_SW_N")
	)
	(segment
		(start 30.861 -52.8066)
		(end 30.861 -53.3654)
		(width 0.08382)
		(layer "In2.Cu")
		(net "FM_BMC_DEBUG_SW_N")
	)
	(segment
		(start 55.086758 -75.1078)
		(end 56.180228 -76.20127)
		(width 0.08382)
		(layer "In2.Cu")
		(net "FM_BMC_DEBUG_SW_N")
	)
	(segment
		(start 12.14501 -58.113676)
		(end 12.14501 -63.503302)
		(width 0.08382)
		(layer "In2.Cu")
		(net "FM_BMC_DEBUG_SW_N")
	)
	(segment
		(start 28.270962 -72.6948)
		(end 35.002216 -72.6948)
		(width 0.08382)
		(layer "In2.Cu")
		(net "FM_BMC_DEBUG_SW_N")
	)
	(segment
		(start 22.8854 -57.0738)
		(end 19.600418 -53.788818)
		(width 0.08382)
		(layer "In2.Cu")
		(net "FM_BMC_DEBUG_SW_N")
	)
	(segment
		(start 16.552418 -53.788818)
		(end 14.5796 -51.816)
		(width 0.08382)
		(layer "In2.Cu")
		(net "FM_BMC_DEBUG_SW_N")
	)
	(segment
		(start 52.73421 -75.1078)
		(end 55.086758 -75.1078)
		(width 0.08382)
		(layer "In2.Cu")
		(net "FM_BMC_DEBUG_SW_N")
	)
	(segment
		(start 31.27248 -54.124352)
		(end 31.272226 -54.124606)
		(width 0.08382)
		(layer "In2.Cu")
		(net "FM_BMC_DEBUG_SW_N")
	)
	(segment
		(start 31.214822 -52.452778)
		(end 30.861 -52.8066)
		(width 0.08382)
		(layer "In2.Cu")
		(net "FM_BMC_DEBUG_SW_N")
	)
	(segment
		(start 36.1442 -52.6034)
		(end 35.5346 -51.9938)
		(width 0.08382)
		(layer "In2.Cu")
		(net "FM_BMC_DEBUG_SW_N")
	)
	(segment
		(start 43.707812 -72.81672)
		(end 50.44313 -72.81672)
		(width 0.08382)
		(layer "In2.Cu")
		(net "FM_BMC_DEBUG_SW_N")
	)
	(segment
		(start 21.65731 -67.78625)
		(end 22.15642 -67.28714)
		(width 0.08382)
		(layer "In2.Cu")
		(net "FM_BMC_DEBUG_SW_N")
	)
	(segment
		(start 61.6458 -77.394308)
		(end 61.6458 -77.9272)
		(width 0.08382)
		(layer "In2.Cu")
		(net "FM_BMC_DEBUG_SW_N")
	)
	(segment
		(start 31.272226 -54.124606)
		(end 31.272226 -55.343298)
		(width 0.08382)
		(layer "In2.Cu")
		(net "FM_BMC_DEBUG_SW_N")
	)
	(segment
		(start 28.03398 -70.78853)
		(end 28.03398 -71.814182)
		(width 0.08382)
		(layer "In2.Cu")
		(net "FM_BMC_DEBUG_SW_N")
	)
	(segment
		(start 12.9794 -51.816)
		(end 12.7 -51.5366)
		(width 0.08382)
		(layer "In2.Cu")
		(net "FM_BMC_DEBUG_SW_N")
	)
	(segment
		(start 28.574492 -57.765442)
		(end 27.588972 -58.17362)
		(width 0.08382)
		(layer "In2.Cu")
		(net "FM_BMC_DEBUG_SW_N")
	)
	(segment
		(start 27.59456 -99.38004)
		(end 26.900886 -100.073714)
		(width 0.10668)
		(layer "In4.Cu")
		(net "FM_BMC_DEBUG_SW_N")
	)
	(segment
		(start 30.162246 -72.980042)
		(end 30.162246 -76.949808)
		(width 0.10668)
		(layer "In4.Cu")
		(net "FM_BMC_DEBUG_SW_N")
	)
	(segment
		(start 31.272226 -55.320438)
		(end 30.17647 -57.966864)
		(width 0.10668)
		(layer "In4.Cu")
		(net "FM_BMC_DEBUG_SW_N")
	)
	(segment
		(start 30.162246 -76.949808)
		(end 29.514546 -77.597508)
		(width 0.10668)
		(layer "In4.Cu")
		(net "FM_BMC_DEBUG_SW_N")
	)
	(segment
		(start 27.6606 -94.8182)
		(end 28.60294 -95.76054)
		(width 0.10668)
		(layer "In4.Cu")
		(net "FM_BMC_DEBUG_SW_N")
	)
	(segment
		(start 30.17647 -57.966864)
		(end 30.17647 -58.896758)
		(width 0.10668)
		(layer "In4.Cu")
		(net "FM_BMC_DEBUG_SW_N")
	)
	(segment
		(start 23.525988 -102.9462)
		(end 22.729698 -103.74249)
		(width 0.10668)
		(layer "In4.Cu")
		(net "FM_BMC_DEBUG_SW_N")
	)
	(segment
		(start 25.28824 -102.9462)
		(end 23.525988 -102.9462)
		(width 0.10668)
		(layer "In4.Cu")
		(net "FM_BMC_DEBUG_SW_N")
	)
	(segment
		(start 30.17647 -58.896758)
		(end 29.5529 -59.520328)
		(width 0.10668)
		(layer "In4.Cu")
		(net "FM_BMC_DEBUG_SW_N")
	)
	(segment
		(start 29.514546 -77.597508)
		(end 29.514546 -84.54644)
		(width 0.10668)
		(layer "In4.Cu")
		(net "FM_BMC_DEBUG_SW_N")
	)
	(segment
		(start 29.477716 -63.615316)
		(end 29.477716 -64.634872)
		(width 0.10668)
		(layer "In4.Cu")
		(net "FM_BMC_DEBUG_SW_N")
	)
	(segment
		(start 30.03804 -68.961)
		(end 30.03804 -71.023988)
		(width 0.10668)
		(layer "In4.Cu")
		(net "FM_BMC_DEBUG_SW_N")
	)
	(segment
		(start 26.900886 -100.073714)
		(end 26.900886 -104.391714)
		(width 0.10668)
		(layer "In4.Cu")
		(net "FM_BMC_DEBUG_SW_N")
	)
	(segment
		(start 25.975818 -103.633778)
		(end 25.28824 -102.9462)
		(width 0.10668)
		(layer "In4.Cu")
		(net "FM_BMC_DEBUG_SW_N")
	)
	(segment
		(start 31.27248 -54.124352)
		(end 31.272226 -54.124606)
		(width 0.10668)
		(layer "In4.Cu")
		(net "FM_BMC_DEBUG_SW_N")
	)
	(segment
		(start 28.60294 -97.15246)
		(end 27.59456 -98.16084)
		(width 0.10668)
		(layer "In4.Cu")
		(net "FM_BMC_DEBUG_SW_N")
	)
	(segment
		(start 26.900886 -104.391714)
		(end 26.560018 -104.732582)
		(width 0.10668)
		(layer "In4.Cu")
		(net "FM_BMC_DEBUG_SW_N")
	)
	(segment
		(start 28.60294 -95.76054)
		(end 28.60294 -97.15246)
		(width 0.10668)
		(layer "In4.Cu")
		(net "FM_BMC_DEBUG_SW_N")
	)
	(segment
		(start 30.35046 -65.507616)
		(end 30.35046 -68.64858)
		(width 0.10668)
		(layer "In4.Cu")
		(net "FM_BMC_DEBUG_SW_N")
	)
	(segment
		(start 29.40812 -63.54572)
		(end 29.477716 -63.615316)
		(width 0.10668)
		(layer "In4.Cu")
		(net "FM_BMC_DEBUG_SW_N")
	)
	(segment
		(start 30.35046 -68.64858)
		(end 30.03804 -68.961)
		(width 0.10668)
		(layer "In4.Cu")
		(net "FM_BMC_DEBUG_SW_N")
	)
	(segment
		(start 30.03804 -71.023988)
		(end 29.81198 -71.250048)
		(width 0.10668)
		(layer "In4.Cu")
		(net "FM_BMC_DEBUG_SW_N")
	)
	(segment
		(start 29.75864 -90.560906)
		(end 29.75864 -92.11056)
		(width 0.10668)
		(layer "In4.Cu")
		(net "FM_BMC_DEBUG_SW_N")
	)
	(segment
		(start 29.5529 -61.21654)
		(end 29.40812 -61.36132)
		(width 0.10668)
		(layer "In4.Cu")
		(net "FM_BMC_DEBUG_SW_N")
	)
	(segment
		(start 28.6004 -93.2688)
		(end 28.0416 -93.2688)
		(width 0.10668)
		(layer "In4.Cu")
		(net "FM_BMC_DEBUG_SW_N")
	)
	(segment
		(start 26.348182 -104.732582)
		(end 25.975818 -104.360218)
		(width 0.10668)
		(layer "In4.Cu")
		(net "FM_BMC_DEBUG_SW_N")
	)
	(segment
		(start 29.40812 -61.36132)
		(end 29.40812 -63.54572)
		(width 0.10668)
		(layer "In4.Cu")
		(net "FM_BMC_DEBUG_SW_N")
	)
	(segment
		(start 29.75864 -92.11056)
		(end 28.6004 -93.2688)
		(width 0.10668)
		(layer "In4.Cu")
		(net "FM_BMC_DEBUG_SW_N")
	)
	(segment
		(start 27.59456 -98.16084)
		(end 27.59456 -99.38004)
		(width 0.10668)
		(layer "In4.Cu")
		(net "FM_BMC_DEBUG_SW_N")
	)
	(segment
		(start 29.82214 -90.497406)
		(end 29.75864 -90.560906)
		(width 0.10668)
		(layer "In4.Cu")
		(net "FM_BMC_DEBUG_SW_N")
	)
	(segment
		(start 29.514546 -84.54644)
		(end 29.82214 -84.854034)
		(width 0.10668)
		(layer "In4.Cu")
		(net "FM_BMC_DEBUG_SW_N")
	)
	(segment
		(start 29.82214 -84.854034)
		(end 29.82214 -90.497406)
		(width 0.10668)
		(layer "In4.Cu")
		(net "FM_BMC_DEBUG_SW_N")
	)
	(segment
		(start 27.6606 -93.6498)
		(end 27.6606 -94.8182)
		(width 0.10668)
		(layer "In4.Cu")
		(net "FM_BMC_DEBUG_SW_N")
	)
	(segment
		(start 29.5529 -59.520328)
		(end 29.5529 -61.21654)
		(width 0.10668)
		(layer "In4.Cu")
		(net "FM_BMC_DEBUG_SW_N")
	)
	(segment
		(start 26.560018 -104.732582)
		(end 26.348182 -104.732582)
		(width 0.10668)
		(layer "In4.Cu")
		(net "FM_BMC_DEBUG_SW_N")
	)
	(segment
		(start 29.477716 -64.634872)
		(end 30.35046 -65.507616)
		(width 0.10668)
		(layer "In4.Cu")
		(net "FM_BMC_DEBUG_SW_N")
	)
	(segment
		(start 28.0416 -93.2688)
		(end 27.6606 -93.6498)
		(width 0.10668)
		(layer "In4.Cu")
		(net "FM_BMC_DEBUG_SW_N")
	)
	(segment
		(start 29.81198 -72.629776)
		(end 30.162246 -72.980042)
		(width 0.10668)
		(layer "In4.Cu")
		(net "FM_BMC_DEBUG_SW_N")
	)
	(segment
		(start 31.272226 -54.124606)
		(end 31.272226 -55.320438)
		(width 0.10668)
		(layer "In4.Cu")
		(net "FM_BMC_DEBUG_SW_N")
	)
	(segment
		(start 29.81198 -71.250048)
		(end 29.81198 -72.629776)
		(width 0.10668)
		(layer "In4.Cu")
		(net "FM_BMC_DEBUG_SW_N")
	)
	(segment
		(start 25.975818 -104.360218)
		(end 25.975818 -103.633778)
		(width 0.10668)
		(layer "In4.Cu")
		(net "FM_BMC_DEBUG_SW_N")
	)
	(segment
		(start 45.72 -35.02025)
		(end 45.72 -35.89274)
		(width 0.11684)
		(layer "F.Cu")
		(net "FM_BMC_DBP_PRESENT_R_N")
	)
	(segment
		(start 46.12513 -37.260276)
		(end 46.685454 -37.8206)
		(width 0.11684)
		(layer "F.Cu")
		(net "FM_BMC_DBP_PRESENT_R_N")
	)
	(segment
		(start 46.12513 -36.29787)
		(end 46.12513 -37.260276)
		(width 0.11684)
		(layer "F.Cu")
		(net "FM_BMC_DBP_PRESENT_R_N")
	)
	(segment
		(start 48.499776 -39.122858)
		(end 48.499776 -39.776146)
		(width 0.11684)
		(layer "F.Cu")
		(net "FM_BMC_DBP_PRESENT_R_N")
	)
	(segment
		(start 46.685454 -37.8206)
		(end 47.197518 -37.8206)
		(width 0.11684)
		(layer "F.Cu")
		(net "FM_BMC_DBP_PRESENT_R_N")
	)
	(segment
		(start 47.197518 -37.8206)
		(end 48.499776 -39.122858)
		(width 0.11684)
		(layer "F.Cu")
		(net "FM_BMC_DBP_PRESENT_R_N")
	)
	(segment
		(start 45.72 -35.89274)
		(end 46.12513 -36.29787)
		(width 0.11684)
		(layer "F.Cu")
		(net "FM_BMC_DBP_PRESENT_R_N")
	)
	(segment
		(start 48.499776 -39.776146)
		(end 48.895 -40.17137)
		(width 0.11684)
		(layer "F.Cu")
		(net "FM_BMC_DBP_PRESENT_R_N")
	)
	(via
		(at 46.12513 -36.29787)
		(size 0.762)
		(drill 0.381)
		(layers "F.Cu" "B.Cu")
		(net "FM_BMC_DBP_PRESENT_R_N")
	)
	(segment
		(start 64.094868 -56.171338)
		(end 64.490092 -56.566562)
		(width 0.1016)
		(layer "F.Cu")
		(net "NC_DP_BMC_TX1_P")
	)
	(via
		(at 64.490092 -56.566562)
		(size 0.4572)
		(drill 0.254)
		(layers "F.Cu" "B.Cu")
		(net "NC_DP_BMC_TX1_P")
	)
	(segment
		(start 64.094868 -55.371238)
		(end 64.490092 -55.766462)
		(width 0.1016)
		(layer "F.Cu")
		(net "NC_DP_BMC_TX1_N")
	)
	(via
		(at 64.490092 -55.766462)
		(size 0.4572)
		(drill 0.254)
		(layers "F.Cu" "B.Cu")
		(net "NC_DP_BMC_TX1_N")
	)
	(segment
		(start 63.295022 -56.971184)
		(end 63.690246 -57.366408)
		(width 0.1016)
		(layer "F.Cu")
		(net "NC_DP_BMC_AUX_P")
	)
	(via
		(at 63.690246 -57.366408)
		(size 0.4572)
		(drill 0.254)
		(layers "F.Cu" "B.Cu")
		(net "NC_DP_BMC_AUX_P")
	)
	(segment
		(start 63.295022 -56.171338)
		(end 63.690246 -56.566562)
		(width 0.1016)
		(layer "F.Cu")
		(net "NC_DP_BMC_AUX_N")
	)
	(via
		(at 63.690246 -56.566562)
		(size 0.4572)
		(drill 0.254)
		(layers "F.Cu" "B.Cu")
		(net "NC_DP_BMC_AUX_N")
	)
	(segment
		(start 53.695092 -40.971216)
		(end 53.299868 -40.575992)
		(width 0.11684)
		(layer "F.Cu")
		(net "FM_DBP_CPU_PREQ_GF_N")
	)
	(via
		(at 53.299868 -40.575992)
		(size 0.4572)
		(drill 0.254)
		(layers "F.Cu" "B.Cu")
		(net "FM_DBP_CPU_PREQ_GF_N")
	)
	(segment
		(start 52.991258 -37.052758)
		(end 52.991258 -37.697664)
		(width 0.11684)
		(layer "B.Cu")
		(net "FM_DBP_CPU_PREQ_GF_N")
	)
	(segment
		(start 52.896008 -39.938706)
		(end 53.134768 -40.177466)
		(width 0.11684)
		(layer "B.Cu")
		(net "FM_DBP_CPU_PREQ_GF_N")
	)
	(segment
		(start 52.705 -39.318946)
		(end 52.896008 -39.509954)
		(width 0.11684)
		(layer "B.Cu")
		(net "FM_DBP_CPU_PREQ_GF_N")
	)
	(segment
		(start 52.705 -35.814)
		(end 52.989988 -36.098988)
		(width 0.11684)
		(layer "B.Cu")
		(net "FM_DBP_CPU_PREQ_GF_N")
	)
	(segment
		(start 52.989988 -37.051488)
		(end 52.991258 -37.052758)
		(width 0.11684)
		(layer "B.Cu")
		(net "FM_DBP_CPU_PREQ_GF_N")
	)
	(segment
		(start 52.578 -35.04565)
		(end 52.705 -35.17265)
		(width 0.11684)
		(layer "B.Cu")
		(net "FM_DBP_CPU_PREQ_GF_N")
	)
	(segment
		(start 52.989988 -36.098988)
		(end 52.989988 -36.29787)
		(width 0.11684)
		(layer "B.Cu")
		(net "FM_DBP_CPU_PREQ_GF_N")
	)
	(segment
		(start 52.991258 -36.956746)
		(end 52.989988 -36.958016)
		(width 0.11684)
		(layer "B.Cu")
		(net "FM_DBP_CPU_PREQ_GF_N")
	)
	(segment
		(start 52.991258 -36.29914)
		(end 52.991258 -36.956746)
		(width 0.11684)
		(layer "B.Cu")
		(net "FM_DBP_CPU_PREQ_GF_N")
	)
	(segment
		(start 52.989988 -36.29787)
		(end 52.991258 -36.29914)
		(width 0.11684)
		(layer "B.Cu")
		(net "FM_DBP_CPU_PREQ_GF_N")
	)
	(segment
		(start 52.705 -35.17265)
		(end 52.705 -35.814)
		(width 0.11684)
		(layer "B.Cu")
		(net "FM_DBP_CPU_PREQ_GF_N")
	)
	(segment
		(start 53.134768 -40.177466)
		(end 53.299868 -40.575992)
		(width 0.11684)
		(layer "B.Cu")
		(net "FM_DBP_CPU_PREQ_GF_N")
	)
	(segment
		(start 52.896008 -39.509954)
		(end 52.896008 -39.938706)
		(width 0.11684)
		(layer "B.Cu")
		(net "FM_DBP_CPU_PREQ_GF_N")
	)
	(segment
		(start 52.991258 -37.697664)
		(end 52.705 -37.983922)
		(width 0.11684)
		(layer "B.Cu")
		(net "FM_DBP_CPU_PREQ_GF_N")
	)
	(segment
		(start 52.705 -37.983922)
		(end 52.705 -39.318946)
		(width 0.11684)
		(layer "B.Cu")
		(net "FM_DBP_CPU_PREQ_GF_N")
	)
	(segment
		(start 52.989988 -36.958016)
		(end 52.989988 -37.051488)
		(width 0.11684)
		(layer "B.Cu")
		(net "FM_DBP_CPU_PREQ_GF_N")
	)
	(segment
		(start 29.21635 -25.908)
		(end 29.21635 -26.6192)
		(width 0.381)
		(layer "F.Cu")
		(net "CRT_VCC5")
	)
	(segment
		(start 29.21635 -26.6192)
		(end 29.21635 -27.3304)
		(width 0.381)
		(layer "F.Cu")
		(net "CRT_VCC5")
	)
	(via
		(at 36.322 -4.39674)
		(size 0.6604)
		(drill 0.3302)
		(layers "F.Cu" "B.Cu")
		(net "CRT_VCC5")
	)
	(via
		(at 30.4038 -22.6568)
		(size 0.508)
		(drill 0.254)
		(layers "F.Cu" "B.Cu")
		(net "CRT_VCC5")
	)
	(via
		(at 29.9212 -37.3888)
		(size 0.508)
		(drill 0.254)
		(layers "F.Cu" "B.Cu")
		(net "CRT_VCC5")
	)
	(via
		(at 27.6352 -23.3426)
		(size 0.508)
		(drill 0.254)
		(layers "F.Cu" "B.Cu")
		(net "CRT_VCC5")
	)
	(via
		(at 29.21635 -26.6192)
		(size 0.508)
		(drill 0.254)
		(layers "F.Cu" "B.Cu")
		(net "CRT_VCC5")
	)
	(via
		(at 32.2072 -33.7566)
		(size 0.6604)
		(drill 0.3302)
		(layers "F.Cu" "B.Cu")
		(net "CRT_VCC5")
	)
	(via
		(at 30.6832 -37.3888)
		(size 0.508)
		(drill 0.254)
		(layers "F.Cu" "B.Cu")
		(net "CRT_VCC5")
	)
	(via
		(at 30.5562 -34.2392)
		(size 0.6604)
		(drill 0.3302)
		(layers "F.Cu" "B.Cu")
		(net "CRT_VCC5")
	)
	(segment
		(start 41.5036 -4.00685)
		(end 36.71189 -4.00685)
		(width 0.381)
		(layer "B.Cu")
		(net "CRT_VCC5")
	)
	(segment
		(start 34.83483 -20.98802)
		(end 34.41065 -21.4122)
		(width 0.381)
		(layer "B.Cu")
		(net "CRT_VCC5")
	)
	(segment
		(start 34.41065 -21.4122)
		(end 34.41065 -23.72995)
		(width 0.381)
		(layer "B.Cu")
		(net "CRT_VCC5")
	)
	(segment
		(start 33.562036 -7.156704)
		(end 33.562036 -13.064236)
		(width 0.381)
		(layer "B.Cu")
		(net "CRT_VCC5")
	)
	(segment
		(start 34.925 -16.22425)
		(end 34.544 -16.60525)
		(width 0.381)
		(layer "B.Cu")
		(net "CRT_VCC5")
	)
	(segment
		(start 32.9946 -24.0284)
		(end 30.91307 -23.16607)
		(width 0.381)
		(layer "B.Cu")
		(net "CRT_VCC5")
	)
	(segment
		(start 34.544 -16.60525)
		(end 34.544 -18.9738)
		(width 0.381)
		(layer "B.Cu")
		(net "CRT_VCC5")
	)
	(segment
		(start 33.562036 -13.064236)
		(end 34.925 -14.4272)
		(width 0.381)
		(layer "B.Cu")
		(net "CRT_VCC5")
	)
	(segment
		(start 34.925 -14.4272)
		(end 34.925 -16.22425)
		(width 0.381)
		(layer "B.Cu")
		(net "CRT_VCC5")
	)
	(segment
		(start 36.322 -4.39674)
		(end 33.562036 -7.156704)
		(width 0.381)
		(layer "B.Cu")
		(net "CRT_VCC5")
	)
	(segment
		(start 34.544 -18.9738)
		(end 34.83483 -19.26463)
		(width 0.381)
		(layer "B.Cu")
		(net "CRT_VCC5")
	)
	(segment
		(start 36.71189 -4.00685)
		(end 36.322 -4.39674)
		(width 0.381)
		(layer "B.Cu")
		(net "CRT_VCC5")
	)
	(segment
		(start 30.91307 -23.16607)
		(end 30.4038 -22.6568)
		(width 0.381)
		(layer "B.Cu")
		(net "CRT_VCC5")
	)
	(segment
		(start 34.41065 -23.72995)
		(end 34.1122 -24.0284)
		(width 0.381)
		(layer "B.Cu")
		(net "CRT_VCC5")
	)
	(segment
		(start 34.83483 -19.26463)
		(end 34.83483 -20.98802)
		(width 0.381)
		(layer "B.Cu")
		(net "CRT_VCC5")
	)
	(segment
		(start 34.1122 -24.0284)
		(end 32.9946 -24.0284)
		(width 0.381)
		(layer "B.Cu")
		(net "CRT_VCC5")
	)
	(segment
		(start 43.51655 -69.2912)
		(end 43.51655 -67.837812)
		(width 0.254)
		(layer "F.Cu")
		(net "BMC_HEARTBEAT_R_N")
	)
	(segment
		(start 43.51655 -67.837812)
		(end 43.445938 -67.7672)
		(width 0.254)
		(layer "F.Cu")
		(net "BMC_HEARTBEAT_R_N")
	)
	(segment
		(start 44.090844 -69.746368)
		(end 44.270676 -69.9262)
		(width 0.254)
		(layer "F.Cu")
		(net "BMC_HEARTBEAT_N")
	)
	(segment
		(start 47.699676 -55.766462)
		(end 47.699676 -54.97576)
		(width 0.11684)
		(layer "F.Cu")
		(net "BMC_HEARTBEAT_N")
	)
	(segment
		(start 41.783 -67.564)
		(end 42.2148 -67.9958)
		(width 0.254)
		(layer "F.Cu")
		(net "BMC_HEARTBEAT_N")
	)
	(segment
		(start 45.96765 -69.55155)
		(end 45.96765 -69.2912)
		(width 0.254)
		(layer "F.Cu")
		(net "BMC_HEARTBEAT_N")
	)
	(segment
		(start 45.9994 -69.25945)
		(end 45.9994 -68.2498)
		(width 0.254)
		(layer "F.Cu")
		(net "BMC_HEARTBEAT_N")
	)
	(segment
		(start 42.2148 -67.9958)
		(end 42.2148 -70.2564)
		(width 0.254)
		(layer "F.Cu")
		(net "BMC_HEARTBEAT_N")
	)
	(segment
		(start 45.96765 -69.2912)
		(end 45.9994 -69.25945)
		(width 0.254)
		(layer "F.Cu")
		(net "BMC_HEARTBEAT_N")
	)
	(segment
		(start 44.270676 -69.9262)
		(end 45.593 -69.9262)
		(width 0.254)
		(layer "F.Cu")
		(net "BMC_HEARTBEAT_N")
	)
	(segment
		(start 43.37939 -70.17639)
		(end 43.37939 -70.160134)
		(width 0.254)
		(layer "F.Cu")
		(net "BMC_HEARTBEAT_N")
	)
	(segment
		(start 42.3926 -70.4342)
		(end 43.12158 -70.4342)
		(width 0.254)
		(layer "F.Cu")
		(net "BMC_HEARTBEAT_N")
	)
	(segment
		(start 43.12158 -70.4342)
		(end 43.37939 -70.17639)
		(width 0.254)
		(layer "F.Cu")
		(net "BMC_HEARTBEAT_N")
	)
	(segment
		(start 45.5168 -67.7672)
		(end 44.946062 -67.7672)
		(width 0.254)
		(layer "F.Cu")
		(net "BMC_HEARTBEAT_N")
	)
	(segment
		(start 47.699676 -54.97576)
		(end 47.295054 -54.571138)
		(width 0.11684)
		(layer "F.Cu")
		(net "BMC_HEARTBEAT_N")
	)
	(segment
		(start 42.2148 -70.2564)
		(end 42.3926 -70.4342)
		(width 0.254)
		(layer "F.Cu")
		(net "BMC_HEARTBEAT_N")
	)
	(segment
		(start 43.37939 -70.160134)
		(end 43.793156 -69.746368)
		(width 0.254)
		(layer "F.Cu")
		(net "BMC_HEARTBEAT_N")
	)
	(segment
		(start 43.793156 -69.746368)
		(end 44.090844 -69.746368)
		(width 0.254)
		(layer "F.Cu")
		(net "BMC_HEARTBEAT_N")
	)
	(segment
		(start 45.9994 -68.2498)
		(end 45.5168 -67.7672)
		(width 0.254)
		(layer "F.Cu")
		(net "BMC_HEARTBEAT_N")
	)
	(segment
		(start 45.593 -69.9262)
		(end 45.96765 -69.55155)
		(width 0.254)
		(layer "F.Cu")
		(net "BMC_HEARTBEAT_N")
	)
	(via
		(at 41.783 -67.564)
		(size 0.508)
		(drill 0.254)
		(layers "F.Cu" "B.Cu")
		(net "BMC_HEARTBEAT_N")
	)
	(via
		(at 47.699676 -55.766462)
		(size 0.4572)
		(drill 0.254)
		(layers "F.Cu" "B.Cu")
		(net "BMC_HEARTBEAT_N")
	)
	(segment
		(start 47.1043 -59.4233)
		(end 46.9138 -59.6138)
		(width 0.254)
		(layer "In9.Cu")
		(net "BMC_HEARTBEAT_N")
	)
	(segment
		(start 41.7576 -67.5386)
		(end 41.783 -67.564)
		(width 0.254)
		(layer "In9.Cu")
		(net "BMC_HEARTBEAT_N")
	)
	(segment
		(start 46.1264 -59.9694)
		(end 46.1264 -60.6298)
		(width 0.254)
		(layer "In9.Cu")
		(net "BMC_HEARTBEAT_N")
	)
	(segment
		(start 42.545 -64.2874)
		(end 42.545 -65.2272)
		(width 0.254)
		(layer "In9.Cu")
		(net "BMC_HEARTBEAT_N")
	)
	(segment
		(start 48.1076 -58.42)
		(end 47.1043 -59.4233)
		(width 0.08382)
		(layer "In9.Cu")
		(net "BMC_HEARTBEAT_N")
	)
	(segment
		(start 42.0878 -63.119)
		(end 42.0878 -63.8302)
		(width 0.254)
		(layer "In9.Cu")
		(net "BMC_HEARTBEAT_N")
	)
	(segment
		(start 41.5798 -67.5386)
		(end 41.7576 -67.5386)
		(width 0.254)
		(layer "In9.Cu")
		(net "BMC_HEARTBEAT_N")
	)
	(segment
		(start 47.740062 -55.766462)
		(end 48.1076 -56.134)
		(width 0.08382)
		(layer "In9.Cu")
		(net "BMC_HEARTBEAT_N")
	)
	(segment
		(start 45.212 -61.5442)
		(end 43.6626 -61.5442)
		(width 0.254)
		(layer "In9.Cu")
		(net "BMC_HEARTBEAT_N")
	)
	(segment
		(start 46.9138 -59.6138)
		(end 46.482 -59.6138)
		(width 0.254)
		(layer "In9.Cu")
		(net "BMC_HEARTBEAT_N")
	)
	(segment
		(start 42.0878 -63.8302)
		(end 42.545 -64.2874)
		(width 0.254)
		(layer "In9.Cu")
		(net "BMC_HEARTBEAT_N")
	)
	(segment
		(start 46.482 -59.6138)
		(end 46.1264 -59.9694)
		(width 0.254)
		(layer "In9.Cu")
		(net "BMC_HEARTBEAT_N")
	)
	(segment
		(start 43.6626 -61.5442)
		(end 42.0878 -63.119)
		(width 0.254)
		(layer "In9.Cu")
		(net "BMC_HEARTBEAT_N")
	)
	(segment
		(start 41.3258 -67.2846)
		(end 41.5798 -67.5386)
		(width 0.254)
		(layer "In9.Cu")
		(net "BMC_HEARTBEAT_N")
	)
	(segment
		(start 42.545 -65.2272)
		(end 41.3258 -66.4464)
		(width 0.254)
		(layer "In9.Cu")
		(net "BMC_HEARTBEAT_N")
	)
	(segment
		(start 46.1264 -60.6298)
		(end 45.212 -61.5442)
		(width 0.254)
		(layer "In9.Cu")
		(net "BMC_HEARTBEAT_N")
	)
	(segment
		(start 41.3258 -66.4464)
		(end 41.3258 -67.2846)
		(width 0.254)
		(layer "In9.Cu")
		(net "BMC_HEARTBEAT_N")
	)
	(segment
		(start 48.1076 -56.134)
		(end 48.1076 -58.42)
		(width 0.08382)
		(layer "In9.Cu")
		(net "BMC_HEARTBEAT_N")
	)
	(segment
		(start 47.699676 -55.766462)
		(end 47.740062 -55.766462)
		(width 0.08382)
		(layer "In9.Cu")
		(net "BMC_HEARTBEAT_N")
	)
	(via
		(at 40.373808 -5.131562)
		(size 0.6604)
		(drill 0.3302)
		(layers "F.Cu" "B.Cu")
		(net "BMC_DDC_BUF_PWR")
	)
	(segment
		(start 40.256968 -5.014722)
		(end 40.373808 -5.131562)
		(width 0.11684)
		(layer "B.Cu")
		(net "BMC_DDC_BUF_PWR")
	)
	(segment
		(start 43.749722 -5.014722)
		(end 44.285662 -5.014722)
		(width 0.11684)
		(layer "B.Cu")
		(net "BMC_DDC_BUF_PWR")
	)
	(segment
		(start 42.370248 -4.365498)
		(end 43.100498 -4.365498)
		(width 0.11684)
		(layer "B.Cu")
		(net "BMC_DDC_BUF_PWR")
	)
	(segment
		(start 40.373808 -5.131562)
		(end 41.604184 -5.131562)
		(width 0.11684)
		(layer "B.Cu")
		(net "BMC_DDC_BUF_PWR")
	)
	(segment
		(start 41.604184 -5.131562)
		(end 42.370248 -4.365498)
		(width 0.11684)
		(layer "B.Cu")
		(net "BMC_DDC_BUF_PWR")
	)
	(segment
		(start 39.078662 -5.014722)
		(end 40.256968 -5.014722)
		(width 0.11684)
		(layer "B.Cu")
		(net "BMC_DDC_BUF_PWR")
	)
	(segment
		(start 43.100498 -4.365498)
		(end 43.749722 -5.014722)
		(width 0.11684)
		(layer "B.Cu")
		(net "BMC_DDC_BUF_PWR")
	)
	(segment
		(start 45.067728 -5.014722)
		(end 45.5676 -4.51485)
		(width 0.11684)
		(layer "B.Cu")
		(net "BMC_DDC_BUF_PWR")
	)
	(segment
		(start 44.285662 -5.014722)
		(end 45.067728 -5.014722)
		(width 0.11684)
		(layer "B.Cu")
		(net "BMC_DDC_BUF_PWR")
	)
	(via
		(at 40.317928 -3.20675)
		(size 0.6604)
		(drill 0.3302)
		(layers "F.Cu" "B.Cu")
		(net "BMC_DDC_BUF_EN")
	)
	(segment
		(start 39.078662 -3.214878)
		(end 40.3098 -3.214878)
		(width 0.11684)
		(layer "B.Cu")
		(net "BMC_DDC_BUF_EN")
	)
	(segment
		(start 41.636696 -3.20675)
		(end 42.265346 -3.8354)
		(width 0.11684)
		(layer "B.Cu")
		(net "BMC_DDC_BUF_EN")
	)
	(segment
		(start 40.3098 -3.214878)
		(end 40.317928 -3.20675)
		(width 0.11684)
		(layer "B.Cu")
		(net "BMC_DDC_BUF_EN")
	)
	(segment
		(start 40.317928 -3.20675)
		(end 41.5036 -3.20675)
		(width 0.11684)
		(layer "B.Cu")
		(net "BMC_DDC_BUF_EN")
	)
	(segment
		(start 41.5036 -3.20675)
		(end 41.636696 -3.20675)
		(width 0.11684)
		(layer "B.Cu")
		(net "BMC_DDC_BUF_EN")
	)
	(segment
		(start 44.285662 -3.71856)
		(end 44.285662 -3.214878)
		(width 0.11684)
		(layer "B.Cu")
		(net "BMC_DDC_BUF_EN")
	)
	(segment
		(start 42.265346 -3.8354)
		(end 44.168822 -3.8354)
		(width 0.11684)
		(layer "B.Cu")
		(net "BMC_DDC_BUF_EN")
	)
	(segment
		(start 44.168822 -3.8354)
		(end 44.285662 -3.71856)
		(width 0.11684)
		(layer "B.Cu")
		(net "BMC_DDC_BUF_EN")
	)
	(segment
		(start 59.046618 -28.21305)
		(end 59.5884 -28.21305)
		(width 0.11684)
		(layer "F.Cu")
		(net "BMC_CLK_25M_R")
	)
	(segment
		(start 58.824368 -28.067)
		(end 58.900568 -28.067)
		(width 0.11684)
		(layer "F.Cu")
		(net "BMC_CLK_25M_R")
	)
	(segment
		(start 58.293 -28.067)
		(end 58.824368 -28.067)
		(width 0.11684)
		(layer "F.Cu")
		(net "BMC_CLK_25M_R")
	)
	(segment
		(start 58.900568 -28.067)
		(end 59.046618 -28.21305)
		(width 0.11684)
		(layer "F.Cu")
		(net "BMC_CLK_25M_R")
	)
	(segment
		(start 58.123328 -28.887928)
		(end 58.123328 -28.236672)
		(width 0.11684)
		(layer "F.Cu")
		(net "BMC_CLK_25M_R")
	)
	(segment
		(start 58.123328 -28.236672)
		(end 58.293 -28.067)
		(width 0.11684)
		(layer "F.Cu")
		(net "BMC_CLK_25M_R")
	)
	(via
		(at 58.824368 -28.067)
		(size 0.508)
		(drill 0.254)
		(layers "F.Cu" "B.Cu")
		(net "BMC_CLK_25M_R")
	)
	(segment
		(start 59.5884 -26.92908)
		(end 59.85002 -26.66746)
		(width 0.11684)
		(layer "F.Cu")
		(net "BMC_CLK_25M")
	)
	(segment
		(start 57.695084 -41.771316)
		(end 58.090308 -41.376092)
		(width 0.11684)
		(layer "F.Cu")
		(net "BMC_CLK_25M")
	)
	(segment
		(start 59.5884 -27.41295)
		(end 59.5884 -26.92908)
		(width 0.11684)
		(layer "F.Cu")
		(net "BMC_CLK_25M")
	)
	(via
		(at 58.090308 -41.376092)
		(size 0.4572)
		(drill 0.254)
		(layers "F.Cu" "B.Cu")
		(net "BMC_CLK_25M")
	)
	(via
		(at 59.85002 -26.66746)
		(size 0.508)
		(drill 0.254)
		(layers "F.Cu" "B.Cu")
		(net "BMC_CLK_25M")
	)
	(segment
		(start 60.540138 -34.47288)
		(end 58.29554 -36.717478)
		(width 0.10668)
		(layer "In4.Cu")
		(net "BMC_CLK_25M")
	)
	(segment
		(start 63.062358 -34.47288)
		(end 60.540138 -34.47288)
		(width 0.10668)
		(layer "In4.Cu")
		(net "BMC_CLK_25M")
	)
	(segment
		(start 59.85002 -26.66746)
		(end 59.6646 -26.85288)
		(width 0.10668)
		(layer "In4.Cu")
		(net "BMC_CLK_25M")
	)
	(segment
		(start 62.054994 -29.54528)
		(end 62.05728 -29.54528)
		(width 0.10668)
		(layer "In4.Cu")
		(net "BMC_CLK_25M")
	)
	(segment
		(start 57.694068 -39.374572)
		(end 57.694068 -40.979852)
		(width 0.10668)
		(layer "In4.Cu")
		(net "BMC_CLK_25M")
	)
	(segment
		(start 61.04382 -27.87142)
		(end 61.517784 -28.345384)
		(width 0.10668)
		(layer "In4.Cu")
		(net "BMC_CLK_25M")
	)
	(segment
		(start 63.222378 -31.119064)
		(end 63.222378 -34.31286)
		(width 0.10668)
		(layer "In4.Cu")
		(net "BMC_CLK_25M")
	)
	(segment
		(start 58.29554 -36.717478)
		(end 58.29554 -38.7731)
		(width 0.10668)
		(layer "In4.Cu")
		(net "BMC_CLK_25M")
	)
	(segment
		(start 61.517784 -28.345384)
		(end 61.517784 -29.005784)
		(width 0.10668)
		(layer "In4.Cu")
		(net "BMC_CLK_25M")
	)
	(segment
		(start 60.21832 -27.87142)
		(end 61.04382 -27.87142)
		(width 0.10668)
		(layer "In4.Cu")
		(net "BMC_CLK_25M")
	)
	(segment
		(start 61.517784 -29.005784)
		(end 61.6966 -29.1846)
		(width 0.10668)
		(layer "In4.Cu")
		(net "BMC_CLK_25M")
	)
	(segment
		(start 62.17666 -29.66466)
		(end 62.17666 -30.073346)
		(width 0.10668)
		(layer "In4.Cu")
		(net "BMC_CLK_25M")
	)
	(segment
		(start 59.6646 -26.85288)
		(end 59.6646 -27.3177)
		(width 0.10668)
		(layer "In4.Cu")
		(net "BMC_CLK_25M")
	)
	(segment
		(start 57.694068 -40.979852)
		(end 58.090308 -41.376092)
		(width 0.10668)
		(layer "In4.Cu")
		(net "BMC_CLK_25M")
	)
	(segment
		(start 63.222378 -34.31286)
		(end 63.062358 -34.47288)
		(width 0.10668)
		(layer "In4.Cu")
		(net "BMC_CLK_25M")
	)
	(segment
		(start 62.05728 -29.54528)
		(end 62.17666 -29.66466)
		(width 0.10668)
		(layer "In4.Cu")
		(net "BMC_CLK_25M")
	)
	(segment
		(start 61.6966 -29.1846)
		(end 61.6966 -29.186886)
		(width 0.10668)
		(layer "In4.Cu")
		(net "BMC_CLK_25M")
	)
	(segment
		(start 59.6646 -27.3177)
		(end 60.21832 -27.87142)
		(width 0.10668)
		(layer "In4.Cu")
		(net "BMC_CLK_25M")
	)
	(segment
		(start 58.29554 -38.7731)
		(end 57.694068 -39.374572)
		(width 0.10668)
		(layer "In4.Cu")
		(net "BMC_CLK_25M")
	)
	(segment
		(start 61.6966 -29.186886)
		(end 62.054994 -29.54528)
		(width 0.10668)
		(layer "In4.Cu")
		(net "BMC_CLK_25M")
	)
	(segment
		(start 62.17666 -30.073346)
		(end 63.222378 -31.119064)
		(width 0.10668)
		(layer "In4.Cu")
		(net "BMC_CLK_25M")
	)
	(segment
		(start 48.499776 -57.366408)
		(end 48.895 -56.971184)
		(width 0.11684)
		(layer "F.Cu")
		(net "A_BMC_DACREST")
	)
	(segment
		(start 47.699676 -57.366408)
		(end 48.499776 -57.366408)
		(width 0.11684)
		(layer "F.Cu")
		(net "A_BMC_DACREST")
	)
	(via
		(at 47.699676 -57.366408)
		(size 0.4572)
		(drill 0.254)
		(layers "F.Cu" "B.Cu")
		(net "A_BMC_DACREST")
	)
	(segment
		(start 46.727618 -58.555128)
		(end 45.620178 -59.662568)
		(width 0.11684)
		(layer "B.Cu")
		(net "A_BMC_DACREST")
	)
	(segment
		(start 44.49953 -60.41136)
		(end 44.24045 -60.58408)
		(width 0.11684)
		(layer "B.Cu")
		(net "A_BMC_DACREST")
	)
	(segment
		(start 43.1038 -61.5442)
		(end 43.1038 -61.77915)
		(width 0.11684)
		(layer "B.Cu")
		(net "A_BMC_DACREST")
	)
	(segment
		(start 47.28845 -57.994296)
		(end 47.28845 -58.327544)
		(width 0.11684)
		(layer "B.Cu")
		(net "A_BMC_DACREST")
	)
	(segment
		(start 44.499784 -60.410852)
		(end 44.49953 -60.41136)
		(width 0.11684)
		(layer "B.Cu")
		(net "A_BMC_DACREST")
	)
	(segment
		(start 47.699676 -57.366408)
		(end 47.699676 -57.58307)
		(width 0.11684)
		(layer "B.Cu")
		(net "A_BMC_DACREST")
	)
	(segment
		(start 45.620178 -59.662568)
		(end 44.499784 -60.410852)
		(width 0.11684)
		(layer "B.Cu")
		(net "A_BMC_DACREST")
	)
	(segment
		(start 43.70959 -60.93841)
		(end 43.1038 -61.5442)
		(width 0.11684)
		(layer "B.Cu")
		(net "A_BMC_DACREST")
	)
	(segment
		(start 44.24045 -60.58408)
		(end 43.70959 -60.93841)
		(width 0.11684)
		(layer "B.Cu")
		(net "A_BMC_DACREST")
	)
	(segment
		(start 47.060866 -58.555128)
		(end 46.727618 -58.555128)
		(width 0.11684)
		(layer "B.Cu")
		(net "A_BMC_DACREST")
	)
	(segment
		(start 47.28845 -58.327544)
		(end 47.060866 -58.555128)
		(width 0.11684)
		(layer "B.Cu")
		(net "A_BMC_DACREST")
	)
	(segment
		(start 47.699676 -57.58307)
		(end 47.28845 -57.994296)
		(width 0.11684)
		(layer "B.Cu")
		(net "A_BMC_DACREST")
	)
	(segment
		(start 52.094892 -57.771284)
		(end 51.699668 -58.166508)
		(width 0.11684)
		(layer "F.Cu")
		(net "A_BMC_ADCVREFP1")
	)
	(via
		(at 51.699668 -58.166508)
		(size 0.4572)
		(drill 0.254)
		(layers "F.Cu" "B.Cu")
		(net "A_BMC_ADCVREFP1")
	)
	(segment
		(start 51.55946 -61.451998)
		(end 51.55946 -61.165486)
		(width 0.11684)
		(layer "B.Cu")
		(net "A_BMC_ADCVREFP1")
	)
	(segment
		(start 51.305206 -60.911232)
		(end 51.305206 -60.26277)
		(width 0.11684)
		(layer "B.Cu")
		(net "A_BMC_ADCVREFP1")
	)
	(segment
		(start 51.29784 -58.568336)
		(end 51.699668 -58.166508)
		(width 0.11684)
		(layer "B.Cu")
		(net "A_BMC_ADCVREFP1")
	)
	(segment
		(start 51.29784 -60.255404)
		(end 51.29784 -58.568336)
		(width 0.11684)
		(layer "B.Cu")
		(net "A_BMC_ADCVREFP1")
	)
	(segment
		(start 51.305206 -60.26277)
		(end 51.29784 -60.255404)
		(width 0.11684)
		(layer "B.Cu")
		(net "A_BMC_ADCVREFP1")
	)
	(segment
		(start 51.55946 -61.165486)
		(end 51.305206 -60.911232)
		(width 0.11684)
		(layer "B.Cu")
		(net "A_BMC_ADCVREFP1")
	)
	(segment
		(start 49.6951 -56.971184)
		(end 49.299876 -57.366408)
		(width 0.11684)
		(layer "F.Cu")
		(net "A_BMC_ADCVREFP0")
	)
	(via
		(at 49.299876 -57.366408)
		(size 0.4572)
		(drill 0.254)
		(layers "F.Cu" "B.Cu")
		(net "A_BMC_ADCVREFP0")
	)
	(segment
		(start 46.954694 -60.120276)
		(end 48.4378 -58.63717)
		(width 0.11684)
		(layer "B.Cu")
		(net "A_BMC_ADCVREFP0")
	)
	(segment
		(start 46.954694 -60.541662)
		(end 46.954694 -60.120276)
		(width 0.11684)
		(layer "B.Cu")
		(net "A_BMC_ADCVREFP0")
	)
	(segment
		(start 46.96206 -60.580524)
		(end 46.977808 -60.564776)
		(width 0.1143)
		(layer "B.Cu")
		(net "A_BMC_ADCVREFP0")
	)
	(segment
		(start 48.881792 -57.366408)
		(end 49.299876 -57.366408)
		(width 0.11684)
		(layer "B.Cu")
		(net "A_BMC_ADCVREFP0")
	)
	(segment
		(start 46.96206 -61.57976)
		(end 46.96206 -60.580524)
		(width 0.1143)
		(layer "B.Cu")
		(net "A_BMC_ADCVREFP0")
	)
	(segment
		(start 48.4378 -57.8104)
		(end 48.881792 -57.366408)
		(width 0.11684)
		(layer "B.Cu")
		(net "A_BMC_ADCVREFP0")
	)
	(segment
		(start 48.4378 -58.63717)
		(end 48.4378 -57.8104)
		(width 0.11684)
		(layer "B.Cu")
		(net "A_BMC_ADCVREFP0")
	)
	(segment
		(start 46.977808 -60.564776)
		(end 46.954694 -60.541662)
		(width 0.11684)
		(layer "B.Cu")
		(net "A_BMC_ADCVREFP0")
	)
	(segment
		(start 51.295046 -57.771284)
		(end 50.899822 -58.166508)
		(width 0.11684)
		(layer "F.Cu")
		(net "A_BMC_ADCVREFN1")
	)
	(via
		(at 50.899822 -58.166508)
		(size 0.4572)
		(drill 0.254)
		(layers "F.Cu" "B.Cu")
		(net "A_BMC_ADCVREFN1")
	)
	(segment
		(start 50.899822 -58.416444)
		(end 50.497994 -58.818272)
		(width 0.11684)
		(layer "B.Cu")
		(net "A_BMC_ADCVREFN1")
	)
	(segment
		(start 50.54346 -61.451998)
		(end 50.54346 -61.048646)
		(width 0.11684)
		(layer "B.Cu")
		(net "A_BMC_ADCVREFN1")
	)
	(segment
		(start 50.899822 -58.166508)
		(end 50.899822 -58.416444)
		(width 0.11684)
		(layer "B.Cu")
		(net "A_BMC_ADCVREFN1")
	)
	(segment
		(start 50.497994 -60.255658)
		(end 50.505106 -60.26277)
		(width 0.11684)
		(layer "B.Cu")
		(net "A_BMC_ADCVREFN1")
	)
	(segment
		(start 50.497994 -58.818272)
		(end 50.497994 -60.255658)
		(width 0.11684)
		(layer "B.Cu")
		(net "A_BMC_ADCVREFN1")
	)
	(segment
		(start 50.505106 -61.010292)
		(end 50.505106 -60.26277)
		(width 0.11684)
		(layer "B.Cu")
		(net "A_BMC_ADCVREFN1")
	)
	(segment
		(start 50.54346 -61.048646)
		(end 50.505106 -61.010292)
		(width 0.11684)
		(layer "B.Cu")
		(net "A_BMC_ADCVREFN1")
	)
	(segment
		(start 49.6951 -56.171338)
		(end 49.299876 -56.566562)
		(width 0.11684)
		(layer "F.Cu")
		(net "A_BMC_ADCVREFN0")
	)
	(via
		(at 49.299876 -56.566562)
		(size 0.4572)
		(drill 0.254)
		(layers "F.Cu" "B.Cu")
		(net "A_BMC_ADCVREFN0")
	)
	(segment
		(start 49.299876 -56.566562)
		(end 48.133254 -57.733184)
		(width 0.11684)
		(layer "B.Cu")
		(net "A_BMC_ADCVREFN0")
	)
	(segment
		(start 46.177708 -60.558934)
		(end 46.177708 -60.564776)
		(width 0.11684)
		(layer "B.Cu")
		(net "A_BMC_ADCVREFN0")
	)
	(segment
		(start 46.177708 -60.564776)
		(end 46.201076 -60.588144)
		(width 0.1143)
		(layer "B.Cu")
		(net "A_BMC_ADCVREFN0")
	)
	(segment
		(start 46.201076 -60.999116)
		(end 46.0502 -61.149992)
		(width 0.1143)
		(layer "B.Cu")
		(net "A_BMC_ADCVREFN0")
	)
	(segment
		(start 48.133254 -58.603388)
		(end 46.177708 -60.558934)
		(width 0.11684)
		(layer "B.Cu")
		(net "A_BMC_ADCVREFN0")
	)
	(segment
		(start 46.201076 -60.588144)
		(end 46.201076 -60.999116)
		(width 0.1143)
		(layer "B.Cu")
		(net "A_BMC_ADCVREFN0")
	)
	(segment
		(start 48.133254 -57.733184)
		(end 48.133254 -58.603388)
		(width 0.11684)
		(layer "B.Cu")
		(net "A_BMC_ADCVREFN0")
	)
	(segment
		(start 46.0502 -61.149992)
		(end 46.0502 -61.57595)
		(width 0.1143)
		(layer "B.Cu")
		(net "A_BMC_ADCVREFN0")
	)
	(segment
		(start 49.82718 -63.695834)
		(end 50.30978 -64.178434)
		(width 0.11684)
		(layer "F.Cu")
		(net "A_BMC_ADCREXT1")
	)
	(segment
		(start 50.07483 -64.798956)
		(end 50.07483 -66.25082)
		(width 0.11684)
		(layer "F.Cu")
		(net "A_BMC_ADCREXT1")
	)
	(segment
		(start 50.30978 -64.178434)
		(end 50.30978 -64.564006)
		(width 0.11684)
		(layer "F.Cu")
		(net "A_BMC_ADCREXT1")
	)
	(segment
		(start 50.30978 -64.564006)
		(end 50.07483 -64.798956)
		(width 0.11684)
		(layer "F.Cu")
		(net "A_BMC_ADCREXT1")
	)
	(segment
		(start 49.82718 -62.370208)
		(end 49.82718 -63.695834)
		(width 0.11684)
		(layer "F.Cu")
		(net "A_BMC_ADCREXT1")
	)
	(segment
		(start 51.295046 -60.902342)
		(end 49.82718 -62.370208)
		(width 0.11684)
		(layer "F.Cu")
		(net "A_BMC_ADCREXT1")
	)
	(segment
		(start 51.295046 -59.37123)
		(end 51.295046 -60.902342)
		(width 0.11684)
		(layer "F.Cu")
		(net "A_BMC_ADCREXT1")
	)
	(via
		(at 49.82718 -62.370208)
		(size 0.762)
		(drill 0.381)
		(layers "F.Cu" "B.Cu")
		(net "A_BMC_ADCREXT1")
	)
	(segment
		(start 49.6951 -60.0583)
		(end 49.6951 -59.37123)
		(width 0.11684)
		(layer "F.Cu")
		(net "A_BMC_ADCREXT0")
	)
	(segment
		(start 48.439832 -62.367414)
		(end 48.439832 -62.816232)
		(width 0.11684)
		(layer "F.Cu")
		(net "A_BMC_ADCREXT0")
	)
	(segment
		(start 49.053496 -61.75375)
		(end 49.955704 -61.75375)
		(width 0.11684)
		(layer "F.Cu")
		(net "A_BMC_ADCREXT0")
	)
	(segment
		(start 48.650652 -63.027052)
		(end 48.650652 -63.566294)
		(width 0.11684)
		(layer "F.Cu")
		(net "A_BMC_ADCREXT0")
	)
	(segment
		(start 48.439832 -62.367414)
		(end 49.053496 -61.75375)
		(width 0.11684)
		(layer "F.Cu")
		(net "A_BMC_ADCREXT0")
	)
	(segment
		(start 49.955704 -61.75375)
		(end 50.4698 -61.239654)
		(width 0.11684)
		(layer "F.Cu")
		(net "A_BMC_ADCREXT0")
	)
	(segment
		(start 50.4698 -60.833)
		(end 49.6951 -60.0583)
		(width 0.11684)
		(layer "F.Cu")
		(net "A_BMC_ADCREXT0")
	)
	(segment
		(start 48.439832 -62.816232)
		(end 48.650652 -63.027052)
		(width 0.11684)
		(layer "F.Cu")
		(net "A_BMC_ADCREXT0")
	)
	(segment
		(start 50.4698 -61.239654)
		(end 50.4698 -60.833)
		(width 0.11684)
		(layer "F.Cu")
		(net "A_BMC_ADCREXT0")
	)
	(via
		(at 48.439832 -62.367414)
		(size 0.762)
		(drill 0.381)
		(layers "F.Cu" "B.Cu")
		(net "A_BMC_ADCREXT0")
	)
	(segment
		(start 48.895 -55.371238)
		(end 48.499776 -55.766462)
		(width 0.3556)
		(layer "F.Cu")
		(net "A_BMC_ADCAV33")
	)
	(segment
		(start 48.895 -54.571138)
		(end 48.895 -55.371238)
		(width 0.3556)
		(layer "F.Cu")
		(net "A_BMC_ADCAV33")
	)
	(via
		(at 48.499776 -55.766462)
		(size 0.4572)
		(drill 0.254)
		(layers "F.Cu" "B.Cu")
		(net "A_BMC_ADCAV33")
	)
	(via
		(at 43.18 -56.769)
		(size 0.6604)
		(drill 0.3302)
		(layers "F.Cu" "B.Cu")
		(net "A_BMC_ADCAV33")
	)
	(zone
		(layer "F.Cu")
		(hatch none 0.5)
		(connect_pads
			(clearance 0)
		)
		(min_thickness 0.25)
		(keepout
			(tracks allowed)
			(vias allowed)
			(pads allowed)
			(copperpour allowed)
			(footprints not_allowed)
		)
		(placement
			(enabled no)
			(sheetname "")
		)
		(fill
			(thermal_gap 0.5)
			(thermal_bridge_width 0.5)
			(island_removal_mode 0)
		)
		(polygon
			(pts
				(xy 2.29997 -8.389874) (xy 13.699998 -8.389874) (xy 13.699998 -0.999998) (xy 12.7 -0.999998) (xy 12.7 -7.590028)
				(xy 3.299968 -7.590028) (xy 3.299968 -0.999998) (xy 2.29997 -0.999998)
			)
		)
	)
	(zone
		(layer "F.Cu")
		(hatch none 0.5)
		(connect_pads
			(clearance 0)
		)
		(min_thickness 0.25)
		(keepout
			(tracks allowed)
			(vias allowed)
			(pads allowed)
			(copperpour allowed)
			(footprints not_allowed)
		)
		(placement
			(enabled no)
			(sheetname "")
		)
		(fill
			(thermal_gap 0.5)
			(thermal_bridge_width 0.5)
			(island_removal_mode 0)
		)
		(polygon
			(pts
				(xy 34.414206 -0.999998) (xy 34.414206 -17.100042) (xy 51.429666 -17.100042) (xy 51.429666 -0.999998)
				(xy 50.429668 -0.999998) (xy 50.429668 -16.20012) (xy 35.414204 -16.20012) (xy 35.414204 -0.999998)
			)
		)
	)
	(zone
		(layer "F.Cu")
		(hatch none 0.5)
		(connect_pads
			(clearance 0)
		)
		(min_thickness 0.25)
		(keepout
			(tracks not_allowed)
			(vias allowed)
			(pads allowed)
			(copperpour not_allowed)
			(footprints allowed)
		)
		(placement
			(enabled no)
			(sheetname "")
		)
		(fill
			(thermal_gap 0.5)
			(thermal_bridge_width 0.5)
			(island_removal_mode 0)
		)
		(polygon
			(pts
				(arc
					(start 80.88503 -22.690074)
					(mid 83.90001 -19.675094)
					(end 86.91499 -22.690074)
				)
				(arc
					(start 86.91499 -22.690074)
					(mid 83.90001 -25.705054)
					(end 80.88503 -22.690074)
				)
			)
		)
	)
	(zone
		(layer "F.Cu")
		(hatch none 0.5)
		(connect_pads
			(clearance 0)
		)
		(min_thickness 0.25)
		(keepout
			(tracks allowed)
			(vias allowed)
			(pads allowed)
			(copperpour allowed)
			(footprints not_allowed)
		)
		(placement
			(enabled no)
			(sheetname "")
		)
		(fill
			(thermal_gap 0.5)
			(thermal_bridge_width 0.5)
			(island_removal_mode 0)
		)
		(polygon
			(pts
				(arc
					(start 68.969382 -110.400084)
					(mid 68.525918 -107.056362)
					(end 69.499988 -103.827072)
				)
				(xy 69.499988 -78.000098) (xy 56.500014 -78.000098)
				(arc
					(start 56.500014 -100.506276)
					(mid 57.651485 -100.052544)
					(end 58.859166 -99.781868)
				)
				(xy 58.859166 -88.720168) (xy 66.544698 -88.720168) (xy 66.544698 -100.991924)
				(arc
					(start 64.359028 -100.991924)
					(mid 67.580897 -105.144456)
					(end 67.530726 -110.400084)
				)
			)
		)
	)
	(zone
		(layer "F.Cu")
		(hatch none 0.5)
		(connect_pads
			(clearance 0)
		)
		(min_thickness 0.25)
		(keepout
			(tracks allowed)
			(vias allowed)
			(pads allowed)
			(copperpour allowed)
			(footprints not_allowed)
		)
		(placement
			(enabled no)
			(sheetname "")
		)
		(fill
			(thermal_gap 0.5)
			(thermal_bridge_width 0.5)
			(island_removal_mode 0)
		)
		(polygon
			(pts
				(arc
					(start 23.550118 -46.589188)
					(mid 26.75001 -43.389296)
					(end 29.949902 -46.589188)
				)
				(arc
					(start 29.949902 -48.189134)
					(mid 26.75001 -51.389026)
					(end 23.550118 -48.189134)
				)
			)
		)
		(polygon
			(pts
				(arc
					(start 28.349956 -48.189134)
					(mid 26.75001 -49.78908)
					(end 25.150064 -48.189134)
				)
				(arc
					(start 25.150064 -46.589188)
					(mid 26.75001 -44.989242)
					(end 28.349956 -46.589188)
				)
			)
		)
	)
	(zone
		(layer "F.Cu")
		(hatch none 0.5)
		(connect_pads
			(clearance 0)
		)
		(min_thickness 0.25)
		(keepout
			(tracks allowed)
			(vias allowed)
			(pads allowed)
			(copperpour allowed)
			(footprints not_allowed)
		)
		(placement
			(enabled no)
			(sheetname "")
		)
		(fill
			(thermal_gap 0.5)
			(thermal_bridge_width 0.5)
			(island_removal_mode 0)
		)
		(polygon
			(pts
				(arc
					(start 8.850122 -11.789918)
					(mid 5.600192 -15.039848)
					(end 2.350008 -11.789918)
				)
				(arc
					(start 2.350008 -11.789918)
					(mid 5.600192 -8.539734)
					(end 8.850122 -11.789918)
				)
			)
		)
		(polygon
			(pts
				(arc
					(start 3.999992 -11.789918)
					(mid 5.599938 -10.189972)
					(end 7.199884 -11.789918)
				)
				(arc
					(start 7.199884 -11.789918)
					(mid 5.599938 -13.389864)
					(end 3.999992 -11.789918)
				)
			)
		)
	)
	(zone
		(layer "F.Cu")
		(hatch none 0.5)
		(connect_pads
			(clearance 0)
		)
		(min_thickness 0.25)
		(keepout
			(tracks allowed)
			(vias allowed)
			(pads allowed)
			(copperpour allowed)
			(footprints allowed)
		)
		(placement
			(enabled no)
			(sheetname "")
		)
		(fill
			(thermal_gap 0.5)
			(thermal_bridge_width 0.5)
			(island_removal_mode 0)
		)
		(polygon
			(pts
				(xy 30.349952 -101.907594) (xy 13.252196 -101.907594) (xy 13.252196 -84.86394) (xy 30.349952 -84.86394)
			)
		)
	)
	(zone
		(layer "F.Cu")
		(hatch none 0.5)
		(connect_pads
			(clearance 0)
		)
		(min_thickness 0.25)
		(keepout
			(tracks allowed)
			(vias allowed)
			(pads allowed)
			(copperpour allowed)
			(footprints not_allowed)
		)
		(placement
			(enabled no)
			(sheetname "")
		)
		(fill
			(thermal_gap 0.5)
			(thermal_bridge_width 0.5)
			(island_removal_mode 0)
		)
		(polygon
			(pts
				(arc
					(start 80.859122 -100.991924)
					(mid 84.080902 -105.144513)
					(end 84.030566 -110.400084)
				)
				(xy 86.000082 -110.400084) (xy 86.000082 -78.000098) (xy 73.000108 -78.000098)
				(arc
					(start 73.000108 -100.506276)
					(mid 74.151579 -100.052544)
					(end 75.35926 -99.781868)
				)
				(xy 75.35926 -88.720168) (xy 83.044792 -88.720168) (xy 83.044792 -100.991924)
			)
		)
	)
	(zone
		(layer "F.Cu")
		(hatch none 0.5)
		(connect_pads
			(clearance 0)
		)
		(min_thickness 0.25)
		(keepout
			(tracks allowed)
			(vias allowed)
			(pads allowed)
			(copperpour allowed)
			(footprints not_allowed)
		)
		(placement
			(enabled no)
			(sheetname "")
		)
		(fill
			(thermal_gap 0.5)
			(thermal_bridge_width 0.5)
			(island_removal_mode 0)
		)
		(polygon
			(pts
				(xy 21.249894 -60.289186) (xy 32.250126 -60.289186) (xy 32.250126 -34.78911) (xy 21.249894 -34.78911)
			)
		)
		(polygon
			(pts
				(arc
					(start 28.349956 -48.189134)
					(mid 26.75001 -49.78908)
					(end 25.150064 -48.189134)
				)
				(arc
					(start 25.150064 -46.589188)
					(mid 26.75001 -44.989242)
					(end 28.349956 -46.589188)
				)
			)
		)
		(polygon
			(pts
				(arc
					(start 28.64993 -54.189122)
					(mid 26.75001 -56.089042)
					(end 24.85009 -54.189122)
				)
				(arc
					(start 24.85009 -54.189122)
					(mid 26.75001 -52.289202)
					(end 28.64993 -54.189122)
				)
			)
		)
	)
	(zone
		(layer "F.Cu")
		(hatch none 0.5)
		(connect_pads
			(clearance 0)
		)
		(min_thickness 0.25)
		(keepout
			(tracks allowed)
			(vias allowed)
			(pads allowed)
			(copperpour allowed)
			(footprints allowed)
		)
		(placement
			(enabled no)
			(sheetname "")
		)
		(fill
			(thermal_gap 0.5)
			(thermal_bridge_width 0.5)
			(island_removal_mode 0)
		)
		(polygon
			(pts
				(xy 19.1516 -118.745) (xy 19.1516 -116.078) (xy 27.3304 -116.078) (xy 27.3304 -118.745)
			)
		)
	)
	(zone
		(layer "F.Cu")
		(hatch none 0.5)
		(connect_pads
			(clearance 0)
		)
		(min_thickness 0.25)
		(keepout
			(tracks not_allowed)
			(vias allowed)
			(pads allowed)
			(copperpour not_allowed)
			(footprints allowed)
		)
		(placement
			(enabled no)
			(sheetname "")
		)
		(fill
			(thermal_gap 0.5)
			(thermal_bridge_width 0.5)
			(island_removal_mode 0)
		)
		(polygon
			(pts
				(arc
					(start 2.350008 -11.789918)
					(mid 5.600192 -8.539734)
					(end 8.850122 -11.789918)
				)
				(arc
					(start 8.850122 -11.789918)
					(mid 5.600192 -15.039848)
					(end 2.350008 -11.789918)
				)
			)
		)
	)
	(zone
		(layer "F.Cu")
		(hatch none 0.5)
		(connect_pads
			(clearance 0)
		)
		(min_thickness 0.25)
		(keepout
			(tracks not_allowed)
			(vias allowed)
			(pads allowed)
			(copperpour not_allowed)
			(footprints allowed)
		)
		(placement
			(enabled no)
			(sheetname "")
		)
		(fill
			(thermal_gap 0.5)
			(thermal_bridge_width 0.5)
			(island_removal_mode 0)
		)
		(polygon
			(pts
				(arc
					(start 24.85009 -54.189122)
					(mid 26.75001 -52.289202)
					(end 28.64993 -54.189122)
				)
				(arc
					(start 28.64993 -54.189122)
					(mid 26.75001 -56.089042)
					(end 24.85009 -54.189122)
				)
			)
		)
	)
	(zone
		(layer "F.Cu")
		(hatch none 0.5)
		(connect_pads
			(clearance 0)
		)
		(min_thickness 0.25)
		(keepout
			(tracks allowed)
			(vias allowed)
			(pads allowed)
			(copperpour allowed)
			(footprints allowed)
		)
		(placement
			(enabled no)
			(sheetname "")
		)
		(fill
			(thermal_gap 0.5)
			(thermal_bridge_width 0.5)
			(island_removal_mode 0)
		)
		(polygon
			(pts
				(xy 7.6708 -64.8208) (xy 7.6708 -63.119) (xy 8.4836 -63.119) (xy 8.4836 -64.8208)
			)
		)
	)
	(zone
		(layer "F.Cu")
		(hatch none 0.5)
		(connect_pads
			(clearance 0)
		)
		(min_thickness 0.25)
		(keepout
			(tracks allowed)
			(vias allowed)
			(pads allowed)
			(copperpour allowed)
			(footprints allowed)
		)
		(placement
			(enabled no)
			(sheetname "")
		)
		(fill
			(thermal_gap 0.5)
			(thermal_bridge_width 0.5)
			(island_removal_mode 0)
		)
		(polygon
			(pts
				(xy 67.854576 -118.471696) (xy 67.854576 -116.064284) (xy 67.854576 -115.640104) (xy 68.100194 -115.394486)
				(xy 70.202298 -115.394486) (xy 70.408038 -115.600226) (xy 70.408038 -116.064284) (xy 70.408038 -118.471696)
			)
		)
	)
	(zone
		(layer "F.Cu")
		(hatch none 0.5)
		(connect_pads
			(clearance 0)
		)
		(min_thickness 0.25)
		(keepout
			(tracks allowed)
			(vias allowed)
			(pads allowed)
			(copperpour allowed)
			(footprints not_allowed)
		)
		(placement
			(enabled no)
			(sheetname "")
		)
		(fill
			(thermal_gap 0.5)
			(thermal_bridge_width 0.5)
			(island_removal_mode 0)
		)
		(polygon
			(pts
				(arc
					(start 32.250126 -36.71951)
					(mid 33.122319 -37.216688)
					(end 33.949894 -37.78504)
				)
				(xy 33.949894 -34.120074) (xy 33.250124 -34.120074) (xy 33.250124 -17.120108) (xy 33.949894 -17.120108)
				(arc
					(start 33.949894 -15.619984)
					(mid 24.159808 -23.581873)
					(end 29.9593 -34.78911)
				)
				(xy 32.250126 -34.78911)
			)
		)
	)
	(zone
		(layer "F.Cu")
		(hatch none 0.5)
		(connect_pads
			(clearance 0)
		)
		(min_thickness 0.25)
		(keepout
			(tracks not_allowed)
			(vias allowed)
			(pads allowed)
			(copperpour not_allowed)
			(footprints allowed)
		)
		(placement
			(enabled no)
			(sheetname "")
		)
		(fill
			(thermal_gap 0.5)
			(thermal_bridge_width 0.5)
			(island_removal_mode 0)
		)
		(polygon
			(pts
				(arc
					(start 81.449926 -11.789918)
					(mid 84.70011 -8.539734)
					(end 87.95004 -11.789918)
				)
				(arc
					(start 87.95004 -11.789918)
					(mid 84.70011 -15.039848)
					(end 81.449926 -11.789918)
				)
			)
		)
	)
	(zone
		(layer "F.Cu")
		(hatch none 0.5)
		(connect_pads
			(clearance 0)
		)
		(min_thickness 0.25)
		(keepout
			(tracks allowed)
			(vias allowed)
			(pads allowed)
			(copperpour allowed)
			(footprints allowed)
		)
		(placement
			(enabled no)
			(sheetname "")
		)
		(fill
			(thermal_gap 0.5)
			(thermal_bridge_width 0.5)
			(island_removal_mode 0)
		)
		(polygon
			(pts
				(xy 34.7218 -93.9038) (xy 34.7218 -91.821) (xy 44.3738 -91.821) (xy 44.3738 -93.9038)
			)
		)
	)
	(zone
		(layer "F.Cu")
		(hatch none 0.5)
		(connect_pads
			(clearance 0)
		)
		(min_thickness 0.25)
		(keepout
			(tracks allowed)
			(vias allowed)
			(pads allowed)
			(copperpour allowed)
			(footprints not_allowed)
		)
		(placement
			(enabled no)
			(sheetname "")
		)
		(fill
			(thermal_gap 0.5)
			(thermal_bridge_width 0.5)
			(island_removal_mode 0)
		)
		(polygon
			(pts
				(arc
					(start 62.999874 -107.700064)
					(mid 59.99988 -110.700058)
					(end 56.999886 -107.700064)
				)
				(arc
					(start 56.999886 -107.700064)
					(mid 59.99988 -104.70007)
					(end 62.999874 -107.700064)
				)
			)
		)
		(polygon
			(pts
				(arc
					(start 61.699902 -107.700064)
					(mid 60.000134 -109.399832)
					(end 58.300112 -107.700064)
				)
				(arc
					(start 58.300112 -107.700064)
					(mid 60.000134 -106.000042)
					(end 61.699902 -107.700064)
				)
			)
		)
	)
	(zone
		(layer "F.Cu")
		(hatch none 0.5)
		(connect_pads
			(clearance 0)
		)
		(min_thickness 0.25)
		(keepout
			(tracks not_allowed)
			(vias allowed)
			(pads allowed)
			(copperpour not_allowed)
			(footprints allowed)
		)
		(placement
			(enabled no)
			(sheetname "")
		)
		(fill
			(thermal_gap 0.5)
			(thermal_bridge_width 0.5)
			(island_removal_mode 0)
		)
		(polygon
			(pts
				(arc
					(start 85.464904 -22.690074)
					(mid 83.90001 -24.254968)
					(end 82.335116 -22.690074)
				)
				(arc
					(start 82.335116 -22.690074)
					(mid 83.90001 -21.12518)
					(end 85.464904 -22.690074)
				)
			)
		)
	)
	(zone
		(layer "F.Cu")
		(hatch none 0.5)
		(connect_pads
			(clearance 0)
		)
		(min_thickness 0.25)
		(keepout
			(tracks not_allowed)
			(vias allowed)
			(pads allowed)
			(copperpour not_allowed)
			(footprints allowed)
		)
		(placement
			(enabled no)
			(sheetname "")
		)
		(fill
			(thermal_gap 0.5)
			(thermal_bridge_width 0.5)
			(island_removal_mode 0)
		)
		(polygon
			(pts
				(arc
					(start 7.664958 -22.690074)
					(mid 6.100064 -24.254968)
					(end 4.534916 -22.690074)
				)
				(arc
					(start 4.534916 -22.690074)
					(mid 6.100064 -21.124926)
					(end 7.664958 -22.690074)
				)
			)
		)
	)
	(zone
		(layer "F.Cu")
		(hatch none 0.5)
		(connect_pads
			(clearance 0)
		)
		(min_thickness 0.25)
		(keepout
			(tracks allowed)
			(vias allowed)
			(pads allowed)
			(copperpour allowed)
			(footprints allowed)
		)
		(placement
			(enabled no)
			(sheetname "")
		)
		(fill
			(thermal_gap 0.5)
			(thermal_bridge_width 0.5)
			(island_removal_mode 0)
		)
		(polygon
			(pts
				(xy 56.288178 -119.241316) (xy 56.288178 -113.511076) (xy 63.981584 -113.511076) (xy 63.981584 -119.241316)
			)
		)
	)
	(zone
		(layer "F.Cu")
		(hatch none 0.5)
		(connect_pads
			(clearance 0)
		)
		(min_thickness 0.25)
		(keepout
			(tracks allowed)
			(vias allowed)
			(pads allowed)
			(copperpour allowed)
			(footprints not_allowed)
		)
		(placement
			(enabled no)
			(sheetname "")
		)
		(fill
			(thermal_gap 0.5)
			(thermal_bridge_width 0.5)
			(island_removal_mode 0)
		)
		(polygon
			(pts
				(xy 33.250124 -34.120074) (xy 38.850062 -34.120074) (xy 38.850062 -17.120108) (xy 33.250124 -17.120108)
			)
		)
		(polygon
			(pts
				(xy 37.850064 -33.120076) (xy 37.850064 -18.120106) (xy 34.250122 -18.120106) (xy 34.250122 -33.120076)
			)
		)
	)
	(zone
		(layer "F.Cu")
		(hatch none 0.5)
		(connect_pads
			(clearance 0)
		)
		(min_thickness 0.25)
		(keepout
			(tracks allowed)
			(vias allowed)
			(pads allowed)
			(copperpour allowed)
			(footprints not_allowed)
		)
		(placement
			(enabled no)
			(sheetname "")
		)
		(fill
			(thermal_gap 0.5)
			(thermal_bridge_width 0.5)
			(island_removal_mode 0)
		)
		(polygon
			(pts
				(arc
					(start 32.250126 -36.71951)
					(mid 36.996998 -41.139947)
					(end 38.749986 -47.38497)
				)
				(xy 38.749986 -72.084946) (xy 14.750034 -72.084946)
				(arc
					(start 14.750034 -47.38497)
					(mid 16.502968 -41.139914)
					(end 21.249894 -36.71951)
				)
				(xy 21.249894 -60.289186) (xy 32.250126 -60.289186)
			)
		)
	)
	(zone
		(layer "F.Cu")
		(hatch none 0.5)
		(connect_pads
			(clearance 0)
		)
		(min_thickness 0.25)
		(keepout
			(tracks allowed)
			(vias allowed)
			(pads allowed)
			(copperpour allowed)
			(footprints not_allowed)
		)
		(placement
			(enabled no)
			(sheetname "")
		)
		(fill
			(thermal_gap 0.5)
			(thermal_bridge_width 0.5)
			(island_removal_mode 0)
		)
		(polygon
			(pts
				(xy 86.250018 -110.400084)
				(arc
					(start 86.250018 -24.578818)
					(mid 82.898824 -25.53393)
					(end 80.88503 -22.690074)
				)
				(arc
					(start 80.88503 -22.690074)
					(mid 82.898719 -19.846217)
					(end 86.250018 -20.801076)
				)
				(arc
					(start 86.250018 -14.646656)
					(mid 83.037912 -14.582813)
					(end 81.449926 -11.789918)
				)
				(arc
					(start 81.449926 -11.789918)
					(mid 83.037894 -8.997083)
					(end 86.250018 -8.933434)
				)
				(xy 86.250018 -8.48995) (xy 76.300076 -8.48995) (xy 76.300076 -8.89) (xy 64.900048 -8.89) (xy 64.900048 -9.390126)
				(xy 51.429666 -9.390126) (xy 51.429666 -17.100042)
				(arc
					(start 44.08551 -17.100042)
					(mid 48.472894 -28.340276)
					(end 38.850062 -35.619944)
				)
				(xy 38.850062 -34.120074) (xy 33.949894 -34.120074)
				(arc
					(start 33.949894 -37.78504)
					(mid 37.483103 -42.018422)
					(end 38.749986 -47.38497)
				)
				(xy 38.749986 -82.23504) (xy 14.750034 -82.23504)
				(arc
					(start 14.750034 -47.38497)
					(mid 16.502968 -41.139914)
					(end 21.249894 -36.71951)
				)
				(xy 21.249894 -34.78911)
				(arc
					(start 29.9593 -34.78911)
					(mid 24.159882 -23.581889)
					(end 33.949894 -15.619984)
				)
				(xy 33.949894 -17.120108) (xy 38.850062 -17.120108) (xy 38.850062 -17.100042) (xy 34.414206 -17.100042)
				(xy 34.414206 -0.999998) (xy 34.250122 -0.999998) (xy 34.250122 -9.390126) (xy 27.750008 -9.390126)
				(xy 27.750008 -0.999998) (xy 27.500072 -0.999998) (xy 27.500072 -9.390126) (xy 20.999958 -9.390126)
				(xy 20.999958 -0.999998) (xy 20.750022 -0.999998) (xy 20.750022 -9.390126) (xy 14.249908 -9.390126)
				(xy 14.249908 -0.999998) (xy 13.699998 -0.999998) (xy 13.699998 -8.389874) (xy 3.750056 -8.389874)
				(arc
					(start 3.750056 -9.117838)
					(mid 7.10849 -8.91102)
					(end 8.850122 -11.789918)
				)
				(arc
					(start 8.850122 -11.789918)
					(mid 7.108421 -14.668683)
					(end 3.750056 -14.461998)
				)
				(arc
					(start 3.750056 -20.801076)
					(mid 7.101396 -19.846101)
					(end 9.115044 -22.690074)
				)
				(arc
					(start 9.115044 -22.690074)
					(mid 7.101262 -25.533963)
					(end 3.750056 -24.578818)
				)
				(xy 3.750056 -110.400084)
				(arc
					(start 52.469034 -110.398814)
					(mid 52.591537 -104.681232)
					(end 56.500014 -100.506276)
				)
				(xy 56.500014 -78.000098) (xy 69.499988 -78.000098)
				(arc
					(start 69.499988 -103.827072)
					(mid 70.993769 -101.896566)
					(end 73.000108 -100.506276)
				)
				(xy 73.000108 -78.000098) (xy 86.000082 -78.000098) (xy 86.000082 -110.400084)
			)
		)
		(polygon
			(pts
				(xy 3.800094 -84.000086) (xy 3.800094 -106.069892) (xy 8.299958 -106.069892) (xy 8.299958 -84.000086)
			)
		)
		(polygon
			(pts
				(xy 31.850076 -109.46511) (xy 31.850076 -105.855008) (xy 30.850078 -105.855008) (xy 30.850078 -89.965022)
				(xy 31.850076 -89.965022) (xy 31.850076 -86.35492) (xy 47.15002 -86.35492) (xy 47.15002 -89.965022)
				(xy 48.150018 -89.965022) (xy 48.150018 -105.855008) (xy 47.15002 -105.855008) (xy 47.15002 -109.46511)
			)
		)
	)
	(zone
		(layer "F.Cu")
		(hatch none 0.5)
		(connect_pads
			(clearance 0)
		)
		(min_thickness 0.25)
		(keepout
			(tracks allowed)
			(vias allowed)
			(pads allowed)
			(copperpour allowed)
			(footprints not_allowed)
		)
		(placement
			(enabled no)
			(sheetname "")
		)
		(fill
			(thermal_gap 0.5)
			(thermal_bridge_width 0.5)
			(island_removal_mode 0)
		)
		(polygon
			(pts
				(arc
					(start 87.95004 -11.789918)
					(mid 84.70011 -15.039848)
					(end 81.449926 -11.789918)
				)
				(arc
					(start 81.449926 -11.789918)
					(mid 84.70011 -8.539734)
					(end 87.95004 -11.789918)
				)
			)
		)
		(polygon
			(pts
				(arc
					(start 83.09991 -11.789918)
					(mid 84.70011 -10.189718)
					(end 86.300056 -11.789918)
				)
				(arc
					(start 86.300056 -11.789918)
					(mid 84.70011 -13.389864)
					(end 83.09991 -11.789918)
				)
			)
		)
	)
	(zone
		(layer "F.Cu")
		(hatch none 0.5)
		(connect_pads
			(clearance 0)
		)
		(min_thickness 0.25)
		(keepout
			(tracks allowed)
			(vias allowed)
			(pads allowed)
			(copperpour allowed)
			(footprints not_allowed)
		)
		(placement
			(enabled no)
			(sheetname "")
		)
		(fill
			(thermal_gap 0.5)
			(thermal_bridge_width 0.5)
			(island_removal_mode 0)
		)
		(polygon
			(pts
				(xy 27.750008 -0.999998) (xy 27.750008 -9.390126) (xy 34.250122 -9.390126) (xy 34.250122 -0.999998)
				(xy 33.349946 -0.999998) (xy 33.349946 -8.48995) (xy 28.64993 -8.48995) (xy 28.64993 -0.999998)
			)
		)
	)
	(zone
		(layer "F.Cu")
		(hatch none 0.5)
		(connect_pads
			(clearance 0)
		)
		(min_thickness 0.25)
		(keepout
			(tracks not_allowed)
			(vias allowed)
			(pads allowed)
			(copperpour not_allowed)
			(footprints allowed)
		)
		(placement
			(enabled no)
			(sheetname "")
		)
		(fill
			(thermal_gap 0.5)
			(thermal_bridge_width 0.5)
			(island_removal_mode 0)
		)
		(polygon
			(pts
				(arc
					(start 23.550118 -46.589188)
					(mid 26.75001 -43.389296)
					(end 29.949902 -46.589188)
				)
				(arc
					(start 29.949902 -48.189134)
					(mid 26.75001 -51.389026)
					(end 23.550118 -48.189134)
				)
			)
		)
		(polygon
			(pts
				(arc
					(start 28.349956 -48.189134)
					(mid 26.75001 -49.78908)
					(end 25.150064 -48.189134)
				)
				(arc
					(start 25.150064 -46.589188)
					(mid 26.75001 -44.989242)
					(end 28.349956 -46.589188)
				)
			)
		)
	)
	(zone
		(layer "F.Cu")
		(hatch none 0.5)
		(connect_pads
			(clearance 0)
		)
		(min_thickness 0.25)
		(keepout
			(tracks allowed)
			(vias allowed)
			(pads allowed)
			(copperpour allowed)
			(footprints not_allowed)
		)
		(placement
			(enabled no)
			(sheetname "")
		)
		(fill
			(thermal_gap 0.5)
			(thermal_bridge_width 0.5)
			(island_removal_mode 0)
		)
		(polygon
			(pts
				(xy 76.300076 -8.48995) (xy 87.700104 -8.48995) (xy 87.700104 -0.999998) (xy 86.700106 -0.999998)
				(xy 86.700106 -7.590028) (xy 77.300074 -7.590028) (xy 77.300074 -0.999998) (xy 75.300078 -0.999998)
				(xy 75.300078 -7.990078) (xy 65.900046 -7.990078) (xy 65.900046 -0.999998) (xy 64.000126 -0.999998)
				(xy 64.000126 -8.48995) (xy 59.30011 -8.48995) (xy 59.30011 -0.999998) (xy 58.399934 -0.999998)
				(xy 58.399934 -9.390126) (xy 64.900048 -9.390126) (xy 64.900048 -8.89) (xy 76.300076 -8.89)
			)
		)
	)
	(zone
		(layer "F.Cu")
		(hatch none 0.5)
		(connect_pads
			(clearance 0)
		)
		(min_thickness 0.25)
		(keepout
			(tracks allowed)
			(vias allowed)
			(pads allowed)
			(copperpour allowed)
			(footprints not_allowed)
		)
		(placement
			(enabled no)
			(sheetname "")
		)
		(fill
			(thermal_gap 0.5)
			(thermal_bridge_width 0.5)
			(island_removal_mode 0)
		)
		(polygon
			(pts
				(arc
					(start 24.500078 -54.189122)
					(mid 26.75001 -51.93919)
					(end 28.999942 -54.189122)
				)
				(arc
					(start 28.999942 -54.189122)
					(mid 26.75001 -56.439054)
					(end 24.500078 -54.189122)
				)
			)
		)
		(polygon
			(pts
				(arc
					(start 28.64993 -54.189122)
					(mid 26.75001 -56.089042)
					(end 24.85009 -54.189122)
				)
				(arc
					(start 24.85009 -54.189122)
					(mid 26.75001 -52.289202)
					(end 28.64993 -54.189122)
				)
			)
		)
	)
	(zone
		(layer "F.Cu")
		(hatch none 0.5)
		(connect_pads
			(clearance 0)
		)
		(min_thickness 0.25)
		(keepout
			(tracks allowed)
			(vias allowed)
			(pads allowed)
			(copperpour allowed)
			(footprints allowed)
		)
		(placement
			(enabled no)
			(sheetname "")
		)
		(fill
			(thermal_gap 0.5)
			(thermal_bridge_width 0.5)
			(island_removal_mode 0)
		)
		(polygon
			(pts
				(xy 63.7794 -28.194) (xy 63.7794 -27.0002) (xy 64.4144 -27.0002) (xy 64.4144 -28.194)
			)
		)
	)
	(zone
		(layer "F.Cu")
		(hatch none 0.5)
		(connect_pads
			(clearance 0)
		)
		(min_thickness 0.25)
		(keepout
			(tracks allowed)
			(vias allowed)
			(pads allowed)
			(copperpour allowed)
			(footprints not_allowed)
		)
		(placement
			(enabled no)
			(sheetname "")
		)
		(fill
			(thermal_gap 0.5)
			(thermal_bridge_width 0.5)
			(island_removal_mode 0)
		)
		(polygon
			(pts
				(xy 31.850076 -86.35492) (xy 31.850076 -89.965022) (xy 47.15002 -89.965022) (xy 47.15002 -86.35492)
			)
		)
	)
	(zone
		(layer "F.Cu")
		(hatch none 0.5)
		(connect_pads
			(clearance 0)
		)
		(min_thickness 0.25)
		(keepout
			(tracks allowed)
			(vias allowed)
			(pads allowed)
			(copperpour allowed)
			(footprints not_allowed)
		)
		(placement
			(enabled no)
			(sheetname "")
		)
		(fill
			(thermal_gap 0.5)
			(thermal_bridge_width 0.5)
			(island_removal_mode 0)
		)
		(polygon
			(pts
				(xy 51.649884 -9.390126) (xy 58.149998 -9.390126) (xy 58.149998 -0.999998) (xy 57.250076 -0.999998)
				(xy 57.250076 -8.48995) (xy 52.55006 -8.48995) (xy 52.55006 -0.999998) (xy 51.649884 -0.999998)
			)
		)
	)
	(zone
		(layer "F.Cu")
		(hatch none 0.5)
		(connect_pads
			(clearance 0)
		)
		(min_thickness 0.25)
		(keepout
			(tracks not_allowed)
			(vias allowed)
			(pads allowed)
			(copperpour not_allowed)
			(footprints allowed)
		)
		(placement
			(enabled no)
			(sheetname "")
		)
		(fill
			(thermal_gap 0.5)
			(thermal_bridge_width 0.5)
			(island_removal_mode 0)
		)
		(polygon
			(pts
				(arc
					(start 3.085084 -22.690074)
					(mid 6.100064 -19.675094)
					(end 9.115044 -22.690074)
				)
				(arc
					(start 9.115044 -22.690074)
					(mid 6.100064 -25.705054)
					(end 3.085084 -22.690074)
				)
			)
		)
	)
	(zone
		(layer "F.Cu")
		(hatch none 0.5)
		(connect_pads
			(clearance 0)
		)
		(min_thickness 0.25)
		(keepout
			(tracks allowed)
			(vias allowed)
			(pads allowed)
			(copperpour allowed)
			(footprints not_allowed)
		)
		(placement
			(enabled no)
			(sheetname "")
		)
		(fill
			(thermal_gap 0.5)
			(thermal_bridge_width 0.5)
			(island_removal_mode 0)
		)
		(polygon
			(pts
				(xy 38.850062 -17.100042)
				(arc
					(start 44.08551 -17.100042)
					(mid 48.472894 -28.340276)
					(end 38.850062 -35.619944)
				)
			)
		)
	)
	(zone
		(layer "F.Cu")
		(hatch none 0.5)
		(connect_pads
			(clearance 0)
		)
		(min_thickness 0.25)
		(keepout
			(tracks not_allowed)
			(vias allowed)
			(pads allowed)
			(copperpour not_allowed)
			(footprints allowed)
		)
		(placement
			(enabled no)
			(sheetname "")
		)
		(fill
			(thermal_gap 0.5)
			(thermal_bridge_width 0.5)
			(island_removal_mode 0)
		)
		(polygon
			(pts
				(arc
					(start 29.949902 -46.589188)
					(mid 26.75001 -43.389296)
					(end 23.550118 -46.589188)
				)
				(arc
					(start 23.550118 -48.189134)
					(mid 26.75001 -51.389026)
					(end 29.949902 -48.189134)
				)
			)
		)
	)
	(zone
		(layer "F.Cu")
		(hatch none 0.5)
		(connect_pads
			(clearance 0)
		)
		(min_thickness 0.25)
		(keepout
			(tracks allowed)
			(vias allowed)
			(pads allowed)
			(copperpour allowed)
			(footprints allowed)
		)
		(placement
			(enabled no)
			(sheetname "")
		)
		(fill
			(thermal_gap 0.5)
			(thermal_bridge_width 0.5)
			(island_removal_mode 0)
		)
		(polygon
			(pts
				(xy 41.7576 -19.685) (xy 41.7576 -17.2212) (xy 42.9514 -17.2212) (xy 42.9514 -19.685)
			)
		)
	)
	(zone
		(layer "F.Cu")
		(hatch none 0.5)
		(connect_pads
			(clearance 0)
		)
		(min_thickness 0.25)
		(keepout
			(tracks allowed)
			(vias allowed)
			(pads allowed)
			(copperpour allowed)
			(footprints not_allowed)
		)
		(placement
			(enabled no)
			(sheetname "")
		)
		(fill
			(thermal_gap 0.5)
			(thermal_bridge_width 0.5)
			(island_removal_mode 0)
		)
		(polygon
			(pts
				(xy 30.850078 -89.965022) (xy 30.850078 -105.855008) (xy 48.150018 -105.855008) (xy 48.150018 -89.965022)
			)
		)
		(polygon
			(pts
				(xy 31.850076 -90.96502) (xy 31.850076 -104.85501) (xy 47.15002 -104.85501) (xy 47.15002 -90.96502)
			)
		)
	)
	(zone
		(layer "F.Cu")
		(hatch none 0.5)
		(connect_pads
			(clearance 0)
		)
		(min_thickness 0.25)
		(keepout
			(tracks allowed)
			(vias allowed)
			(pads allowed)
			(copperpour allowed)
			(footprints not_allowed)
		)
		(placement
			(enabled no)
			(sheetname "")
		)
		(fill
			(thermal_gap 0.5)
			(thermal_bridge_width 0.5)
			(island_removal_mode 0)
		)
		(polygon
			(pts
				(arc
					(start 1.999996 -113.300002)
					(mid 1.292891 -113.007109)
					(end 0.999998 -112.300004)
				)
				(xy 3.750056 -112.300004) (xy 3.750056 -110.400084) (xy 52.469034 -110.398814) (xy 67.530726 -110.400084)
				(xy 68.969382 -110.400084) (xy 84.030566 -110.400084) (xy 86.250018 -110.400084) (xy 86.250018 -112.300004)
				(arc
					(start 89.000076 -112.300004)
					(mid 88.707183 -113.007109)
					(end 88.000078 -113.300002)
				)
				(arc
					(start 85.499956 -113.300002)
					(mid 84.439372 -113.739468)
					(end 84.000086 -114.800126)
				)
				(xy 84.000086 -118.864126) (xy 83.690714 -119.400066) (xy 80.404208 -119.400066) (xy 80.240124 -119.235728)
				(xy 80.240124 -114.800126)
				(arc
					(start 80.239616 -114.772186)
					(mid 79.790735 -113.729559)
					(end 78.74 -113.300002)
				)
				(arc
					(start 77.239876 -113.300002)
					(mid 76.179292 -113.739468)
					(end 75.740006 -114.800126)
				)
				(xy 75.740006 -119.235728) (xy 75.575668 -119.400066) (xy 67.949318 -119.400066) (xy 67.78498 -119.235728)
				(arc
					(start 67.78498 -114.525044)
					(mid 65.660016 -112.40008)
					(end 63.535052 -114.525044)
				)
				(xy 63.535052 -119.235728) (xy 63.370714 -119.400066) (xy 47.349156 -119.400066) (xy 47.185072 -119.235728)
				(arc
					(start 47.185072 -114.324892)
					(mid 45.260006 -112.399826)
					(end 43.33494 -114.324892)
				)
				(xy 43.33494 -119.235728) (xy 43.170856 -119.400066) (xy 35.539172 -119.400066) (xy 35.375088 -119.235728)
				(arc
					(start 35.375088 -114.77498)
					(mid 33.000188 -112.40008)
					(end 30.625034 -114.77498)
				)
				(xy 30.625034 -119.235728) (xy 30.460696 -119.400066) (xy 14.429232 -119.400066) (xy 14.264894 -119.235728)
				(arc
					(start 14.264894 -114.800126)
					(mid 13.825592 -113.739558)
					(end 12.765024 -113.300002)
				)
				(arc
					(start 11.2649 -113.300002)
					(mid 10.204316 -113.739468)
					(end 9.76503 -114.800126)
				)
				(xy 9.76503 -119.235728) (xy 9.600692 -119.400066) (xy 6.30936 -119.400066) (xy 5.999988 -118.864126)
				(arc
					(start 5.999988 -114.800126)
					(mid 5.560686 -113.739558)
					(end 4.500118 -113.300002)
				)
			)
		)
	)
	(zone
		(layer "F.Cu")
		(hatch none 0.5)
		(connect_pads
			(clearance 0)
		)
		(min_thickness 0.25)
		(keepout
			(tracks allowed)
			(vias allowed)
			(pads allowed)
			(copperpour allowed)
			(footprints allowed)
		)
		(placement
			(enabled no)
			(sheetname "")
		)
		(fill
			(thermal_gap 0.5)
			(thermal_bridge_width 0.5)
			(island_removal_mode 0)
		)
		(polygon
			(pts
				(xy 35.179 -19.558) (xy 35.179 -18.7452) (xy 37.0078 -18.7452) (xy 37.0078 -19.558)
			)
		)
	)
	(zone
		(layer "F.Cu")
		(hatch none 0.5)
		(connect_pads
			(clearance 0)
		)
		(min_thickness 0.25)
		(keepout
			(tracks not_allowed)
			(vias allowed)
			(pads allowed)
			(copperpour not_allowed)
			(footprints allowed)
		)
		(placement
			(enabled no)
			(sheetname "")
		)
		(fill
			(thermal_gap 0.5)
			(thermal_bridge_width 0.5)
			(island_removal_mode 0)
		)
		(polygon
			(pts
				(arc
					(start 28.999942 -54.189122)
					(mid 26.75001 -56.439054)
					(end 24.500078 -54.189122)
				)
				(arc
					(start 24.500078 -54.189122)
					(mid 26.75001 -51.93919)
					(end 28.999942 -54.189122)
				)
			)
		)
	)
	(zone
		(layer "F.Cu")
		(hatch none 0.5)
		(connect_pads
			(clearance 0)
		)
		(min_thickness 0.25)
		(keepout
			(tracks allowed)
			(vias allowed)
			(pads allowed)
			(copperpour allowed)
			(footprints allowed)
		)
		(placement
			(enabled no)
			(sheetname "")
		)
		(fill
			(thermal_gap 0.5)
			(thermal_bridge_width 0.5)
			(island_removal_mode 0)
		)
		(polygon
			(pts
				(xy 73.05548 -41.269666) (xy 74.537062 -41.269666) (xy 75.390502 -40.416226) (xy 77.907388 -40.416226)
				(xy 78.582774 -41.091612) (xy 78.760828 -41.269666) (xy 79.23276 -41.269666) (xy 80.436974 -41.269666)
				(xy 80.436974 -54.985666) (xy 73.23836 -54.985666) (xy 72.494648 -54.985666) (xy 72.262492 -54.75351)
				(xy 72.262492 -44.82084) (xy 71.874126 -44.432474) (xy 71.874126 -43.777408) (xy 72.262492 -43.389042)
				(xy 72.262492 -42.73296) (xy 72.262492 -41.269666)
			)
		)
	)
	(zone
		(layer "F.Cu")
		(hatch none 0.5)
		(connect_pads
			(clearance 0)
		)
		(min_thickness 0.25)
		(keepout
			(tracks allowed)
			(vias allowed)
			(pads allowed)
			(copperpour allowed)
			(footprints not_allowed)
		)
		(placement
			(enabled no)
			(sheetname "")
		)
		(fill
			(thermal_gap 0.5)
			(thermal_bridge_width 0.5)
			(island_removal_mode 0)
		)
		(polygon
			(pts
				(xy 14.249908 -0.999998) (xy 14.249908 -9.390126) (xy 20.750022 -9.390126) (xy 20.750022 -0.999998)
				(xy 19.8501 -0.999998) (xy 19.8501 -8.48995) (xy 15.150084 -8.48995) (xy 15.150084 -0.999998)
			)
		)
	)
	(zone
		(layer "F.Cu")
		(hatch none 0.5)
		(connect_pads
			(clearance 0)
		)
		(min_thickness 0.25)
		(keepout
			(tracks allowed)
			(vias allowed)
			(pads allowed)
			(copperpour allowed)
			(footprints allowed)
		)
		(placement
			(enabled no)
			(sheetname "")
		)
		(fill
			(thermal_gap 0.5)
			(thermal_bridge_width 0.5)
			(island_removal_mode 0)
		)
		(polygon
			(pts
				(xy 65.590166 -39.144956) (xy 65.590166 -41.061894) (xy 66.849498 -42.321226) (xy 66.849498 -43.03395)
				(xy 65.617344 -44.266104) (xy 65.590166 -44.293282) (xy 65.590166 -47.902368) (xy 65.851024 -48.163226)
				(xy 65.851024 -48.741584) (xy 65.845182 -48.741584) (xy 65.590166 -48.9966) (xy 65.590166 -59.962034)
				(xy 65.590166 -60.140596) (xy 65.442846 -60.287916) (xy 64.914526 -60.816236) (xy 63.743586 -60.816236)
				(xy 63.461392 -60.534042) (xy 63.461392 -60.528708) (xy 63.2206 -60.287916) (xy 62.099698 -60.287916)
				(xy 61.662056 -60.725558) (xy 59.348878 -60.725558) (xy 58.962544 -60.339224) (xy 58.911236 -60.287916)
				(xy 48.4378 -60.287916) (xy 48.4378 -60.3504) (xy 47.2948 -61.4934) (xy 46.7868 -61.4934) (xy 44.6024 -63.6778)
				(xy 44.6024 -65.278) (xy 44.45 -65.4304) (xy 40.3606 -65.4304) (xy 40.0304 -65.1002) (xy 40.0304 -62.6364)
				(xy 42.1132 -60.5536) (xy 42.1132 -59.6392) (xy 43.5102 -58.2422) (xy 44.201588 -58.2422) (xy 44.201588 -58.166)
				(xy 44.201588 -44.146978) (xy 43.960796 -43.906186) (xy 43.960796 -40.967406) (xy 44.201588 -40.726614)
				(xy 44.201588 -39.455598) (xy 44.201588 -38.952932) (xy 44.38269 -38.77183) (xy 63.05042 -38.77183)
				(xy 63.63843 -38.18382) (xy 64.19977 -37.62248) (xy 64.87414 -37.62248) (xy 65.541652 -38.289992)
				(xy 65.541652 -38.77183) (xy 65.590166 -38.820344)
			)
		)
	)
	(zone
		(layer "F.Cu")
		(hatch none 0.5)
		(connect_pads
			(clearance 0)
		)
		(min_thickness 0.25)
		(keepout
			(tracks allowed)
			(vias allowed)
			(pads allowed)
			(copperpour allowed)
			(footprints not_allowed)
		)
		(placement
			(enabled no)
			(sheetname "")
		)
		(fill
			(thermal_gap 0.5)
			(thermal_bridge_width 0.5)
			(island_removal_mode 0)
		)
		(polygon
			(pts
				(xy 83.044792 -100.991924) (xy 83.044792 -88.720168) (xy 75.35926 -88.720168) (xy 75.35926 -100.991924)
			)
		)
		(polygon
			(pts
				(xy 76.359258 -89.720166) (xy 76.359258 -99.991926) (xy 82.044794 -99.991926) (xy 82.044794 -89.720166)
			)
		)
	)
	(zone
		(layer "F.Cu")
		(hatch none 0.5)
		(connect_pads
			(clearance 0)
		)
		(min_thickness 0.25)
		(keepout
			(tracks allowed)
			(vias allowed)
			(pads allowed)
			(copperpour allowed)
			(footprints allowed)
		)
		(placement
			(enabled no)
			(sheetname "")
		)
		(fill
			(thermal_gap 0.5)
			(thermal_bridge_width 0.5)
			(island_removal_mode 0)
		)
		(polygon
			(pts
				(xy 31.242 -81.788) (xy 31.242 -80.01) (xy 31.8516 -80.01) (xy 31.8516 -81.788)
			)
		)
	)
	(zone
		(layer "F.Cu")
		(hatch none 0.5)
		(connect_pads
			(clearance 0)
		)
		(min_thickness 0.25)
		(keepout
			(tracks allowed)
			(vias allowed)
			(pads allowed)
			(copperpour allowed)
			(footprints allowed)
		)
		(placement
			(enabled no)
			(sheetname "")
		)
		(fill
			(thermal_gap 0.5)
			(thermal_bridge_width 0.5)
			(island_removal_mode 0)
		)
		(polygon
			(pts
				(xy 76.433172 -37.946838) (xy 76.433172 -36.131246) (xy 80.599788 -36.131246) (xy 80.599788 -37.946838)
			)
		)
	)
	(zone
		(layer "F.Cu")
		(hatch none 0.5)
		(connect_pads
			(clearance 0)
		)
		(min_thickness 0.25)
		(keepout
			(tracks allowed)
			(vias allowed)
			(pads allowed)
			(copperpour allowed)
			(footprints not_allowed)
		)
		(placement
			(enabled no)
			(sheetname "")
		)
		(fill
			(thermal_gap 0.5)
			(thermal_bridge_width 0.5)
			(island_removal_mode 0)
		)
		(polygon
			(pts
				(xy 58.859166 -100.991924) (xy 66.544698 -100.991924) (xy 66.544698 -88.720168) (xy 58.859166 -88.720168)
			)
		)
		(polygon
			(pts
				(xy 59.859164 -89.720166) (xy 59.859164 -99.991926) (xy 65.5447 -99.991926) (xy 65.5447 -89.720166)
			)
		)
	)
	(zone
		(layer "F.Cu")
		(hatch none 0.5)
		(connect_pads
			(clearance 0)
		)
		(min_thickness 0.25)
		(keepout
			(tracks allowed)
			(vias allowed)
			(pads allowed)
			(copperpour allowed)
			(footprints allowed)
		)
		(placement
			(enabled no)
			(sheetname "")
		)
		(fill
			(thermal_gap 0.5)
			(thermal_bridge_width 0.5)
			(island_removal_mode 0)
		)
		(polygon
			(pts
				(xy 42.6466 -23.5204) (xy 42.6466 -20.8026) (xy 44.2468 -20.8026) (xy 44.2468 -23.5204)
			)
		)
	)
	(zone
		(layer "F.Cu")
		(hatch none 0.5)
		(connect_pads
			(clearance 0)
		)
		(min_thickness 0.25)
		(keepout
			(tracks not_allowed)
			(vias allowed)
			(pads allowed)
			(copperpour not_allowed)
			(footprints allowed)
		)
		(placement
			(enabled no)
			(sheetname "")
		)
		(fill
			(thermal_gap 0.5)
			(thermal_bridge_width 0.5)
			(island_removal_mode 0)
		)
		(polygon
			(pts
				(arc
					(start 73.49998 -107.700064)
					(mid 76.499974 -104.70007)
					(end 79.499968 -107.700064)
				)
				(arc
					(start 79.499968 -107.700064)
					(mid 76.499974 -110.700058)
					(end 73.49998 -107.700064)
				)
			)
		)
	)
	(zone
		(layer "F.Cu")
		(hatch none 0.5)
		(connect_pads
			(clearance 0)
		)
		(min_thickness 0.25)
		(keepout
			(tracks allowed)
			(vias allowed)
			(pads allowed)
			(copperpour allowed)
			(footprints not_allowed)
		)
		(placement
			(enabled no)
			(sheetname "")
		)
		(fill
			(thermal_gap 0.5)
			(thermal_bridge_width 0.5)
			(island_removal_mode 0)
		)
		(polygon
			(pts
				(xy 75.35926 -100.991924)
				(arc
					(start 80.859122 -100.991924)
					(mid 84.080902 -105.144513)
					(end 84.030566 -110.400084)
				)
				(arc
					(start 68.969382 -110.400084)
					(mid 69.645426 -103.575129)
					(end 75.35926 -99.781868)
				)
			)
		)
	)
	(zone
		(layer "F.Cu")
		(hatch none 0.5)
		(connect_pads
			(clearance 0)
		)
		(min_thickness 0.25)
		(keepout
			(tracks allowed)
			(vias allowed)
			(pads allowed)
			(copperpour allowed)
			(footprints not_allowed)
		)
		(placement
			(enabled no)
			(sheetname "")
		)
		(fill
			(thermal_gap 0.5)
			(thermal_bridge_width 0.5)
			(island_removal_mode 0)
		)
		(polygon
			(pts
				(xy 38.675056 -72.084946) (xy 14.824964 -72.084946) (xy 14.824964 -82.23504) (xy 38.675056 -82.23504)
			)
		)
		(polygon
			(pts
				(xy 37.675058 -81.235042) (xy 37.675058 -73.084944) (xy 15.824962 -73.084944) (xy 15.824962 -81.235042)
			)
		)
	)
	(zone
		(layer "F.Cu")
		(hatch none 0.5)
		(connect_pads
			(clearance 0)
		)
		(min_thickness 0.25)
		(keepout
			(tracks allowed)
			(vias allowed)
			(pads allowed)
			(copperpour allowed)
			(footprints allowed)
		)
		(placement
			(enabled no)
			(sheetname "")
		)
		(fill
			(thermal_gap 0.5)
			(thermal_bridge_width 0.5)
			(island_removal_mode 0)
		)
		(polygon
			(pts
				(xy 40.2082 -23.5204) (xy 40.2082 -20.7772) (xy 41.8846 -20.7772) (xy 41.8846 -23.5204)
			)
		)
	)
	(zone
		(layer "F.Cu")
		(hatch none 0.5)
		(connect_pads
			(clearance 0)
		)
		(min_thickness 0.25)
		(keepout
			(tracks allowed)
			(vias allowed)
			(pads allowed)
			(copperpour allowed)
			(footprints not_allowed)
		)
		(placement
			(enabled no)
			(sheetname "")
		)
		(fill
			(thermal_gap 0.5)
			(thermal_bridge_width 0.5)
			(island_removal_mode 0)
		)
		(polygon
			(pts
				(arc
					(start 79.499968 -107.700064)
					(mid 76.499974 -110.700058)
					(end 73.49998 -107.700064)
				)
				(arc
					(start 73.49998 -107.700064)
					(mid 76.499974 -104.70007)
					(end 79.499968 -107.700064)
				)
			)
		)
		(polygon
			(pts
				(arc
					(start 78.199996 -107.700064)
					(mid 76.499974 -109.400086)
					(end 74.799952 -107.700064)
				)
				(arc
					(start 74.799952 -107.700064)
					(mid 76.499974 -106.000042)
					(end 78.199996 -107.700064)
				)
			)
		)
	)
	(zone
		(layer "F.Cu")
		(hatch none 0.5)
		(connect_pads
			(clearance 0)
		)
		(min_thickness 0.25)
		(keepout
			(tracks allowed)
			(vias allowed)
			(pads allowed)
			(copperpour allowed)
			(footprints allowed)
		)
		(placement
			(enabled no)
			(sheetname "")
		)
		(fill
			(thermal_gap 0.5)
			(thermal_bridge_width 0.5)
			(island_removal_mode 0)
		)
		(polygon
			(pts
				(xy 31.375604 -32.4612) (xy 32.7914 -32.4612) (xy 34.163 -31.0896) (xy 34.163 -25.6794) (xy 33.8582 -25.3746)
				(xy 30.5308 -25.3746) (xy 29.6926 -26.2128) (xy 29.6926 -30.778196)
			)
		)
	)
	(zone
		(layer "F.Cu")
		(hatch none 0.5)
		(connect_pads
			(clearance 0)
		)
		(min_thickness 0.25)
		(keepout
			(tracks allowed)
			(vias allowed)
			(pads allowed)
			(copperpour allowed)
			(footprints allowed)
		)
		(placement
			(enabled no)
			(sheetname "")
		)
		(fill
			(thermal_gap 0.5)
			(thermal_bridge_width 0.5)
			(island_removal_mode 0)
		)
		(polygon
			(pts
				(xy 82.93481 -73.719182) (xy 85.447632 -73.719182) (xy 85.6488 -73.518014) (xy 85.6488 -72.341232)
				(xy 85.447886 -72.140318) (xy 82.965798 -72.140318) (xy 82.84718 -72.258936) (xy 82.84718 -73.631552)
			)
		)
	)
	(zone
		(layer "F.Cu")
		(hatch none 0.5)
		(connect_pads
			(clearance 0)
		)
		(min_thickness 0.25)
		(keepout
			(tracks not_allowed)
			(vias allowed)
			(pads allowed)
			(copperpour not_allowed)
			(footprints allowed)
		)
		(placement
			(enabled no)
			(sheetname "")
		)
		(fill
			(thermal_gap 0.5)
			(thermal_bridge_width 0.5)
			(island_removal_mode 0)
		)
		(polygon
			(pts
				(arc
					(start 7.199884 -11.789918)
					(mid 5.599938 -13.389864)
					(end 3.999992 -11.789918)
				)
				(arc
					(start 3.999992 -11.789918)
					(mid 5.599938 -10.189972)
					(end 7.199884 -11.789918)
				)
			)
		)
	)
	(zone
		(layer "F.Cu")
		(hatch none 0.5)
		(connect_pads
			(clearance 0)
		)
		(min_thickness 0.25)
		(keepout
			(tracks allowed)
			(vias allowed)
			(pads allowed)
			(copperpour allowed)
			(footprints not_allowed)
		)
		(placement
			(enabled no)
			(sheetname "")
		)
		(fill
			(thermal_gap 0.5)
			(thermal_bridge_width 0.5)
			(island_removal_mode 0)
		)
		(polygon
			(pts
				(xy 58.859166 -100.991924)
				(arc
					(start 64.359028 -100.991924)
					(mid 67.580897 -105.144456)
					(end 67.530726 -110.400084)
				)
				(arc
					(start 52.469288 -110.400084)
					(mid 53.145332 -103.575129)
					(end 58.859166 -99.781868)
				)
			)
		)
	)
	(zone
		(layer "F.Cu")
		(hatch none 0.5)
		(connect_pads
			(clearance 0)
		)
		(min_thickness 0.25)
		(keepout
			(tracks allowed)
			(vias allowed)
			(pads allowed)
			(copperpour allowed)
			(footprints not_allowed)
		)
		(placement
			(enabled no)
			(sheetname "")
		)
		(fill
			(thermal_gap 0.5)
			(thermal_bridge_width 0.5)
			(island_removal_mode 0)
		)
		(polygon
			(pts
				(arc
					(start 86.91499 -22.690074)
					(mid 83.90001 -25.705054)
					(end 80.88503 -22.690074)
				)
				(arc
					(start 80.88503 -22.690074)
					(mid 83.90001 -19.675094)
					(end 86.91499 -22.690074)
				)
			)
		)
		(polygon
			(pts
				(arc
					(start 82.335116 -22.690074)
					(mid 83.90001 -21.12518)
					(end 85.464904 -22.690074)
				)
				(arc
					(start 85.464904 -22.690074)
					(mid 83.90001 -24.254968)
					(end 82.335116 -22.690074)
				)
			)
		)
	)
	(zone
		(layer "F.Cu")
		(hatch none 0.5)
		(connect_pads
			(clearance 0)
		)
		(min_thickness 0.25)
		(keepout
			(tracks allowed)
			(vias allowed)
			(pads allowed)
			(copperpour allowed)
			(footprints allowed)
		)
		(placement
			(enabled no)
			(sheetname "")
		)
		(fill
			(thermal_gap 0.5)
			(thermal_bridge_width 0.5)
			(island_removal_mode 0)
		)
		(polygon
			(pts
				(xy 21.5392 -74.2442) (xy 21.5392 -71.7296) (xy 20.5486 -71.7296) (xy 20.5486 -74.2442)
			)
		)
	)
	(zone
		(layer "F.Cu")
		(hatch none 0.5)
		(connect_pads
			(clearance 0)
		)
		(min_thickness 0.25)
		(keepout
			(tracks not_allowed)
			(vias allowed)
			(pads allowed)
			(copperpour not_allowed)
			(footprints allowed)
		)
		(placement
			(enabled no)
			(sheetname "")
		)
		(fill
			(thermal_gap 0.5)
			(thermal_bridge_width 0.5)
			(island_removal_mode 0)
		)
		(polygon
			(pts
				(arc
					(start 25.150064 -48.189134)
					(mid 26.75001 -49.78908)
					(end 28.349956 -48.189134)
				)
				(arc
					(start 28.349956 -46.589188)
					(mid 26.75001 -44.989242)
					(end 25.150064 -46.589188)
				)
			)
		)
	)
	(zone
		(layer "F.Cu")
		(hatch none 0.5)
		(connect_pads
			(clearance 0)
		)
		(min_thickness 0.25)
		(keepout
			(tracks allowed)
			(vias allowed)
			(pads allowed)
			(copperpour allowed)
			(footprints not_allowed)
		)
		(placement
			(enabled no)
			(sheetname "")
		)
		(fill
			(thermal_gap 0.5)
			(thermal_bridge_width 0.5)
			(island_removal_mode 0)
		)
		(polygon
			(pts
				(arc
					(start 9.115044 -22.690074)
					(mid 6.100064 -25.705054)
					(end 3.085084 -22.690074)
				)
				(arc
					(start 3.085084 -22.690074)
					(mid 6.100064 -19.675094)
					(end 9.115044 -22.690074)
				)
			)
		)
		(polygon
			(pts
				(arc
					(start 4.534916 -22.690074)
					(mid 6.100064 -21.124926)
					(end 7.664958 -22.690074)
				)
				(arc
					(start 7.664958 -22.690074)
					(mid 6.100064 -24.254968)
					(end 4.534916 -22.690074)
				)
			)
		)
	)
	(zone
		(layer "F.Cu")
		(hatch none 0.5)
		(connect_pads
			(clearance 0)
		)
		(min_thickness 0.25)
		(keepout
			(tracks not_allowed)
			(vias allowed)
			(pads allowed)
			(copperpour not_allowed)
			(footprints allowed)
		)
		(placement
			(enabled no)
			(sheetname "")
		)
		(fill
			(thermal_gap 0.5)
			(thermal_bridge_width 0.5)
			(island_removal_mode 0)
		)
		(polygon
			(pts
				(arc
					(start 86.300056 -11.789918)
					(mid 84.70011 -13.389864)
					(end 83.09991 -11.789918)
				)
				(arc
					(start 83.09991 -11.789918)
					(mid 84.70011 -10.189718)
					(end 86.300056 -11.789918)
				)
			)
		)
	)
	(zone
		(layer "F.Cu")
		(hatch none 0.5)
		(connect_pads
			(clearance 0)
		)
		(min_thickness 0.25)
		(keepout
			(tracks allowed)
			(vias allowed)
			(pads allowed)
			(copperpour allowed)
			(footprints not_allowed)
		)
		(placement
			(enabled no)
			(sheetname "")
		)
		(fill
			(thermal_gap 0.5)
			(thermal_bridge_width 0.5)
			(island_removal_mode 0)
		)
		(polygon
			(pts
				(xy 89.000076 -112.300004)
				(arc
					(start 89.000076 -1.999996)
					(mid 88.707183 -1.292891)
					(end 88.000078 -0.999998)
				)
				(xy 87.700104 -0.999998) (xy 87.700104 -8.050022) (xy 86.250018 -8.050022)
				(arc
					(start 86.250018 -8.933434)
					(mid 87.950213 -11.790111)
					(end 86.250018 -14.646656)
				)
				(arc
					(start 86.250018 -20.801076)
					(mid 86.915114 -22.689975)
					(end 86.250018 -24.578818)
				)
				(xy 86.250018 -112.300004)
			)
		)
	)
	(zone
		(layer "F.Cu")
		(hatch none 0.5)
		(connect_pads
			(clearance 0)
		)
		(min_thickness 0.25)
		(keepout
			(tracks allowed)
			(vias allowed)
			(pads allowed)
			(copperpour allowed)
			(footprints allowed)
		)
		(placement
			(enabled no)
			(sheetname "")
		)
		(fill
			(thermal_gap 0.5)
			(thermal_bridge_width 0.5)
			(island_removal_mode 0)
		)
		(polygon
			(pts
				(xy 7.62 -67.4116) (xy 7.62 -66.0654) (xy 9.9314 -66.0654) (xy 9.9314 -67.4116)
			)
		)
	)
	(zone
		(layer "F.Cu")
		(hatch none 0.5)
		(connect_pads
			(clearance 0)
		)
		(min_thickness 0.25)
		(keepout
			(tracks allowed)
			(vias allowed)
			(pads allowed)
			(copperpour allowed)
			(footprints not_allowed)
		)
		(placement
			(enabled no)
			(sheetname "")
		)
		(fill
			(thermal_gap 0.5)
			(thermal_bridge_width 0.5)
			(island_removal_mode 0)
		)
		(polygon
			(pts
				(xy 0.999998 -112.300004) (xy 3.750056 -112.300004)
				(arc
					(start 3.750056 -24.578818)
					(mid 3.085119 -22.689975)
					(end 3.750056 -20.801076)
				)
				(arc
					(start 3.750056 -14.461998)
					(mid 2.350003 -11.789918)
					(end 3.750056 -9.117838)
				)
				(xy 3.750056 -8.050022) (xy 2.29997 -8.050022) (xy 2.29997 -0.999998)
				(arc
					(start 1.999996 -0.999998)
					(mid 1.292891 -1.292891)
					(end 0.999998 -1.999996)
				)
			)
		)
	)
	(zone
		(layer "F.Cu")
		(hatch none 0.5)
		(connect_pads
			(clearance 0)
		)
		(min_thickness 0.25)
		(keepout
			(tracks not_allowed)
			(vias allowed)
			(pads allowed)
			(copperpour not_allowed)
			(footprints allowed)
		)
		(placement
			(enabled no)
			(sheetname "")
		)
		(fill
			(thermal_gap 0.5)
			(thermal_bridge_width 0.5)
			(island_removal_mode 0)
		)
		(polygon
			(pts
				(arc
					(start 56.999886 -107.700064)
					(mid 59.99988 -104.70007)
					(end 62.999874 -107.700064)
				)
				(arc
					(start 62.999874 -107.700064)
					(mid 59.99988 -110.700058)
					(end 56.999886 -107.700064)
				)
			)
		)
	)
	(zone
		(layer "F.Cu")
		(hatch none 0.5)
		(connect_pads
			(clearance 0)
		)
		(min_thickness 0.25)
		(keepout
			(tracks allowed)
			(vias allowed)
			(pads allowed)
			(copperpour allowed)
			(footprints not_allowed)
		)
		(placement
			(enabled no)
			(sheetname "")
		)
		(fill
			(thermal_gap 0.5)
			(thermal_bridge_width 0.5)
			(island_removal_mode 0)
		)
		(polygon
			(pts
				(xy 31.850076 -109.46511) (xy 47.15002 -109.46511) (xy 47.15002 -105.855008) (xy 31.850076 -105.855008)
			)
		)
	)
	(zone
		(layer "F.Cu")
		(hatch none 0.5)
		(connect_pads
			(clearance 0)
		)
		(min_thickness 0.25)
		(keepout
			(tracks allowed)
			(vias allowed)
			(pads allowed)
			(copperpour allowed)
			(footprints not_allowed)
		)
		(placement
			(enabled no)
			(sheetname "")
		)
		(fill
			(thermal_gap 0.5)
			(thermal_bridge_width 0.5)
			(island_removal_mode 0)
		)
		(polygon
			(pts
				(xy 3.800094 -84.000086) (xy 3.800094 -106.069892) (xy 8.299958 -106.069892) (xy 8.299958 -84.000086)
			)
		)
		(polygon
			(pts
				(xy 7.29996 -85.000084) (xy 4.800092 -85.000084) (xy 4.800092 -105.069894) (xy 7.29996 -105.069894)
			)
		)
	)
	(zone
		(layer "F.Cu")
		(hatch none 0.5)
		(connect_pads
			(clearance 0)
		)
		(min_thickness 0.25)
		(keepout
			(tracks allowed)
			(vias allowed)
			(pads allowed)
			(copperpour allowed)
			(footprints allowed)
		)
		(placement
			(enabled no)
			(sheetname "")
		)
		(fill
			(thermal_gap 0.5)
			(thermal_bridge_width 0.5)
			(island_removal_mode 0)
		)
		(polygon
			(pts
				(xy 32.2326 -21.0058) (xy 32.2326 -19.5326) (xy 34.9758 -19.5326) (xy 34.9758 -21.0058)
			)
		)
	)
	(zone
		(layer "F.Cu")
		(hatch none 0.5)
		(connect_pads
			(clearance 0)
		)
		(min_thickness 0.25)
		(keepout
			(tracks allowed)
			(vias allowed)
			(pads allowed)
			(copperpour allowed)
			(footprints not_allowed)
		)
		(placement
			(enabled no)
			(sheetname "")
		)
		(fill
			(thermal_gap 0.5)
			(thermal_bridge_width 0.5)
			(island_removal_mode 0)
		)
		(polygon
			(pts
				(xy 20.999958 -0.999998) (xy 20.999958 -9.390126) (xy 27.500072 -9.390126) (xy 27.500072 -0.999998)
				(xy 26.599896 -0.999998) (xy 26.599896 -8.48995) (xy 21.89988 -8.48995) (xy 21.89988 -0.999998)
			)
		)
	)
	(zone
		(layer "F.Cu")
		(hatch none 0.5)
		(connect_pads
			(clearance 0)
		)
		(min_thickness 0.25)
		(keepout
			(tracks allowed)
			(vias allowed)
			(pads allowed)
			(copperpour allowed)
			(footprints allowed)
		)
		(placement
			(enabled no)
			(sheetname "")
		)
		(fill
			(thermal_gap 0.5)
			(thermal_bridge_width 0.5)
			(island_removal_mode 0)
		)
		(polygon
			(pts
				(xy 34.7726 -103.9368) (xy 34.7726 -101.9048) (xy 44.2976 -101.9048) (xy 44.2976 -103.9368)
			)
		)
	)
	(zone
		(layers "F.Cu" "B.Cu" "In1.Cu" "In2.Cu" "In3.Cu" "In4.Cu" "In5.Cu" "In6.Cu"
			"In7.Cu" "In8.Cu" "In9.Cu" "In10.Cu"
		)
		(hatch none 0.5)
		(connect_pads
			(clearance 0)
		)
		(min_thickness 0.25)
		(keepout
			(tracks not_allowed)
			(vias allowed)
			(pads allowed)
			(copperpour not_allowed)
			(footprints allowed)
		)
		(placement
			(enabled no)
			(sheetname "")
		)
		(fill
			(thermal_gap 0.5)
			(thermal_bridge_width 0.5)
			(island_removal_mode 0)
		)
		(polygon
			(pts
				(arc
					(start 24.35098 -112.771682)
					(mid 23.96998 -113.152682)
					(end 24.35098 -113.533682)
				)
				(arc
					(start 25.23998 -113.533682)
					(mid 25.62098 -113.152682)
					(end 25.23998 -112.771682)
				)
			)
		)
	)
	(zone
		(layers "F.Cu" "B.Cu" "In1.Cu" "In2.Cu" "In3.Cu" "In4.Cu" "In5.Cu" "In6.Cu"
			"In7.Cu" "In8.Cu" "In9.Cu" "In10.Cu"
		)
		(hatch none 0.5)
		(connect_pads
			(clearance 0)
		)
		(min_thickness 0.25)
		(keepout
			(tracks not_allowed)
			(vias allowed)
			(pads allowed)
			(copperpour not_allowed)
			(footprints allowed)
		)
		(placement
			(enabled no)
			(sheetname "")
		)
		(fill
			(thermal_gap 0.5)
			(thermal_bridge_width 0.5)
			(island_removal_mode 0)
		)
		(polygon
			(pts
				(arc
					(start 14.727428 -115.149376)
					(mid 14.346428 -114.768376)
					(end 13.965428 -115.149376)
				)
				(arc
					(start 13.965428 -116.038376)
					(mid 14.346428 -116.419376)
					(end 14.727428 -116.038376)
				)
			)
		)
	)
	(zone
		(layers "F.Cu" "B.Cu" "In1.Cu" "In2.Cu" "In3.Cu" "In4.Cu" "In5.Cu" "In6.Cu"
			"In7.Cu" "In8.Cu" "In9.Cu" "In10.Cu"
		)
		(hatch none 0.5)
		(connect_pads
			(clearance 0)
		)
		(min_thickness 0.25)
		(keepout
			(tracks not_allowed)
			(vias allowed)
			(pads allowed)
			(copperpour not_allowed)
			(footprints allowed)
		)
		(placement
			(enabled no)
			(sheetname "")
		)
		(fill
			(thermal_gap 0.5)
			(thermal_bridge_width 0.5)
			(island_removal_mode 0)
		)
		(polygon
			(pts
				(arc
					(start 68.001388 -45.285914)
					(mid 68.382388 -44.904914)
					(end 68.001388 -44.523914)
				)
				(arc
					(start 67.112388 -44.523914)
					(mid 66.731388 -44.904914)
					(end 67.112388 -45.285914)
				)
			)
		)
	)
	(zone
		(layers "F.Cu" "B.Cu" "In1.Cu" "In2.Cu" "In3.Cu" "In4.Cu" "In5.Cu" "In6.Cu"
			"In7.Cu" "In8.Cu" "In9.Cu" "In10.Cu"
		)
		(hatch none 0.5)
		(connect_pads
			(clearance 0)
		)
		(min_thickness 0.25)
		(keepout
			(tracks not_allowed)
			(vias allowed)
			(pads allowed)
			(copperpour not_allowed)
			(footprints allowed)
		)
		(placement
			(enabled no)
			(sheetname "")
		)
		(fill
			(thermal_gap 0.5)
			(thermal_bridge_width 0.5)
			(island_removal_mode 0)
		)
		(polygon
			(pts
				(xy 5.211572 -120.620536) (xy 10.737596 -120.620536) (xy 10.737596 -118.708678) (xy 10.33272 -118.708678)
				(xy 10.16254 -118.878858) (xy 9.862058 -118.878858) (xy 9.704324 -118.721124) (xy 6.040628 -118.721124)
				(xy 5.936742 -118.82501) (xy 5.621274 -118.82501) (xy 5.405882 -118.609618) (xy 5.211572 -118.609618)
			)
		)
	)
	(zone
		(layers "F.Cu" "B.Cu" "In1.Cu" "In2.Cu" "In3.Cu" "In4.Cu" "In5.Cu" "In6.Cu"
			"In7.Cu" "In8.Cu" "In9.Cu" "In10.Cu"
		)
		(hatch none 0.5)
		(connect_pads
			(clearance 0)
		)
		(min_thickness 0.25)
		(keepout
			(tracks not_allowed)
			(vias allowed)
			(pads allowed)
			(copperpour not_allowed)
			(footprints allowed)
		)
		(placement
			(enabled no)
			(sheetname "")
		)
		(fill
			(thermal_gap 0.5)
			(thermal_bridge_width 0.5)
			(island_removal_mode 0)
		)
		(polygon
			(pts
				(arc
					(start 67.58432 -53.025548)
					(mid 67.96532 -52.644548)
					(end 67.58432 -52.263548)
				)
				(arc
					(start 66.69532 -52.263548)
					(mid 66.31432 -52.644548)
					(end 66.69532 -53.025548)
				)
			)
		)
	)
	(zone
		(layers "F.Cu" "B.Cu" "In1.Cu" "In2.Cu" "In3.Cu" "In4.Cu" "In5.Cu" "In6.Cu"
			"In7.Cu" "In8.Cu" "In9.Cu" "In10.Cu"
		)
		(hatch none 0.5)
		(connect_pads
			(clearance 0)
		)
		(min_thickness 0.25)
		(keepout
			(tracks not_allowed)
			(vias allowed)
			(pads allowed)
			(copperpour not_allowed)
			(footprints allowed)
		)
		(placement
			(enabled no)
			(sheetname "")
		)
		(fill
			(thermal_gap 0.5)
			(thermal_bridge_width 0.5)
			(island_removal_mode 0)
		)
		(polygon
			(pts
				(arc
					(start 41.922192 -12.668758)
					(mid 41.210992 -13.379958)
					(end 41.922192 -14.091158)
				)
				(arc
					(start 43.922188 -14.091158)
					(mid 44.633388 -13.379958)
					(end 43.922188 -12.668758)
				)
			)
		)
	)
	(zone
		(layers "F.Cu" "B.Cu" "In1.Cu" "In2.Cu" "In3.Cu" "In4.Cu" "In5.Cu" "In6.Cu"
			"In7.Cu" "In8.Cu" "In9.Cu" "In10.Cu"
		)
		(hatch none 0.5)
		(connect_pads
			(clearance 0)
		)
		(min_thickness 0.25)
		(keepout
			(tracks not_allowed)
			(vias allowed)
			(pads allowed)
			(copperpour not_allowed)
			(footprints allowed)
		)
		(placement
			(enabled no)
			(sheetname "")
		)
		(fill
			(thermal_gap 0.5)
			(thermal_bridge_width 0.5)
			(island_removal_mode 0)
		)
		(polygon
			(pts
				(arc
					(start 55.04815 -112.70488)
					(mid 55.42915 -112.32388)
					(end 55.04815 -111.94288)
				)
				(arc
					(start 54.15915 -111.94288)
					(mid 53.77815 -112.32388)
					(end 54.15915 -112.70488)
				)
			)
		)
	)
	(zone
		(layers "F.Cu" "B.Cu" "In1.Cu" "In2.Cu" "In3.Cu" "In4.Cu" "In5.Cu" "In6.Cu"
			"In7.Cu" "In8.Cu" "In9.Cu" "In10.Cu"
		)
		(hatch none 0.5)
		(connect_pads
			(clearance 0)
		)
		(min_thickness 0.25)
		(keepout
			(tracks not_allowed)
			(vias allowed)
			(pads allowed)
			(copperpour not_allowed)
			(footprints allowed)
		)
		(placement
			(enabled no)
			(sheetname "")
		)
		(fill
			(thermal_gap 0.5)
			(thermal_bridge_width 0.5)
			(island_removal_mode 0)
		)
		(polygon
			(pts
				(arc
					(start 63.690246 -59.436254)
					(mid 63.360046 -59.766454)
					(end 63.690246 -60.096654)
				)
				(arc
					(start 64.490092 -60.096654)
					(mid 64.820292 -59.766454)
					(end 64.490092 -59.436254)
				)
			)
		)
	)
	(zone
		(layers "F.Cu" "B.Cu" "In1.Cu" "In2.Cu" "In3.Cu" "In4.Cu" "In5.Cu" "In6.Cu"
			"In7.Cu" "In8.Cu" "In9.Cu" "In10.Cu"
		)
		(hatch none 0.5)
		(connect_pads
			(clearance 0)
		)
		(min_thickness 0.25)
		(keepout
			(tracks not_allowed)
			(vias allowed)
			(pads allowed)
			(copperpour not_allowed)
			(footprints allowed)
		)
		(placement
			(enabled no)
			(sheetname "")
		)
		(fill
			(thermal_gap 0.5)
			(thermal_bridge_width 0.5)
			(island_removal_mode 0)
		)
		(polygon
			(pts
				(arc
					(start 44.922186 -14.168882)
					(mid 44.210986 -14.880082)
					(end 44.922186 -15.591282)
				)
				(arc
					(start 46.922182 -15.591282)
					(mid 47.633382 -14.880082)
					(end 46.922182 -14.168882)
				)
			)
		)
	)
	(zone
		(layers "F.Cu" "B.Cu" "In1.Cu" "In2.Cu" "In3.Cu" "In4.Cu" "In5.Cu" "In6.Cu"
			"In7.Cu" "In8.Cu" "In9.Cu" "In10.Cu"
		)
		(name "Package Keepin")
		(hatch none 0.5)
		(connect_pads
			(clearance 0)
		)
		(min_thickness 0.25)
		(keepout
			(tracks allowed)
			(vias allowed)
			(pads allowed)
			(copperpour allowed)
			(footprints allowed)
		)
		(placement
			(enabled no)
			(sheetname "")
		)
		(fill
			(thermal_gap 0.5)
			(thermal_bridge_width 0.5)
			(island_removal_mode 0)
		)
		(polygon
			(pts
				(xy 83.68157 -119.384064) (xy 83.984084 -118.859808)
				(arc
					(start 83.984084 -114.799872)
					(mid 84.428147 -113.728063)
					(end 85.499956 -113.284)
				)
				(arc
					(start 88.000078 -113.284)
					(mid 88.695868 -112.995794)
					(end 88.984074 -112.300004)
				)
				(xy 88.984074 -94.345506) (xy 93.01607 -94.345506)
				(arc
					(start 93.01607 -118.400068)
					(mid 93.304276 -119.095858)
					(end 94.000066 -119.384064)
				)
				(arc
					(start 121.000012 -119.384064)
					(mid 121.695802 -119.095858)
					(end 121.984008 -118.400068)
				)
				(arc
					(start 121.984008 129.499868)
					(mid 121.695802 130.195658)
					(end 121.000012 130.483864)
				)
				(arc
					(start 94.000066 130.483864)
					(mid 93.304276 130.195658)
					(end 93.01607 129.499868)
				)
				(xy 93.01607 -93.719904) (xy 88.984074 -93.719904) (xy 88.984074 -86.016084)
				(arc
					(start 87.749888 -86.016084)
					(mid 86.678169 -85.572006)
					(end 86.234016 -84.500212)
				)
				(arc
					(start 86.234016 -81.999836)
					(mid 86.678079 -80.928027)
					(end 87.749888 -80.483964)
				)
				(xy 88.984074 -80.483964)
				(arc
					(start 88.984074 -1.999996)
					(mid 88.695868 -1.304206)
					(end 88.000078 -1.016)
				)
				(arc
					(start 1.999996 -1.016)
					(mid 1.304206 -1.304206)
					(end 1.016 -1.999996)
				)
				(xy 1.016 -80.483964)
				(arc
					(start 2.249932 -80.483964)
					(mid 3.321995 -80.928027)
					(end 3.766058 -82.00009)
				)
				(arc
					(start 3.766058 -84.499958)
					(mid 3.321995 -85.572021)
					(end 2.249932 -86.016084)
				)
				(xy 1.016 -86.016084) (xy 1.016 -93.82633) (xy -3.015996 -93.82633)
				(arc
					(start -3.015996 -6.59003)
					(mid -3.304202 -5.89424)
					(end -3.999992 -5.606034)
				)
				(arc
					(start -17.78 -5.606034)
					(mid -18.47579 -5.89424)
					(end -18.763996 -6.59003)
				)
				(arc
					(start -18.763996 -118.400068)
					(mid -18.47579 -119.095858)
					(end -17.78 -119.384064)
				)
				(arc
					(start -3.999992 -119.384064)
					(mid -3.304202 -119.095858)
					(end -3.015996 -118.400068)
				)
				(xy -3.015996 -94.248732) (xy 1.016 -94.248732)
				(arc
					(start 1.016 -112.300004)
					(mid 1.304206 -112.995794)
					(end 1.999996 -113.284)
				)
				(arc
					(start 4.500118 -113.284)
					(mid 5.571927 -113.728063)
					(end 6.01599 -114.799872)
				)
				(xy 6.01599 -118.859808) (xy 6.318504 -119.384064) (xy 9.594088 -119.384064) (xy 9.749028 -119.229124)
				(arc
					(start 9.749028 -114.799872)
					(mid 10.193091 -113.728063)
					(end 11.2649 -113.284)
				)
				(arc
					(start 12.765024 -113.284)
					(mid 13.836833 -113.728063)
					(end 14.280896 -114.799872)
				)
				(xy 14.280896 -119.229124) (xy 14.435836 -119.384064) (xy 30.454092 -119.384064) (xy 30.609032 -119.229124)
				(arc
					(start 30.609032 -114.77498)
					(mid 32.999934 -112.384078)
					(end 35.39109 -114.77498)
				)
				(xy 35.39109 -119.229378) (xy 35.545776 -119.384064) (xy 43.163998 -119.384064) (xy 43.318938 -119.229124)
				(arc
					(start 43.318938 -114.324892)
					(mid 45.260006 -112.383824)
					(end 47.201074 -114.324892)
				)
				(xy 47.201074 -119.229378) (xy 47.35576 -119.384064) (xy 63.36411 -119.384064) (xy 63.51905 -119.229124)
				(arc
					(start 63.51905 -114.525044)
					(mid 65.660016 -112.384078)
					(end 67.800982 -114.525044)
				)
				(xy 67.800982 -119.229124) (xy 67.955922 -119.384064) (xy 75.569064 -119.384064) (xy 75.724004 -119.229124)
				(arc
					(start 75.724004 -114.799872)
					(mid 76.168067 -113.728063)
					(end 77.239876 -113.284)
				)
				(arc
					(start 78.74 -113.284)
					(mid 79.812063 -113.728063)
					(end 80.256126 -114.800126)
				)
				(xy 80.256126 -119.229378) (xy 80.410812 -119.384064)
			)
		)
	)
	(zone
		(layers "F.Cu" "B.Cu" "In1.Cu" "In2.Cu" "In3.Cu" "In4.Cu" "In5.Cu" "In6.Cu"
			"In7.Cu" "In8.Cu" "In9.Cu" "In10.Cu"
		)
		(hatch none 0.5)
		(connect_pads
			(clearance 0)
		)
		(min_thickness 0.25)
		(keepout
			(tracks not_allowed)
			(vias allowed)
			(pads allowed)
			(copperpour not_allowed)
			(footprints allowed)
		)
		(placement
			(enabled no)
			(sheetname "")
		)
		(fill
			(thermal_gap 0.5)
			(thermal_bridge_width 0.5)
			(island_removal_mode 0)
		)
		(polygon
			(pts
				(arc
					(start 41.2877 -98.763836)
					(mid 41.6687 -98.382836)
					(end 41.2877 -98.001836)
				)
				(arc
					(start 40.3987 -98.001836)
					(mid 40.0177 -98.382836)
					(end 40.3987 -98.763836)
				)
			)
		)
	)
	(zone
		(layers "F.Cu" "B.Cu" "In1.Cu" "In2.Cu" "In3.Cu" "In4.Cu" "In5.Cu" "In6.Cu"
			"In7.Cu" "In8.Cu" "In9.Cu" "In10.Cu"
		)
		(hatch none 0.5)
		(connect_pads
			(clearance 0)
		)
		(min_thickness 0.25)
		(keepout
			(tracks not_allowed)
			(vias allowed)
			(pads allowed)
			(copperpour not_allowed)
			(footprints allowed)
		)
		(placement
			(enabled no)
			(sheetname "")
		)
		(fill
			(thermal_gap 0.5)
			(thermal_bridge_width 0.5)
			(island_removal_mode 0)
		)
		(polygon
			(pts
				(arc
					(start 13.3985 -107.3658)
					(mid 13.0175 -107.7468)
					(end 13.3985 -108.1278)
				)
				(arc
					(start 14.2875 -108.1278)
					(mid 14.6685 -107.7468)
					(end 14.2875 -107.3658)
				)
			)
		)
	)
	(zone
		(layers "F.Cu" "B.Cu" "In1.Cu" "In2.Cu" "In3.Cu" "In4.Cu" "In5.Cu" "In6.Cu"
			"In7.Cu" "In8.Cu" "In9.Cu" "In10.Cu"
		)
		(hatch none 0.5)
		(connect_pads
			(clearance 0)
		)
		(min_thickness 0.25)
		(keepout
			(tracks not_allowed)
			(vias allowed)
			(pads allowed)
			(copperpour not_allowed)
			(footprints allowed)
		)
		(placement
			(enabled no)
			(sheetname "")
		)
		(fill
			(thermal_gap 0.5)
			(thermal_bridge_width 0.5)
			(island_removal_mode 0)
		)
		(polygon
			(pts
				(arc
					(start 16.527526 -115.149376)
					(mid 16.146526 -114.768376)
					(end 15.765526 -115.149376)
				)
				(arc
					(start 15.765526 -116.038376)
					(mid 16.146526 -116.419376)
					(end 16.527526 -116.038376)
				)
			)
		)
	)
	(zone
		(layers "F.Cu" "B.Cu" "In1.Cu" "In2.Cu" "In3.Cu" "In4.Cu" "In5.Cu" "In6.Cu"
			"In7.Cu" "In8.Cu" "In9.Cu" "In10.Cu"
		)
		(hatch none 0.5)
		(connect_pads
			(clearance 0)
		)
		(min_thickness 0.25)
		(keepout
			(tracks not_allowed)
			(vias allowed)
			(pads allowed)
			(copperpour not_allowed)
			(footprints allowed)
		)
		(placement
			(enabled no)
			(sheetname "")
		)
		(fill
			(thermal_gap 0.5)
			(thermal_bridge_width 0.5)
			(island_removal_mode 0)
		)
		(polygon
			(pts
				(arc
					(start 95.494856 -2.746502)
					(mid 95.113856 -3.127502)
					(end 95.494856 -3.508502)
				)
				(arc
					(start 96.358456 -3.508502)
					(mid 96.739456 -3.127502)
					(end 96.358456 -2.746502)
				)
			)
		)
	)
	(zone
		(layers "F.Cu" "B.Cu" "In1.Cu" "In2.Cu" "In3.Cu" "In4.Cu" "In5.Cu" "In6.Cu"
			"In7.Cu" "In8.Cu" "In9.Cu" "In10.Cu"
		)
		(hatch none 0.5)
		(connect_pads
			(clearance 0)
		)
		(min_thickness 0.25)
		(keepout
			(tracks not_allowed)
			(vias allowed)
			(pads allowed)
			(copperpour not_allowed)
			(footprints allowed)
		)
		(placement
			(enabled no)
			(sheetname "")
		)
		(fill
			(thermal_gap 0.5)
			(thermal_bridge_width 0.5)
			(island_removal_mode 0)
		)
		(polygon
			(pts
				(arc
					(start 15.397988 -109.162342)
					(mid 15.016988 -109.543342)
					(end 15.397988 -109.924342)
				)
				(arc
					(start 16.286988 -109.924342)
					(mid 16.667988 -109.543342)
					(end 16.286988 -109.162342)
				)
			)
		)
	)
	(zone
		(layers "F.Cu" "B.Cu" "In1.Cu" "In2.Cu" "In3.Cu" "In4.Cu" "In5.Cu" "In6.Cu"
			"In7.Cu" "In8.Cu" "In9.Cu" "In10.Cu"
		)
		(hatch none 0.5)
		(connect_pads
			(clearance 0)
		)
		(min_thickness 0.25)
		(keepout
			(tracks not_allowed)
			(vias allowed)
			(pads allowed)
			(copperpour not_allowed)
			(footprints allowed)
		)
		(placement
			(enabled no)
			(sheetname "")
		)
		(fill
			(thermal_gap 0.5)
			(thermal_bridge_width 0.5)
			(island_removal_mode 0)
		)
		(polygon
			(pts
				(arc
					(start 20.82546 -113.43259)
					(mid 20.44446 -113.81359)
					(end 20.82546 -114.19459)
				)
				(arc
					(start 21.71446 -114.19459)
					(mid 22.09546 -113.81359)
					(end 21.71446 -113.43259)
				)
			)
		)
	)
	(zone
		(layers "F.Cu" "B.Cu" "In1.Cu" "In2.Cu" "In3.Cu" "In4.Cu" "In5.Cu" "In6.Cu"
			"In7.Cu" "In8.Cu" "In9.Cu" "In10.Cu"
		)
		(hatch none 0.5)
		(connect_pads
			(clearance 0)
		)
		(min_thickness 0.25)
		(keepout
			(tracks not_allowed)
			(vias allowed)
			(pads allowed)
			(copperpour not_allowed)
			(footprints allowed)
		)
		(placement
			(enabled no)
			(sheetname "")
		)
		(fill
			(thermal_gap 0.5)
			(thermal_bridge_width 0.5)
			(island_removal_mode 0)
		)
		(polygon
			(pts
				(arc
					(start 64.824102 -26.568146)
					(mid 64.443102 -26.949146)
					(end 64.824102 -27.330146)
				)
				(arc
					(start 65.713102 -27.330146)
					(mid 66.094102 -26.949146)
					(end 65.713102 -26.568146)
				)
			)
		)
	)
	(zone
		(layers "F.Cu" "B.Cu" "In1.Cu" "In2.Cu" "In3.Cu" "In4.Cu" "In5.Cu" "In6.Cu"
			"In7.Cu" "In8.Cu" "In9.Cu" "In10.Cu"
		)
		(hatch none 0.5)
		(connect_pads
			(clearance 0)
		)
		(min_thickness 0.25)
		(keepout
			(tracks not_allowed)
			(vias allowed)
			(pads allowed)
			(copperpour not_allowed)
			(footprints allowed)
		)
		(placement
			(enabled no)
			(sheetname "")
		)
		(fill
			(thermal_gap 0.5)
			(thermal_bridge_width 0.5)
			(island_removal_mode 0)
		)
		(polygon
			(pts
				(arc
					(start 67.83832 -54.887622)
					(mid 68.21932 -54.506622)
					(end 67.83832 -54.125622)
				)
				(arc
					(start 66.94932 -54.125622)
					(mid 66.56832 -54.506622)
					(end 66.94932 -54.887622)
				)
			)
		)
	)
	(zone
		(layers "F.Cu" "B.Cu" "In1.Cu" "In2.Cu" "In3.Cu" "In4.Cu" "In5.Cu" "In6.Cu"
			"In7.Cu" "In8.Cu" "In9.Cu" "In10.Cu"
		)
		(hatch none 0.5)
		(connect_pads
			(clearance 0)
		)
		(min_thickness 0.25)
		(keepout
			(tracks not_allowed)
			(vias allowed)
			(pads allowed)
			(copperpour not_allowed)
			(footprints allowed)
		)
		(placement
			(enabled no)
			(sheetname "")
		)
		(fill
			(thermal_gap 0.5)
			(thermal_bridge_width 0.5)
			(island_removal_mode 0)
		)
		(polygon
			(pts
				(arc
					(start 56.19115 -104.5591)
					(mid 56.57215 -104.1781)
					(end 56.19115 -103.7971)
				)
				(arc
					(start 55.30215 -103.7971)
					(mid 54.92115 -104.1781)
					(end 55.30215 -104.5591)
				)
			)
		)
	)
	(zone
		(layers "F.Cu" "B.Cu" "In1.Cu" "In2.Cu" "In3.Cu" "In4.Cu" "In5.Cu" "In6.Cu"
			"In7.Cu" "In8.Cu" "In9.Cu" "In10.Cu"
		)
		(name "Route Keepin")
		(hatch none 0.5)
		(connect_pads
			(clearance 0)
		)
		(min_thickness 0.25)
		(keepout
			(tracks allowed)
			(vias allowed)
			(pads allowed)
			(copperpour allowed)
			(footprints allowed)
		)
		(placement
			(enabled no)
			(sheetname "")
		)
		(fill
			(thermal_gap 0.5)
			(thermal_bridge_width 0.5)
			(island_removal_mode 0)
		)
		(polygon
			(pts
				(xy 83.974686 -119.892064) (xy 84.492084 -118.995952)
				(arc
					(start 84.492084 -114.799872)
					(mid 84.787357 -114.087273)
					(end 85.499956 -113.792)
				)
				(arc
					(start 88.000078 -113.792)
					(mid 89.055078 -113.355004)
					(end 89.492074 -112.300004)
				)
				(xy 89.492074 -95.164656) (xy 92.50807 -95.164656)
				(arc
					(start 92.50807 -118.400068)
					(mid 92.945066 -119.455068)
					(end 94.000066 -119.892064)
				)
				(arc
					(start 121.000012 -119.892064)
					(mid 122.055012 -119.455068)
					(end 122.492008 -118.400068)
				)
				(arc
					(start 122.492008 129.499868)
					(mid 122.055012 130.554868)
					(end 121.000012 130.991864)
				)
				(arc
					(start 94.000066 130.991864)
					(mid 92.945066 130.554868)
					(end 92.50807 129.499868)
				)
				(xy 92.50807 -93.781372) (xy 89.492074 -93.781372) (xy 89.492074 -85.508084)
				(arc
					(start 87.749888 -85.508084)
					(mid 87.037379 -85.212795)
					(end 86.742016 -84.500212)
				)
				(arc
					(start 86.742016 -81.999836)
					(mid 87.037289 -81.287237)
					(end 87.749888 -80.991964)
				)
				(xy 89.492074 -80.991964)
				(arc
					(start 89.492074 -1.999996)
					(mid 89.055078 -0.944996)
					(end 88.000078 -0.508)
				)
				(arc
					(start 1.999996 -0.508)
					(mid 0.944996 -0.944996)
					(end 0.508 -1.999996)
				)
				(xy 0.508 -80.991964)
				(arc
					(start 2.249932 -80.991964)
					(mid 2.962785 -81.287237)
					(end 3.258058 -82.00009)
				)
				(arc
					(start 3.258058 -84.499958)
					(mid 2.962785 -85.212811)
					(end 2.249932 -85.508084)
				)
				(xy 0.508 -85.508084) (xy 0.508 -94.033086) (xy -2.507996 -94.033086)
				(arc
					(start -2.507996 -6.59003)
					(mid -2.944992 -5.53503)
					(end -3.999992 -5.098034)
				)
				(arc
					(start -17.78 -5.098034)
					(mid -18.835 -5.53503)
					(end -19.271996 -6.59003)
				)
				(arc
					(start -19.271996 -118.400068)
					(mid -18.835 -119.455068)
					(end -17.78 -119.892064)
				)
				(arc
					(start -3.999992 -119.892064)
					(mid -2.944992 -119.455068)
					(end -2.507996 -118.400068)
				)
				(xy -2.507996 -95.22841) (xy 0.508 -95.22841)
				(arc
					(start 0.508 -112.300004)
					(mid 0.944996 -113.355004)
					(end 1.999996 -113.792)
				)
				(arc
					(start 4.500118 -113.792)
					(mid 5.212717 -114.087273)
					(end 5.50799 -114.799872)
				)
				(xy 5.50799 -118.995952) (xy 6.025388 -119.892064) (xy 9.804654 -119.892064) (xy 10.257028 -119.43969)
				(arc
					(start 10.257028 -114.799872)
					(mid 10.552301 -114.087273)
					(end 11.2649 -113.792)
				)
				(arc
					(start 12.765024 -113.792)
					(mid 13.477623 -114.087273)
					(end 13.772896 -114.799872)
				)
				(xy 13.772896 -119.43969) (xy 14.22527 -119.892064) (xy 30.664658 -119.892064) (xy 31.117032 -119.43969)
				(arc
					(start 31.117032 -114.77498)
					(mid 32.999934 -112.892078)
					(end 34.88309 -114.77498)
				)
				(xy 34.88309 -119.43969) (xy 35.335464 -119.892064) (xy 43.374564 -119.892064) (xy 43.826938 -119.43969)
				(arc
					(start 43.826938 -114.324892)
					(mid 45.260006 -112.891824)
					(end 46.693074 -114.324892)
				)
				(xy 46.693074 -119.43969) (xy 47.145448 -119.892064) (xy 63.574676 -119.892064) (xy 64.02705 -119.43969)
				(arc
					(start 64.02705 -114.525044)
					(mid 65.660016 -112.892078)
					(end 67.292982 -114.525044)
				)
				(xy 67.292982 -119.43969) (xy 67.745356 -119.892064) (xy 75.77963 -119.892064) (xy 76.232004 -119.43969)
				(arc
					(start 76.232004 -114.799872)
					(mid 76.527277 -114.087273)
					(end 77.239876 -113.792)
				)
				(arc
					(start 78.74 -113.792)
					(mid 79.452853 -114.087273)
					(end 79.748126 -114.800126)
				)
				(xy 79.748126 -119.43969) (xy 80.2005 -119.892064)
			)
		)
	)
	(zone
		(layers "F.Cu" "B.Cu" "In1.Cu" "In2.Cu" "In3.Cu" "In4.Cu" "In5.Cu" "In6.Cu"
			"In7.Cu" "In8.Cu" "In9.Cu" "In10.Cu"
		)
		(hatch none 0.5)
		(connect_pads
			(clearance 0)
		)
		(min_thickness 0.25)
		(keepout
			(tracks not_allowed)
			(vias allowed)
			(pads allowed)
			(copperpour not_allowed)
			(footprints allowed)
		)
		(placement
			(enabled no)
			(sheetname "")
		)
		(fill
			(thermal_gap 0.5)
			(thermal_bridge_width 0.5)
			(island_removal_mode 0)
		)
		(polygon
			(pts
				(arc
					(start 64.490092 -58.636154)
					(mid 64.159892 -58.966354)
					(end 64.490092 -59.296554)
				)
				(arc
					(start 65.289938 -59.296554)
					(mid 65.620138 -58.966354)
					(end 65.289938 -58.636154)
				)
			)
		)
	)
	(zone
		(layers "F.Cu" "B.Cu" "In1.Cu" "In2.Cu" "In3.Cu" "In4.Cu" "In5.Cu" "In6.Cu"
			"In7.Cu" "In8.Cu" "In9.Cu" "In10.Cu"
		)
		(hatch none 0.5)
		(connect_pads
			(clearance 0)
		)
		(min_thickness 0.25)
		(keepout
			(tracks not_allowed)
			(vias allowed)
			(pads allowed)
			(copperpour not_allowed)
			(footprints allowed)
		)
		(placement
			(enabled no)
			(sheetname "")
		)
		(fill
			(thermal_gap 0.5)
			(thermal_bridge_width 0.5)
			(island_removal_mode 0)
		)
		(polygon
			(pts
				(arc
					(start 95.494856 -96.54159)
					(mid 95.113856 -96.92259)
					(end 95.494856 -97.30359)
				)
				(arc
					(start 96.358456 -97.30359)
					(mid 96.739456 -96.92259)
					(end 96.358456 -96.54159)
				)
			)
		)
	)
	(zone
		(layers "F.Cu" "B.Cu" "In1.Cu" "In2.Cu" "In3.Cu" "In4.Cu" "In5.Cu" "In6.Cu"
			"In7.Cu" "In8.Cu" "In9.Cu" "In10.Cu"
		)
		(hatch none 0.5)
		(connect_pads
			(clearance 0)
		)
		(min_thickness 0.25)
		(keepout
			(tracks not_allowed)
			(vias allowed)
			(pads allowed)
			(copperpour not_allowed)
			(footprints allowed)
		)
		(placement
			(enabled no)
			(sheetname "")
		)
		(fill
			(thermal_gap 0.5)
			(thermal_bridge_width 0.5)
			(island_removal_mode 0)
		)
		(polygon
			(pts
				(arc
					(start 95.494856 55.234586)
					(mid 95.113856 54.853586)
					(end 95.494856 54.472586)
				)
				(arc
					(start 96.358456 54.472586)
					(mid 96.739456 54.853586)
					(end 96.358456 55.234586)
				)
			)
		)
	)
	(zone
		(layers "F.Cu" "B.Cu" "In1.Cu" "In2.Cu" "In3.Cu" "In4.Cu" "In5.Cu" "In6.Cu"
			"In7.Cu" "In8.Cu" "In9.Cu" "In10.Cu"
		)
		(hatch none 0.5)
		(connect_pads
			(clearance 0)
		)
		(min_thickness 0.25)
		(keepout
			(tracks not_allowed)
			(vias allowed)
			(pads allowed)
			(copperpour not_allowed)
			(footprints allowed)
		)
		(placement
			(enabled no)
			(sheetname "")
		)
		(fill
			(thermal_gap 0.5)
			(thermal_bridge_width 0.5)
			(island_removal_mode 0)
		)
		(polygon
			(pts
				(arc
					(start 95.479616 -16.992346)
					(mid 95.098616 -17.373346)
					(end 95.479616 -17.754346)
				)
				(arc
					(start 96.343216 -17.754346)
					(mid 96.724216 -17.373346)
					(end 96.343216 -16.992346)
				)
			)
		)
	)
	(zone
		(layers "F.Cu" "B.Cu" "In1.Cu" "In2.Cu" "In3.Cu" "In4.Cu" "In5.Cu" "In6.Cu"
			"In7.Cu" "In8.Cu" "In9.Cu" "In10.Cu"
		)
		(hatch none 0.5)
		(connect_pads
			(clearance 0)
		)
		(min_thickness 0.25)
		(keepout
			(tracks not_allowed)
			(vias allowed)
			(pads allowed)
			(copperpour not_allowed)
			(footprints allowed)
		)
		(placement
			(enabled no)
			(sheetname "")
		)
		(fill
			(thermal_gap 0.5)
			(thermal_bridge_width 0.5)
			(island_removal_mode 0)
		)
		(polygon
			(pts
				(xy 79.443834 -120.620536) (xy 84.969858 -120.620536) (xy 84.969858 -118.708678) (xy 84.564982 -118.708678)
				(xy 84.394802 -118.878858) (xy 84.09432 -118.878858) (xy 83.936586 -118.721124) (xy 80.27289 -118.721124)
				(xy 80.169004 -118.82501) (xy 79.853536 -118.82501) (xy 79.638144 -118.609618) (xy 79.443834 -118.609618)
			)
		)
	)
	(zone
		(layers "F.Cu" "B.Cu" "In1.Cu" "In2.Cu" "In3.Cu" "In4.Cu" "In5.Cu" "In6.Cu"
			"In7.Cu" "In8.Cu" "In9.Cu" "In10.Cu"
		)
		(hatch none 0.5)
		(connect_pads
			(clearance 0)
		)
		(min_thickness 0.25)
		(keepout
			(tracks not_allowed)
			(vias allowed)
			(pads allowed)
			(copperpour not_allowed)
			(footprints allowed)
		)
		(placement
			(enabled no)
			(sheetname "")
		)
		(fill
			(thermal_gap 0.5)
			(thermal_bridge_width 0.5)
			(island_removal_mode 0)
		)
		(polygon
			(pts
				(arc
					(start 100.835968 118.289578)
					(mid 100.454968 117.908578)
					(end 100.835968 117.527578)
				)
				(arc
					(start 101.699568 117.527578)
					(mid 102.080568 117.908578)
					(end 101.699568 118.289578)
				)
			)
		)
	)
	(zone
		(layers "F.Cu" "B.Cu" "In1.Cu" "In2.Cu" "In3.Cu" "In4.Cu" "In5.Cu" "In6.Cu"
			"In7.Cu" "In8.Cu" "In9.Cu" "In10.Cu"
		)
		(hatch none 0.5)
		(connect_pads
			(clearance 0)
		)
		(min_thickness 0.25)
		(keepout
			(tracks not_allowed)
			(vias allowed)
			(pads allowed)
			(copperpour not_allowed)
			(footprints allowed)
		)
		(placement
			(enabled no)
			(sheetname "")
		)
		(fill
			(thermal_gap 0.5)
			(thermal_bridge_width 0.5)
			(island_removal_mode 0)
		)
		(polygon
			(pts
				(arc
					(start 25.57526 -16.94815)
					(mid 25.95626 -17.32915)
					(end 26.33726 -16.94815)
				)
				(arc
					(start 26.33726 -16.05915)
					(mid 25.95626 -15.67815)
					(end 25.57526 -16.05915)
				)
			)
		)
	)
	(zone
		(layers "F.Cu" "B.Cu" "In1.Cu" "In2.Cu" "In3.Cu" "In4.Cu" "In5.Cu" "In6.Cu"
			"In7.Cu" "In8.Cu" "In9.Cu" "In10.Cu"
		)
		(hatch none 0.5)
		(connect_pads
			(clearance 0)
		)
		(min_thickness 0.25)
		(keepout
			(tracks not_allowed)
			(vias allowed)
			(pads allowed)
			(copperpour not_allowed)
			(footprints allowed)
		)
		(placement
			(enabled no)
			(sheetname "")
		)
		(fill
			(thermal_gap 0.5)
			(thermal_bridge_width 0.5)
			(island_removal_mode 0)
		)
		(polygon
			(pts
				(arc
					(start 18.3261 -107.365546)
					(mid 17.9451 -107.746546)
					(end 18.3261 -108.127546)
				)
				(arc
					(start 19.2151 -108.127546)
					(mid 19.5961 -107.746546)
					(end 19.2151 -107.365546)
				)
			)
		)
	)
	(zone
		(layers "F.Cu" "B.Cu" "In1.Cu" "In2.Cu" "In3.Cu" "In4.Cu" "In5.Cu" "In6.Cu"
			"In7.Cu" "In8.Cu" "In9.Cu" "In10.Cu"
		)
		(hatch none 0.5)
		(connect_pads
			(clearance 0)
		)
		(min_thickness 0.25)
		(keepout
			(tracks not_allowed)
			(vias allowed)
			(pads allowed)
			(copperpour not_allowed)
			(footprints allowed)
		)
		(placement
			(enabled no)
			(sheetname "")
		)
		(fill
			(thermal_gap 0.5)
			(thermal_bridge_width 0.5)
			(island_removal_mode 0)
		)
		(polygon
			(pts
				(arc
					(start 43.014138 -24.074374)
					(mid 42.633138 -24.455374)
					(end 43.014138 -24.836374)
				)
				(arc
					(start 43.903138 -24.836374)
					(mid 44.284138 -24.455374)
					(end 43.903138 -24.074374)
				)
			)
		)
	)
	(zone
		(layers "F.Cu" "B.Cu" "In1.Cu" "In2.Cu" "In3.Cu" "In4.Cu" "In5.Cu" "In6.Cu"
			"In7.Cu" "In8.Cu" "In9.Cu" "In10.Cu"
		)
		(hatch none 0.5)
		(connect_pads
			(clearance 0)
		)
		(min_thickness 0.25)
		(keepout
			(tracks not_allowed)
			(vias allowed)
			(pads allowed)
			(copperpour not_allowed)
			(footprints allowed)
		)
		(placement
			(enabled no)
			(sheetname "")
		)
		(fill
			(thermal_gap 0.5)
			(thermal_bridge_width 0.5)
			(island_removal_mode 0)
		)
		(polygon
			(pts
				(arc
					(start 23.571454 -114.628422)
					(mid 23.190454 -115.009422)
					(end 23.571454 -115.390422)
				)
				(arc
					(start 24.460454 -115.390422)
					(mid 24.841454 -115.009422)
					(end 24.460454 -114.628422)
				)
			)
		)
	)
	(zone
		(layers "F.Cu" "B.Cu" "In1.Cu" "In2.Cu" "In3.Cu" "In4.Cu" "In5.Cu" "In6.Cu"
			"In7.Cu" "In8.Cu" "In9.Cu" "In10.Cu"
		)
		(hatch none 0.5)
		(connect_pads
			(clearance 0)
		)
		(min_thickness 0.25)
		(keepout
			(tracks not_allowed)
			(vias allowed)
			(pads allowed)
			(copperpour not_allowed)
			(footprints allowed)
		)
		(placement
			(enabled no)
			(sheetname "")
		)
		(fill
			(thermal_gap 0.5)
			(thermal_bridge_width 0.5)
			(island_removal_mode 0)
		)
		(polygon
			(pts
				(arc
					(start 63.690246 -57.836308)
					(mid 63.360046 -58.166508)
					(end 63.690246 -58.496708)
				)
				(arc
					(start 64.490092 -58.496708)
					(mid 64.820292 -58.166508)
					(end 64.490092 -57.836308)
				)
			)
		)
	)
	(zone
		(layers "F.Cu" "B.Cu" "In1.Cu" "In2.Cu" "In3.Cu" "In4.Cu" "In5.Cu" "In6.Cu"
			"In7.Cu" "In8.Cu" "In9.Cu" "In10.Cu"
		)
		(hatch none 0.5)
		(connect_pads
			(clearance 0)
		)
		(min_thickness 0.25)
		(keepout
			(tracks not_allowed)
			(vias allowed)
			(pads allowed)
			(copperpour not_allowed)
			(footprints allowed)
		)
		(placement
			(enabled no)
			(sheetname "")
		)
		(fill
			(thermal_gap 0.5)
			(thermal_bridge_width 0.5)
			(island_removal_mode 0)
		)
		(polygon
			(pts
				(arc
					(start 60.92698 -60.019184)
					(mid 60.59678 -60.349384)
					(end 60.92698 -60.679584)
				)
				(arc
					(start 61.726826 -60.679584)
					(mid 62.057026 -60.349384)
					(end 61.726826 -60.019184)
				)
			)
		)
	)
	(zone
		(layers "F.Cu" "B.Cu" "In1.Cu" "In2.Cu" "In3.Cu" "In4.Cu" "In5.Cu" "In6.Cu"
			"In7.Cu" "In8.Cu" "In9.Cu" "In10.Cu"
		)
		(hatch none 0.5)
		(connect_pads
			(clearance 0)
		)
		(min_thickness 0.25)
		(keepout
			(tracks not_allowed)
			(vias allowed)
			(pads allowed)
			(copperpour not_allowed)
			(footprints allowed)
		)
		(placement
			(enabled no)
			(sheetname "")
		)
		(fill
			(thermal_gap 0.5)
			(thermal_bridge_width 0.5)
			(island_removal_mode 0)
		)
		(polygon
			(pts
				(arc
					(start 46.3169 -98.332036)
					(mid 46.6979 -97.951036)
					(end 46.3169 -97.570036)
				)
				(arc
					(start 45.4279 -97.570036)
					(mid 45.0469 -97.951036)
					(end 45.4279 -98.332036)
				)
			)
		)
	)
	(zone
		(layers "F.Cu" "B.Cu" "In1.Cu" "In2.Cu" "In3.Cu" "In4.Cu" "In5.Cu" "In6.Cu"
			"In7.Cu" "In8.Cu" "In9.Cu" "In10.Cu"
		)
		(hatch none 0.5)
		(connect_pads
			(clearance 0)
		)
		(min_thickness 0.25)
		(keepout
			(tracks not_allowed)
			(vias allowed)
			(pads allowed)
			(copperpour not_allowed)
			(footprints allowed)
		)
		(placement
			(enabled no)
			(sheetname "")
		)
		(fill
			(thermal_gap 0.5)
			(thermal_bridge_width 0.5)
			(island_removal_mode 0)
		)
		(polygon
			(pts
				(arc
					(start 28.857956 -46.589188)
					(mid 26.75001 -44.481242)
					(end 24.642064 -46.589188)
				)
				(arc
					(start 24.642064 -48.189134)
					(mid 26.75001 -50.29708)
					(end 28.857956 -48.189134)
				)
			)
		)
	)
	(zone
		(layers "F.Cu" "B.Cu" "In1.Cu" "In2.Cu" "In3.Cu" "In4.Cu" "In5.Cu" "In6.Cu"
			"In7.Cu" "In8.Cu" "In9.Cu" "In10.Cu"
		)
		(hatch none 0.5)
		(connect_pads
			(clearance 0)
		)
		(min_thickness 0.25)
		(keepout
			(tracks not_allowed)
			(vias allowed)
			(pads allowed)
			(copperpour not_allowed)
			(footprints allowed)
		)
		(placement
			(enabled no)
			(sheetname "")
		)
		(fill
			(thermal_gap 0.5)
			(thermal_bridge_width 0.5)
			(island_removal_mode 0)
		)
		(polygon
			(pts
				(arc
					(start 95.479616 111.66983)
					(mid 95.098616 111.28883)
					(end 95.479616 110.90783)
				)
				(arc
					(start 96.343216 110.90783)
					(mid 96.724216 111.28883)
					(end 96.343216 111.66983)
				)
			)
		)
	)
	(zone
		(layers "F.Cu" "B.Cu" "In1.Cu" "In2.Cu" "In3.Cu" "In4.Cu" "In5.Cu" "In6.Cu"
			"In7.Cu" "In8.Cu" "In9.Cu" "In10.Cu"
		)
		(hatch none 0.5)
		(connect_pads
			(clearance 0)
		)
		(min_thickness 0.25)
		(keepout
			(tracks not_allowed)
			(vias allowed)
			(pads allowed)
			(copperpour not_allowed)
			(footprints allowed)
		)
		(placement
			(enabled no)
			(sheetname "")
		)
		(fill
			(thermal_gap 0.5)
			(thermal_bridge_width 0.5)
			(island_removal_mode 0)
		)
		(polygon
			(pts
				(arc
					(start 60.96 -58.166508)
					(mid 61.2902 -58.496708)
					(end 61.6204 -58.166508)
				)
				(arc
					(start 61.6204 -57.366662)
					(mid 61.2902 -57.036462)
					(end 60.96 -57.366662)
				)
			)
		)
	)
	(zone
		(layers "F.Cu" "B.Cu" "In1.Cu" "In2.Cu" "In3.Cu" "In4.Cu" "In5.Cu" "In6.Cu"
			"In7.Cu" "In8.Cu" "In9.Cu" "In10.Cu"
		)
		(hatch none 0.5)
		(connect_pads
			(clearance 0)
		)
		(min_thickness 0.25)
		(keepout
			(tracks not_allowed)
			(vias allowed)
			(pads allowed)
			(copperpour not_allowed)
			(footprints allowed)
		)
		(placement
			(enabled no)
			(sheetname "")
		)
		(fill
			(thermal_gap 0.5)
			(thermal_bridge_width 0.5)
			(island_removal_mode 0)
		)
		(polygon
			(pts
				(arc
					(start 62.0903 -58.636154)
					(mid 61.7601 -58.966354)
					(end 62.0903 -59.296554)
				)
				(arc
					(start 62.890146 -59.296554)
					(mid 63.220346 -58.966354)
					(end 62.890146 -58.636154)
				)
			)
		)
	)
	(zone
		(layers "F.Cu" "B.Cu" "In1.Cu" "In2.Cu" "In3.Cu" "In4.Cu" "In5.Cu" "In6.Cu"
			"In7.Cu" "In8.Cu" "In9.Cu" "In10.Cu"
		)
		(hatch none 0.5)
		(connect_pads
			(clearance 0)
		)
		(min_thickness 0.25)
		(keepout
			(tracks not_allowed)
			(vias allowed)
			(pads allowed)
			(copperpour not_allowed)
			(footprints allowed)
		)
		(placement
			(enabled no)
			(sheetname "")
		)
		(fill
			(thermal_gap 0.5)
			(thermal_bridge_width 0.5)
			(island_removal_mode 0)
		)
		(polygon
			(pts
				(arc
					(start 62.607952 -26.490168)
					(mid 62.226952 -26.871168)
					(end 62.607952 -27.252168)
				)
				(arc
					(start 63.496952 -27.252168)
					(mid 63.877952 -26.871168)
					(end 63.496952 -26.490168)
				)
			)
		)
	)
	(zone
		(layers "F.Cu" "B.Cu" "In1.Cu" "In2.Cu" "In3.Cu" "In4.Cu" "In5.Cu" "In6.Cu"
			"In7.Cu" "In8.Cu" "In9.Cu" "In10.Cu"
		)
		(hatch none 0.5)
		(connect_pads
			(clearance 0)
		)
		(min_thickness 0.25)
		(keepout
			(tracks not_allowed)
			(vias allowed)
			(pads allowed)
			(copperpour not_allowed)
			(footprints allowed)
		)
		(placement
			(enabled no)
			(sheetname "")
		)
		(fill
			(thermal_gap 0.5)
			(thermal_bridge_width 0.5)
			(island_removal_mode 0)
		)
		(polygon
			(pts
				(arc
					(start 40.620442 -24.074374)
					(mid 40.239442 -24.455374)
					(end 40.620442 -24.836374)
				)
				(arc
					(start 41.509442 -24.836374)
					(mid 41.890442 -24.455374)
					(end 41.509442 -24.074374)
				)
			)
		)
	)
	(zone
		(layers "F.Cu" "B.Cu" "In1.Cu" "In2.Cu" "In3.Cu" "In4.Cu" "In5.Cu" "In6.Cu"
			"In7.Cu" "In8.Cu" "In9.Cu" "In10.Cu"
		)
		(hatch none 0.5)
		(connect_pads
			(clearance 0)
		)
		(min_thickness 0.25)
		(keepout
			(tracks not_allowed)
			(vias allowed)
			(pads allowed)
			(copperpour not_allowed)
			(footprints allowed)
		)
		(placement
			(enabled no)
			(sheetname "")
		)
		(fill
			(thermal_gap 0.5)
			(thermal_bridge_width 0.5)
			(island_removal_mode 0)
		)
		(polygon
			(pts
				(arc
					(start 100.85832 31.120334)
					(mid 100.47732 30.739334)
					(end 100.85832 30.358334)
				)
				(arc
					(start 101.72192 30.358334)
					(mid 102.10292 30.739334)
					(end 101.72192 31.120334)
				)
			)
		)
	)
	(zone
		(layers "F.Cu" "B.Cu" "In1.Cu" "In2.Cu" "In3.Cu" "In4.Cu" "In5.Cu" "In6.Cu"
			"In7.Cu" "In8.Cu" "In9.Cu" "In10.Cu"
		)
		(hatch none 0.5)
		(connect_pads
			(clearance 0)
		)
		(min_thickness 0.25)
		(keepout
			(tracks not_allowed)
			(vias allowed)
			(pads allowed)
			(copperpour not_allowed)
			(footprints allowed)
		)
		(placement
			(enabled no)
			(sheetname "")
		)
		(fill
			(thermal_gap 0.5)
			(thermal_bridge_width 0.5)
			(island_removal_mode 0)
		)
		(polygon
			(pts
				(arc
					(start 95.472504 40.988742)
					(mid 95.091504 40.607742)
					(end 95.472504 40.226742)
				)
				(arc
					(start 96.336104 40.226742)
					(mid 96.717104 40.607742)
					(end 96.336104 40.988742)
				)
			)
		)
	)
	(zone
		(layers "F.Cu" "B.Cu" "In1.Cu" "In2.Cu" "In3.Cu" "In4.Cu" "In5.Cu" "In6.Cu"
			"In7.Cu" "In8.Cu" "In9.Cu" "In10.Cu"
		)
		(hatch none 0.5)
		(connect_pads
			(clearance 0)
		)
		(min_thickness 0.25)
		(keepout
			(tracks not_allowed)
			(vias allowed)
			(pads allowed)
			(copperpour not_allowed)
			(footprints allowed)
		)
		(placement
			(enabled no)
			(sheetname "")
		)
		(fill
			(thermal_gap 0.5)
			(thermal_bridge_width 0.5)
			(island_removal_mode 0)
		)
		(polygon
			(pts
				(arc
					(start 38.922198 -14.168882)
					(mid 38.210998 -14.880082)
					(end 38.922198 -15.591282)
				)
				(arc
					(start 40.922194 -15.591282)
					(mid 41.633394 -14.880082)
					(end 40.922194 -14.168882)
				)
			)
		)
	)
	(zone
		(layers "F.Cu" "B.Cu" "In2.Cu" "In4.Cu" "In5.Cu" "In6.Cu" "In7.Cu" "In9.Cu")
		(hatch none 0.5)
		(connect_pads
			(clearance 0)
		)
		(min_thickness 0.25)
		(keepout
			(tracks not_allowed)
			(vias allowed)
			(pads allowed)
			(copperpour not_allowed)
			(footprints allowed)
		)
		(placement
			(enabled no)
			(sheetname "")
		)
		(fill yes
			(thermal_gap 0.5)
			(thermal_bridge_width 0.5)
			(island_removal_mode 0)
		)
		(polygon
			(pts
				(arc
					(start 30.050232 -54.189122)
					(mid 23.450296 -54.189122)
					(end 30.050232 -54.189122)
				)
			)
		)
	)
	(zone
		(layer "B.Cu")
		(hatch none 0.5)
		(connect_pads
			(clearance 0)
		)
		(min_thickness 0.25)
		(keepout
			(tracks allowed)
			(vias allowed)
			(pads allowed)
			(copperpour allowed)
			(footprints not_allowed)
		)
		(placement
			(enabled no)
			(sheetname "")
		)
		(fill
			(thermal_gap 0.5)
			(thermal_bridge_width 0.5)
			(island_removal_mode 0)
		)
		(polygon
			(pts
				(arc
					(start 23.550118 -46.589188)
					(mid 26.75001 -43.389296)
					(end 29.949902 -46.589188)
				)
				(arc
					(start 29.949902 -48.189134)
					(mid 29.626736 -49.590788)
					(end 28.72232 -50.709322)
				)
				(arc
					(start 28.72232 -50.709322)
					(mid 30.20611 -52.175384)
					(end 30.750002 -54.189122)
				)
				(arc
					(start 30.750002 -54.189122)
					(mid 24.736302 -57.645518)
					(end 24.7777 -50.709322)
				)
				(arc
					(start 24.7777 -50.709322)
					(mid 23.873264 -49.590798)
					(end 23.550118 -48.189134)
				)
			)
		)
		(polygon
			(pts
				(arc
					(start 25.150064 -48.189134)
					(mid 26.75001 -49.78908)
					(end 28.349956 -48.189134)
				)
				(arc
					(start 28.349956 -46.589188)
					(mid 26.75001 -44.989242)
					(end 25.150064 -46.589188)
				)
			)
		)
		(polygon
			(pts
				(arc
					(start 26.75001 -56.089296)
					(mid 28.64993 -54.189376)
					(end 26.75001 -52.289202)
				)
				(arc
					(start 26.75001 -52.289202)
					(mid 24.849836 -54.189376)
					(end 26.75001 -56.089296)
				)
			)
		)
	)
	(zone
		(layer "B.Cu")
		(hatch none 0.5)
		(connect_pads
			(clearance 0)
		)
		(min_thickness 0.25)
		(keepout
			(tracks not_allowed)
			(vias allowed)
			(pads allowed)
			(copperpour not_allowed)
			(footprints allowed)
		)
		(placement
			(enabled no)
			(sheetname "")
		)
		(fill
			(thermal_gap 0.5)
			(thermal_bridge_width 0.5)
			(island_removal_mode 0)
		)
		(polygon
			(pts
				(arc
					(start 26.75001 -56.089296)
					(mid 28.64993 -54.189376)
					(end 26.75001 -52.289202)
				)
				(arc
					(start 26.75001 -52.289202)
					(mid 24.849836 -54.189376)
					(end 26.75001 -56.089296)
				)
			)
		)
	)
	(zone
		(layer "B.Cu")
		(hatch none 0.5)
		(connect_pads
			(clearance 0)
		)
		(min_thickness 0.25)
		(keepout
			(tracks allowed)
			(vias allowed)
			(pads allowed)
			(copperpour allowed)
			(footprints not_allowed)
		)
		(placement
			(enabled no)
			(sheetname "")
		)
		(fill
			(thermal_gap 0.5)
			(thermal_bridge_width 0.5)
			(island_removal_mode 0)
		)
		(polygon
			(pts
				(arc
					(start 5.2959 -19.784314)
					(mid 4.443048 -20.171175)
					(end 3.750056 -20.801076)
				)
				(arc
					(start 3.750056 -19.57324)
					(mid 4.517819 -19.71656)
					(end 5.2959 -19.784314)
				)
			)
		)
	)
	(zone
		(layer "B.Cu")
		(hatch none 0.5)
		(connect_pads
			(clearance 0)
		)
		(min_thickness 0.25)
		(keepout
			(tracks not_allowed)
			(vias allowed)
			(pads allowed)
			(copperpour not_allowed)
			(footprints allowed)
		)
		(placement
			(enabled no)
			(sheetname "")
		)
		(fill
			(thermal_gap 0.5)
			(thermal_bridge_width 0.5)
			(island_removal_mode 0)
		)
		(polygon
			(pts
				(arc
					(start 5.599938 -8.539988)
					(mid 2.349754 -11.790172)
					(end 5.599938 -15.040102)
				)
				(arc
					(start 5.599938 -15.040102)
					(mid 8.849868 -11.790172)
					(end 5.599938 -8.539988)
				)
			)
		)
	)
	(zone
		(layer "B.Cu")
		(hatch none 0.5)
		(connect_pads
			(clearance 0)
		)
		(min_thickness 0.25)
		(keepout
			(tracks not_allowed)
			(vias allowed)
			(pads allowed)
			(copperpour not_allowed)
			(footprints allowed)
		)
		(placement
			(enabled no)
			(sheetname "")
		)
		(fill
			(thermal_gap 0.5)
			(thermal_bridge_width 0.5)
			(island_removal_mode 0)
		)
		(polygon
			(pts
				(arc
					(start 7.664958 -22.690074)
					(mid 6.100064 -21.12518)
					(end 4.534916 -22.690074)
				)
				(arc
					(start 4.534916 -22.690074)
					(mid 6.100064 -24.255222)
					(end 7.664958 -22.690074)
				)
			)
		)
	)
	(zone
		(layer "B.Cu")
		(hatch none 0.5)
		(connect_pads
			(clearance 0)
		)
		(min_thickness 0.25)
		(keepout
			(tracks allowed)
			(vias allowed)
			(pads allowed)
			(copperpour allowed)
			(footprints allowed)
		)
		(placement
			(enabled no)
			(sheetname "")
		)
		(fill
			(thermal_gap 0.5)
			(thermal_bridge_width 0.5)
			(island_removal_mode 0)
		)
		(polygon
			(pts
				(xy 41.0718 -94.9706) (xy 41.0718 -93.2688) (xy 42.9768 -93.2688) (xy 42.9768 -94.9706)
			)
		)
	)
	(zone
		(layer "B.Cu")
		(hatch none 0.5)
		(connect_pads
			(clearance 0)
		)
		(min_thickness 0.25)
		(keepout
			(tracks allowed)
			(vias allowed)
			(pads allowed)
			(copperpour allowed)
			(footprints allowed)
		)
		(placement
			(enabled no)
			(sheetname "")
		)
		(fill
			(thermal_gap 0.5)
			(thermal_bridge_width 0.5)
			(island_removal_mode 0)
		)
		(polygon
			(pts
				(xy 15.6464 -118.5672) (xy 15.6464 -115.7478) (xy 15.6464 -114.8334) (xy 18.034 -114.8334) (xy 18.034 -116.2558)
				(xy 16.6116 -116.2558) (xy 16.6116 -118.5672)
			)
		)
	)
	(zone
		(layer "B.Cu")
		(hatch none 0.5)
		(connect_pads
			(clearance 0)
		)
		(min_thickness 0.25)
		(keepout
			(tracks allowed)
			(vias allowed)
			(pads allowed)
			(copperpour allowed)
			(footprints allowed)
		)
		(placement
			(enabled no)
			(sheetname "")
		)
		(fill
			(thermal_gap 0.5)
			(thermal_bridge_width 0.5)
			(island_removal_mode 0)
		)
		(polygon
			(pts
				(xy 74.00417 -79.185262) (xy 74.00417 -76.576936) (xy 76.636372 -76.576936) (xy 76.636372 -79.185262)
			)
		)
	)
	(zone
		(layer "B.Cu")
		(hatch none 0.5)
		(connect_pads
			(clearance 0)
		)
		(min_thickness 0.25)
		(keepout
			(tracks allowed)
			(vias allowed)
			(pads allowed)
			(copperpour allowed)
			(footprints allowed)
		)
		(placement
			(enabled no)
			(sheetname "")
		)
		(fill
			(thermal_gap 0.5)
			(thermal_bridge_width 0.5)
			(island_removal_mode 0)
		)
		(polygon
			(pts
				(xy 13.253466 -101.896672) (xy 13.253466 -84.859114) (xy 30.347412 -84.859114) (xy 30.347412 -101.896672)
			)
		)
	)
	(zone
		(layer "B.Cu")
		(hatch none 0.5)
		(connect_pads
			(clearance 0)
		)
		(min_thickness 0.25)
		(keepout
			(tracks not_allowed)
			(vias allowed)
			(pads allowed)
			(copperpour not_allowed)
			(footprints allowed)
		)
		(placement
			(enabled no)
			(sheetname "")
		)
		(fill
			(thermal_gap 0.5)
			(thermal_bridge_width 0.5)
			(island_removal_mode 0)
		)
		(polygon
			(pts
				(arc
					(start 78.199996 -107.700064)
					(mid 76.499974 -106.000042)
					(end 74.799952 -107.700064)
				)
				(arc
					(start 74.799952 -107.700064)
					(mid 76.499974 -109.400086)
					(end 78.199996 -107.700064)
				)
			)
		)
	)
	(zone
		(layer "B.Cu")
		(hatch none 0.5)
		(connect_pads
			(clearance 0)
		)
		(min_thickness 0.25)
		(keepout
			(tracks not_allowed)
			(vias allowed)
			(pads allowed)
			(copperpour not_allowed)
			(footprints allowed)
		)
		(placement
			(enabled no)
			(sheetname "")
		)
		(fill
			(thermal_gap 0.5)
			(thermal_bridge_width 0.5)
			(island_removal_mode 0)
		)
		(polygon
			(pts
				(arc
					(start 28.349956 -46.589188)
					(mid 26.75001 -44.989242)
					(end 25.150064 -46.589188)
				)
				(arc
					(start 25.150064 -48.189134)
					(mid 26.75001 -49.78908)
					(end 28.349956 -48.189134)
				)
			)
		)
	)
	(zone
		(layer "B.Cu")
		(hatch none 0.5)
		(connect_pads
			(clearance 0)
		)
		(min_thickness 0.25)
		(keepout
			(tracks not_allowed)
			(vias allowed)
			(pads allowed)
			(copperpour not_allowed)
			(footprints allowed)
		)
		(placement
			(enabled no)
			(sheetname "")
		)
		(fill
			(thermal_gap 0.5)
			(thermal_bridge_width 0.5)
			(island_removal_mode 0)
		)
		(polygon
			(pts
				(arc
					(start 24.7777 -50.709322)
					(mid 24.736249 -57.645609)
					(end 30.750002 -54.189122)
				)
				(arc
					(start 30.750002 -54.189122)
					(mid 30.206099 -52.175391)
					(end 28.72232 -50.709322)
				)
				(arc
					(start 28.72232 -50.709322)
					(mid 29.626756 -49.590798)
					(end 29.949902 -48.189134)
				)
				(arc
					(start 29.949902 -46.589188)
					(mid 26.75001 -43.389296)
					(end 23.550118 -46.589188)
				)
				(arc
					(start 23.550118 -48.189134)
					(mid 23.873284 -49.590788)
					(end 24.7777 -50.709322)
				)
			)
		)
	)
	(zone
		(layer "B.Cu")
		(hatch none 0.5)
		(connect_pads
			(clearance 0)
		)
		(min_thickness 0.25)
		(keepout
			(tracks allowed)
			(vias allowed)
			(pads allowed)
			(copperpour allowed)
			(footprints not_allowed)
		)
		(placement
			(enabled no)
			(sheetname "")
		)
		(fill
			(thermal_gap 0.5)
			(thermal_bridge_width 0.5)
			(island_removal_mode 0)
		)
		(polygon
			(pts
				(arc
					(start 0.999998 -1.999996)
					(mid 1.292891 -1.292891)
					(end 1.999996 -0.999998)
				)
				(xy 27.999944 -0.999998) (xy 27.999944 -16.390112) (xy 0.999998 -16.390112)
			)
		)
	)
	(zone
		(layer "B.Cu")
		(hatch none 0.5)
		(connect_pads
			(clearance 0)
		)
		(min_thickness 0.25)
		(keepout
			(tracks allowed)
			(vias allowed)
			(pads allowed)
			(copperpour allowed)
			(footprints not_allowed)
		)
		(placement
			(enabled no)
			(sheetname "")
		)
		(fill
			(thermal_gap 0.5)
			(thermal_bridge_width 0.5)
			(island_removal_mode 0)
		)
		(polygon
			(pts
				(xy 86.250018 -112.300004) (xy 89.000076 -112.300004) (xy 89.000076 -16.390112) (xy 86.250018 -16.390112)
				(arc
					(start 86.250018 -20.801076)
					(mid 86.743943 -21.688751)
					(end 86.91499 -22.690074)
				)
				(arc
					(start 86.91499 -22.690074)
					(mid 86.743887 -23.691263)
					(end 86.250018 -24.578818)
				)
			)
		)
	)
	(zone
		(layer "B.Cu")
		(hatch none 0.5)
		(connect_pads
			(clearance 0)
		)
		(min_thickness 0.25)
		(keepout
			(tracks allowed)
			(vias allowed)
			(pads allowed)
			(copperpour allowed)
			(footprints not_allowed)
		)
		(placement
			(enabled no)
			(sheetname "")
		)
		(fill
			(thermal_gap 0.5)
			(thermal_bridge_width 0.5)
			(island_removal_mode 0)
		)
		(polygon
			(pts
				(xy 75.000104 -16.390112) (xy 27.999944 -16.390112) (xy 27.999944 -0.999998) (xy 75.000104 -0.999998)
			)
		)
	)
	(zone
		(layer "B.Cu")
		(hatch none 0.5)
		(connect_pads
			(clearance 0)
		)
		(min_thickness 0.25)
		(keepout
			(tracks allowed)
			(vias allowed)
			(pads allowed)
			(copperpour allowed)
			(footprints not_allowed)
		)
		(placement
			(enabled no)
			(sheetname "")
		)
		(fill
			(thermal_gap 0.5)
			(thermal_bridge_width 0.5)
			(island_removal_mode 0)
		)
		(polygon
			(pts
				(arc
					(start 86.250018 -20.801076)
					(mid 85.565963 -20.176954)
					(end 84.724748 -19.789902)
				)
				(arc
					(start 84.724748 -19.789902)
					(mid 85.491016 -19.750818)
					(end 86.250018 -19.638518)
				)
			)
		)
	)
	(zone
		(layer "B.Cu")
		(hatch none 0.5)
		(connect_pads
			(clearance 0)
		)
		(min_thickness 0.25)
		(keepout
			(tracks allowed)
			(vias allowed)
			(pads allowed)
			(copperpour allowed)
			(footprints not_allowed)
		)
		(placement
			(enabled no)
			(sheetname "")
		)
		(fill
			(thermal_gap 0.5)
			(thermal_bridge_width 0.5)
			(island_removal_mode 0)
		)
		(polygon
			(pts
				(arc
					(start 9.115044 -22.690074)
					(mid 6.100064 -19.675094)
					(end 3.085084 -22.690074)
				)
				(arc
					(start 3.085084 -22.690074)
					(mid 6.100064 -25.705054)
					(end 9.115044 -22.690074)
				)
			)
		)
		(polygon
			(pts
				(arc
					(start 4.534916 -22.690074)
					(mid 6.100064 -24.255222)
					(end 7.664958 -22.690074)
				)
				(arc
					(start 7.664958 -22.690074)
					(mid 6.100064 -21.12518)
					(end 4.534916 -22.690074)
				)
			)
		)
	)
	(zone
		(layer "B.Cu")
		(hatch none 0.5)
		(connect_pads
			(clearance 0)
		)
		(min_thickness 0.25)
		(keepout
			(tracks allowed)
			(vias allowed)
			(pads allowed)
			(copperpour allowed)
			(footprints not_allowed)
		)
		(placement
			(enabled no)
			(sheetname "")
		)
		(fill
			(thermal_gap 0.5)
			(thermal_bridge_width 0.5)
			(island_removal_mode 0)
		)
		(polygon
			(pts
				(arc
					(start 5.599938 -8.539988)
					(mid 2.349754 -11.790172)
					(end 5.599938 -15.040102)
				)
				(arc
					(start 5.599938 -15.040102)
					(mid 8.849868 -11.790172)
					(end 5.599938 -8.539988)
				)
			)
		)
		(polygon
			(pts
				(arc
					(start 5.599938 -13.390118)
					(mid 7.199884 -11.790172)
					(end 5.599938 -10.189972)
				)
				(arc
					(start 5.599938 -10.189972)
					(mid 3.999738 -11.790172)
					(end 5.599938 -13.390118)
				)
			)
		)
	)
	(zone
		(layer "B.Cu")
		(hatch none 0.5)
		(connect_pads
			(clearance 0)
		)
		(min_thickness 0.25)
		(keepout
			(tracks allowed)
			(vias allowed)
			(pads allowed)
			(copperpour allowed)
			(footprints not_allowed)
		)
		(placement
			(enabled no)
			(sheetname "")
		)
		(fill
			(thermal_gap 0.5)
			(thermal_bridge_width 0.5)
			(island_removal_mode 0)
		)
		(polygon
			(pts
				(arc
					(start 79.499968 -107.700064)
					(mid 76.499974 -104.70007)
					(end 73.49998 -107.700064)
				)
				(arc
					(start 73.49998 -107.700064)
					(mid 76.499974 -110.700058)
					(end 79.499968 -107.700064)
				)
			)
		)
		(polygon
			(pts
				(arc
					(start 74.799952 -107.700064)
					(mid 76.499974 -109.400086)
					(end 78.199996 -107.700064)
				)
				(arc
					(start 78.199996 -107.700064)
					(mid 76.499974 -106.000042)
					(end 74.799952 -107.700064)
				)
			)
		)
	)
	(zone
		(layer "B.Cu")
		(hatch none 0.5)
		(connect_pads
			(clearance 0)
		)
		(min_thickness 0.25)
		(keepout
			(tracks not_allowed)
			(vias allowed)
			(pads allowed)
			(copperpour not_allowed)
			(footprints allowed)
		)
		(placement
			(enabled no)
			(sheetname "")
		)
		(fill
			(thermal_gap 0.5)
			(thermal_bridge_width 0.5)
			(island_removal_mode 0)
		)
		(polygon
			(pts
				(arc
					(start 86.91499 -22.690074)
					(mid 83.90001 -19.675094)
					(end 80.88503 -22.690074)
				)
				(arc
					(start 80.88503 -22.690074)
					(mid 83.90001 -25.705054)
					(end 86.91499 -22.690074)
				)
			)
		)
	)
	(zone
		(layer "B.Cu")
		(hatch none 0.5)
		(connect_pads
			(clearance 0)
		)
		(min_thickness 0.25)
		(keepout
			(tracks allowed)
			(vias allowed)
			(pads allowed)
			(copperpour allowed)
			(footprints allowed)
		)
		(placement
			(enabled no)
			(sheetname "")
		)
		(fill
			(thermal_gap 0.5)
			(thermal_bridge_width 0.5)
			(island_removal_mode 0)
		)
		(polygon
			(pts
				(xy 45.085 -97.5106) (xy 45.085 -96.1644) (xy 46.609 -96.1644) (xy 46.609 -97.5106)
			)
		)
	)
	(zone
		(layer "B.Cu")
		(hatch none 0.5)
		(connect_pads
			(clearance 0)
		)
		(min_thickness 0.25)
		(keepout
			(tracks allowed)
			(vias allowed)
			(pads allowed)
			(copperpour allowed)
			(footprints not_allowed)
		)
		(placement
			(enabled no)
			(sheetname "")
		)
		(fill
			(thermal_gap 0.5)
			(thermal_bridge_width 0.5)
			(island_removal_mode 0)
		)
		(polygon
			(pts
				(arc
					(start 84.70011 -8.539988)
					(mid 81.449926 -11.790172)
					(end 84.70011 -15.040102)
				)
				(arc
					(start 84.70011 -15.040102)
					(mid 87.95004 -11.790172)
					(end 84.70011 -8.539988)
				)
			)
		)
		(polygon
			(pts
				(arc
					(start 84.70011 -13.390118)
					(mid 86.300056 -11.790172)
					(end 84.70011 -10.189972)
				)
				(arc
					(start 84.70011 -10.189972)
					(mid 83.09991 -11.790172)
					(end 84.70011 -13.390118)
				)
			)
		)
	)
	(zone
		(layer "B.Cu")
		(hatch none 0.5)
		(connect_pads
			(clearance 0)
		)
		(min_thickness 0.25)
		(keepout
			(tracks allowed)
			(vias allowed)
			(pads allowed)
			(copperpour allowed)
			(footprints not_allowed)
		)
		(placement
			(enabled no)
			(sheetname "")
		)
		(fill
			(thermal_gap 0.5)
			(thermal_bridge_width 0.5)
			(island_removal_mode 0)
		)
		(polygon
			(pts
				(arc
					(start 62.999874 -107.700064)
					(mid 59.99988 -104.70007)
					(end 56.999886 -107.700064)
				)
				(arc
					(start 56.999886 -107.700064)
					(mid 59.99988 -110.700058)
					(end 62.999874 -107.700064)
				)
			)
		)
		(polygon
			(pts
				(arc
					(start 58.300112 -107.700064)
					(mid 60.000134 -109.400086)
					(end 61.699902 -107.700064)
				)
				(arc
					(start 61.699902 -107.700064)
					(mid 60.000134 -106.000296)
					(end 58.300112 -107.700064)
				)
			)
		)
	)
	(zone
		(layer "B.Cu")
		(hatch none 0.5)
		(connect_pads
			(clearance 0)
		)
		(min_thickness 0.25)
		(keepout
			(tracks allowed)
			(vias allowed)
			(pads allowed)
			(copperpour allowed)
			(footprints allowed)
		)
		(placement
			(enabled no)
			(sheetname "")
		)
		(fill
			(thermal_gap 0.5)
			(thermal_bridge_width 0.5)
			(island_removal_mode 0)
		)
		(polygon
			(pts
				(xy 14.0462 -118.491) (xy 14.0462 -116.5098) (xy 14.859 -116.5098) (xy 14.859 -118.491)
			)
		)
	)
	(zone
		(layer "B.Cu")
		(hatch none 0.5)
		(connect_pads
			(clearance 0)
		)
		(min_thickness 0.25)
		(keepout
			(tracks allowed)
			(vias allowed)
			(pads allowed)
			(copperpour allowed)
			(footprints not_allowed)
		)
		(placement
			(enabled no)
			(sheetname "")
		)
		(fill
			(thermal_gap 0.5)
			(thermal_bridge_width 0.5)
			(island_removal_mode 0)
		)
		(polygon
			(pts
				(arc
					(start 86.91499 -22.690074)
					(mid 83.90001 -19.675094)
					(end 80.88503 -22.690074)
				)
				(arc
					(start 80.88503 -22.690074)
					(mid 83.90001 -25.705054)
					(end 86.91499 -22.690074)
				)
			)
		)
		(polygon
			(pts
				(arc
					(start 82.335116 -22.690074)
					(mid 83.90001 -24.254968)
					(end 85.464904 -22.690074)
				)
				(arc
					(start 85.464904 -22.690074)
					(mid 83.90001 -21.12518)
					(end 82.335116 -22.690074)
				)
			)
		)
	)
	(zone
		(layer "B.Cu")
		(hatch none 0.5)
		(connect_pads
			(clearance 0)
		)
		(min_thickness 0.25)
		(keepout
			(tracks allowed)
			(vias allowed)
			(pads allowed)
			(copperpour allowed)
			(footprints allowed)
		)
		(placement
			(enabled no)
			(sheetname "")
		)
		(fill
			(thermal_gap 0.5)
			(thermal_bridge_width 0.5)
			(island_removal_mode 0)
		)
		(polygon
			(pts
				(xy 72.3265 -54.697122) (xy 72.3265 -49.073054) (xy 71.971916 -48.71847) (xy 71.971916 -47.750984)
				(xy 72.3265 -47.3964) (xy 72.3265 -47.201582) (xy 72.3265 -46.098714) (xy 72.3265 -45.39615) (xy 72.324722 -45.394372)
				(xy 72.3265 -45.392594) (xy 72.3265 -45.277278) (xy 72.3265 -40.783002) (xy 80.223868 -40.783002)
				(xy 80.28178 -40.840914) (xy 80.28178 -48.45939) (xy 80.28178 -54.697122) (xy 79.661512 -54.697122)
				(xy 79.614268 -54.744366) (xy 79.614268 -55.304436) (xy 79.57058 -55.348124) (xy 79.556864 -55.36184)
				(xy 79.234538 -55.684166) (xy 78.606396 -55.684166) (xy 78.272894 -55.350664) (xy 78.272894 -55.003954)
				(xy 77.966062 -54.697122)
			)
		)
	)
	(zone
		(layer "B.Cu")
		(hatch none 0.5)
		(connect_pads
			(clearance 0)
		)
		(min_thickness 0.25)
		(keepout
			(tracks allowed)
			(vias allowed)
			(pads allowed)
			(copperpour allowed)
			(footprints not_allowed)
		)
		(placement
			(enabled no)
			(sheetname "")
		)
		(fill
			(thermal_gap 0.5)
			(thermal_bridge_width 0.5)
			(island_removal_mode 0)
		)
		(polygon
			(pts
				(arc
					(start 78.154784 -16.390112)
					(mid 81.720727 -19.214727)
					(end 86.250018 -19.638518)
				)
				(xy 86.250018 -16.390112)
			)
		)
	)
	(zone
		(layer "B.Cu")
		(hatch none 0.5)
		(connect_pads
			(clearance 0)
		)
		(min_thickness 0.25)
		(keepout
			(tracks not_allowed)
			(vias allowed)
			(pads allowed)
			(copperpour not_allowed)
			(footprints allowed)
		)
		(placement
			(enabled no)
			(sheetname "")
		)
		(fill
			(thermal_gap 0.5)
			(thermal_bridge_width 0.5)
			(island_removal_mode 0)
		)
		(polygon
			(pts
				(arc
					(start 58.300112 -107.700064)
					(mid 60.000134 -109.400086)
					(end 61.699902 -107.700064)
				)
				(arc
					(start 61.699902 -107.700064)
					(mid 60.000134 -106.000296)
					(end 58.300112 -107.700064)
				)
			)
		)
	)
	(zone
		(layer "B.Cu")
		(hatch none 0.5)
		(connect_pads
			(clearance 0)
		)
		(min_thickness 0.25)
		(keepout
			(tracks allowed)
			(vias allowed)
			(pads allowed)
			(copperpour allowed)
			(footprints allowed)
		)
		(placement
			(enabled no)
			(sheetname "")
		)
		(fill
			(thermal_gap 0.5)
			(thermal_bridge_width 0.5)
			(island_removal_mode 0)
		)
		(polygon
			(pts
				(xy 55.9816 -118.6688) (xy 55.9816 -116.205) (xy 56.769 -116.205) (xy 56.769 -118.6688)
			)
		)
	)
	(zone
		(layer "B.Cu")
		(hatch none 0.5)
		(connect_pads
			(clearance 0)
		)
		(min_thickness 0.25)
		(keepout
			(tracks allowed)
			(vias allowed)
			(pads allowed)
			(copperpour allowed)
			(footprints allowed)
		)
		(placement
			(enabled no)
			(sheetname "")
		)
		(fill
			(thermal_gap 0.5)
			(thermal_bridge_width 0.5)
			(island_removal_mode 0)
		)
		(polygon
			(pts
				(xy 65.526412 -40.197786) (xy 65.526412 -44.294044) (xy 65.526412 -48.812704) (xy 65.526412 -60.204604)
				(xy 44.190412 -60.204604) (xy 43.944286 -59.958478) (xy 43.944286 -43.455844) (xy 43.77055 -43.282108)
				(xy 43.318938 -42.830496) (xy 43.318938 -42.177716) (xy 43.318938 -39.791386) (xy 43.321732 -39.788592)
				(xy 43.321732 -39.09949) (xy 43.321732 -38.780974) (xy 43.772328 -38.330378) (xy 59.574176 -38.330378)
				(xy 60.158376 -38.330378) (xy 60.696602 -38.868604) (xy 64.6176 -38.868604) (xy 65.532 -39.783004)
				(xy 65.532 -40.192452)
			)
		)
	)
	(zone
		(layer "B.Cu")
		(hatch none 0.5)
		(connect_pads
			(clearance 0)
		)
		(min_thickness 0.25)
		(keepout
			(tracks not_allowed)
			(vias allowed)
			(pads allowed)
			(copperpour not_allowed)
			(footprints allowed)
		)
		(placement
			(enabled no)
			(sheetname "")
		)
		(fill
			(thermal_gap 0.5)
			(thermal_bridge_width 0.5)
			(island_removal_mode 0)
		)
		(polygon
			(pts
				(arc
					(start 84.70011 -13.390118)
					(mid 86.300056 -11.790172)
					(end 84.70011 -10.189972)
				)
				(arc
					(start 84.70011 -10.189972)
					(mid 83.09991 -11.790172)
					(end 84.70011 -13.390118)
				)
			)
		)
	)
	(zone
		(layer "B.Cu")
		(hatch none 0.5)
		(connect_pads
			(clearance 0)
		)
		(min_thickness 0.25)
		(keepout
			(tracks not_allowed)
			(vias allowed)
			(pads allowed)
			(copperpour not_allowed)
			(footprints allowed)
		)
		(placement
			(enabled no)
			(sheetname "")
		)
		(fill
			(thermal_gap 0.5)
			(thermal_bridge_width 0.5)
			(island_removal_mode 0)
		)
		(polygon
			(pts
				(arc
					(start 5.599938 -13.390118)
					(mid 7.199884 -11.790172)
					(end 5.599938 -10.189972)
				)
				(arc
					(start 5.599938 -10.189972)
					(mid 3.999738 -11.790172)
					(end 5.599938 -13.390118)
				)
			)
		)
	)
	(zone
		(layer "B.Cu")
		(hatch none 0.5)
		(connect_pads
			(clearance 0)
		)
		(min_thickness 0.25)
		(keepout
			(tracks allowed)
			(vias allowed)
			(pads allowed)
			(copperpour allowed)
			(footprints allowed)
		)
		(placement
			(enabled no)
			(sheetname "")
		)
		(fill
			(thermal_gap 0.5)
			(thermal_bridge_width 0.5)
			(island_removal_mode 0)
		)
		(polygon
			(pts
				(xy 39.9034 -91.7956) (xy 39.9034 -89.6112) (xy 43.6626 -89.6112) (xy 43.6626 -91.7956)
			)
		)
	)
	(zone
		(layer "B.Cu")
		(hatch none 0.5)
		(connect_pads
			(clearance 0)
		)
		(min_thickness 0.25)
		(keepout
			(tracks not_allowed)
			(vias allowed)
			(pads allowed)
			(copperpour not_allowed)
			(footprints allowed)
		)
		(placement
			(enabled no)
			(sheetname "")
		)
		(fill
			(thermal_gap 0.5)
			(thermal_bridge_width 0.5)
			(island_removal_mode 0)
		)
		(polygon
			(pts
				(arc
					(start 9.115044 -22.690074)
					(mid 6.100064 -19.675094)
					(end 3.085084 -22.690074)
				)
				(arc
					(start 3.085084 -22.690074)
					(mid 6.100064 -25.705054)
					(end 9.115044 -22.690074)
				)
			)
		)
	)
	(zone
		(layer "B.Cu")
		(hatch none 0.5)
		(connect_pads
			(clearance 0)
		)
		(min_thickness 0.25)
		(keepout
			(tracks not_allowed)
			(vias allowed)
			(pads allowed)
			(copperpour not_allowed)
			(footprints allowed)
		)
		(placement
			(enabled no)
			(sheetname "")
		)
		(fill
			(thermal_gap 0.5)
			(thermal_bridge_width 0.5)
			(island_removal_mode 0)
		)
		(polygon
			(pts
				(arc
					(start 62.999874 -107.700064)
					(mid 59.99988 -104.70007)
					(end 56.999886 -107.700064)
				)
				(arc
					(start 56.999886 -107.700064)
					(mid 59.99988 -110.700058)
					(end 62.999874 -107.700064)
				)
			)
		)
	)
	(zone
		(layer "B.Cu")
		(hatch none 0.5)
		(connect_pads
			(clearance 0)
		)
		(min_thickness 0.25)
		(keepout
			(tracks not_allowed)
			(vias allowed)
			(pads allowed)
			(copperpour not_allowed)
			(footprints allowed)
		)
		(placement
			(enabled no)
			(sheetname "")
		)
		(fill
			(thermal_gap 0.5)
			(thermal_bridge_width 0.5)
			(island_removal_mode 0)
		)
		(polygon
			(pts
				(arc
					(start 85.464904 -22.690074)
					(mid 83.90001 -21.12518)
					(end 82.335116 -22.690074)
				)
				(arc
					(start 82.335116 -22.690074)
					(mid 83.90001 -24.254968)
					(end 85.464904 -22.690074)
				)
			)
		)
	)
	(zone
		(layer "B.Cu")
		(hatch none 0.5)
		(connect_pads
			(clearance 0)
		)
		(min_thickness 0.25)
		(keepout
			(tracks allowed)
			(vias allowed)
			(pads allowed)
			(copperpour allowed)
			(footprints allowed)
		)
		(placement
			(enabled no)
			(sheetname "")
		)
		(fill
			(thermal_gap 0.5)
			(thermal_bridge_width 0.5)
			(island_removal_mode 0)
		)
		(polygon
			(pts
				(xy 54.1528 -118.6434) (xy 54.1528 -116.205) (xy 54.9656 -116.205) (xy 54.9656 -118.6434)
			)
		)
	)
	(zone
		(layer "B.Cu")
		(hatch none 0.5)
		(connect_pads
			(clearance 0)
		)
		(min_thickness 0.25)
		(keepout
			(tracks allowed)
			(vias allowed)
			(pads allowed)
			(copperpour allowed)
			(footprints allowed)
		)
		(placement
			(enabled no)
			(sheetname "")
		)
		(fill
			(thermal_gap 0.5)
			(thermal_bridge_width 0.5)
			(island_removal_mode 0)
		)
		(polygon
			(pts
				(xy 74.02322 -79.114904) (xy 74.074528 -79.063596) (xy 76.59624 -79.063596) (xy 76.81341 -79.280766)
				(xy 76.81341 -80.061054) (xy 76.766928 -80.107536) (xy 75.312778 -80.107536) (xy 74.887582 -80.532732)
				(xy 74.887582 -80.594708) (xy 74.529188 -80.953102) (xy 73.879202 -80.953102) (xy 73.759822 -80.833722)
				(xy 73.759822 -79.378302)
			)
		)
	)
	(zone
		(layer "B.Cu")
		(hatch none 0.5)
		(connect_pads
			(clearance 0)
		)
		(min_thickness 0.25)
		(keepout
			(tracks allowed)
			(vias allowed)
			(pads allowed)
			(copperpour allowed)
			(footprints not_allowed)
		)
		(placement
			(enabled no)
			(sheetname "")
		)
		(fill
			(thermal_gap 0.5)
			(thermal_bridge_width 0.5)
			(island_removal_mode 0)
		)
		(polygon
			(pts
				(arc
					(start 78.154784 -16.390112)
					(mid 80.491943 -18.593912)
					(end 83.50758 -19.700748)
				)
				(arc
					(start 83.50758 -19.700748)
					(mid 81.633599 -20.701745)
					(end 80.88503 -22.690074)
				)
				(arc
					(start 80.88503 -22.690074)
					(mid 82.898812 -25.533963)
					(end 86.250018 -24.578818)
				)
				(xy 86.250018 -107.899962)
				(arc
					(start 79.493364 -107.899962)
					(mid 79.498333 -107.800068)
					(end 79.499968 -107.700064)
				)
				(arc
					(start 79.499968 -107.700064)
					(mid 76.499974 -104.70007)
					(end 73.49998 -107.700064)
				)
				(arc
					(start 73.49998 -107.700064)
					(mid 73.501614 -107.800068)
					(end 73.506584 -107.899962)
				)
				(arc
					(start 62.99327 -107.899962)
					(mid 62.998239 -107.800068)
					(end 62.999874 -107.700064)
				)
				(arc
					(start 62.999874 -107.700064)
					(mid 59.99988 -104.70007)
					(end 56.999886 -107.700064)
				)
				(arc
					(start 56.999886 -107.700064)
					(mid 57.001647 -107.80007)
					(end 57.006744 -107.899962)
				)
				(xy 3.750056 -107.899962)
				(arc
					(start 3.750056 -24.578818)
					(mid 7.10125 -25.53393)
					(end 9.115044 -22.690074)
				)
				(arc
					(start 9.115044 -22.690074)
					(mid 8.413298 -20.756411)
					(end 6.634734 -19.722846)
				)
				(arc
					(start 6.634734 -19.722846)
					(mid 9.7402 -18.635497)
					(end 12.145264 -16.390112)
				)
			)
		)
		(polygon
			(pts
				(arc
					(start 22.750018 -54.189122)
					(mid 26.75001 -58.189114)
					(end 30.750002 -54.189122)
				)
				(arc
					(start 30.750002 -54.189122)
					(mid 30.206099 -52.175391)
					(end 28.72232 -50.709322)
				)
				(arc
					(start 28.72232 -50.709322)
					(mid 29.626756 -49.590798)
					(end 29.949902 -48.189134)
				)
				(arc
					(start 29.949902 -46.589188)
					(mid 26.75001 -43.389296)
					(end 23.550118 -46.589188)
				)
				(arc
					(start 23.550118 -48.189134)
					(mid 23.873284 -49.590788)
					(end 24.7777 -50.709322)
				)
				(arc
					(start 24.7777 -50.709322)
					(mid 23.29391 -52.175384)
					(end 22.750018 -54.189122)
				)
			)
		)
	)
	(zone
		(layer "B.Cu")
		(hatch none 0.5)
		(connect_pads
			(clearance 0)
		)
		(min_thickness 0.25)
		(keepout
			(tracks not_allowed)
			(vias allowed)
			(pads allowed)
			(copperpour not_allowed)
			(footprints allowed)
		)
		(placement
			(enabled no)
			(sheetname "")
		)
		(fill
			(thermal_gap 0.5)
			(thermal_bridge_width 0.5)
			(island_removal_mode 0)
		)
		(polygon
			(pts
				(arc
					(start 30.750002 -54.189122)
					(mid 30.206099 -52.175391)
					(end 28.72232 -50.709322)
				)
				(arc
					(start 28.72232 -50.709322)
					(mid 29.626756 -49.590798)
					(end 29.949902 -48.189134)
				)
				(arc
					(start 29.949902 -46.589188)
					(mid 26.75001 -43.389296)
					(end 23.550118 -46.589188)
				)
				(arc
					(start 23.550118 -48.189134)
					(mid 23.873284 -49.590788)
					(end 24.7777 -50.709322)
				)
				(arc
					(start 24.7777 -50.709322)
					(mid 24.736249 -57.645609)
					(end 30.750002 -54.189122)
				)
			)
		)
		(polygon
			(pts
				(arc
					(start 25.150064 -48.189134)
					(mid 26.75001 -49.78908)
					(end 28.349956 -48.189134)
				)
				(arc
					(start 28.349956 -46.589188)
					(mid 26.75001 -44.989242)
					(end 25.150064 -46.589188)
				)
			)
		)
		(polygon
			(pts
				(arc
					(start 26.75001 -56.089296)
					(mid 28.64993 -54.189376)
					(end 26.75001 -52.289202)
				)
				(arc
					(start 26.75001 -52.289202)
					(mid 24.849836 -54.189376)
					(end 26.75001 -56.089296)
				)
			)
		)
	)
	(zone
		(layer "B.Cu")
		(hatch none 0.5)
		(connect_pads
			(clearance 0)
		)
		(min_thickness 0.25)
		(keepout
			(tracks not_allowed)
			(vias allowed)
			(pads allowed)
			(copperpour not_allowed)
			(footprints allowed)
		)
		(placement
			(enabled no)
			(sheetname "")
		)
		(fill
			(thermal_gap 0.5)
			(thermal_bridge_width 0.5)
			(island_removal_mode 0)
		)
		(polygon
			(pts
				(arc
					(start 84.70011 -8.539988)
					(mid 81.449926 -11.790172)
					(end 84.70011 -15.040102)
				)
				(arc
					(start 84.70011 -15.040102)
					(mid 87.95004 -11.790172)
					(end 84.70011 -8.539988)
				)
			)
		)
	)
	(zone
		(layer "B.Cu")
		(hatch none 0.5)
		(connect_pads
			(clearance 0)
		)
		(min_thickness 0.25)
		(keepout
			(tracks not_allowed)
			(vias allowed)
			(pads allowed)
			(copperpour not_allowed)
			(footprints allowed)
		)
		(placement
			(enabled no)
			(sheetname "")
		)
		(fill
			(thermal_gap 0.5)
			(thermal_bridge_width 0.5)
			(island_removal_mode 0)
		)
		(polygon
			(pts
				(arc
					(start 79.499968 -107.700064)
					(mid 76.499974 -104.70007)
					(end 73.49998 -107.700064)
				)
				(arc
					(start 73.49998 -107.700064)
					(mid 76.499974 -110.700058)
					(end 79.499968 -107.700064)
				)
			)
		)
	)
	(zone
		(layer "B.Cu")
		(hatch none 0.5)
		(connect_pads
			(clearance 0)
		)
		(min_thickness 0.25)
		(keepout
			(tracks allowed)
			(vias allowed)
			(pads allowed)
			(copperpour allowed)
			(footprints not_allowed)
		)
		(placement
			(enabled no)
			(sheetname "")
		)
		(fill
			(thermal_gap 0.5)
			(thermal_bridge_width 0.5)
			(island_removal_mode 0)
		)
		(polygon
			(pts
				(arc
					(start 12.145264 -16.390112)
					(mid 8.436311 -19.270402)
					(end 3.750056 -19.57324)
				)
				(xy 3.750056 -16.390112)
			)
		)
	)
	(zone
		(layer "B.Cu")
		(hatch none 0.5)
		(connect_pads
			(clearance 0)
		)
		(min_thickness 0.25)
		(keepout
			(tracks allowed)
			(vias allowed)
			(pads allowed)
			(copperpour allowed)
			(footprints allowed)
		)
		(placement
			(enabled no)
			(sheetname "")
		)
		(fill
			(thermal_gap 0.5)
			(thermal_bridge_width 0.5)
			(island_removal_mode 0)
		)
		(polygon
			(pts
				(xy 79.50073 -53.380132) (xy 79.50073 -50.857404) (xy 81.259172 -50.857404) (xy 81.259172 -53.380132)
			)
		)
	)
	(zone
		(layer "B.Cu")
		(hatch none 0.5)
		(connect_pads
			(clearance 0)
		)
		(min_thickness 0.25)
		(keepout
			(tracks allowed)
			(vias allowed)
			(pads allowed)
			(copperpour allowed)
			(footprints allowed)
		)
		(placement
			(enabled no)
			(sheetname "")
		)
		(fill
			(thermal_gap 0.5)
			(thermal_bridge_width 0.5)
			(island_removal_mode 0)
		)
		(polygon
			(pts
				(xy 21.0312 -118.745) (xy 21.0312 -116.4082) (xy 22.098 -116.4082) (xy 22.098 -118.745)
			)
		)
	)
	(zone
		(layer "B.Cu")
		(hatch none 0.5)
		(connect_pads
			(clearance 0)
		)
		(min_thickness 0.25)
		(keepout
			(tracks allowed)
			(vias allowed)
			(pads allowed)
			(copperpour allowed)
			(footprints allowed)
		)
		(placement
			(enabled no)
			(sheetname "")
		)
		(fill
			(thermal_gap 0.5)
			(thermal_bridge_width 0.5)
			(island_removal_mode 0)
		)
		(polygon
			(pts
				(xy 75.5396 -85.2424) (xy 75.5396 -83.8708) (xy 77.1652 -83.8708) (xy 77.1652 -85.2424)
			)
		)
	)
	(zone
		(layer "B.Cu")
		(hatch none 0.5)
		(connect_pads
			(clearance 0)
		)
		(min_thickness 0.25)
		(keepout
			(tracks allowed)
			(vias allowed)
			(pads allowed)
			(copperpour allowed)
			(footprints not_allowed)
		)
		(placement
			(enabled no)
			(sheetname "")
		)
		(fill
			(thermal_gap 0.5)
			(thermal_bridge_width 0.5)
			(island_removal_mode 0)
		)
		(polygon
			(pts
				(xy 0.999998 -112.300004) (xy 0.999998 -16.390112) (xy 3.750056 -16.390112)
				(arc
					(start 3.750056 -20.801076)
					(mid 3.256131 -21.688751)
					(end 3.085084 -22.690074)
				)
				(arc
					(start 3.085084 -22.690074)
					(mid 3.256187 -23.691263)
					(end 3.750056 -24.578818)
				)
				(xy 3.750056 -112.300004)
			)
		)
	)
	(zone
		(layer "B.Cu")
		(hatch none 0.5)
		(connect_pads
			(clearance 0)
		)
		(min_thickness 0.25)
		(keepout
			(tracks allowed)
			(vias allowed)
			(pads allowed)
			(copperpour allowed)
			(footprints allowed)
		)
		(placement
			(enabled no)
			(sheetname "")
		)
		(fill
			(thermal_gap 0.5)
			(thermal_bridge_width 0.5)
			(island_removal_mode 0)
		)
		(polygon
			(pts
				(xy 67.6402 -119.634) (xy 67.6402 -112.8268) (xy 74.1172 -112.8268) (xy 74.1172 -119.634)
			)
		)
	)
	(zone
		(layer "B.Cu")
		(hatch none 0.5)
		(connect_pads
			(clearance 0)
		)
		(min_thickness 0.25)
		(keepout
			(tracks allowed)
			(vias allowed)
			(pads allowed)
			(copperpour allowed)
			(footprints allowed)
		)
		(placement
			(enabled no)
			(sheetname "")
		)
		(fill
			(thermal_gap 0.5)
			(thermal_bridge_width 0.5)
			(island_removal_mode 0)
		)
		(polygon
			(pts
				(xy 73.9648 -85.762592) (xy 73.9648 -84.97697) (xy 74.8665 -84.97697) (xy 74.8665 -85.762592)
			)
		)
	)
	(zone
		(layer "B.Cu")
		(hatch none 0.5)
		(connect_pads
			(clearance 0)
		)
		(min_thickness 0.25)
		(keepout
			(tracks allowed)
			(vias allowed)
			(pads allowed)
			(copperpour allowed)
			(footprints allowed)
		)
		(placement
			(enabled no)
			(sheetname "")
		)
		(fill
			(thermal_gap 0.5)
			(thermal_bridge_width 0.5)
			(island_removal_mode 0)
		)
		(polygon
			(pts
				(xy 80.42783 -39.533322) (xy 82.511138 -39.533322) (xy 82.511138 -49.166018) (xy 80.42783 -49.166018)
				(xy 80.28178 -49.019968) (xy 80.28178 -39.679372)
			)
		)
	)
	(zone
		(layer "B.Cu")
		(hatch none 0.5)
		(connect_pads
			(clearance 0)
		)
		(min_thickness 0.25)
		(keepout
			(tracks allowed)
			(vias allowed)
			(pads allowed)
			(copperpour allowed)
			(footprints allowed)
		)
		(placement
			(enabled no)
			(sheetname "")
		)
		(fill
			(thermal_gap 0.5)
			(thermal_bridge_width 0.5)
			(island_removal_mode 0)
		)
		(polygon
			(pts
				(xy 76.259944 -38.329362) (xy 76.259944 -35.85083) (xy 81.32572 -35.85083) (xy 81.32572 -38.329362)
			)
		)
	)
	(zone
		(layer "B.Cu")
		(hatch none 0.5)
		(connect_pads
			(clearance 0)
		)
		(min_thickness 0.25)
		(keepout
			(tracks allowed)
			(vias allowed)
			(pads allowed)
			(copperpour allowed)
			(footprints allowed)
		)
		(placement
			(enabled no)
			(sheetname "")
		)
		(fill
			(thermal_gap 0.5)
			(thermal_bridge_width 0.5)
			(island_removal_mode 0)
		)
		(polygon
			(pts
				(xy 83.514184 -49.142142) (xy 83.514184 -39.865808) (xy 85.137498 -39.865808) (xy 85.137498 -49.142142)
			)
		)
	)
	(zone
		(layer "B.Cu")
		(hatch none 0.5)
		(connect_pads
			(clearance 0)
		)
		(min_thickness 0.25)
		(keepout
			(tracks allowed)
			(vias allowed)
			(pads allowed)
			(copperpour allowed)
			(footprints not_allowed)
		)
		(placement
			(enabled no)
			(sheetname "")
		)
		(fill
			(thermal_gap 0.5)
			(thermal_bridge_width 0.5)
			(island_removal_mode 0)
		)
		(polygon
			(pts
				(xy 3.750056 -107.899962)
				(arc
					(start 57.006744 -107.899962)
					(mid 60.000126 -110.700121)
					(end 62.99327 -107.899962)
				)
				(arc
					(start 73.506584 -107.899962)
					(mid 76.499974 -110.700121)
					(end 79.493364 -107.899962)
				)
				(xy 86.250018 -107.899962) (xy 86.250018 -112.300004)
				(arc
					(start 89.000076 -112.300004)
					(mid 88.707183 -113.007109)
					(end 88.000078 -113.300002)
				)
				(arc
					(start 85.499956 -113.300002)
					(mid 84.439372 -113.739468)
					(end 84.000086 -114.800126)
				)
				(xy 84.000086 -118.864126) (xy 83.690714 -119.400066) (xy 80.404208 -119.400066) (xy 80.240124 -119.235728)
				(arc
					(start 80.240124 -114.800126)
					(mid 79.800748 -113.739378)
					(end 78.74 -113.300002)
				)
				(arc
					(start 77.239876 -113.300002)
					(mid 76.179292 -113.739468)
					(end 75.740006 -114.800126)
				)
				(xy 75.740006 -119.235728) (xy 75.575668 -119.400066) (xy 67.949318 -119.400066) (xy 67.78498 -119.235728)
				(arc
					(start 67.78498 -114.525044)
					(mid 65.660016 -112.40008)
					(end 63.535052 -114.525044)
				)
				(xy 63.535052 -119.235728) (xy 63.370714 -119.400066) (xy 47.349156 -119.400066) (xy 47.185072 -119.235728)
				(arc
					(start 47.185072 -114.324892)
					(mid 45.260006 -112.399826)
					(end 43.33494 -114.324892)
				)
				(xy 43.33494 -119.235728) (xy 43.170856 -119.400066) (xy 35.539172 -119.400066) (xy 35.375088 -119.235728)
				(arc
					(start 35.375088 -114.77498)
					(mid 33.000188 -112.40008)
					(end 30.625034 -114.77498)
				)
				(xy 30.625034 -119.235728) (xy 30.460696 -119.400066) (xy 14.429232 -119.400066) (xy 14.264894 -119.235728)
				(arc
					(start 14.264894 -114.800126)
					(mid 13.825592 -113.739558)
					(end 12.765024 -113.300002)
				)
				(arc
					(start 11.2649 -113.300002)
					(mid 10.204316 -113.739468)
					(end 9.76503 -114.800126)
				)
				(xy 9.76503 -119.235728) (xy 9.600692 -119.400066) (xy 6.30936 -119.400066) (xy 5.999988 -118.864126)
				(arc
					(start 5.999988 -114.800126)
					(mid 5.560686 -113.739558)
					(end 4.500118 -113.300002)
				)
				(arc
					(start 1.999996 -113.300002)
					(mid 1.292891 -113.007109)
					(end 0.999998 -112.300004)
				)
				(xy 3.750056 -112.300004)
			)
		)
	)
	(zone
		(layer "B.Cu")
		(hatch none 0.5)
		(connect_pads
			(clearance 0)
		)
		(min_thickness 0.25)
		(keepout
			(tracks allowed)
			(vias allowed)
			(pads allowed)
			(copperpour allowed)
			(footprints allowed)
		)
		(placement
			(enabled no)
			(sheetname "")
		)
		(fill
			(thermal_gap 0.5)
			(thermal_bridge_width 0.5)
			(island_removal_mode 0)
		)
		(polygon
			(pts
				(xy 19.2532 -118.6942) (xy 19.2532 -116.459) (xy 20.1676 -116.459) (xy 20.1676 -118.6942)
			)
		)
	)
	(zone
		(layer "B.Cu")
		(hatch none 0.5)
		(connect_pads
			(clearance 0)
		)
		(min_thickness 0.25)
		(keepout
			(tracks allowed)
			(vias allowed)
			(pads allowed)
			(copperpour allowed)
			(footprints not_allowed)
		)
		(placement
			(enabled no)
			(sheetname "")
		)
		(fill
			(thermal_gap 0.5)
			(thermal_bridge_width 0.5)
			(island_removal_mode 0)
		)
		(polygon
			(pts
				(xy 75.000104 -0.999998)
				(arc
					(start 88.000078 -0.999998)
					(mid 88.707183 -1.292891)
					(end 89.000076 -1.999996)
				)
				(xy 89.000076 -16.390112) (xy 75.000104 -16.390112)
			)
		)
	)
	(zone
		(layer "In1.Cu")
		(hatch none 0.5)
		(connect_pads
			(clearance 0)
		)
		(min_thickness 0.25)
		(keepout
			(tracks not_allowed)
			(vias allowed)
			(pads allowed)
			(copperpour not_allowed)
			(footprints allowed)
		)
		(placement
			(enabled no)
			(sheetname "")
		)
		(fill
			(thermal_gap 0.5)
			(thermal_bridge_width 0.5)
			(island_removal_mode 0)
		)
		(polygon
			(pts
				(xy 101.9048 -103.651304) (xy 101.9048 -104.415844) (xy 100.65512 -104.415844) (xy 100.65512 -103.651304)
			)
		)
	)
	(zone
		(layer "In1.Cu")
		(hatch none 0.5)
		(connect_pads
			(clearance 0)
		)
		(min_thickness 0.25)
		(keepout
			(tracks not_allowed)
			(vias allowed)
			(pads allowed)
			(copperpour not_allowed)
			(footprints allowed)
		)
		(placement
			(enabled no)
			(sheetname "")
		)
		(fill
			(thermal_gap 0.5)
			(thermal_bridge_width 0.5)
			(island_removal_mode 0)
		)
		(polygon
			(pts
				(xy 95.289116 -17.00911) (xy 95.289116 -16.24457) (xy 96.538796 -16.24457) (xy 96.538796 -17.00911)
			)
		)
	)
	(zone
		(layer "In1.Cu")
		(hatch none 0.5)
		(connect_pads
			(clearance 0)
		)
		(min_thickness 0.25)
		(keepout
			(tracks not_allowed)
			(vias allowed)
			(pads allowed)
			(copperpour not_allowed)
			(footprints allowed)
		)
		(placement
			(enabled no)
			(sheetname "")
		)
		(fill
			(thermal_gap 0.5)
			(thermal_bridge_width 0.5)
			(island_removal_mode 0)
		)
		(polygon
			(pts
				(xy 96.548956 -97.286826) (xy 96.548956 -98.051366) (xy 95.299276 -98.051366) (xy 95.299276 -97.286826)
			)
		)
	)
	(zone
		(layer "In1.Cu")
		(hatch none 0.5)
		(connect_pads
			(clearance 0)
		)
		(min_thickness 0.25)
		(keepout
			(tracks not_allowed)
			(vias allowed)
			(pads allowed)
			(copperpour not_allowed)
			(footprints allowed)
		)
		(placement
			(enabled no)
			(sheetname "")
		)
		(fill
			(thermal_gap 0.5)
			(thermal_bridge_width 0.5)
			(island_removal_mode 0)
		)
		(polygon
			(pts
				(xy 103.2002 16.887952) (xy 103.2002 17.652492) (xy 104.44988 17.652492) (xy 104.44988 16.887952)
			)
		)
	)
	(zone
		(layer "In1.Cu")
		(hatch none 0.5)
		(connect_pads
			(clearance 0)
		)
		(min_thickness 0.25)
		(keepout
			(tracks not_allowed)
			(vias allowed)
			(pads allowed)
			(copperpour not_allowed)
			(footprints allowed)
		)
		(placement
			(enabled no)
			(sheetname "")
		)
		(fill
			(thermal_gap 0.5)
			(thermal_bridge_width 0.5)
			(island_removal_mode 0)
		)
		(polygon
			(pts
				(xy 96.548956 -3.491738) (xy 96.548956 -4.256278) (xy 95.299276 -4.256278) (xy 95.299276 -3.491738)
			)
		)
	)
	(zone
		(layer "In1.Cu")
		(hatch none 0.5)
		(connect_pads
			(clearance 0)
		)
		(min_thickness 0.25)
		(keepout
			(tracks not_allowed)
			(vias allowed)
			(pads allowed)
			(copperpour not_allowed)
			(footprints allowed)
		)
		(placement
			(enabled no)
			(sheetname "")
		)
		(fill
			(thermal_gap 0.5)
			(thermal_bridge_width 0.5)
			(island_removal_mode 0)
		)
		(polygon
			(pts
				(xy 95.282004 40.971978) (xy 95.282004 41.736518) (xy 96.531684 41.736518) (xy 96.531684 40.971978)
			)
		)
	)
	(zone
		(layer "In1.Cu")
		(hatch none 0.5)
		(connect_pads
			(clearance 0)
		)
		(min_thickness 0.25)
		(keepout
			(tracks not_allowed)
			(vias allowed)
			(pads allowed)
			(copperpour not_allowed)
			(footprints allowed)
		)
		(placement
			(enabled no)
			(sheetname "")
		)
		(fill
			(thermal_gap 0.5)
			(thermal_bridge_width 0.5)
			(island_removal_mode 0)
		)
		(polygon
			(pts
				(xy 100.6602 -66.747136) (xy 100.6602 -65.982596) (xy 101.90988 -65.982596) (xy 101.90988 -66.747136)
			)
		)
	)
	(zone
		(layer "In1.Cu")
		(hatch none 0.5)
		(connect_pads
			(clearance 0)
		)
		(min_thickness 0.25)
		(keepout
			(tracks not_allowed)
			(vias allowed)
			(pads allowed)
			(copperpour not_allowed)
			(footprints allowed)
		)
		(placement
			(enabled no)
			(sheetname "")
		)
		(fill
			(thermal_gap 0.5)
			(thermal_bridge_width 0.5)
			(island_removal_mode 0)
		)
		(polygon
			(pts
				(xy 104.4448 -53.290216) (xy 104.4448 -54.054756) (xy 103.19512 -54.054756) (xy 103.19512 -53.290216)
			)
		)
	)
	(zone
		(layers "In1.Cu" "In2.Cu")
		(hatch none 0.5)
		(connect_pads
			(clearance 0)
		)
		(min_thickness 0.25)
		(keepout
			(tracks not_allowed)
			(vias allowed)
			(pads allowed)
			(copperpour not_allowed)
			(footprints allowed)
		)
		(placement
			(enabled no)
			(sheetname "")
		)
		(fill yes
			(thermal_gap 0.5)
			(thermal_bridge_width 0.5)
			(island_removal_mode 0)
		)
		(polygon
			(pts
				(xy 41.719754 -18.256504) (xy 41.973754 -18.256504) (xy 41.973754 -18.891504) (xy 41.719754 -18.891504)
			)
		)
	)
	(zone
		(layers "In1.Cu" "In2.Cu")
		(hatch none 0.5)
		(connect_pads
			(clearance 0)
		)
		(min_thickness 0.25)
		(keepout
			(tracks not_allowed)
			(vias allowed)
			(pads allowed)
			(copperpour not_allowed)
			(footprints allowed)
		)
		(placement
			(enabled no)
			(sheetname "")
		)
		(fill yes
			(thermal_gap 0.5)
			(thermal_bridge_width 0.5)
			(island_removal_mode 0)
		)
		(polygon
			(pts
				(xy 64.850264 -28.987242)
				(arc
					(start 64.850264 -28.847034)
					(mid 64.820874 -28.776974)
					(end 64.750442 -28.748482)
				)
				(arc
					(start 64.450214 -28.748482)
					(mid 64.379778 -28.77697)
					(end 64.350392 -28.847034)
				)
				(xy 64.350392 -28.987242) (xy 64.410336 -28.987242) (xy 64.410336 -29.252164) (xy 64.79032 -29.252164)
				(xy 64.79032 -28.987242)
			)
		)
	)
	(zone
		(layers "In1.Cu" "In2.Cu")
		(hatch none 0.5)
		(connect_pads
			(clearance 0)
		)
		(min_thickness 0.25)
		(keepout
			(tracks not_allowed)
			(vias allowed)
			(pads allowed)
			(copperpour not_allowed)
			(footprints allowed)
		)
		(placement
			(enabled no)
			(sheetname "")
		)
		(fill yes
			(thermal_gap 0.5)
			(thermal_bridge_width 0.5)
			(island_removal_mode 0)
		)
		(polygon
			(pts
				(xy 32.96285 -15.147798) (xy 32.96285 -15.858998) (xy 32.35325 -15.858998) (xy 32.35325 -15.147798)
			)
		)
	)
	(zone
		(layers "In1.Cu" "In2.Cu")
		(hatch none 0.5)
		(connect_pads
			(clearance 0)
		)
		(min_thickness 0.25)
		(keepout
			(tracks not_allowed)
			(vias allowed)
			(pads allowed)
			(copperpour not_allowed)
			(footprints allowed)
		)
		(placement
			(enabled no)
			(sheetname "")
		)
		(fill yes
			(thermal_gap 0.5)
			(thermal_bridge_width 0.5)
			(island_removal_mode 0)
		)
		(polygon
			(pts
				(arc
					(start 63.703962 -35.499548)
					(mid 63.774398 -35.47106)
					(end 63.803784 -35.400996)
				)
				(xy 63.803784 -35.260788) (xy 63.74384 -35.260788) (xy 63.74384 -34.995866) (xy 63.363856 -34.995866)
				(xy 63.363856 -35.260788) (xy 63.303912 -35.260788)
				(arc
					(start 63.303912 -35.400996)
					(mid 63.333302 -35.471056)
					(end 63.403734 -35.499548)
				)
			)
		)
	)
	(zone
		(layers "In1.Cu" "In2.Cu")
		(hatch none 0.5)
		(connect_pads
			(clearance 0)
		)
		(min_thickness 0.25)
		(keepout
			(tracks not_allowed)
			(vias allowed)
			(pads allowed)
			(copperpour not_allowed)
			(footprints allowed)
		)
		(placement
			(enabled no)
			(sheetname "")
		)
		(fill yes
			(thermal_gap 0.5)
			(thermal_bridge_width 0.5)
			(island_removal_mode 0)
		)
		(polygon
			(pts
				(xy 42.852848 -22.55266) (xy 43.208448 -22.55266) (xy 43.208448 -23.46706) (xy 42.852848 -23.46706)
			)
		)
	)
	(zone
		(layers "In1.Cu" "In2.Cu")
		(hatch none 0.5)
		(connect_pads
			(clearance 0)
		)
		(min_thickness 0.25)
		(keepout
			(tracks not_allowed)
			(vias allowed)
			(pads allowed)
			(copperpour not_allowed)
			(footprints allowed)
		)
		(placement
			(enabled no)
			(sheetname "")
		)
		(fill yes
			(thermal_gap 0.5)
			(thermal_bridge_width 0.5)
			(island_removal_mode 0)
		)
		(polygon
			(pts
				(xy 65.77711 -27.766264)
				(arc
					(start 65.636902 -27.766264)
					(mid 65.566842 -27.795654)
					(end 65.53835 -27.866086)
				)
				(arc
					(start 65.53835 -28.166314)
					(mid 65.566838 -28.23675)
					(end 65.636902 -28.266136)
				)
				(xy 65.77711 -28.266136) (xy 65.77711 -28.206192) (xy 66.042032 -28.206192) (xy 66.042032 -27.826208)
				(xy 65.77711 -27.826208)
			)
		)
	)
	(zone
		(layers "In1.Cu" "In2.Cu")
		(hatch none 0.5)
		(connect_pads
			(clearance 0)
		)
		(min_thickness 0.25)
		(keepout
			(tracks not_allowed)
			(vias allowed)
			(pads allowed)
			(copperpour not_allowed)
			(footprints allowed)
		)
		(placement
			(enabled no)
			(sheetname "")
		)
		(fill yes
			(thermal_gap 0.5)
			(thermal_bridge_width 0.5)
			(island_removal_mode 0)
		)
		(polygon
			(pts
				(arc
					(start 14.200886 -108.71835)
					(mid 14.13045 -108.746838)
					(end 14.101064 -108.816902)
				)
				(xy 14.101064 -108.95711) (xy 14.161008 -108.95711) (xy 14.161008 -109.222032) (xy 14.540992 -109.222032)
				(xy 14.540992 -108.95711) (xy 14.600936 -108.95711)
				(arc
					(start 14.600936 -108.816902)
					(mid 14.571546 -108.746842)
					(end 14.501114 -108.71835)
				)
			)
		)
	)
	(zone
		(layers "In1.Cu" "In2.Cu")
		(hatch none 0.5)
		(connect_pads
			(clearance 0)
		)
		(min_thickness 0.25)
		(keepout
			(tracks not_allowed)
			(vias allowed)
			(pads allowed)
			(copperpour not_allowed)
			(footprints allowed)
		)
		(placement
			(enabled no)
			(sheetname "")
		)
		(fill yes
			(thermal_gap 0.5)
			(thermal_bridge_width 0.5)
			(island_removal_mode 0)
		)
		(polygon
			(pts
				(xy 42.719498 -17.481296) (xy 42.973498 -17.481296) (xy 42.973498 -18.116296) (xy 42.719498 -18.116296)
			)
		)
	)
	(zone
		(layers "In1.Cu" "In2.Cu")
		(hatch none 0.5)
		(connect_pads
			(clearance 0)
		)
		(min_thickness 0.25)
		(keepout
			(tracks not_allowed)
			(vias allowed)
			(pads allowed)
			(copperpour not_allowed)
			(footprints allowed)
		)
		(placement
			(enabled no)
			(sheetname "")
		)
		(fill yes
			(thermal_gap 0.5)
			(thermal_bridge_width 0.5)
			(island_removal_mode 0)
		)
		(polygon
			(pts
				(arc
					(start 13.085064 -109.877098)
					(mid 13.114454 -109.947158)
					(end 13.184886 -109.97565)
				)
				(arc
					(start 13.485114 -109.97565)
					(mid 13.55555 -109.947162)
					(end 13.584936 -109.877098)
				)
				(xy 13.584936 -109.73689) (xy 13.524992 -109.73689) (xy 13.524992 -109.471968) (xy 13.145008 -109.471968)
				(xy 13.145008 -109.73689) (xy 13.085064 -109.73689)
			)
		)
	)
	(zone
		(layers "In1.Cu" "In2.Cu")
		(hatch none 0.5)
		(connect_pads
			(clearance 0)
		)
		(min_thickness 0.25)
		(keepout
			(tracks not_allowed)
			(vias allowed)
			(pads allowed)
			(copperpour not_allowed)
			(footprints allowed)
		)
		(placement
			(enabled no)
			(sheetname "")
		)
		(fill yes
			(thermal_gap 0.5)
			(thermal_bridge_width 0.5)
			(island_removal_mode 0)
		)
		(polygon
			(pts
				(xy 42.852848 -20.852892) (xy 43.208448 -20.852892) (xy 43.208448 -21.767292) (xy 42.852848 -21.767292)
			)
		)
	)
	(zone
		(layers "In1.Cu" "In2.Cu")
		(hatch none 0.5)
		(connect_pads
			(clearance 0)
		)
		(min_thickness 0.25)
		(keepout
			(tracks not_allowed)
			(vias allowed)
			(pads allowed)
			(copperpour not_allowed)
			(footprints allowed)
		)
		(placement
			(enabled no)
			(sheetname "")
		)
		(fill yes
			(thermal_gap 0.5)
			(thermal_bridge_width 0.5)
			(island_removal_mode 0)
		)
		(polygon
			(pts
				(arc
					(start 62.786006 -34.3408)
					(mid 62.756616 -34.27074)
					(end 62.686184 -34.242248)
				)
				(arc
					(start 62.385956 -34.242248)
					(mid 62.31552 -34.270736)
					(end 62.286134 -34.3408)
				)
				(xy 62.286134 -34.481008) (xy 62.346078 -34.481008) (xy 62.346078 -34.74593) (xy 62.726062 -34.74593)
				(xy 62.726062 -34.481008) (xy 62.786006 -34.481008)
			)
		)
	)
	(zone
		(layers "In1.Cu" "In2.Cu")
		(hatch none 0.5)
		(connect_pads
			(clearance 0)
		)
		(min_thickness 0.25)
		(keepout
			(tracks not_allowed)
			(vias allowed)
			(pads allowed)
			(copperpour not_allowed)
			(footprints allowed)
		)
		(placement
			(enabled no)
			(sheetname "")
		)
		(fill yes
			(thermal_gap 0.5)
			(thermal_bridge_width 0.5)
			(island_removal_mode 0)
		)
		(polygon
			(pts
				(xy 41.219628 -17.481296) (xy 41.473628 -17.481296) (xy 41.473628 -18.116296) (xy 41.219628 -18.116296)
			)
		)
	)
	(zone
		(layers "In1.Cu" "In2.Cu")
		(hatch none 0.5)
		(connect_pads
			(clearance 0)
		)
		(min_thickness 0.25)
		(keepout
			(tracks not_allowed)
			(vias allowed)
			(pads allowed)
			(copperpour not_allowed)
			(footprints allowed)
		)
		(placement
			(enabled no)
			(sheetname "")
		)
		(fill yes
			(thermal_gap 0.5)
			(thermal_bridge_width 0.5)
			(island_removal_mode 0)
		)
		(polygon
			(pts
				(xy 43.219624 -18.256504) (xy 43.473624 -18.256504) (xy 43.473624 -18.891504) (xy 43.219624 -18.891504)
			)
		)
	)
	(zone
		(layers "In1.Cu" "In2.Cu")
		(hatch none 0.5)
		(connect_pads
			(clearance 0)
		)
		(min_thickness 0.25)
		(keepout
			(tracks not_allowed)
			(vias allowed)
			(pads allowed)
			(copperpour not_allowed)
			(footprints allowed)
		)
		(placement
			(enabled no)
			(sheetname "")
		)
		(fill yes
			(thermal_gap 0.5)
			(thermal_bridge_width 0.5)
			(island_removal_mode 0)
		)
		(polygon
			(pts
				(arc
					(start 44.216574 -21.626322)
					(mid 44.187184 -21.556262)
					(end 44.116752 -21.52777)
				)
				(arc
					(start 43.816524 -21.52777)
					(mid 43.746088 -21.556258)
					(end 43.716702 -21.626322)
				)
				(xy 43.716702 -21.76653) (xy 43.776646 -21.76653) (xy 43.776646 -22.031452) (xy 44.15663 -22.031452)
				(xy 44.15663 -21.76653) (xy 44.216574 -21.76653)
			)
		)
	)
	(zone
		(layers "In1.Cu" "In2.Cu")
		(hatch none 0.5)
		(connect_pads
			(clearance 0)
		)
		(min_thickness 0.25)
		(keepout
			(tracks not_allowed)
			(vias allowed)
			(pads allowed)
			(copperpour not_allowed)
			(footprints allowed)
		)
		(placement
			(enabled no)
			(sheetname "")
		)
		(fill yes
			(thermal_gap 0.5)
			(thermal_bridge_width 0.5)
			(island_removal_mode 0)
		)
		(polygon
			(pts
				(arc
					(start 28.800552 -16.242538)
					(mid 28.870612 -16.213148)
					(end 28.899104 -16.142716)
				)
				(arc
					(start 28.899104 -15.842488)
					(mid 28.870616 -15.772052)
					(end 28.800552 -15.742666)
				)
				(xy 28.660344 -15.742666) (xy 28.660344 -15.80261) (xy 28.395422 -15.80261) (xy 28.395422 -16.182594)
				(xy 28.660344 -16.182594) (xy 28.660344 -16.242538)
			)
		)
	)
	(zone
		(layers "In1.Cu" "In2.Cu")
		(hatch none 0.5)
		(connect_pads
			(clearance 0)
		)
		(min_thickness 0.25)
		(keepout
			(tracks not_allowed)
			(vias allowed)
			(pads allowed)
			(copperpour not_allowed)
			(footprints allowed)
		)
		(placement
			(enabled no)
			(sheetname "")
		)
		(fill yes
			(thermal_gap 0.5)
			(thermal_bridge_width 0.5)
			(island_removal_mode 0)
		)
		(polygon
			(pts
				(xy 29.581094 -16.750792) (xy 29.581094 -17.106392) (xy 28.666694 -17.106392) (xy 28.666694 -16.750792)
			)
		)
	)
	(zone
		(layers "In1.Cu" "In2.Cu")
		(hatch none 0.5)
		(connect_pads
			(clearance 0)
		)
		(min_thickness 0.25)
		(keepout
			(tracks not_allowed)
			(vias allowed)
			(pads allowed)
			(copperpour not_allowed)
			(footprints allowed)
		)
		(placement
			(enabled no)
			(sheetname "")
		)
		(fill yes
			(thermal_gap 0.5)
			(thermal_bridge_width 0.5)
			(island_removal_mode 0)
		)
		(polygon
			(pts
				(xy 43.702732 -20.852892) (xy 44.058332 -20.852892) (xy 44.058332 -21.767292) (xy 43.702732 -21.767292)
			)
		)
	)
	(zone
		(layers "In1.Cu" "In2.Cu")
		(hatch none 0.5)
		(connect_pads
			(clearance 0)
		)
		(min_thickness 0.25)
		(keepout
			(tracks not_allowed)
			(vias allowed)
			(pads allowed)
			(copperpour not_allowed)
			(footprints allowed)
		)
		(placement
			(enabled no)
			(sheetname "")
		)
		(fill yes
			(thermal_gap 0.5)
			(thermal_bridge_width 0.5)
			(island_removal_mode 0)
		)
		(polygon
			(pts
				(arc
					(start 28.800552 -17.258538)
					(mid 28.870612 -17.229148)
					(end 28.899104 -17.158716)
				)
				(arc
					(start 28.899104 -16.858488)
					(mid 28.870616 -16.788052)
					(end 28.800552 -16.758666)
				)
				(xy 28.660344 -16.758666) (xy 28.660344 -16.81861) (xy 28.395422 -16.81861) (xy 28.395422 -17.198594)
				(xy 28.660344 -17.198594) (xy 28.660344 -17.258538)
			)
		)
	)
	(zone
		(layers "In1.Cu" "In2.Cu")
		(hatch none 0.5)
		(connect_pads
			(clearance 0)
		)
		(min_thickness 0.25)
		(keepout
			(tracks not_allowed)
			(vias allowed)
			(pads allowed)
			(copperpour not_allowed)
			(footprints allowed)
		)
		(placement
			(enabled no)
			(sheetname "")
		)
		(fill yes
			(thermal_gap 0.5)
			(thermal_bridge_width 0.5)
			(island_removal_mode 0)
		)
		(polygon
			(pts
				(xy 65.36817 -29.767022)
				(arc
					(start 65.36817 -29.90723)
					(mid 65.39756 -29.97729)
					(end 65.467992 -30.005782)
				)
				(arc
					(start 65.76822 -30.005782)
					(mid 65.838656 -29.977294)
					(end 65.868042 -29.90723)
				)
				(xy 65.868042 -29.767022) (xy 65.808098 -29.767022) (xy 65.808098 -29.5021) (xy 65.428114 -29.5021)
				(xy 65.428114 -29.767022)
			)
		)
	)
	(zone
		(layers "In1.Cu" "In2.Cu")
		(hatch none 0.5)
		(connect_pads
			(clearance 0)
		)
		(min_thickness 0.25)
		(keepout
			(tracks not_allowed)
			(vias allowed)
			(pads allowed)
			(copperpour not_allowed)
			(footprints allowed)
		)
		(placement
			(enabled no)
			(sheetname "")
		)
		(fill yes
			(thermal_gap 0.5)
			(thermal_bridge_width 0.5)
			(island_removal_mode 0)
		)
		(polygon
			(pts
				(xy 43.702732 -22.55266) (xy 44.058332 -22.55266) (xy 44.058332 -23.46706) (xy 43.702732 -23.46706)
			)
		)
	)
	(zone
		(layers "In1.Cu" "In2.Cu")
		(hatch none 0.5)
		(connect_pads
			(clearance 0)
		)
		(min_thickness 0.25)
		(keepout
			(tracks not_allowed)
			(vias allowed)
			(pads allowed)
			(copperpour not_allowed)
			(footprints allowed)
		)
		(placement
			(enabled no)
			(sheetname "")
		)
		(fill yes
			(thermal_gap 0.5)
			(thermal_bridge_width 0.5)
			(island_removal_mode 0)
		)
		(polygon
			(pts
				(xy 32.96285 -17.147794) (xy 32.96285 -17.858994) (xy 32.35325 -17.858994) (xy 32.35325 -17.147794)
			)
		)
	)
	(zone
		(layers "In1.Cu" "In2.Cu")
		(hatch none 0.5)
		(connect_pads
			(clearance 0)
		)
		(min_thickness 0.25)
		(keepout
			(tracks not_allowed)
			(vias allowed)
			(pads allowed)
			(copperpour not_allowed)
			(footprints allowed)
		)
		(placement
			(enabled no)
			(sheetname "")
		)
		(fill yes
			(thermal_gap 0.5)
			(thermal_bridge_width 0.5)
			(island_removal_mode 0)
		)
		(polygon
			(pts
				(xy 29.581094 -15.900908) (xy 29.581094 -16.256508) (xy 28.666694 -16.256508) (xy 28.666694 -15.900908)
			)
		)
	)
	(zone
		(layers "In1.Cu" "In2.Cu")
		(hatch none 0.5)
		(connect_pads
			(clearance 0)
		)
		(min_thickness 0.25)
		(keepout
			(tracks not_allowed)
			(vias allowed)
			(pads allowed)
			(copperpour not_allowed)
			(footprints allowed)
		)
		(placement
			(enabled no)
			(sheetname "")
		)
		(fill yes
			(thermal_gap 0.5)
			(thermal_bridge_width 0.5)
			(island_removal_mode 0)
		)
		(polygon
			(pts
				(xy 41.309036 -22.55266) (xy 41.664636 -22.55266) (xy 41.664636 -23.46706) (xy 41.309036 -23.46706)
			)
		)
	)
	(zone
		(layers "In1.Cu" "In2.Cu")
		(hatch none 0.5)
		(connect_pads
			(clearance 0)
		)
		(min_thickness 0.25)
		(keepout
			(tracks not_allowed)
			(vias allowed)
			(pads allowed)
			(copperpour not_allowed)
			(footprints allowed)
		)
		(placement
			(enabled no)
			(sheetname "")
		)
		(fill yes
			(thermal_gap 0.5)
			(thermal_bridge_width 0.5)
			(island_removal_mode 0)
		)
		(polygon
			(pts
				(xy 43.219624 -17.481296) (xy 43.473624 -17.481296) (xy 43.473624 -18.116296) (xy 43.219624 -18.116296)
			)
		)
	)
	(zone
		(layers "In1.Cu" "In2.Cu")
		(hatch none 0.5)
		(connect_pads
			(clearance 0)
		)
		(min_thickness 0.25)
		(keepout
			(tracks not_allowed)
			(vias allowed)
			(pads allowed)
			(copperpour not_allowed)
			(footprints allowed)
		)
		(placement
			(enabled no)
			(sheetname "")
		)
		(fill yes
			(thermal_gap 0.5)
			(thermal_bridge_width 0.5)
			(island_removal_mode 0)
		)
		(polygon
			(pts
				(xy 66.55689 -27.766264) (xy 66.55689 -27.826208) (xy 66.291968 -27.826208) (xy 66.291968 -28.206192)
				(xy 66.55689 -28.206192) (xy 66.55689 -28.266136)
				(arc
					(start 66.697098 -28.266136)
					(mid 66.767158 -28.236746)
					(end 66.79565 -28.166314)
				)
				(arc
					(start 66.79565 -27.866086)
					(mid 66.767162 -27.79565)
					(end 66.697098 -27.766264)
				)
			)
		)
	)
	(zone
		(layers "In1.Cu" "In2.Cu")
		(hatch none 0.5)
		(connect_pads
			(clearance 0)
		)
		(min_thickness 0.25)
		(keepout
			(tracks not_allowed)
			(vias allowed)
			(pads allowed)
			(copperpour not_allowed)
			(footprints allowed)
		)
		(placement
			(enabled no)
			(sheetname "")
		)
		(fill yes
			(thermal_gap 0.5)
			(thermal_bridge_width 0.5)
			(island_removal_mode 0)
		)
		(polygon
			(pts
				(xy 41.309036 -20.852892) (xy 41.664636 -20.852892) (xy 41.664636 -21.767292) (xy 41.309036 -21.767292)
			)
		)
	)
	(zone
		(layers "In1.Cu" "In2.Cu")
		(hatch none 0.5)
		(connect_pads
			(clearance 0)
		)
		(min_thickness 0.25)
		(keepout
			(tracks not_allowed)
			(vias allowed)
			(pads allowed)
			(copperpour not_allowed)
			(footprints allowed)
		)
		(placement
			(enabled no)
			(sheetname "")
		)
		(fill yes
			(thermal_gap 0.5)
			(thermal_bridge_width 0.5)
			(island_removal_mode 0)
		)
		(polygon
			(pts
				(xy 64.350392 -29.767022)
				(arc
					(start 64.350392 -29.90723)
					(mid 64.379782 -29.97729)
					(end 64.450214 -30.005782)
				)
				(arc
					(start 64.750442 -30.005782)
					(mid 64.820878 -29.977294)
					(end 64.850264 -29.90723)
				)
				(xy 64.850264 -29.767022) (xy 64.79032 -29.767022) (xy 64.79032 -29.5021) (xy 64.410336 -29.5021)
				(xy 64.410336 -29.767022)
			)
		)
	)
	(zone
		(layers "In1.Cu" "In2.Cu")
		(hatch none 0.5)
		(connect_pads
			(clearance 0)
		)
		(min_thickness 0.25)
		(keepout
			(tracks not_allowed)
			(vias allowed)
			(pads allowed)
			(copperpour not_allowed)
			(footprints allowed)
		)
		(placement
			(enabled no)
			(sheetname "")
		)
		(fill yes
			(thermal_gap 0.5)
			(thermal_bridge_width 0.5)
			(island_removal_mode 0)
		)
		(polygon
			(pts
				(xy 64.80429 -28.266136)
				(arc
					(start 64.944498 -28.266136)
					(mid 65.014558 -28.236746)
					(end 65.04305 -28.166314)
				)
				(arc
					(start 65.04305 -27.866086)
					(mid 65.014562 -27.79565)
					(end 64.944498 -27.766264)
				)
				(xy 64.80429 -27.766264) (xy 64.80429 -27.826208) (xy 64.539368 -27.826208) (xy 64.539368 -28.206192)
				(xy 64.80429 -28.206192)
			)
		)
	)
	(zone
		(layers "In1.Cu" "In2.Cu")
		(hatch none 0.5)
		(connect_pads
			(clearance 0)
		)
		(min_thickness 0.25)
		(keepout
			(tracks not_allowed)
			(vias allowed)
			(pads allowed)
			(copperpour not_allowed)
			(footprints allowed)
		)
		(placement
			(enabled no)
			(sheetname "")
		)
		(fill yes
			(thermal_gap 0.5)
			(thermal_bridge_width 0.5)
			(island_removal_mode 0)
		)
		(polygon
			(pts
				(xy 27.881326 -15.900908) (xy 27.881326 -16.256508) (xy 26.966926 -16.256508) (xy 26.966926 -15.900908)
			)
		)
	)
	(zone
		(layers "In1.Cu" "In2.Cu")
		(hatch none 0.5)
		(connect_pads
			(clearance 0)
		)
		(min_thickness 0.25)
		(keepout
			(tracks not_allowed)
			(vias allowed)
			(pads allowed)
			(copperpour not_allowed)
			(footprints allowed)
		)
		(placement
			(enabled no)
			(sheetname "")
		)
		(fill yes
			(thermal_gap 0.5)
			(thermal_bridge_width 0.5)
			(island_removal_mode 0)
		)
		(polygon
			(pts
				(arc
					(start 41.723056 -22.78507)
					(mid 41.793492 -22.756582)
					(end 41.822878 -22.686518)
				)
				(xy 41.822878 -22.54631) (xy 41.762934 -22.54631) (xy 41.762934 -22.281388) (xy 41.38295 -22.281388)
				(xy 41.38295 -22.54631) (xy 41.323006 -22.54631)
				(arc
					(start 41.323006 -22.686518)
					(mid 41.352396 -22.756578)
					(end 41.422828 -22.78507)
				)
			)
		)
	)
	(zone
		(layers "In1.Cu" "In2.Cu")
		(hatch none 0.5)
		(connect_pads
			(clearance 0)
		)
		(min_thickness 0.25)
		(keepout
			(tracks not_allowed)
			(vias allowed)
			(pads allowed)
			(copperpour not_allowed)
			(footprints allowed)
		)
		(placement
			(enabled no)
			(sheetname "")
		)
		(fill yes
			(thermal_gap 0.5)
			(thermal_bridge_width 0.5)
			(island_removal_mode 0)
		)
		(polygon
			(pts
				(arc
					(start 40.806878 -21.626322)
					(mid 40.777488 -21.556262)
					(end 40.707056 -21.52777)
				)
				(arc
					(start 40.406828 -21.52777)
					(mid 40.336392 -21.556258)
					(end 40.307006 -21.626322)
				)
				(xy 40.307006 -21.76653) (xy 40.36695 -21.76653) (xy 40.36695 -22.031452) (xy 40.746934 -22.031452)
				(xy 40.746934 -21.76653) (xy 40.806878 -21.76653)
			)
		)
	)
	(zone
		(layers "In1.Cu" "In2.Cu")
		(hatch none 0.5)
		(connect_pads
			(clearance 0)
		)
		(min_thickness 0.25)
		(keepout
			(tracks not_allowed)
			(vias allowed)
			(pads allowed)
			(copperpour not_allowed)
			(footprints allowed)
		)
		(placement
			(enabled no)
			(sheetname "")
		)
		(fill yes
			(thermal_gap 0.5)
			(thermal_bridge_width 0.5)
			(island_removal_mode 0)
		)
		(polygon
			(pts
				(arc
					(start 43.100752 -22.78507)
					(mid 43.171188 -22.756582)
					(end 43.200574 -22.686518)
				)
				(xy 43.200574 -22.54631) (xy 43.14063 -22.54631) (xy 43.14063 -22.281388) (xy 42.760646 -22.281388)
				(xy 42.760646 -22.54631) (xy 42.700702 -22.54631)
				(arc
					(start 42.700702 -22.686518)
					(mid 42.730092 -22.756578)
					(end 42.800524 -22.78507)
				)
			)
		)
	)
	(zone
		(layers "In1.Cu" "In2.Cu")
		(hatch none 0.5)
		(connect_pads
			(clearance 0)
		)
		(min_thickness 0.25)
		(keepout
			(tracks not_allowed)
			(vias allowed)
			(pads allowed)
			(copperpour not_allowed)
			(footprints allowed)
		)
		(placement
			(enabled no)
			(sheetname "")
		)
		(fill yes
			(thermal_gap 0.5)
			(thermal_bridge_width 0.5)
			(island_removal_mode 0)
		)
		(polygon
			(pts
				(arc
					(start 41.822878 -21.626322)
					(mid 41.793488 -21.556262)
					(end 41.723056 -21.52777)
				)
				(arc
					(start 41.422828 -21.52777)
					(mid 41.352392 -21.556258)
					(end 41.323006 -21.626322)
				)
				(xy 41.323006 -21.76653) (xy 41.38295 -21.76653) (xy 41.38295 -22.031452) (xy 41.762934 -22.031452)
				(xy 41.762934 -21.76653) (xy 41.822878 -21.76653)
			)
		)
	)
	(zone
		(layers "In1.Cu" "In2.Cu")
		(hatch none 0.5)
		(connect_pads
			(clearance 0)
		)
		(min_thickness 0.25)
		(keepout
			(tracks not_allowed)
			(vias allowed)
			(pads allowed)
			(copperpour not_allowed)
			(footprints allowed)
		)
		(placement
			(enabled no)
			(sheetname "")
		)
		(fill yes
			(thermal_gap 0.5)
			(thermal_bridge_width 0.5)
			(island_removal_mode 0)
		)
		(polygon
			(pts
				(xy 27.881326 -16.750792) (xy 27.881326 -17.106392) (xy 26.966926 -17.106392) (xy 26.966926 -16.750792)
			)
		)
	)
	(zone
		(layers "In1.Cu" "In2.Cu")
		(hatch none 0.5)
		(connect_pads
			(clearance 0)
		)
		(min_thickness 0.25)
		(keepout
			(tracks not_allowed)
			(vias allowed)
			(pads allowed)
			(copperpour not_allowed)
			(footprints allowed)
		)
		(placement
			(enabled no)
			(sheetname "")
		)
		(fill yes
			(thermal_gap 0.5)
			(thermal_bridge_width 0.5)
			(island_removal_mode 0)
		)
		(polygon
			(pts
				(xy 64.02451 -28.266136) (xy 64.02451 -28.206192) (xy 64.289432 -28.206192) (xy 64.289432 -27.826208)
				(xy 64.02451 -27.826208) (xy 64.02451 -27.766264)
				(arc
					(start 63.884302 -27.766264)
					(mid 63.814242 -27.795654)
					(end 63.78575 -27.866086)
				)
				(arc
					(start 63.78575 -28.166314)
					(mid 63.814238 -28.23675)
					(end 63.884302 -28.266136)
				)
			)
		)
	)
	(zone
		(layers "In1.Cu" "In2.Cu")
		(hatch none 0.5)
		(connect_pads
			(clearance 0)
		)
		(min_thickness 0.25)
		(keepout
			(tracks not_allowed)
			(vias allowed)
			(pads allowed)
			(copperpour not_allowed)
			(footprints allowed)
		)
		(placement
			(enabled no)
			(sheetname "")
		)
		(fill yes
			(thermal_gap 0.5)
			(thermal_bridge_width 0.5)
			(island_removal_mode 0)
		)
		(polygon
			(pts
				(xy 41.219628 -18.256504) (xy 41.473628 -18.256504) (xy 41.473628 -18.891504) (xy 41.219628 -18.891504)
			)
		)
	)
	(zone
		(layers "In1.Cu" "In2.Cu")
		(hatch none 0.5)
		(connect_pads
			(clearance 0)
		)
		(min_thickness 0.25)
		(keepout
			(tracks not_allowed)
			(vias allowed)
			(pads allowed)
			(copperpour not_allowed)
			(footprints allowed)
		)
		(placement
			(enabled no)
			(sheetname "")
		)
		(fill yes
			(thermal_gap 0.5)
			(thermal_bridge_width 0.5)
			(island_removal_mode 0)
		)
		(polygon
			(pts
				(arc
					(start 27.641804 -16.142716)
					(mid 27.670292 -16.213152)
					(end 27.740356 -16.242538)
				)
				(xy 27.880564 -16.242538) (xy 27.880564 -16.182594) (xy 28.145486 -16.182594) (xy 28.145486 -15.80261)
				(xy 27.880564 -15.80261) (xy 27.880564 -15.742666)
				(arc
					(start 27.740356 -15.742666)
					(mid 27.670296 -15.772056)
					(end 27.641804 -15.842488)
				)
			)
		)
	)
	(zone
		(layers "In1.Cu" "In2.Cu")
		(hatch none 0.5)
		(connect_pads
			(clearance 0)
		)
		(min_thickness 0.25)
		(keepout
			(tracks not_allowed)
			(vias allowed)
			(pads allowed)
			(copperpour not_allowed)
			(footprints allowed)
		)
		(placement
			(enabled no)
			(sheetname "")
		)
		(fill yes
			(thermal_gap 0.5)
			(thermal_bridge_width 0.5)
			(island_removal_mode 0)
		)
		(polygon
			(pts
				(arc
					(start 40.707056 -22.78507)
					(mid 40.777492 -22.756582)
					(end 40.806878 -22.686518)
				)
				(xy 40.806878 -22.54631) (xy 40.746934 -22.54631) (xy 40.746934 -22.281388) (xy 40.36695 -22.281388)
				(xy 40.36695 -22.54631) (xy 40.307006 -22.54631)
				(arc
					(start 40.307006 -22.686518)
					(mid 40.336396 -22.756578)
					(end 40.406828 -22.78507)
				)
			)
		)
	)
	(zone
		(layers "In1.Cu" "In2.Cu")
		(hatch none 0.5)
		(connect_pads
			(clearance 0)
		)
		(min_thickness 0.25)
		(keepout
			(tracks not_allowed)
			(vias allowed)
			(pads allowed)
			(copperpour not_allowed)
			(footprints allowed)
		)
		(placement
			(enabled no)
			(sheetname "")
		)
		(fill yes
			(thermal_gap 0.5)
			(thermal_bridge_width 0.5)
			(island_removal_mode 0)
		)
		(polygon
			(pts
				(xy 42.719498 -18.256504) (xy 42.973498 -18.256504) (xy 42.973498 -18.891504) (xy 42.719498 -18.891504)
			)
		)
	)
	(zone
		(layers "In1.Cu" "In2.Cu")
		(hatch none 0.5)
		(connect_pads
			(clearance 0)
		)
		(min_thickness 0.25)
		(keepout
			(tracks not_allowed)
			(vias allowed)
			(pads allowed)
			(copperpour not_allowed)
			(footprints allowed)
		)
		(placement
			(enabled no)
			(sheetname "")
		)
		(fill yes
			(thermal_gap 0.5)
			(thermal_bridge_width 0.5)
			(island_removal_mode 0)
		)
		(polygon
			(pts
				(arc
					(start 63.803784 -34.3408)
					(mid 63.774394 -34.27074)
					(end 63.703962 -34.242248)
				)
				(arc
					(start 63.403734 -34.242248)
					(mid 63.333298 -34.270736)
					(end 63.303912 -34.3408)
				)
				(xy 63.303912 -34.481008) (xy 63.363856 -34.481008) (xy 63.363856 -34.74593) (xy 63.74384 -34.74593)
				(xy 63.74384 -34.481008) (xy 63.803784 -34.481008)
			)
		)
	)
	(zone
		(layers "In1.Cu" "In2.Cu")
		(hatch none 0.5)
		(connect_pads
			(clearance 0)
		)
		(min_thickness 0.25)
		(keepout
			(tracks not_allowed)
			(vias allowed)
			(pads allowed)
			(copperpour not_allowed)
			(footprints allowed)
		)
		(placement
			(enabled no)
			(sheetname "")
		)
		(fill yes
			(thermal_gap 0.5)
			(thermal_bridge_width 0.5)
			(island_removal_mode 0)
		)
		(polygon
			(pts
				(arc
					(start 27.641804 -17.158716)
					(mid 27.670292 -17.229152)
					(end 27.740356 -17.258538)
				)
				(xy 27.880564 -17.258538) (xy 27.880564 -17.198594) (xy 28.145486 -17.198594) (xy 28.145486 -16.81861)
				(xy 27.880564 -16.81861) (xy 27.880564 -16.758666)
				(arc
					(start 27.740356 -16.758666)
					(mid 27.670296 -16.788056)
					(end 27.641804 -16.858488)
				)
			)
		)
	)
	(zone
		(layers "In1.Cu" "In2.Cu")
		(hatch none 0.5)
		(connect_pads
			(clearance 0)
		)
		(min_thickness 0.25)
		(keepout
			(tracks not_allowed)
			(vias allowed)
			(pads allowed)
			(copperpour not_allowed)
			(footprints allowed)
		)
		(placement
			(enabled no)
			(sheetname "")
		)
		(fill yes
			(thermal_gap 0.5)
			(thermal_bridge_width 0.5)
			(island_removal_mode 0)
		)
		(polygon
			(pts
				(arc
					(start 62.686184 -35.499548)
					(mid 62.75662 -35.47106)
					(end 62.786006 -35.400996)
				)
				(xy 62.786006 -35.260788) (xy 62.726062 -35.260788) (xy 62.726062 -34.995866) (xy 62.346078 -34.995866)
				(xy 62.346078 -35.260788) (xy 62.286134 -35.260788)
				(arc
					(start 62.286134 -35.400996)
					(mid 62.315524 -35.471056)
					(end 62.385956 -35.499548)
				)
			)
		)
	)
	(zone
		(layers "In1.Cu" "In2.Cu")
		(hatch none 0.5)
		(connect_pads
			(clearance 0)
		)
		(min_thickness 0.25)
		(keepout
			(tracks not_allowed)
			(vias allowed)
			(pads allowed)
			(copperpour not_allowed)
			(footprints allowed)
		)
		(placement
			(enabled no)
			(sheetname "")
		)
		(fill yes
			(thermal_gap 0.5)
			(thermal_bridge_width 0.5)
			(island_removal_mode 0)
		)
		(polygon
			(pts
				(arc
					(start 43.200574 -21.626322)
					(mid 43.171184 -21.556262)
					(end 43.100752 -21.52777)
				)
				(arc
					(start 42.800524 -21.52777)
					(mid 42.730088 -21.556258)
					(end 42.700702 -21.626322)
				)
				(xy 42.700702 -21.76653) (xy 42.760646 -21.76653) (xy 42.760646 -22.031452) (xy 43.14063 -22.031452)
				(xy 43.14063 -21.76653) (xy 43.200574 -21.76653)
			)
		)
	)
	(zone
		(layers "In1.Cu" "In2.Cu")
		(hatch none 0.5)
		(connect_pads
			(clearance 0)
		)
		(min_thickness 0.25)
		(keepout
			(tracks not_allowed)
			(vias allowed)
			(pads allowed)
			(copperpour not_allowed)
			(footprints allowed)
		)
		(placement
			(enabled no)
			(sheetname "")
		)
		(fill yes
			(thermal_gap 0.5)
			(thermal_bridge_width 0.5)
			(island_removal_mode 0)
		)
		(polygon
			(pts
				(arc
					(start 13.184886 -108.71835)
					(mid 13.11445 -108.746838)
					(end 13.085064 -108.816902)
				)
				(xy 13.085064 -108.95711) (xy 13.145008 -108.95711) (xy 13.145008 -109.222032) (xy 13.524992 -109.222032)
				(xy 13.524992 -108.95711) (xy 13.584936 -108.95711)
				(arc
					(start 13.584936 -108.816902)
					(mid 13.555546 -108.746842)
					(end 13.485114 -108.71835)
				)
			)
		)
	)
	(zone
		(layers "In1.Cu" "In2.Cu")
		(hatch none 0.5)
		(connect_pads
			(clearance 0)
		)
		(min_thickness 0.25)
		(keepout
			(tracks not_allowed)
			(vias allowed)
			(pads allowed)
			(copperpour not_allowed)
			(footprints allowed)
		)
		(placement
			(enabled no)
			(sheetname "")
		)
		(fill yes
			(thermal_gap 0.5)
			(thermal_bridge_width 0.5)
			(island_removal_mode 0)
		)
		(polygon
			(pts
				(xy 65.868042 -28.987242)
				(arc
					(start 65.868042 -28.847034)
					(mid 65.838652 -28.776974)
					(end 65.76822 -28.748482)
				)
				(arc
					(start 65.467992 -28.748482)
					(mid 65.397556 -28.77697)
					(end 65.36817 -28.847034)
				)
				(xy 65.36817 -28.987242) (xy 65.428114 -28.987242) (xy 65.428114 -29.252164) (xy 65.808098 -29.252164)
				(xy 65.808098 -28.987242)
			)
		)
	)
	(zone
		(layers "In1.Cu" "In2.Cu")
		(hatch none 0.5)
		(connect_pads
			(clearance 0)
		)
		(min_thickness 0.25)
		(keepout
			(tracks not_allowed)
			(vias allowed)
			(pads allowed)
			(copperpour not_allowed)
			(footprints allowed)
		)
		(placement
			(enabled no)
			(sheetname "")
		)
		(fill yes
			(thermal_gap 0.5)
			(thermal_bridge_width 0.5)
			(island_removal_mode 0)
		)
		(polygon
			(pts
				(xy 40.459152 -20.852892) (xy 40.814752 -20.852892) (xy 40.814752 -21.767292) (xy 40.459152 -21.767292)
			)
		)
	)
	(zone
		(layers "In1.Cu" "In2.Cu")
		(hatch none 0.5)
		(connect_pads
			(clearance 0)
		)
		(min_thickness 0.25)
		(keepout
			(tracks not_allowed)
			(vias allowed)
			(pads allowed)
			(copperpour not_allowed)
			(footprints allowed)
		)
		(placement
			(enabled no)
			(sheetname "")
		)
		(fill yes
			(thermal_gap 0.5)
			(thermal_bridge_width 0.5)
			(island_removal_mode 0)
		)
		(polygon
			(pts
				(xy 40.459152 -22.55266) (xy 40.814752 -22.55266) (xy 40.814752 -23.46706) (xy 40.459152 -23.46706)
			)
		)
	)
	(zone
		(layers "In1.Cu" "In2.Cu")
		(hatch none 0.5)
		(connect_pads
			(clearance 0)
		)
		(min_thickness 0.25)
		(keepout
			(tracks not_allowed)
			(vias allowed)
			(pads allowed)
			(copperpour not_allowed)
			(footprints allowed)
		)
		(placement
			(enabled no)
			(sheetname "")
		)
		(fill yes
			(thermal_gap 0.5)
			(thermal_bridge_width 0.5)
			(island_removal_mode 0)
		)
		(polygon
			(pts
				(arc
					(start 14.101064 -109.877098)
					(mid 14.130454 -109.947158)
					(end 14.200886 -109.97565)
				)
				(arc
					(start 14.501114 -109.97565)
					(mid 14.57155 -109.947162)
					(end 14.600936 -109.877098)
				)
				(xy 14.600936 -109.73689) (xy 14.540992 -109.73689) (xy 14.540992 -109.471968) (xy 14.161008 -109.471968)
				(xy 14.161008 -109.73689) (xy 14.101064 -109.73689)
			)
		)
	)
	(zone
		(layers "In1.Cu" "In2.Cu")
		(hatch none 0.5)
		(connect_pads
			(clearance 0)
		)
		(min_thickness 0.25)
		(keepout
			(tracks not_allowed)
			(vias allowed)
			(pads allowed)
			(copperpour not_allowed)
			(footprints allowed)
		)
		(placement
			(enabled no)
			(sheetname "")
		)
		(fill yes
			(thermal_gap 0.5)
			(thermal_bridge_width 0.5)
			(island_removal_mode 0)
		)
		(polygon
			(pts
				(xy 41.719754 -17.481296) (xy 41.973754 -17.481296) (xy 41.973754 -18.116296) (xy 41.719754 -18.116296)
			)
		)
	)
	(zone
		(layers "In1.Cu" "In2.Cu")
		(hatch none 0.5)
		(connect_pads
			(clearance 0)
		)
		(min_thickness 0.25)
		(keepout
			(tracks not_allowed)
			(vias allowed)
			(pads allowed)
			(copperpour not_allowed)
			(footprints allowed)
		)
		(placement
			(enabled no)
			(sheetname "")
		)
		(fill yes
			(thermal_gap 0.5)
			(thermal_bridge_width 0.5)
			(island_removal_mode 0)
		)
		(polygon
			(pts
				(arc
					(start 44.116752 -22.78507)
					(mid 44.187188 -22.756582)
					(end 44.216574 -22.686518)
				)
				(xy 44.216574 -22.54631) (xy 44.15663 -22.54631) (xy 44.15663 -22.281388) (xy 43.776646 -22.281388)
				(xy 43.776646 -22.54631) (xy 43.716702 -22.54631)
				(arc
					(start 43.716702 -22.686518)
					(mid 43.746092 -22.756578)
					(end 43.816524 -22.78507)
				)
			)
		)
	)
	(zone
		(layer "In2.Cu")
		(hatch none 0.5)
		(connect_pads
			(clearance 0)
		)
		(min_thickness 0.25)
		(keepout
			(tracks allowed)
			(vias allowed)
			(pads allowed)
			(copperpour allowed)
			(footprints allowed)
		)
		(placement
			(enabled no)
			(sheetname "")
		)
		(fill
			(thermal_gap 0.5)
			(thermal_bridge_width 0.5)
			(island_removal_mode 0)
		)
		(polygon
			(pts
				(xy 30.349952 -101.907594) (xy 13.252196 -101.907594) (xy 13.252196 -86.325202) (xy 19.120612 -86.325202)
				(xy 19.89836 -87.10295) (xy 30.098746 -87.10295) (xy 30.349952 -87.354156)
			)
		)
	)
	(zone
		(layer "In2.Cu")
		(hatch none 0.5)
		(connect_pads
			(clearance 0)
		)
		(min_thickness 0.25)
		(keepout
			(tracks allowed)
			(vias allowed)
			(pads allowed)
			(copperpour allowed)
			(footprints allowed)
		)
		(placement
			(enabled no)
			(sheetname "")
		)
		(fill
			(thermal_gap 0.5)
			(thermal_bridge_width 0.5)
			(island_removal_mode 0)
		)
		(polygon
			(pts
				(xy 66.13652 -42.064686) (xy 66.13652 -51.046126) (xy 66.13652 -54.955186) (xy 66.13652 -61.081666)
				(xy 61.94552 -61.081666) (xy 61.593984 -61.433202) (xy 58.744866 -61.433202) (xy 58.402982 -61.433202)
				(xy 58.051446 -61.081666) (xy 46.08068 -61.081666) (xy 44.915328 -61.081666) (xy 44.02963 -60.195968)
				(xy 44.02963 -59.52236) (xy 43.454066 -58.946796) (xy 43.454066 -56.560466) (xy 43.454066 -54.698138)
				(xy 43.579034 -54.698138) (xy 44.02963 -54.247542) (xy 44.02963 -43.245532) (xy 43.77436 -42.990262)
				(xy 43.332146 -42.548048) (xy 43.332146 -41.41978) (xy 44.02963 -40.722296) (xy 44.02963 -39.214298)
				(xy 44.326302 -38.917626) (xy 56.777382 -38.917626) (xy 56.986424 -38.708584) (xy 59.904376 -38.708584)
				(xy 60.113418 -38.917626) (xy 65.970404 -38.917626) (xy 66.13652 -39.083742)
			)
		)
	)
	(zone
		(layers "In2.Cu" "In4.Cu" "In6.Cu" "In7.Cu" "In9.Cu")
		(hatch none 0.5)
		(connect_pads
			(clearance 0)
		)
		(min_thickness 0.25)
		(keepout
			(tracks not_allowed)
			(vias allowed)
			(pads allowed)
			(copperpour not_allowed)
			(footprints allowed)
		)
		(placement
			(enabled no)
			(sheetname "")
		)
		(fill yes
			(thermal_gap 0.5)
			(thermal_bridge_width 0.5)
			(island_removal_mode 0)
		)
		(polygon
			(pts
				(arc
					(start 30.049978 -54.189122)
					(mid 23.450042 -54.189122)
					(end 30.049978 -54.189122)
				)
			)
		)
	)
	(zone
		(layer "In4.Cu")
		(hatch none 0.5)
		(connect_pads
			(clearance 0)
		)
		(min_thickness 0.25)
		(keepout
			(tracks allowed)
			(vias allowed)
			(pads allowed)
			(copperpour allowed)
			(footprints allowed)
		)
		(placement
			(enabled no)
			(sheetname "")
		)
		(fill
			(thermal_gap 0.5)
			(thermal_bridge_width 0.5)
			(island_removal_mode 0)
		)
		(polygon
			(pts
				(xy 65.57264 -59.621166) (xy 64.36614 -60.827666) (xy 44.80052 -60.827666) (xy 44.2468 -60.273946)
				(xy 44.2468 -53.748178) (xy 43.595036 -53.096414) (xy 43.595036 -52.222908) (xy 44.2468 -51.571144)
				(xy 44.2468 -39.612824) (xy 44.2468 -38.667182) (xy 44.318174 -38.595808) (xy 65.338706 -38.595808)
				(xy 65.57264 -38.829742)
			)
		)
	)
	(zone
		(layer "In4.Cu")
		(hatch none 0.5)
		(connect_pads
			(clearance 0)
		)
		(min_thickness 0.25)
		(keepout
			(tracks allowed)
			(vias allowed)
			(pads allowed)
			(copperpour allowed)
			(footprints allowed)
		)
		(placement
			(enabled no)
			(sheetname "")
		)
		(fill
			(thermal_gap 0.5)
			(thermal_bridge_width 0.5)
			(island_removal_mode 0)
		)
		(polygon
			(pts
				(xy 16.474186 -92.254324) (xy 16.474186 -87.104474) (xy 30.503876 -87.104474) (xy 30.503876 -92.254324)
			)
		)
	)
	(zone
		(layer "In7.Cu")
		(hatch none 0.5)
		(connect_pads
			(clearance 0)
		)
		(min_thickness 0.25)
		(keepout
			(tracks allowed)
			(vias allowed)
			(pads allowed)
			(copperpour allowed)
			(footprints allowed)
		)
		(placement
			(enabled no)
			(sheetname "")
		)
		(fill
			(thermal_gap 0.5)
			(thermal_bridge_width 0.5)
			(island_removal_mode 0)
		)
		(polygon
			(pts
				(xy 66.13652 -41.858946) (xy 66.13652 -50.792126) (xy 66.13652 -54.701186) (xy 66.13652 -60.827666)
				(xy 46.08322 -60.827666) (xy 45.171614 -60.827666) (xy 44.236894 -59.892946) (xy 44.236894 -38.787832)
				(xy 44.35348 -38.671246) (xy 65.75171 -38.671246) (xy 66.13652 -39.056056)
			)
		)
	)
	(zone
		(layer "In7.Cu")
		(hatch none 0.5)
		(connect_pads
			(clearance 0)
		)
		(min_thickness 0.25)
		(keepout
			(tracks allowed)
			(vias allowed)
			(pads allowed)
			(copperpour allowed)
			(footprints allowed)
		)
		(placement
			(enabled no)
			(sheetname "")
		)
		(fill
			(thermal_gap 0.5)
			(thermal_bridge_width 0.5)
			(island_removal_mode 0)
		)
		(polygon
			(pts
				(xy 69.1896 -115.3414) (xy 73.2282 -115.3414) (xy 74.1934 -114.3762) (xy 74.1934 -113.538) (xy 72.136 -111.4806)
				(xy 72.136 -108.7374) (xy 70.8914 -107.4928) (xy 70.8914 -105.156) (xy 69.5452 -103.8098) (xy 69.5452 -103.0732)
				(xy 66.675 -100.203) (xy 66.675 -93.726) (xy 62.6364 -89.6874) (xy 62.6364 -85.5726) (xy 60.9346 -83.8708)
				(xy 60.9346 -79.7052) (xy 53.3908 -72.1614) (xy 50.89652 -72.1614) (xy 47.44212 -68.707) (xy 45.6184 -68.707)
				(xy 45.0088 -68.0974) (xy 45.0088 -67.5894) (xy 45.0342 -67.564) (xy 45.0342 -67.2592) (xy 44.3484 -66.5734)
				(xy 43.18 -66.5734) (xy 42.2402 -65.6336) (xy 42.2402 -64.4652) (xy 41.6306 -63.8556) (xy 39.7002 -63.8556)
				(xy 38.1254 -65.4304) (xy 38.1254 -66.8782) (xy 38.9128 -67.6656) (xy 38.9128 -68.199) (xy 38.862 -68.2498)
				(xy 38.862 -68.3768) (xy 40.4368 -69.9516) (xy 40.4368 -70.22846) (xy 41.50614 -71.2978) (xy 41.8592 -71.2978)
				(xy 44.95292 -74.39152) (xy 47.08398 -74.39152) (xy 48.90262 -76.21016) (xy 49.95926 -76.21016)
				(xy 51.56962 -77.82052) (xy 51.56962 -78.92542) (xy 54.5846 -81.9404) (xy 54.5846 -83.5152) (xy 56.0324 -84.963)
				(xy 56.0324 -86.0806) (xy 56.9214 -86.9696) (xy 56.9214 -88.9) (xy 56.896 -88.9254) (xy 56.896 -90.6526)
				(xy 58.674 -92.4306) (xy 58.674 -94.6912) (xy 62.738 -98.7552) (xy 62.738 -101.346) (xy 65.8876 -104.4956)
				(xy 65.8876 -107.9246) (xy 66.3702 -108.4072) (xy 66.3702 -112.522)
			)
		)
	)
	(zone
		(layer "Cmts.User")
		(hatch none 0.5)
		(connect_pads
			(clearance 0)
		)
		(min_thickness 0.25)
		(keepout
			(tracks allowed)
			(vias allowed)
			(pads allowed)
			(copperpour allowed)
			(footprints allowed)
		)
		(placement
			(enabled no)
			(sheetname "")
		)
		(fill
			(thermal_gap 0.5)
			(thermal_bridge_width 0.5)
			(island_removal_mode 0)
		)
		(polygon
			(pts
				(xy 44.424092 -59.816746) (xy 44.424092 -38.93058) (xy 65.376044 -38.93058) (xy 65.376044 -59.816746)
			)
		)
	)
	(zone
		(layer "Cmts.User")
		(hatch none 0.5)
		(connect_pads
			(clearance 0)
		)
		(min_thickness 0.25)
		(keepout
			(tracks allowed)
			(vias allowed)
			(pads allowed)
			(copperpour allowed)
			(footprints allowed)
		)
		(placement
			(enabled no)
			(sheetname "")
		)
		(fill
			(thermal_gap 0.5)
			(thermal_bridge_width 0.5)
			(island_removal_mode 0)
		)
		(polygon
			(pts
				(xy 101.8413 -105.84434) (xy 101.8413 -103.68534) (xy 105.8037 -103.68534) (xy 105.8037 -105.84434)
			)
		)
	)
	(zone
		(layer "Cmts.User")
		(hatch none 0.5)
		(connect_pads
			(clearance 0)
		)
		(min_thickness 0.25)
		(keepout
			(tracks allowed)
			(vias allowed)
			(pads allowed)
			(copperpour allowed)
			(footprints allowed)
		)
		(placement
			(enabled no)
			(sheetname "")
		)
		(fill
			(thermal_gap 0.5)
			(thermal_bridge_width 0.5)
			(island_removal_mode 0)
		)
		(polygon
			(pts
				(xy 93.945456 -5.684774) (xy 93.945456 -3.525774) (xy 97.907856 -3.525774) (xy 97.907856 -5.684774)
			)
		)
	)
	(zone
		(layer "Cmts.User")
		(hatch none 0.5)
		(connect_pads
			(clearance 0)
		)
		(min_thickness 0.25)
		(keepout
			(tracks allowed)
			(vias allowed)
			(pads allowed)
			(copperpour allowed)
			(footprints allowed)
		)
		(placement
			(enabled no)
			(sheetname "")
		)
		(fill
			(thermal_gap 0.5)
			(thermal_bridge_width 0.5)
			(island_removal_mode 0)
		)
		(polygon
			(pts
				(xy 93.923104 41.006014) (xy 93.923104 43.165014) (xy 97.885504 43.165014) (xy 97.885504 41.006014)
			)
		)
	)
	(zone
		(layer "Cmts.User")
		(hatch none 0.5)
		(connect_pads
			(clearance 0)
		)
		(min_thickness 0.25)
		(keepout
			(tracks allowed)
			(vias allowed)
			(pads allowed)
			(copperpour allowed)
			(footprints allowed)
		)
		(placement
			(enabled no)
			(sheetname "")
		)
		(fill
			(thermal_gap 0.5)
			(thermal_bridge_width 0.5)
			(island_removal_mode 0)
		)
		(polygon
			(pts
				(xy 99.3013 -105.84434) (xy 99.3013 -103.68534) (xy 103.2637 -103.68534) (xy 103.2637 -105.84434)
			)
		)
	)
	(zone
		(layer "Cmts.User")
		(hatch none 0.5)
		(connect_pads
			(clearance 0)
		)
		(min_thickness 0.25)
		(keepout
			(tracks allowed)
			(vias allowed)
			(pads allowed)
			(copperpour allowed)
			(footprints allowed)
		)
		(placement
			(enabled no)
			(sheetname "")
		)
		(fill
			(thermal_gap 0.5)
			(thermal_bridge_width 0.5)
			(island_removal_mode 0)
		)
		(polygon
			(pts
				(xy 28.45943 -91.1606) (xy 28.45943 -86.587076) (xy 14.459458 -86.587076) (xy 14.459458 -100.587048)
				(xy 19.0246 -100.587048) (xy 28.45943 -100.587048)
			)
		)
	)
	(zone
		(layer "Cmts.User")
		(hatch none 0.5)
		(connect_pads
			(clearance 0)
		)
		(min_thickness 0.25)
		(keepout
			(tracks allowed)
			(vias allowed)
			(pads allowed)
			(copperpour allowed)
			(footprints allowed)
		)
		(placement
			(enabled no)
			(sheetname "")
		)
		(fill
			(thermal_gap 0.5)
			(thermal_bridge_width 0.5)
			(island_removal_mode 0)
		)
		(polygon
			(pts
				(xy 101.8413 -55.483252) (xy 101.8413 -53.324252) (xy 105.8037 -53.324252) (xy 105.8037 -55.483252)
			)
		)
	)
	(zone
		(layer "Cmts.User")
		(hatch none 0.5)
		(connect_pads
			(clearance 0)
		)
		(min_thickness 0.25)
		(keepout
			(tracks allowed)
			(vias allowed)
			(pads allowed)
			(copperpour allowed)
			(footprints allowed)
		)
		(placement
			(enabled no)
			(sheetname "")
		)
		(fill
			(thermal_gap 0.5)
			(thermal_bridge_width 0.5)
			(island_removal_mode 0)
		)
		(polygon
			(pts
				(xy 101.8413 -66.7131) (xy 101.8413 -64.5541) (xy 105.8037 -64.5541) (xy 105.8037 -66.7131)
			)
		)
	)
	(zone
		(layer "Cmts.User")
		(hatch none 0.5)
		(connect_pads
			(clearance 0)
		)
		(min_thickness 0.25)
		(keepout
			(tracks allowed)
			(vias allowed)
			(pads allowed)
			(copperpour allowed)
			(footprints allowed)
		)
		(placement
			(enabled no)
			(sheetname "")
		)
		(fill
			(thermal_gap 0.5)
			(thermal_bridge_width 0.5)
			(island_removal_mode 0)
		)
		(polygon
			(pts
				(xy 72.3265 -50.814986) (xy 72.3265 -49.242726) (xy 72.3265 -49.003966) (xy 72.233282 -48.910748)
				(xy 72.233282 -44.7675) (xy 71.620888 -44.155106) (xy 71.620888 -43.706542) (xy 72.233282 -43.094148)
				(xy 72.233282 -41.015666) (xy 72.237346 -41.011602) (xy 73.313544 -41.011602) (xy 80.39354 -41.011602)
				(xy 80.39354 -54.867302) (xy 73.35774 -54.867302) (xy 72.461374 -54.867302) (xy 72.3265 -54.732428)
				(xy 72.3265 -51.074066)
			)
		)
	)
	(zone
		(layer "Cmts.User")
		(hatch none 0.5)
		(connect_pads
			(clearance 0)
		)
		(min_thickness 0.25)
		(keepout
			(tracks allowed)
			(vias allowed)
			(pads allowed)
			(copperpour allowed)
			(footprints allowed)
		)
		(placement
			(enabled no)
			(sheetname "")
		)
		(fill
			(thermal_gap 0.5)
			(thermal_bridge_width 0.5)
			(island_removal_mode 0)
		)
		(polygon
			(pts
				(xy 93.945456 -99.479862) (xy 93.945456 -97.320862) (xy 97.907856 -97.320862) (xy 97.907856 -99.479862)
			)
		)
	)
	(zone
		(layer "Cmts.User")
		(hatch none 0.5)
		(connect_pads
			(clearance 0)
		)
		(min_thickness 0.25)
		(keepout
			(tracks allowed)
			(vias allowed)
			(pads allowed)
			(copperpour allowed)
			(footprints allowed)
		)
		(placement
			(enabled no)
			(sheetname "")
		)
		(fill
			(thermal_gap 0.5)
			(thermal_bridge_width 0.5)
			(island_removal_mode 0)
		)
		(polygon
			(pts
				(xy 93.930216 111.687102) (xy 93.930216 113.846102) (xy 97.892616 113.846102) (xy 97.892616 111.687102)
			)
		)
	)
	(zone
		(layer "Cmts.User")
		(hatch none 0.5)
		(connect_pads
			(clearance 0)
		)
		(min_thickness 0.25)
		(keepout
			(tracks allowed)
			(vias allowed)
			(pads allowed)
			(copperpour allowed)
			(footprints allowed)
		)
		(placement
			(enabled no)
			(sheetname "")
		)
		(fill
			(thermal_gap 0.5)
			(thermal_bridge_width 0.5)
			(island_removal_mode 0)
		)
		(polygon
			(pts
				(xy 99.3013 16.921988) (xy 99.3013 19.080988) (xy 103.2637 19.080988) (xy 103.2637 16.921988)
			)
		)
	)
	(zone
		(layer "Cmts.User")
		(hatch none 0.5)
		(connect_pads
			(clearance 0)
		)
		(min_thickness 0.25)
		(keepout
			(tracks allowed)
			(vias allowed)
			(pads allowed)
			(copperpour allowed)
			(footprints allowed)
		)
		(placement
			(enabled no)
			(sheetname "")
		)
		(fill
			(thermal_gap 0.5)
			(thermal_bridge_width 0.5)
			(island_removal_mode 0)
		)
		(polygon
			(pts
				(xy 93.945456 52.296314) (xy 93.945456 54.455314) (xy 97.907856 54.455314) (xy 97.907856 52.296314)
			)
		)
	)
	(zone
		(layer "Cmts.User")
		(hatch none 0.5)
		(connect_pads
			(clearance 0)
		)
		(min_thickness 0.25)
		(keepout
			(tracks allowed)
			(vias allowed)
			(pads allowed)
			(copperpour allowed)
			(footprints allowed)
		)
		(placement
			(enabled no)
			(sheetname "")
		)
		(fill
			(thermal_gap 0.5)
			(thermal_bridge_width 0.5)
			(island_removal_mode 0)
		)
		(polygon
			(pts
				(xy 99.3013 -55.483252) (xy 99.3013 -53.324252) (xy 103.2637 -53.324252) (xy 103.2637 -55.483252)
			)
		)
	)
	(zone
		(layer "Cmts.User")
		(hatch none 0.5)
		(connect_pads
			(clearance 0)
		)
		(min_thickness 0.25)
		(keepout
			(tracks allowed)
			(vias allowed)
			(pads allowed)
			(copperpour allowed)
			(footprints allowed)
		)
		(placement
			(enabled no)
			(sheetname "")
		)
		(fill
			(thermal_gap 0.5)
			(thermal_bridge_width 0.5)
			(island_removal_mode 0)
		)
		(polygon
			(pts
				(xy 99.286568 118.30685) (xy 99.286568 120.46585) (xy 103.248968 120.46585) (xy 103.248968 118.30685)
			)
		)
	)
	(zone
		(layer "Cmts.User")
		(hatch none 0.5)
		(connect_pads
			(clearance 0)
		)
		(min_thickness 0.25)
		(keepout
			(tracks allowed)
			(vias allowed)
			(pads allowed)
			(copperpour allowed)
			(footprints allowed)
		)
		(placement
			(enabled no)
			(sheetname "")
		)
		(fill
			(thermal_gap 0.5)
			(thermal_bridge_width 0.5)
			(island_removal_mode 0)
		)
		(polygon
			(pts
				(xy 99.30892 28.182062) (xy 99.30892 30.341062) (xy 103.27132 30.341062) (xy 103.27132 28.182062)
			)
		)
	)
	(zone
		(layer "Cmts.User")
		(hatch none 0.5)
		(connect_pads
			(clearance 0)
		)
		(min_thickness 0.25)
		(keepout
			(tracks allowed)
			(vias allowed)
			(pads allowed)
			(copperpour allowed)
			(footprints allowed)
		)
		(placement
			(enabled no)
			(sheetname "")
		)
		(fill
			(thermal_gap 0.5)
			(thermal_bridge_width 0.5)
			(island_removal_mode 0)
		)
		(polygon
			(pts
				(xy 99.3013 -66.7131) (xy 99.3013 -64.5541) (xy 103.2637 -64.5541) (xy 103.2637 -66.7131)
			)
		)
	)
	(zone
		(layer "Cmts.User")
		(hatch none 0.5)
		(connect_pads
			(clearance 0)
		)
		(min_thickness 0.25)
		(keepout
			(tracks allowed)
			(vias allowed)
			(pads allowed)
			(copperpour allowed)
			(footprints allowed)
		)
		(placement
			(enabled no)
			(sheetname "")
		)
		(fill
			(thermal_gap 0.5)
			(thermal_bridge_width 0.5)
			(island_removal_mode 0)
		)
		(polygon
			(pts
				(xy 101.8413 16.921988) (xy 101.8413 19.080988) (xy 105.8037 19.080988) (xy 105.8037 16.921988)
			)
		)
	)
	(zone
		(layer "Cmts.User")
		(hatch none 0.5)
		(connect_pads
			(clearance 0)
		)
		(min_thickness 0.25)
		(keepout
			(tracks allowed)
			(vias allowed)
			(pads allowed)
			(copperpour allowed)
			(footprints allowed)
		)
		(placement
			(enabled no)
			(sheetname "")
		)
		(fill
			(thermal_gap 0.5)
			(thermal_bridge_width 0.5)
			(island_removal_mode 0)
		)
		(polygon
			(pts
				(xy 93.930216 -16.975074) (xy 93.930216 -14.816074) (xy 97.892616 -14.816074) (xy 97.892616 -16.975074)
			)
		)
	)
	(zone
		(layer "In9.Cu")
		(hatch none 0.5)
		(connect_pads
			(clearance 0)
		)
		(min_thickness 0.25)
		(keepout
			(tracks allowed)
			(vias allowed)
			(pads allowed)
			(copperpour allowed)
			(footprints allowed)
		)
		(placement
			(enabled no)
			(sheetname "")
		)
		(fill
			(thermal_gap 0.5)
			(thermal_bridge_width 0.5)
			(island_removal_mode 0)
		)
		(polygon
			(pts
				(xy 27.912822 -97.564702) (xy 31.608014 -97.564702) (xy 32.249618 -96.923098) (xy 32.249618 -91.291918)
				(xy 31.983934 -91.026234) (xy 27.757882 -91.026234) (xy 27.525472 -91.258644) (xy 27.525472 -97.177352)
			)
		)
	)
	(zone
		(layer "In9.Cu")
		(hatch none 0.5)
		(connect_pads
			(clearance 0)
		)
		(min_thickness 0.25)
		(keepout
			(tracks allowed)
			(vias allowed)
			(pads allowed)
			(copperpour allowed)
			(footprints allowed)
		)
		(placement
			(enabled no)
			(sheetname "")
		)
		(fill
			(thermal_gap 0.5)
			(thermal_bridge_width 0.5)
			(island_removal_mode 0)
		)
		(polygon
			(pts
				(xy 65.57264 -59.875166) (xy 64.36614 -61.081666) (xy 44.80052 -61.081666) (xy 44.2468 -60.527946)
				(xy 44.2468 -54.002178) (xy 43.595036 -53.350414) (xy 43.595036 -52.476908) (xy 44.2468 -51.825144)
				(xy 44.2468 -39.866824) (xy 44.2468 -38.921182) (xy 44.318174 -38.849808) (xy 65.338706 -38.849808)
				(xy 65.57264 -39.083742)
			)
		)
	)
	(zone
		(layers "In9.Cu" "In10.Cu")
		(hatch none 0.5)
		(connect_pads
			(clearance 0)
		)
		(min_thickness 0.25)
		(keepout
			(tracks not_allowed)
			(vias allowed)
			(pads allowed)
			(copperpour not_allowed)
			(footprints allowed)
		)
		(placement
			(enabled no)
			(sheetname "")
		)
		(fill yes
			(thermal_gap 0.5)
			(thermal_bridge_width 0.5)
			(island_removal_mode 0)
		)
		(polygon
			(pts
				(arc
					(start 61.727334 -62.614556)
					(mid 61.79777 -62.586068)
					(end 61.827156 -62.516004)
				)
				(xy 61.827156 -62.375796) (xy 61.767212 -62.375796) (xy 61.767212 -62.110874) (xy 61.387228 -62.110874)
				(xy 61.387228 -62.375796) (xy 61.327284 -62.375796)
				(arc
					(start 61.327284 -62.516004)
					(mid 61.356674 -62.586064)
					(end 61.427106 -62.614556)
				)
			)
		)
	)
	(zone
		(layers "In9.Cu" "In10.Cu")
		(hatch none 0.5)
		(connect_pads
			(clearance 0)
		)
		(min_thickness 0.25)
		(keepout
			(tracks not_allowed)
			(vias allowed)
			(pads allowed)
			(copperpour not_allowed)
			(footprints allowed)
		)
		(placement
			(enabled no)
			(sheetname "")
		)
		(fill yes
			(thermal_gap 0.5)
			(thermal_bridge_width 0.5)
			(island_removal_mode 0)
		)
		(polygon
			(pts
				(arc
					(start 45.489114 -97.45345)
					(mid 45.55955 -97.424962)
					(end 45.588936 -97.354898)
				)
				(xy 45.588936 -97.21469) (xy 45.528992 -97.21469) (xy 45.528992 -96.949768) (xy 45.149008 -96.949768)
				(xy 45.149008 -97.21469) (xy 45.089064 -97.21469)
				(arc
					(start 45.089064 -97.354898)
					(mid 45.118454 -97.424958)
					(end 45.188886 -97.45345)
				)
			)
		)
	)
	(zone
		(layers "In9.Cu" "In10.Cu")
		(hatch none 0.5)
		(connect_pads
			(clearance 0)
		)
		(min_thickness 0.25)
		(keepout
			(tracks not_allowed)
			(vias allowed)
			(pads allowed)
			(copperpour not_allowed)
			(footprints allowed)
		)
		(placement
			(enabled no)
			(sheetname "")
		)
		(fill yes
			(thermal_gap 0.5)
			(thermal_bridge_width 0.5)
			(island_removal_mode 0)
		)
		(polygon
			(pts
				(xy 42.540174 -93.2688) (xy 42.819574 -93.2688) (xy 42.819574 -93.9292) (xy 42.540174 -93.9292)
			)
		)
	)
	(zone
		(layers "In9.Cu" "In10.Cu")
		(hatch none 0.5)
		(connect_pads
			(clearance 0)
		)
		(min_thickness 0.25)
		(keepout
			(tracks not_allowed)
			(vias allowed)
			(pads allowed)
			(copperpour not_allowed)
			(footprints allowed)
		)
		(placement
			(enabled no)
			(sheetname "")
		)
		(fill yes
			(thermal_gap 0.5)
			(thermal_bridge_width 0.5)
			(island_removal_mode 0)
		)
		(polygon
			(pts
				(arc
					(start 62.743334 -62.614556)
					(mid 62.81377 -62.586068)
					(end 62.843156 -62.516004)
				)
				(xy 62.843156 -62.375796) (xy 62.783212 -62.375796) (xy 62.783212 -62.110874) (xy 62.403228 -62.110874)
				(xy 62.403228 -62.375796) (xy 62.343284 -62.375796)
				(arc
					(start 62.343284 -62.516004)
					(mid 62.372674 -62.586064)
					(end 62.443106 -62.614556)
				)
			)
		)
	)
	(zone
		(layers "In9.Cu" "In10.Cu")
		(hatch none 0.5)
		(connect_pads
			(clearance 0)
		)
		(min_thickness 0.25)
		(keepout
			(tracks not_allowed)
			(vias allowed)
			(pads allowed)
			(copperpour not_allowed)
			(footprints allowed)
		)
		(placement
			(enabled no)
			(sheetname "")
		)
		(fill yes
			(thermal_gap 0.5)
			(thermal_bridge_width 0.5)
			(island_removal_mode 0)
		)
		(polygon
			(pts
				(xy 41.540176 -93.2688) (xy 41.819576 -93.2688) (xy 41.819576 -93.9292) (xy 41.540176 -93.9292)
			)
		)
	)
	(zone
		(layers "In9.Cu" "In10.Cu")
		(hatch none 0.5)
		(connect_pads
			(clearance 0)
		)
		(min_thickness 0.25)
		(keepout
			(tracks not_allowed)
			(vias allowed)
			(pads allowed)
			(copperpour not_allowed)
			(footprints allowed)
		)
		(placement
			(enabled no)
			(sheetname "")
		)
		(fill yes
			(thermal_gap 0.5)
			(thermal_bridge_width 0.5)
			(island_removal_mode 0)
		)
		(polygon
			(pts
				(arc
					(start 62.443106 -61.357256)
					(mid 62.37267 -61.385744)
					(end 62.343284 -61.455808)
				)
				(xy 62.343284 -61.596016) (xy 62.403228 -61.596016) (xy 62.403228 -61.860938) (xy 62.783212 -61.860938)
				(xy 62.783212 -61.596016) (xy 62.843156 -61.596016)
				(arc
					(start 62.843156 -61.455808)
					(mid 62.813766 -61.385748)
					(end 62.743334 -61.357256)
				)
			)
		)
	)
	(zone
		(layers "In9.Cu" "In10.Cu")
		(hatch none 0.5)
		(connect_pads
			(clearance 0)
		)
		(min_thickness 0.25)
		(keepout
			(tracks not_allowed)
			(vias allowed)
			(pads allowed)
			(copperpour not_allowed)
			(footprints allowed)
		)
		(placement
			(enabled no)
			(sheetname "")
		)
		(fill yes
			(thermal_gap 0.5)
			(thermal_bridge_width 0.5)
			(island_removal_mode 0)
		)
		(polygon
			(pts
				(arc
					(start 45.188886 -96.19615)
					(mid 45.11845 -96.224638)
					(end 45.089064 -96.294702)
				)
				(xy 45.089064 -96.43491) (xy 45.149008 -96.43491) (xy 45.149008 -96.699832) (xy 45.528992 -96.699832)
				(xy 45.528992 -96.43491) (xy 45.588936 -96.43491)
				(arc
					(start 45.588936 -96.294702)
					(mid 45.559546 -96.224642)
					(end 45.489114 -96.19615)
				)
			)
		)
	)
	(zone
		(layers "In9.Cu" "In10.Cu")
		(hatch none 0.5)
		(connect_pads
			(clearance 0)
		)
		(min_thickness 0.25)
		(keepout
			(tracks not_allowed)
			(vias allowed)
			(pads allowed)
			(copperpour not_allowed)
			(footprints allowed)
		)
		(placement
			(enabled no)
			(sheetname "")
		)
		(fill yes
			(thermal_gap 0.5)
			(thermal_bridge_width 0.5)
			(island_removal_mode 0)
		)
		(polygon
			(pts
				(xy 40.540178 -91.068652) (xy 40.819578 -91.068652) (xy 40.819578 -91.729052) (xy 40.540178 -91.729052)
			)
		)
	)
	(zone
		(layers "In9.Cu" "In10.Cu")
		(hatch none 0.5)
		(connect_pads
			(clearance 0)
		)
		(min_thickness 0.25)
		(keepout
			(tracks not_allowed)
			(vias allowed)
			(pads allowed)
			(copperpour not_allowed)
			(footprints allowed)
		)
		(placement
			(enabled no)
			(sheetname "")
		)
		(fill yes
			(thermal_gap 0.5)
			(thermal_bridge_width 0.5)
			(island_removal_mode 0)
		)
		(polygon
			(pts
				(arc
					(start 46.505114 -97.45345)
					(mid 46.57555 -97.424962)
					(end 46.604936 -97.354898)
				)
				(xy 46.604936 -97.21469) (xy 46.544992 -97.21469) (xy 46.544992 -96.949768) (xy 46.165008 -96.949768)
				(xy 46.165008 -97.21469) (xy 46.105064 -97.21469)
				(arc
					(start 46.105064 -97.354898)
					(mid 46.134454 -97.424958)
					(end 46.204886 -97.45345)
				)
			)
		)
	)
	(zone
		(layers "In9.Cu" "In10.Cu")
		(hatch none 0.5)
		(connect_pads
			(clearance 0)
		)
		(min_thickness 0.25)
		(keepout
			(tracks not_allowed)
			(vias allowed)
			(pads allowed)
			(copperpour not_allowed)
			(footprints allowed)
		)
		(placement
			(enabled no)
			(sheetname "")
		)
		(fill yes
			(thermal_gap 0.5)
			(thermal_bridge_width 0.5)
			(island_removal_mode 0)
		)
		(polygon
			(pts
				(xy 40.040306 -91.068652) (xy 40.319706 -91.068652) (xy 40.319706 -91.729052) (xy 40.040306 -91.729052)
			)
		)
	)
	(zone
		(layers "In9.Cu" "In10.Cu")
		(hatch none 0.5)
		(connect_pads
			(clearance 0)
		)
		(min_thickness 0.25)
		(keepout
			(tracks not_allowed)
			(vias allowed)
			(pads allowed)
			(copperpour not_allowed)
			(footprints allowed)
		)
		(placement
			(enabled no)
			(sheetname "")
		)
		(fill yes
			(thermal_gap 0.5)
			(thermal_bridge_width 0.5)
			(island_removal_mode 0)
		)
		(polygon
			(pts
				(xy 43.0403 -93.2688) (xy 43.3197 -93.2688) (xy 43.3197 -93.9292) (xy 43.0403 -93.9292)
			)
		)
	)
	(zone
		(layers "In9.Cu" "In10.Cu")
		(hatch none 0.5)
		(connect_pads
			(clearance 0)
		)
		(min_thickness 0.25)
		(keepout
			(tracks not_allowed)
			(vias allowed)
			(pads allowed)
			(copperpour not_allowed)
			(footprints allowed)
		)
		(placement
			(enabled no)
			(sheetname "")
		)
		(fill yes
			(thermal_gap 0.5)
			(thermal_bridge_width 0.5)
			(island_removal_mode 0)
		)
		(polygon
			(pts
				(xy 42.540174 -91.068652) (xy 42.819574 -91.068652) (xy 42.819574 -91.729052) (xy 42.540174 -91.729052)
			)
		)
	)
	(zone
		(layers "In9.Cu" "In10.Cu")
		(hatch none 0.5)
		(connect_pads
			(clearance 0)
		)
		(min_thickness 0.25)
		(keepout
			(tracks not_allowed)
			(vias allowed)
			(pads allowed)
			(copperpour not_allowed)
			(footprints allowed)
		)
		(placement
			(enabled no)
			(sheetname "")
		)
		(fill yes
			(thermal_gap 0.5)
			(thermal_bridge_width 0.5)
			(island_removal_mode 0)
		)
		(polygon
			(pts
				(xy 42.040302 -93.2688) (xy 42.319702 -93.2688) (xy 42.319702 -93.9292) (xy 42.040302 -93.9292)
			)
		)
	)
	(zone
		(layers "In9.Cu" "In10.Cu")
		(hatch none 0.5)
		(connect_pads
			(clearance 0)
		)
		(min_thickness 0.25)
		(keepout
			(tracks not_allowed)
			(vias allowed)
			(pads allowed)
			(copperpour not_allowed)
			(footprints allowed)
		)
		(placement
			(enabled no)
			(sheetname "")
		)
		(fill yes
			(thermal_gap 0.5)
			(thermal_bridge_width 0.5)
			(island_removal_mode 0)
		)
		(polygon
			(pts
				(xy 42.040302 -91.068652) (xy 42.319702 -91.068652) (xy 42.319702 -91.729052) (xy 42.040302 -91.729052)
			)
		)
	)
	(zone
		(layers "In9.Cu" "In10.Cu")
		(hatch none 0.5)
		(connect_pads
			(clearance 0)
		)
		(min_thickness 0.25)
		(keepout
			(tracks not_allowed)
			(vias allowed)
			(pads allowed)
			(copperpour not_allowed)
			(footprints allowed)
		)
		(placement
			(enabled no)
			(sheetname "")
		)
		(fill yes
			(thermal_gap 0.5)
			(thermal_bridge_width 0.5)
			(island_removal_mode 0)
		)
		(polygon
			(pts
				(arc
					(start 61.427106 -61.357256)
					(mid 61.35667 -61.385744)
					(end 61.327284 -61.455808)
				)
				(xy 61.327284 -61.596016) (xy 61.387228 -61.596016) (xy 61.387228 -61.860938) (xy 61.767212 -61.860938)
				(xy 61.767212 -61.596016) (xy 61.827156 -61.596016)
				(arc
					(start 61.827156 -61.455808)
					(mid 61.797766 -61.385748)
					(end 61.727334 -61.357256)
				)
			)
		)
	)
	(zone
		(layers "In9.Cu" "In10.Cu")
		(hatch none 0.5)
		(connect_pads
			(clearance 0)
		)
		(min_thickness 0.25)
		(keepout
			(tracks not_allowed)
			(vias allowed)
			(pads allowed)
			(copperpour not_allowed)
			(footprints allowed)
		)
		(placement
			(enabled no)
			(sheetname "")
		)
		(fill yes
			(thermal_gap 0.5)
			(thermal_bridge_width 0.5)
			(island_removal_mode 0)
		)
		(polygon
			(pts
				(arc
					(start 46.204886 -96.19615)
					(mid 46.13445 -96.224638)
					(end 46.105064 -96.294702)
				)
				(xy 46.105064 -96.43491) (xy 46.165008 -96.43491) (xy 46.165008 -96.699832) (xy 46.544992 -96.699832)
				(xy 46.544992 -96.43491) (xy 46.604936 -96.43491)
				(arc
					(start 46.604936 -96.294702)
					(mid 46.575546 -96.224642)
					(end 46.505114 -96.19615)
				)
			)
		)
	)
	(zone
		(layer "In10.Cu")
		(hatch none 0.5)
		(connect_pads
			(clearance 0)
		)
		(min_thickness 0.25)
		(keepout
			(tracks not_allowed)
			(vias allowed)
			(pads allowed)
			(copperpour not_allowed)
			(footprints allowed)
		)
		(placement
			(enabled no)
			(sheetname "")
		)
		(fill
			(thermal_gap 0.5)
			(thermal_bridge_width 0.5)
			(island_removal_mode 0)
		)
		(polygon
			(pts
				(xy 101.9048 -53.290216) (xy 101.9048 -54.054756) (xy 100.65512 -54.054756) (xy 100.65512 -53.290216)
			)
		)
	)
	(zone
		(layer "In10.Cu")
		(hatch none 0.5)
		(connect_pads
			(clearance 0)
		)
		(min_thickness 0.25)
		(keepout
			(tracks not_allowed)
			(vias allowed)
			(pads allowed)
			(copperpour not_allowed)
			(footprints allowed)
		)
		(placement
			(enabled no)
			(sheetname "")
		)
		(fill
			(thermal_gap 0.5)
			(thermal_bridge_width 0.5)
			(island_removal_mode 0)
		)
		(polygon
			(pts
				(xy 100.6602 16.887952) (xy 100.6602 17.652492) (xy 101.90988 17.652492) (xy 101.90988 16.887952)
			)
		)
	)
	(zone
		(layer "In10.Cu")
		(hatch none 0.5)
		(connect_pads
			(clearance 0)
		)
		(min_thickness 0.25)
		(keepout
			(tracks not_allowed)
			(vias allowed)
			(pads allowed)
			(copperpour not_allowed)
			(footprints allowed)
		)
		(placement
			(enabled no)
			(sheetname "")
		)
		(fill
			(thermal_gap 0.5)
			(thermal_bridge_width 0.5)
			(island_removal_mode 0)
		)
		(polygon
			(pts
				(xy 95.289116 111.653066) (xy 95.289116 112.417606) (xy 96.538796 112.417606) (xy 96.538796 111.653066)
			)
		)
	)
	(zone
		(layer "In10.Cu")
		(hatch none 0.5)
		(connect_pads
			(clearance 0)
		)
		(min_thickness 0.25)
		(keepout
			(tracks not_allowed)
			(vias allowed)
			(pads allowed)
			(copperpour not_allowed)
			(footprints allowed)
		)
		(placement
			(enabled no)
			(sheetname "")
		)
		(fill
			(thermal_gap 0.5)
			(thermal_bridge_width 0.5)
			(island_removal_mode 0)
		)
		(polygon
			(pts
				(xy 103.2002 -66.747136) (xy 103.2002 -65.982596) (xy 104.44988 -65.982596) (xy 104.44988 -66.747136)
			)
		)
	)
	(zone
		(layer "In10.Cu")
		(hatch none 0.5)
		(connect_pads
			(clearance 0)
		)
		(min_thickness 0.25)
		(keepout
			(tracks not_allowed)
			(vias allowed)
			(pads allowed)
			(copperpour not_allowed)
			(footprints allowed)
		)
		(placement
			(enabled no)
			(sheetname "")
		)
		(fill
			(thermal_gap 0.5)
			(thermal_bridge_width 0.5)
			(island_removal_mode 0)
		)
		(polygon
			(pts
				(xy 96.548956 54.48935) (xy 96.548956 53.72481) (xy 95.299276 53.72481) (xy 95.299276 54.48935)
			)
		)
	)
	(zone
		(layer "In10.Cu")
		(hatch none 0.5)
		(connect_pads
			(clearance 0)
		)
		(min_thickness 0.25)
		(keepout
			(tracks not_allowed)
			(vias allowed)
			(pads allowed)
			(copperpour not_allowed)
			(footprints allowed)
		)
		(placement
			(enabled no)
			(sheetname "")
		)
		(fill
			(thermal_gap 0.5)
			(thermal_bridge_width 0.5)
			(island_removal_mode 0)
		)
		(polygon
			(pts
				(xy 100.645468 118.272814) (xy 100.645468 119.037354) (xy 101.895148 119.037354) (xy 101.895148 118.272814)
			)
		)
	)
	(zone
		(layer "In10.Cu")
		(hatch none 0.5)
		(connect_pads
			(clearance 0)
		)
		(min_thickness 0.25)
		(keepout
			(tracks not_allowed)
			(vias allowed)
			(pads allowed)
			(copperpour not_allowed)
			(footprints allowed)
		)
		(placement
			(enabled no)
			(sheetname "")
		)
		(fill
			(thermal_gap 0.5)
			(thermal_bridge_width 0.5)
			(island_removal_mode 0)
		)
		(polygon
			(pts
				(xy 101.91242 30.375098) (xy 101.91242 29.610558) (xy 100.66274 29.610558) (xy 100.66274 30.375098)
			)
		)
	)
	(zone
		(layer "In10.Cu")
		(hatch none 0.5)
		(connect_pads
			(clearance 0)
		)
		(min_thickness 0.25)
		(keepout
			(tracks not_allowed)
			(vias allowed)
			(pads allowed)
			(copperpour not_allowed)
			(footprints allowed)
		)
		(placement
			(enabled no)
			(sheetname "")
		)
		(fill
			(thermal_gap 0.5)
			(thermal_bridge_width 0.5)
			(island_removal_mode 0)
		)
		(polygon
			(pts
				(xy 104.4448 -103.651304) (xy 104.4448 -104.415844) (xy 103.19512 -104.415844) (xy 103.19512 -103.651304)
			)
		)
	)
)
